LOGICAL PART CROSS REFERENCE - 16-Jun-2017 AT 17:50:48

DRAWING: @BASEBOARD_FAB2_LIB.BASEBOARD_FAB2(SCH_1):PAGE21 

RES_0402-221,1.0%,1/16W,CHIP,GA  I149  R6N10
   1 SVID_ALERT0_CPU0_N      A @BASEBOARD_FAB2_LIB.BASEBOARD_FAB2(SCH_1):SVID_ALERT0_CPU0_N
   2 SVID_ALERT0_CPU0_R_N      B @BASEBOARD_FAB2_LIB.BASEBOARD_FAB2(SCH_1):SVID_ALERT0_CPU0_R_N

RES_0402-0.0,5%,1/16W,CHIP,G21A  I150  R6N12
   1 SVID_CLK0_CPU0      A @BASEBOARD_FAB2_LIB.BASEBOARD_FAB2(SCH_1):SVID_CLK0_CPU0
   2 SVID_CLK0_CPU0_R      B @BASEBOARD_FAB2_LIB.BASEBOARD_FAB2(SCH_1):SVID_CLK0_CPU0_R

RES_0402-0.0,5%,1/16W,CHIP,G21A  I151  R6N11
   1 SVID_DIO0_CPU0      A @BASEBOARD_FAB2_LIB.BASEBOARD_FAB2(SCH_1):SVID_DIO0_CPU0
   2 SVID_DIO0_CPU0_R      B @BASEBOARD_FAB2_LIB.BASEBOARD_FAB2(SCH_1):SVID_DIO0_CPU0_R

RES_0402-221,1.0%,1/16W,CHIP,GA  I152  R6B3
   1 SVID_ALERT1_CPU0_N      A @BASEBOARD_FAB2_LIB.BASEBOARD_FAB2(SCH_1):SVID_ALERT1_CPU0_N
   2 SVID_ALERT1_CPU0_R_N      B @BASEBOARD_FAB2_LIB.BASEBOARD_FAB2(SCH_1):SVID_ALERT1_CPU0_R_N

RES_0402-0.0,5%,1/16W,CHIP,G21A  I153  R6B5
   1 SVID_CLK1_CPU0      A @BASEBOARD_FAB2_LIB.BASEBOARD_FAB2(SCH_1):SVID_CLK1_CPU0
   2 SVID_CLK1_CPU0_R      B @BASEBOARD_FAB2_LIB.BASEBOARD_FAB2(SCH_1):SVID_CLK1_CPU0_R

RES_0402-0.0,5%,1/16W,CHIP,G21A  I154  R6B4
   1 SVID_DIO1_CPU0      A @BASEBOARD_FAB2_LIB.BASEBOARD_FAB2(SCH_1):SVID_DIO1_CPU0
   2 SVID_DIO1_CPU0_R      B @BASEBOARD_FAB2_LIB.BASEBOARD_FAB2(SCH_1):SVID_DIO1_CPU0_R

RES_0402-100.0,1%,1/16W,CHIP,GA  I159  R6B2
   1 PVCCIO_CPU0      A @BASEBOARD_FAB2_LIB.BASEBOARD_FAB2(SCH_1):PVCCIO_CPU0
   2 SVID_DIO1_CPU0_R      B @BASEBOARD_FAB2_LIB.BASEBOARD_FAB2(SCH_1):SVID_DIO1_CPU0_R

RES_0402-49.9,1%,1/16W,CHIP,G2A  I161  R6B1
   1 PVCCIO_CPU0      A @BASEBOARD_FAB2_LIB.BASEBOARD_FAB2(SCH_1):PVCCIO_CPU0
   2 SVID_ALERT1_CPU0_R_N      B @BASEBOARD_FAB2_LIB.BASEBOARD_FAB2(SCH_1):SVID_ALERT1_CPU0_R_N

RES_0402-100.0,1%,1/16W,CHIP,GA  I163  R6N2
   1 SVID_DIO0_CPU0_R      A @BASEBOARD_FAB2_LIB.BASEBOARD_FAB2(SCH_1):SVID_DIO0_CPU0_R
   2 PVCCIO_CPU0      B @BASEBOARD_FAB2_LIB.BASEBOARD_FAB2(SCH_1):PVCCIO_CPU0

RES_0402-49.9,1%,1/16W,CHIP,G2A  I164  R6N1
   1 SVID_ALERT0_CPU0_R_N      A @BASEBOARD_FAB2_LIB.BASEBOARD_FAB2(SCH_1):SVID_ALERT0_CPU0_R_N
   2 PVCCIO_CPU0      B @BASEBOARD_FAB2_LIB.BASEBOARD_FAB2(SCH_1):PVCCIO_CPU0

RES_0402-90.9,1%,1/16W,CHIP,G2A  I177  R5D1
   1 A_CPU0_DEF_RCOMP0      A @BASEBOARD_FAB2_LIB.BASEBOARD_FAB2(SCH_1):A_CPU0_DEF_RCOMP0
   2    GND      B @BASEBOARD_FAB2_LIB.BASEBOARD_FAB2(SCH_1):GND

RES_0402-90.9,1%,1/16W,CHIP,G2A  I178  R5D2
   1 A_CPU0_DEF_RCOMP1      A @BASEBOARD_FAB2_LIB.BASEBOARD_FAB2(SCH_1):A_CPU0_DEF_RCOMP1
   2    GND      B @BASEBOARD_FAB2_LIB.BASEBOARD_FAB2(SCH_1):GND

RES_0402-100.0,1%,1/16W,CHIP,GA  I179  R6D1
   1 A_CPU0_DEF_RCOMP2      A @BASEBOARD_FAB2_LIB.BASEBOARD_FAB2(SCH_1):A_CPU0_DEF_RCOMP2
   2    GND      B @BASEBOARD_FAB2_LIB.BASEBOARD_FAB2(SCH_1):GND

RES_0402-90.9,1%,1/16W,CHIP,G2A  I180  R4P8
   1 A_CPU0_ABC_RCOMP0      A @BASEBOARD_FAB2_LIB.BASEBOARD_FAB2(SCH_1):A_CPU0_ABC_RCOMP0
   2    GND      B @BASEBOARD_FAB2_LIB.BASEBOARD_FAB2(SCH_1):GND

RES_0402-90.9,1%,1/16W,CHIP,G2A  I181  R4P10
   1 A_CPU0_ABC_RCOMP1      A @BASEBOARD_FAB2_LIB.BASEBOARD_FAB2(SCH_1):A_CPU0_ABC_RCOMP1
   2    GND      B @BASEBOARD_FAB2_LIB.BASEBOARD_FAB2(SCH_1):GND

RES_0402-100.0,1%,1/16W,CHIP,GA  I182  R4P11
   1 A_CPU0_ABC_RCOMP2      A @BASEBOARD_FAB2_LIB.BASEBOARD_FAB2(SCH_1):A_CPU0_ABC_RCOMP2
   2    GND      B @BASEBOARD_FAB2_LIB.BASEBOARD_FAB2(SCH_1):GND

RES_0402-49.9,1%,1/16W,CHIP,G2A  I184  R6D11
   1 A_CPU0_UPI01_RBIAS      A @BASEBOARD_FAB2_LIB.BASEBOARD_FAB2(SCH_1):A_CPU0_UPI01_RBIAS
   2    GND      B @BASEBOARD_FAB2_LIB.BASEBOARD_FAB2(SCH_1):GND

RES_0402-49.9,1%,1/16W,CHIP,G2A  I186  R4P3
   1 A_CPU0_PE012_RBIAS      A @BASEBOARD_FAB2_LIB.BASEBOARD_FAB2(SCH_1):A_CPU0_PE012_RBIAS
   2    GND      B @BASEBOARD_FAB2_LIB.BASEBOARD_FAB2(SCH_1):GND

RES_0402-49.9,1%,1/16W,CHIP,G2A  I188  R4P2
   1 A_CPU0_PE3_RBIAS      A @BASEBOARD_FAB2_LIB.BASEBOARD_FAB2(SCH_1):A_CPU0_PE3_RBIAS
   2    GND      B @BASEBOARD_FAB2_LIB.BASEBOARD_FAB2(SCH_1):GND

RES_0402-49.9,1%,1/16W,CHIP,G2A  I189  R4P4
   1 A_CPU0_UPI2_RBIAS      A @BASEBOARD_FAB2_LIB.BASEBOARD_FAB2(SCH_1):A_CPU0_UPI2_RBIAS
   2    GND      B @BASEBOARD_FAB2_LIB.BASEBOARD_FAB2(SCH_1):GND

RES_0402-49.9,1%,1/16W,CHIP,G2A  I204  R6D2
   1 A_CPU0_MCP01_RBIAS      A @BASEBOARD_FAB2_LIB.BASEBOARD_FAB2(SCH_1):A_CPU0_MCP01_RBIAS
   2    GND      B @BASEBOARD_FAB2_LIB.BASEBOARD_FAB2(SCH_1):GND

SOCKET_P_MECH_A_RIGHT-P0,PLASTA  I216  XRU1
SOCKET_P_MECH_A_LEFT-P0,PLASTIA  I217  XLU1
RES_0402-49.9,1%,1/16W,CHIP,G2A  I219  R4P19
   1 H_PMSYNC_CLK_24M_CPU0      A @BASEBOARD_FAB2_LIB.BASEBOARD_FAB2(SCH_1):H_PMSYNC_CLK_24M_CPU0
   2 H_PMSYNC_CLK_24M      B @BASEBOARD_FAB2_LIB.BASEBOARD_FAB2(SCH_1):H_PMSYNC_CLK_24M

RES_0402-1.8K,1%,1/16W,CHIP,G2A  I227  R5N2
   1 P3V3_STBY      A @BASEBOARD_FAB2_LIB.BASEBOARD_FAB2(SCH_1):P3V3_STBY
   2 FM_CPU0_PROC_ID1      B @BASEBOARD_FAB2_LIB.BASEBOARD_FAB2(SCH_1):FM_CPU0_PROC_ID1

RES_0402-10.0K,1%,1/16W,CHIP,GA  I238  R5N1
   1 P3V3_STBY      A @BASEBOARD_FAB2_LIB.BASEBOARD_FAB2(SCH_1):P3V3_STBY
   2 FM_CPU0_PKGID0      B @BASEBOARD_FAB2_LIB.BASEBOARD_FAB2(SCH_1):FM_CPU0_PKGID0

RES_0402-10.0K,1%,1/16W,CHIP,GA  I239  R5N5
   1 P3V3_STBY      A @BASEBOARD_FAB2_LIB.BASEBOARD_FAB2(SCH_1):P3V3_STBY
   2 FM_CPU0_PKGID1      B @BASEBOARD_FAB2_LIB.BASEBOARD_FAB2(SCH_1):FM_CPU0_PKGID1

RES_0402-10.0K,1%,1/16W,CHIP,GA  I240  R5N3
   1 P3V3_STBY      A @BASEBOARD_FAB2_LIB.BASEBOARD_FAB2(SCH_1):P3V3_STBY
   2 FM_CPU0_PKGID2      B @BASEBOARD_FAB2_LIB.BASEBOARD_FAB2(SCH_1):FM_CPU0_PKGID2

RES_0402-1.8K,1%,1/16W,CHIP,G2A  I241  R5N4
   1 P3V3_STBY      A @BASEBOARD_FAB2_LIB.BASEBOARD_FAB2(SCH_1):P3V3_STBY
   2 FM_CPU0_PROC_ID0      B @BASEBOARD_FAB2_LIB.BASEBOARD_FAB2(SCH_1):FM_CPU0_PROC_ID0

RES_0402-49.9,1%,1/16W,CHIP,G2A  I244  R4P18
   1 H_PM_SYNC_GTL_R1      A @BASEBOARD_FAB2_LIB.BASEBOARD_FAB2(SCH_1):H_PM_SYNC_GTL_R1
   2 H_PM_SYNC_GTL      B @BASEBOARD_FAB2_LIB.BASEBOARD_FAB2(SCH_1):H_PM_SYNC_GTL

RES_0402-4.75K,1%,1/16W,CHIP,GA  I258  R4R5
   1 P3V3_STBY      A @BASEBOARD_FAB2_LIB.BASEBOARD_FAB2(SCH_1):P3V3_STBY
   2 FM_CPU0_SKTOCC_LVT3_N      B @BASEBOARD_FAB2_LIB.BASEBOARD_FAB2(SCH_1):FM_CPU0_SKTOCC_LVT3_N

SKX_EXT_B_BGA1-IC,TBD  I259  U5D1
AU24 CLK_100M_CPU0_BCLK0_DN BCLK0_DN @BASEBOARD_FAB2_LIB.BASEBOARD_FAB2(SCH_1):CLK_100M_CPU0_BCLK0_DN
AW24 CLK_100M_CPU0_BCLK0_DP BCLK0_DP @BASEBOARD_FAB2_LIB.BASEBOARD_FAB2(SCH_1):CLK_100M_CPU0_BCLK0_DP
CR26 CLK_100M_CPU0_BCLK1_DN BCLK1_DN @BASEBOARD_FAB2_LIB.BASEBOARD_FAB2(SCH_1):CLK_100M_CPU0_BCLK1_DN
CP27 CLK_100M_CPU0_BCLK1_DP BCLK1_DP @BASEBOARD_FAB2_LIB.BASEBOARD_FAB2(SCH_1):CLK_100M_CPU0_BCLK1_DP
CT25 CLK_100M_CPU0_BCLK2_DN BCLK2_DN @BASEBOARD_FAB2_LIB.BASEBOARD_FAB2(SCH_1):CLK_100M_CPU0_BCLK2_DN
CU26 CLK_100M_CPU0_BCLK2_DP BCLK2_DP @BASEBOARD_FAB2_LIB.BASEBOARD_FAB2(SCH_1):CLK_100M_CPU0_BCLK2_DP
BA20 PD_CPU0_BIST_ENABLE BIST_ENABLE @BASEBOARD_FAB2_LIB.BASEBOARD_FAB2(SCH_1):PD_CPU0_BIST_ENABLE
BD23 H_CPU0_BMCINIT BMCINIT @BASEBOARD_FAB2_LIB.BASEBOARD_FAB2(SCH_1):H_CPU0_BMCINIT
AC12 XDP_CPU_OBSFN_B1_MBP7_N BPM_N<7> @BASEBOARD_FAB2_LIB.BASEBOARD_FAB2(SCH_1):XDP_CPU_OBSFN_B1_MBP7_N
AE12 XDP_CPU_OBSFN_B0_MBP6_N BPM_N<6> @BASEBOARD_FAB2_LIB.BASEBOARD_FAB2(SCH_1):XDP_CPU_OBSFN_B0_MBP6_N
 Y11 TP_XDP_CPU0_OBSDATA_A3_MBP5_N BPM_N<5> @BASEBOARD_FAB2_LIB.BASEBOARD_FAB2(SCH_1):TP_XDP_CPU0_OBSDATA_A3_MBP5_N
AA12 TP_XDP_CPU0_OBSDATA_A2_MBP4_N BPM_N<4> @BASEBOARD_FAB2_LIB.BASEBOARD_FAB2(SCH_1):TP_XDP_CPU0_OBSDATA_A2_MBP4_N
AF11 TP_XDP_CPU0_OBSDATA_A1_MBP3_N BPM_N<3> @BASEBOARD_FAB2_LIB.BASEBOARD_FAB2(SCH_1):TP_XDP_CPU0_OBSDATA_A1_MBP3_N
AG10 TP_XDP_CPU0_OBSDATA_A0_MBP2_N BPM_N<2> @BASEBOARD_FAB2_LIB.BASEBOARD_FAB2(SCH_1):TP_XDP_CPU0_OBSDATA_A0_MBP2_N
AH11 XDP_CPU_MBP1_N BPM_N<1> @BASEBOARD_FAB2_LIB.BASEBOARD_FAB2(SCH_1):XDP_CPU_MBP1_N
AJ10 XDP_CPU_MBP0_N BPM_N<0> @BASEBOARD_FAB2_LIB.BASEBOARD_FAB2(SCH_1):XDP_CPU_MBP0_N
AL14 H_CPU0_CATERR_G_N CATERR_N @BASEBOARD_FAB2_LIB.BASEBOARD_FAB2(SCH_1):H_CPU0_CATERR_G_N
AN30 PWRGD_CPU0_DRAMPWROK_ABC_G DDR012_DRAM_PWR_OK @BASEBOARD_FAB2_LIB.BASEBOARD_FAB2(SCH_1):PWRGD_CPU0_DRAMPWROK_ABC_G
AC42 A_CPU0_ABC_RCOMP2 DDR012_RCOMP<2> @BASEBOARD_FAB2_LIB.BASEBOARD_FAB2(SCH_1):A_CPU0_ABC_RCOMP2
AB43 A_CPU0_ABC_RCOMP1 DDR012_RCOMP<1> @BASEBOARD_FAB2_LIB.BASEBOARD_FAB2(SCH_1):A_CPU0_ABC_RCOMP1
 Y43 A_CPU0_ABC_RCOMP0 DDR012_RCOMP<0> @BASEBOARD_FAB2_LIB.BASEBOARD_FAB2(SCH_1):A_CPU0_ABC_RCOMP0
 U64 M_ABC_RST_N DDR012_RESET_N @BASEBOARD_FAB2_LIB.BASEBOARD_FAB2(SCH_1):M_ABC_RST_N
AJ18 SMB_DDR_ABC_SCL_G_R DDR012_SPDSCL @BASEBOARD_FAB2_LIB.BASEBOARD_FAB2(SCH_1):SMB_DDR_ABC_SCL_G_R
AF17 SMB_DDR_ABC_SDA_G_R DDR012_SPDSDA @BASEBOARD_FAB2_LIB.BASEBOARD_FAB2(SCH_1):SMB_DDR_ABC_SDA_G_R
AJ64 M_A_CPU_VREF DDR0_CAVREF @BASEBOARD_FAB2_LIB.BASEBOARD_FAB2(SCH_1):M_A_CPU_VREF
AK63 M_B_CPU_VREF DDR1_CAVREF @BASEBOARD_FAB2_LIB.BASEBOARD_FAB2(SCH_1):M_B_CPU_VREF
AH63 M_C_CPU_VREF DDR2_CAVREF @BASEBOARD_FAB2_LIB.BASEBOARD_FAB2(SCH_1):M_C_CPU_VREF
CR28 PWRGD_CPU0_DRAMPWROK_DEF_G DDR345_DRAM_PWR_OK @BASEBOARD_FAB2_LIB.BASEBOARD_FAB2(SCH_1):PWRGD_CPU0_DRAMPWROK_DEF_G
DD49 A_CPU0_DEF_RCOMP2 DDR345_RCOMP<2> @BASEBOARD_FAB2_LIB.BASEBOARD_FAB2(SCH_1):A_CPU0_DEF_RCOMP2
DD47 A_CPU0_DEF_RCOMP1 DDR345_RCOMP<1> @BASEBOARD_FAB2_LIB.BASEBOARD_FAB2(SCH_1):A_CPU0_DEF_RCOMP1
DC48 A_CPU0_DEF_RCOMP0 DDR345_RCOMP<0> @BASEBOARD_FAB2_LIB.BASEBOARD_FAB2(SCH_1):A_CPU0_DEF_RCOMP0
DV63 M_DEF_RST_N DDR345_RESET_N @BASEBOARD_FAB2_LIB.BASEBOARD_FAB2(SCH_1):M_DEF_RST_N
AE18 SMB_DDR_DEF_SCL_G_R DDR345_SPDSCL @BASEBOARD_FAB2_LIB.BASEBOARD_FAB2(SCH_1):SMB_DDR_DEF_SCL_G_R
AD17 SMB_DDR_DEF_SDA_G_R DDR345_SPDSDA @BASEBOARD_FAB2_LIB.BASEBOARD_FAB2(SCH_1):SMB_DDR_DEF_SDA_G_R
CP61 M_D_CPU_VREF DDR3_CAVREF @BASEBOARD_FAB2_LIB.BASEBOARD_FAB2(SCH_1):M_D_CPU_VREF
CT61 M_E_CPU_VREF DDR4_CAVREF @BASEBOARD_FAB2_LIB.BASEBOARD_FAB2(SCH_1):M_E_CPU_VREF
CV61 M_F_CPU_VREF DDR5_CAVREF @BASEBOARD_FAB2_LIB.BASEBOARD_FAB2(SCH_1):M_F_CPU_VREF
AJ14 PD_CPU0_EAR_N  EAR_N @BASEBOARD_FAB2_LIB.BASEBOARD_FAB2(SCH_1):PD_CPU0_EAR_N
AL12 H_CPU0_ERR2_G_N ERROR_N<2> @BASEBOARD_FAB2_LIB.BASEBOARD_FAB2(SCH_1):H_CPU0_ERR2_G_N
AK11 H_CPU0_ERR1_G_N ERROR_N<1> @BASEBOARD_FAB2_LIB.BASEBOARD_FAB2(SCH_1):H_CPU0_ERR1_G_N
AJ12 H_CPU0_ERR0_G_N ERROR_N<0> @BASEBOARD_FAB2_LIB.BASEBOARD_FAB2(SCH_1):H_CPU0_ERR0_G_N
AV17 PU_CPU0_FRMAGENT FRMAGENT @BASEBOARD_FAB2_LIB.BASEBOARD_FAB2(SCH_1):PU_CPU0_FRMAGENT
AE20 PU_CPU0_LEGACY_SKT LEGACY_SKT @BASEBOARD_FAB2_LIB.BASEBOARD_FAB2(SCH_1):PU_CPU0_LEGACY_SKT
CT31 A_CPU0_MCP01_RBIAS MCP01_RBIAS<1> @BASEBOARD_FAB2_LIB.BASEBOARD_FAB2(SCH_1):A_CPU0_MCP01_RBIAS
CU32 A_CPU0_MCP01_RBIAS MCP01_RBIAS<0> @BASEBOARD_FAB2_LIB.BASEBOARD_FAB2(SCH_1):A_CPU0_MCP01_RBIAS
AH13 H_CPU0_MEMABC_MEMHOT_G_N MEM_HOT_C012_N @BASEBOARD_FAB2_LIB.BASEBOARD_FAB2(SCH_1):H_CPU0_MEMABC_MEMHOT_G_N
AF13 H_CPU0_MEMDEF_MEMHOT_G_N MEM_HOT_C345_N @BASEBOARD_FAB2_LIB.BASEBOARD_FAB2(SCH_1):H_CPU0_MEMDEF_MEMHOT_G_N
AN20 H_CPU0_MSMI_G_N MSMI_N @BASEBOARD_FAB2_LIB.BASEBOARD_FAB2(SCH_1):H_CPU0_MSMI_G_N
AP11 TP_NMI_CPU0    NMI @BASEBOARD_FAB2_LIB.BASEBOARD_FAB2(SCH_1):TP_NMI_CPU0
CL30 A_CPU0_PE012_RBIAS PE012_RBIAS<1> @BASEBOARD_FAB2_LIB.BASEBOARD_FAB2(SCH_1):A_CPU0_PE012_RBIAS
CN30 A_CPU0_PE012_RBIAS PE012_RBIAS<0> @BASEBOARD_FAB2_LIB.BASEBOARD_FAB2(SCH_1):A_CPU0_PE012_RBIAS
CR30 A_CPU0_PE3_RBIAS PE3_RBIAS<1> @BASEBOARD_FAB2_LIB.BASEBOARD_FAB2(SCH_1):A_CPU0_PE3_RBIAS
CP29 A_CPU0_PE3_RBIAS PE3_RBIAS<0> @BASEBOARD_FAB2_LIB.BASEBOARD_FAB2(SCH_1):A_CPU0_PE3_RBIAS
AU12 PECI_CPU_G   PECI @BASEBOARD_FAB2_LIB.BASEBOARD_FAB2(SCH_1):PECI_CPU_G
AM19 SMB_CPU0_PE_HP_GTL_SCL PE_HP_SCL @BASEBOARD_FAB2_LIB.BASEBOARD_FAB2(SCH_1):SMB_CPU0_PE_HP_GTL_SCL
AL18 SMB_CPU0_PE_HP_GTL_SDA PE_HP_SDA @BASEBOARD_FAB2_LIB.BASEBOARD_FAB2(SCH_1):SMB_CPU0_PE_HP_GTL_SDA
CW56 PD_PIROM_CPU0_ADDR2 PIROM_ADDR<2> @BASEBOARD_FAB2_LIB.BASEBOARD_FAB2(SCH_1):PD_PIROM_CPU0_ADDR2
CV57 PD_PIROM_CPU0_ADDR1 PIROM_ADDR<1> @BASEBOARD_FAB2_LIB.BASEBOARD_FAB2(SCH_1):PD_PIROM_CPU0_ADDR1
CU58 PD_PIROM_CPU0_ADDR0 PIROM_ADDR<0> @BASEBOARD_FAB2_LIB.BASEBOARD_FAB2(SCH_1):PD_PIROM_CPU0_ADDR0
DA72 FM_CPU0_PKGID2 PKGID<2> @BASEBOARD_FAB2_LIB.BASEBOARD_FAB2(SCH_1):FM_CPU0_PKGID2
CW72 FM_CPU0_PKGID1 PKGID<1> @BASEBOARD_FAB2_LIB.BASEBOARD_FAB2(SCH_1):FM_CPU0_PKGID1
DC72 FM_CPU0_PKGID0 PKGID<0> @BASEBOARD_FAB2_LIB.BASEBOARD_FAB2(SCH_1):FM_CPU0_PKGID0
AR14 H_PM_SYNC_GTL_R1 PMSYNC @BASEBOARD_FAB2_LIB.BASEBOARD_FAB2(SCH_1):H_PM_SYNC_GTL_R1
AT19 H_PMSYNC_CLK_24M_CPU0 PMSYNC_CLK @BASEBOARD_FAB2_LIB.BASEBOARD_FAB2(SCH_1):H_PMSYNC_CLK_24M_CPU0
AF15 H_CPU0_FAST_WAKE_N PM_FAST_WAKE_N @BASEBOARD_FAB2_LIB.BASEBOARD_FAB2(SCH_1):H_CPU0_FAST_WAKE_N
AG16 XDP_CPU_PRDY_N PRDY_N @BASEBOARD_FAB2_LIB.BASEBOARD_FAB2(SCH_1):XDP_CPU_PRDY_N
AR12 XDP_CPU_PREQ_N PREQ_N @BASEBOARD_FAB2_LIB.BASEBOARD_FAB2(SCH_1):XDP_CPU_PREQ_N
AB17 TP_CPU0_PROCDIS_G_N PROCDIS_N @BASEBOARD_FAB2_LIB.BASEBOARD_FAB2(SCH_1):TP_CPU0_PROCDIS_G_N
AC16 H_CPU0_PROCHOT_G_N PROCHOT_N @BASEBOARD_FAB2_LIB.BASEBOARD_FAB2(SCH_1):H_CPU0_PROCHOT_G_N
DB71 FM_CPU0_PROC_ID1 PROC_ID<1> @BASEBOARD_FAB2_LIB.BASEBOARD_FAB2(SCH_1):FM_CPU0_PROC_ID1
CY71 FM_CPU0_PROC_ID0 PROC_ID<0> @BASEBOARD_FAB2_LIB.BASEBOARD_FAB2(SCH_1):FM_CPU0_PROC_ID0
BC24 PWRGD_CPU0_G PWRGOOD @BASEBOARD_FAB2_LIB.BASEBOARD_FAB2(SCH_1):PWRGD_CPU0_G
AP21 RST_CPU0_G_N RESET_N @BASEBOARD_FAB2_LIB.BASEBOARD_FAB2(SCH_1):RST_CPU0_G_N
AR18 PU_CPU0_SAFE_MODE_BOOT SAFE_MODE_BOOT @BASEBOARD_FAB2_LIB.BASEBOARD_FAB2(SCH_1):PU_CPU0_SAFE_MODE_BOOT
AB13 FM_CPU0_SKTOCC_LVT3_N SKTOCC_N @BASEBOARD_FAB2_LIB.BASEBOARD_FAB2(SCH_1):FM_CPU0_SKTOCC_LVT3_N
CT59 SMB_PIROM_CPU0_SCL SMBCLK @BASEBOARD_FAB2_LIB.BASEBOARD_FAB2(SCH_1):SMB_PIROM_CPU0_SCL
CW58 SMB_PIROM_CPU0_SDA SMBDAT @BASEBOARD_FAB2_LIB.BASEBOARD_FAB2(SCH_1):SMB_PIROM_CPU0_SDA
CV59 FM_CPU0_SM_WP  SM_WP @BASEBOARD_FAB2_LIB.BASEBOARD_FAB2(SCH_1):FM_CPU0_SM_WP
AU20 TP_CPU0_SOCKET_ID_2 SOCKET_ID<2> @BASEBOARD_FAB2_LIB.BASEBOARD_FAB2(SCH_1):TP_CPU0_SOCKET_ID_2
AU16 PU_CPU0_SOCKET_ID_1 SOCKET_ID<1> @BASEBOARD_FAB2_LIB.BASEBOARD_FAB2(SCH_1):PU_CPU0_SOCKET_ID_1
AU22 PU_CPU0_SOCKET_ID_0 SOCKET_ID<0> @BASEBOARD_FAB2_LIB.BASEBOARD_FAB2(SCH_1):PU_CPU0_SOCKET_ID_0
DL44 SVID_ALERT1_CPU0_N SVIDALERT_N<1> @BASEBOARD_FAB2_LIB.BASEBOARD_FAB2(SCH_1):SVID_ALERT1_CPU0_N
DE44 SVID_ALERT0_CPU0_N SVIDALERT_N<0> @BASEBOARD_FAB2_LIB.BASEBOARD_FAB2(SCH_1):SVID_ALERT0_CPU0_N
DG44 SVID_CLK1_CPU0 SVIDCLK<1> @BASEBOARD_FAB2_LIB.BASEBOARD_FAB2(SCH_1):SVID_CLK1_CPU0
DC44 SVID_CLK0_CPU0 SVIDCLK<0> @BASEBOARD_FAB2_LIB.BASEBOARD_FAB2(SCH_1):SVID_CLK0_CPU0
DJ44 SVID_DIO1_CPU0 SVIDDATA<1> @BASEBOARD_FAB2_LIB.BASEBOARD_FAB2(SCH_1):SVID_DIO1_CPU0
DB45 SVID_DIO0_CPU0 SVIDDATA<0> @BASEBOARD_FAB2_LIB.BASEBOARD_FAB2(SCH_1):SVID_DIO0_CPU0
AA14 XDP_CPU_TCK0    TCK @BASEBOARD_FAB2_LIB.BASEBOARD_FAB2(SCH_1):XDP_CPU_TCK0
AC14 XDP_CPU_TDI    TDI @BASEBOARD_FAB2_LIB.BASEBOARD_FAB2(SCH_1):XDP_CPU_TDI
AE14 XDP_CPU0_TDO    TDO @BASEBOARD_FAB2_LIB.BASEBOARD_FAB2(SCH_1):XDP_CPU0_TDO
AY19 PD_CPU0_TEST12 TEST_12 @BASEBOARD_FAB2_LIB.BASEBOARD_FAB2(SCH_1):PD_CPU0_TEST12
DB51 PD_CPU0_TEST13 TEST_13 @BASEBOARD_FAB2_LIB.BASEBOARD_FAB2(SCH_1):PD_CPU0_TEST13
DC50 PD_CPU0_TEST14 TEST_14 @BASEBOARD_FAB2_LIB.BASEBOARD_FAB2(SCH_1):PD_CPU0_TEST14
AW14 PD_CPU0_KSFC_DIS TEST_15 @BASEBOARD_FAB2_LIB.BASEBOARD_FAB2(SCH_1):PD_CPU0_KSFC_DIS
AB15 H_CPU0_THERMTRIP_G_N THERMTRIP_N @BASEBOARD_FAB2_LIB.BASEBOARD_FAB2(SCH_1):H_CPU0_THERMTRIP_G_N
 W14 XDP_CPU_TMS    TMS @BASEBOARD_FAB2_LIB.BASEBOARD_FAB2(SCH_1):XDP_CPU_TMS
 Y13 XDP_CPU_TRST_N TRST_N @BASEBOARD_FAB2_LIB.BASEBOARD_FAB2(SCH_1):XDP_CPU_TRST_N
AM11 PU_CPU0_TSC_SYNC TSC_SYNC @BASEBOARD_FAB2_LIB.BASEBOARD_FAB2(SCH_1):PU_CPU0_TSC_SYNC
AW18 PU_CPU0_TXT_AGENT TXT_AGENT @BASEBOARD_FAB2_LIB.BASEBOARD_FAB2(SCH_1):PU_CPU0_TXT_AGENT
AV15 PD_CPU0_TXT_PLTEN TXT_PLTEN @BASEBOARD_FAB2_LIB.BASEBOARD_FAB2(SCH_1):PD_CPU0_TXT_PLTEN
AP29 A_CPU0_UPI01_RBIAS UPI01_RBIAS<1> @BASEBOARD_FAB2_LIB.BASEBOARD_FAB2(SCH_1):A_CPU0_UPI01_RBIAS
AT29 A_CPU0_UPI01_RBIAS UPI01_RBIAS<0> @BASEBOARD_FAB2_LIB.BASEBOARD_FAB2(SCH_1):A_CPU0_UPI01_RBIAS
CK29 A_CPU0_UPI2_RBIAS UPI2_RBIAS<1> @BASEBOARD_FAB2_LIB.BASEBOARD_FAB2(SCH_1):A_CPU0_UPI2_RBIAS
CL28 A_CPU0_UPI2_RBIAS UPI2_RBIAS<0> @BASEBOARD_FAB2_LIB.BASEBOARD_FAB2(SCH_1):A_CPU0_UPI2_RBIAS


DRAWING: @BASEBOARD_FAB2_LIB.BASEBOARD_FAB2(SCH_1):PAGE22 

RES_0402-49.9,1%,1/16W,CHIP,G2A  I188  R5R1
   1 PD_CPU0_RSVD_TEST_1      A @BASEBOARD_FAB2_LIB.BASEBOARD_FAB2(SCH_1):PD_CPU0_RSVD_TEST_1
   2    GND      B @BASEBOARD_FAB2_LIB.BASEBOARD_FAB2(SCH_1):GND

RES_0402-49.9,1%,1/16W,CHIP,G2A  I190  R5P4
   1 PD_CPU0_RSVD_TEST_2      A @BASEBOARD_FAB2_LIB.BASEBOARD_FAB2(SCH_1):PD_CPU0_RSVD_TEST_2
   2    GND      B @BASEBOARD_FAB2_LIB.BASEBOARD_FAB2(SCH_1):GND

SKX_EXT_B_BGA1-IC,TBD  I204  U5D1
AV21 CPU_XDP_PRESENT_N DEBUG_EN_N @BASEBOARD_FAB2_LIB.BASEBOARD_FAB2(SCH_1):CPU_XDP_PRESENT_N
AW12 PD_CPU0_DMIMODE_OVERRIDE DMIMODE_OVERRIDE @BASEBOARD_FAB2_LIB.BASEBOARD_FAB2(SCH_1):PD_CPU0_DMIMODE_OVERRIDE
AU14 H_CPU0_FIVR_FAULT_G FIVR_FAULT @BASEBOARD_FAB2_LIB.BASEBOARD_FAB2(SCH_1):H_CPU0_FIVR_FAULT_G
AP17 XDP_CPU_PWR_DEBUG_N PWR_DEBUG_N @BASEBOARD_FAB2_LIB.BASEBOARD_FAB2(SCH_1):XDP_CPU_PWR_DEBUG_N
  A4 TP_CPU0_RSVD_304 RSVD<304> @BASEBOARD_FAB2_LIB.BASEBOARD_FAB2(SCH_1):TP_CPU0_RSVD_304
  A6 TP_CPU0_RSVD_303 RSVD<303> @BASEBOARD_FAB2_LIB.BASEBOARD_FAB2(SCH_1):TP_CPU0_RSVD_303
 A14 P1V8_MCP_CPU0 RSVD<302> @BASEBOARD_FAB2_LIB.BASEBOARD_FAB2(SCH_1):P1V8_MCP_CPU0
 A16 P1V8_MCP_CPU0 RSVD<301> @BASEBOARD_FAB2_LIB.BASEBOARD_FAB2(SCH_1):P1V8_MCP_CPU0
 A24 TP_CPU0_RSVD_300 RSVD<300> @BASEBOARD_FAB2_LIB.BASEBOARD_FAB2(SCH_1):TP_CPU0_RSVD_300
  B3 TP_CPU0_RSVD_299 RSVD<299> @BASEBOARD_FAB2_LIB.BASEBOARD_FAB2(SCH_1):TP_CPU0_RSVD_299
  B7 TP_CPU0_RSVD_298 RSVD<298> @BASEBOARD_FAB2_LIB.BASEBOARD_FAB2(SCH_1):TP_CPU0_RSVD_298
 B13 P1V8_MCP_CPU0 RSVD<296> @BASEBOARD_FAB2_LIB.BASEBOARD_FAB2(SCH_1):P1V8_MCP_CPU0
 B15 P1V8_MCP_CPU0 RSVD<295> @BASEBOARD_FAB2_LIB.BASEBOARD_FAB2(SCH_1):P1V8_MCP_CPU0
 B17 P1V8_MCP_CPU0 RSVD<294> @BASEBOARD_FAB2_LIB.BASEBOARD_FAB2(SCH_1):P1V8_MCP_CPU0
 B77 TP_CPU0_RSVD_293 RSVD<293> @BASEBOARD_FAB2_LIB.BASEBOARD_FAB2(SCH_1):TP_CPU0_RSVD_293
 B81 TP_CPU0_RSVD_292 RSVD<292> @BASEBOARD_FAB2_LIB.BASEBOARD_FAB2(SCH_1):TP_CPU0_RSVD_292
  C6 TP_CPU0_RSVD_291 RSVD<291> @BASEBOARD_FAB2_LIB.BASEBOARD_FAB2(SCH_1):TP_CPU0_RSVD_291
 C18 TP_CPU0_RSVD_290 RSVD<290> @BASEBOARD_FAB2_LIB.BASEBOARD_FAB2(SCH_1):TP_CPU0_RSVD_290
 C24 TP_CPU0_RSVD_289 RSVD<289> @BASEBOARD_FAB2_LIB.BASEBOARD_FAB2(SCH_1):TP_CPU0_RSVD_289
 C82 TP_CPU0_RSVD_288 RSVD<288> @BASEBOARD_FAB2_LIB.BASEBOARD_FAB2(SCH_1):TP_CPU0_RSVD_288
  D5 TP_CPU0_RSVD_287 RSVD<287> @BASEBOARD_FAB2_LIB.BASEBOARD_FAB2(SCH_1):TP_CPU0_RSVD_287
 D17 TP_CPU0_RSVD_286 RSVD<286> @BASEBOARD_FAB2_LIB.BASEBOARD_FAB2(SCH_1):TP_CPU0_RSVD_286
 D65 TP_CPU0_RSVD_285 RSVD<285> @BASEBOARD_FAB2_LIB.BASEBOARD_FAB2(SCH_1):TP_CPU0_RSVD_285
 D83 TP_CPU0_RSVD_284 RSVD<284> @BASEBOARD_FAB2_LIB.BASEBOARD_FAB2(SCH_1):TP_CPU0_RSVD_284
  E2 TP_CPU0_RSVD_283 RSVD<283> @BASEBOARD_FAB2_LIB.BASEBOARD_FAB2(SCH_1):TP_CPU0_RSVD_283
  E4 TP_CPU0_RSVD_282 RSVD<282> @BASEBOARD_FAB2_LIB.BASEBOARD_FAB2(SCH_1):TP_CPU0_RSVD_282
 E24 TP_CPU0_RSVD_281 RSVD<281> @BASEBOARD_FAB2_LIB.BASEBOARD_FAB2(SCH_1):TP_CPU0_RSVD_281
 E84 TP_CPU0_RSVD_280 RSVD<280> @BASEBOARD_FAB2_LIB.BASEBOARD_FAB2(SCH_1):TP_CPU0_RSVD_280
  F3 TP_CPU0_RSVD_279 RSVD<279> @BASEBOARD_FAB2_LIB.BASEBOARD_FAB2(SCH_1):TP_CPU0_RSVD_279
 F23 TP_CPU0_RSVD_278 RSVD<278> @BASEBOARD_FAB2_LIB.BASEBOARD_FAB2(SCH_1):TP_CPU0_RSVD_278
 F65 TP_CPU0_RSVD_277 RSVD<277> @BASEBOARD_FAB2_LIB.BASEBOARD_FAB2(SCH_1):TP_CPU0_RSVD_277
 F83 TP_CPU0_RSVD_276 RSVD<276> @BASEBOARD_FAB2_LIB.BASEBOARD_FAB2(SCH_1):TP_CPU0_RSVD_276
  G2 TP_CPU0_RSVD_275 RSVD<275> @BASEBOARD_FAB2_LIB.BASEBOARD_FAB2(SCH_1):TP_CPU0_RSVD_275
 G64 TP_CPU0_RSVD_274 RSVD<274> @BASEBOARD_FAB2_LIB.BASEBOARD_FAB2(SCH_1):TP_CPU0_RSVD_274
 G84 TP_CPU0_RSVD_273 RSVD<273> @BASEBOARD_FAB2_LIB.BASEBOARD_FAB2(SCH_1):TP_CPU0_RSVD_273
  H1 TP_CPU0_RSVD_272 RSVD<272> @BASEBOARD_FAB2_LIB.BASEBOARD_FAB2(SCH_1):TP_CPU0_RSVD_272
 H83 TP_CPU0_RSVD_271 RSVD<271> @BASEBOARD_FAB2_LIB.BASEBOARD_FAB2(SCH_1):TP_CPU0_RSVD_271
 H85 TP_CPU0_RSVD_270 RSVD<270> @BASEBOARD_FAB2_LIB.BASEBOARD_FAB2(SCH_1):TP_CPU0_RSVD_270
 J46 TP_CPU0_RSVD_269 RSVD<269> @BASEBOARD_FAB2_LIB.BASEBOARD_FAB2(SCH_1):TP_CPU0_RSVD_269
 J62 TP_CPU0_RSVD_268 RSVD<268> @BASEBOARD_FAB2_LIB.BASEBOARD_FAB2(SCH_1):TP_CPU0_RSVD_268
 K61 TP_CPU0_RSVD_267 RSVD<267> @BASEBOARD_FAB2_LIB.BASEBOARD_FAB2(SCH_1):TP_CPU0_RSVD_267
 M63 TP_CPU0_RSVD_266 RSVD<266> @BASEBOARD_FAB2_LIB.BASEBOARD_FAB2(SCH_1):TP_CPU0_RSVD_266
 P65 TP_CPU0_RSVD_265 RSVD<265> @BASEBOARD_FAB2_LIB.BASEBOARD_FAB2(SCH_1):TP_CPU0_RSVD_265
 R62 TP_CPU0_RSVD_264 RSVD<264> @BASEBOARD_FAB2_LIB.BASEBOARD_FAB2(SCH_1):TP_CPU0_RSVD_264
 R66 TP_CPU0_RSVD_263 RSVD<263> @BASEBOARD_FAB2_LIB.BASEBOARD_FAB2(SCH_1):TP_CPU0_RSVD_263
 T67 TP_CPU0_RSVD_262 RSVD<262> @BASEBOARD_FAB2_LIB.BASEBOARD_FAB2(SCH_1):TP_CPU0_RSVD_262
 U66 TP_CPU0_RSVD_261 RSVD<261> @BASEBOARD_FAB2_LIB.BASEBOARD_FAB2(SCH_1):TP_CPU0_RSVD_261
 V65 TP_CPU0_RSVD_260 RSVD<260> @BASEBOARD_FAB2_LIB.BASEBOARD_FAB2(SCH_1):TP_CPU0_RSVD_260
 V67 TP_CPU0_RSVD_259 RSVD<259> @BASEBOARD_FAB2_LIB.BASEBOARD_FAB2(SCH_1):TP_CPU0_RSVD_259
 W66 TP_CPU0_RSVD_258 RSVD<258> @BASEBOARD_FAB2_LIB.BASEBOARD_FAB2(SCH_1):TP_CPU0_RSVD_258
 Y23 FM_CPU0_RC_ERROR_N RSVD<257> @BASEBOARD_FAB2_LIB.BASEBOARD_FAB2(SCH_1):FM_CPU0_RC_ERROR_N
 Y65 TP_CPU0_RSVD_256 RSVD<256> @BASEBOARD_FAB2_LIB.BASEBOARD_FAB2(SCH_1):TP_CPU0_RSVD_256
AD47 TP_CPU0_RSVD_254 RSVD<254> @BASEBOARD_FAB2_LIB.BASEBOARD_FAB2(SCH_1):TP_CPU0_RSVD_254
AD49 TP_CPU0_RSVD_253 RSVD<253> @BASEBOARD_FAB2_LIB.BASEBOARD_FAB2(SCH_1):TP_CPU0_RSVD_253
AD51 TP_CPU0_RSVD_252 RSVD<252> @BASEBOARD_FAB2_LIB.BASEBOARD_FAB2(SCH_1):TP_CPU0_RSVD_252
AE46 TP_CPU0_RSVD_251 RSVD<251> @BASEBOARD_FAB2_LIB.BASEBOARD_FAB2(SCH_1):TP_CPU0_RSVD_251
AE48 TP_CPU0_RSVD_250 RSVD<250> @BASEBOARD_FAB2_LIB.BASEBOARD_FAB2(SCH_1):TP_CPU0_RSVD_250
AE50 TP_CPU0_RSVD_249 RSVD<249> @BASEBOARD_FAB2_LIB.BASEBOARD_FAB2(SCH_1):TP_CPU0_RSVD_249
AE52 TP_CPU0_RSVD_248 RSVD<248> @BASEBOARD_FAB2_LIB.BASEBOARD_FAB2(SCH_1):TP_CPU0_RSVD_248
AE72 TP_CPU0_RSVD_247 RSVD<247> @BASEBOARD_FAB2_LIB.BASEBOARD_FAB2(SCH_1):TP_CPU0_RSVD_247
AF19 TP_CPU0_RSVD_246 RSVD<246> @BASEBOARD_FAB2_LIB.BASEBOARD_FAB2(SCH_1):TP_CPU0_RSVD_246
AF47 TP_CPU0_RSVD_245 RSVD<245> @BASEBOARD_FAB2_LIB.BASEBOARD_FAB2(SCH_1):TP_CPU0_RSVD_245
AF49 TP_CPU0_RSVD_244 RSVD<244> @BASEBOARD_FAB2_LIB.BASEBOARD_FAB2(SCH_1):TP_CPU0_RSVD_244
AF51 TP_CPU0_RSVD_243 RSVD<243> @BASEBOARD_FAB2_LIB.BASEBOARD_FAB2(SCH_1):TP_CPU0_RSVD_243
AF53 TP_CPU0_RSVD_242 RSVD<242> @BASEBOARD_FAB2_LIB.BASEBOARD_FAB2(SCH_1):TP_CPU0_RSVD_242
AF71 TP_CPU0_RSVD_241 RSVD<241> @BASEBOARD_FAB2_LIB.BASEBOARD_FAB2(SCH_1):TP_CPU0_RSVD_241
AG20 TP_CPU0_RSVD_240 RSVD<240> @BASEBOARD_FAB2_LIB.BASEBOARD_FAB2(SCH_1):TP_CPU0_RSVD_240
AG48 TP_CPU0_RSVD_239 RSVD<239> @BASEBOARD_FAB2_LIB.BASEBOARD_FAB2(SCH_1):TP_CPU0_RSVD_239
AG50 TP_CPU0_RSVD_238 RSVD<238> @BASEBOARD_FAB2_LIB.BASEBOARD_FAB2(SCH_1):TP_CPU0_RSVD_238
AG52 TP_CPU0_RSVD_237 RSVD<237> @BASEBOARD_FAB2_LIB.BASEBOARD_FAB2(SCH_1):TP_CPU0_RSVD_237
AG54 TP_CPU0_RSVD_236 RSVD<236> @BASEBOARD_FAB2_LIB.BASEBOARD_FAB2(SCH_1):TP_CPU0_RSVD_236
AG56 TP_CPU0_RSVD_235 RSVD<235> @BASEBOARD_FAB2_LIB.BASEBOARD_FAB2(SCH_1):TP_CPU0_RSVD_235
AG72 TP_CPU0_RSVD_234 RSVD<234> @BASEBOARD_FAB2_LIB.BASEBOARD_FAB2(SCH_1):TP_CPU0_RSVD_234
AH15 TP_CPU0_RSVD_233 RSVD<233> @BASEBOARD_FAB2_LIB.BASEBOARD_FAB2(SCH_1):TP_CPU0_RSVD_233
AH19 TP_CPU0_RSVD_232 RSVD<232> @BASEBOARD_FAB2_LIB.BASEBOARD_FAB2(SCH_1):TP_CPU0_RSVD_232
AH55 TP_CPU0_RSVD_231 RSVD<231> @BASEBOARD_FAB2_LIB.BASEBOARD_FAB2(SCH_1):TP_CPU0_RSVD_231
AH57 TP_CPU0_RSVD_230 RSVD<230> @BASEBOARD_FAB2_LIB.BASEBOARD_FAB2(SCH_1):TP_CPU0_RSVD_230
AH71 TP_CPU0_RSVD_229 RSVD<229> @BASEBOARD_FAB2_LIB.BASEBOARD_FAB2(SCH_1):TP_CPU0_RSVD_229
AH73 TP_CPU0_RSVD_228 RSVD<228> @BASEBOARD_FAB2_LIB.BASEBOARD_FAB2(SCH_1):TP_CPU0_RSVD_228
AJ20 TP_CPU0_RSVD_227 RSVD<227> @BASEBOARD_FAB2_LIB.BASEBOARD_FAB2(SCH_1):TP_CPU0_RSVD_227
AJ56 TP_CPU0_RSVD_226 RSVD<226> @BASEBOARD_FAB2_LIB.BASEBOARD_FAB2(SCH_1):TP_CPU0_RSVD_226
AJ58 TP_CPU0_RSVD_225 RSVD<225> @BASEBOARD_FAB2_LIB.BASEBOARD_FAB2(SCH_1):TP_CPU0_RSVD_225
AJ60 TP_CPU0_RSVD_224 RSVD<224> @BASEBOARD_FAB2_LIB.BASEBOARD_FAB2(SCH_1):TP_CPU0_RSVD_224
AJ62 TP_CPU0_RSVD_223 RSVD<223> @BASEBOARD_FAB2_LIB.BASEBOARD_FAB2(SCH_1):TP_CPU0_RSVD_223
AJ70 TP_CPU0_RSVD_222 RSVD<222> @BASEBOARD_FAB2_LIB.BASEBOARD_FAB2(SCH_1):TP_CPU0_RSVD_222
AK21 VSENSE_P1V8MCP_CPU0_SKT_VSEN RSVD<221> @BASEBOARD_FAB2_LIB.BASEBOARD_FAB2(SCH_1):VSENSE_P1V8MCP_CPU0_SKT_VSEN
AK27 CLK_322M_OSC_CPU0_RC_DP RSVD<220> @BASEBOARD_FAB2_LIB.BASEBOARD_FAB2(SCH_1):CLK_322M_OSC_CPU0_RC_DP
AK57 TP_CPU0_RSVD_219 RSVD<219> @BASEBOARD_FAB2_LIB.BASEBOARD_FAB2(SCH_1):TP_CPU0_RSVD_219
AK59 TP_CPU0_RSVD_218 RSVD<218> @BASEBOARD_FAB2_LIB.BASEBOARD_FAB2(SCH_1):TP_CPU0_RSVD_218
AK61 TP_CPU0_RSVD_217 RSVD<217> @BASEBOARD_FAB2_LIB.BASEBOARD_FAB2(SCH_1):TP_CPU0_RSVD_217
AK69 TP_CPU0_RSVD_216 RSVD<216> @BASEBOARD_FAB2_LIB.BASEBOARD_FAB2(SCH_1):TP_CPU0_RSVD_216
AL20 VSENSE_P1V8MCP_CPU0_SKT_VRTN RSVD<215> @BASEBOARD_FAB2_LIB.BASEBOARD_FAB2(SCH_1):VSENSE_P1V8MCP_CPU0_SKT_VRTN
AL22 TP_CPU0_RSVD_214 RSVD<214> @BASEBOARD_FAB2_LIB.BASEBOARD_FAB2(SCH_1):TP_CPU0_RSVD_214
AL26 CLK_322M_OSC_CPU0_RC_DN RSVD<213> @BASEBOARD_FAB2_LIB.BASEBOARD_FAB2(SCH_1):CLK_322M_OSC_CPU0_RC_DN
AL58 TP_CPU0_RSVD_212 RSVD<212> @BASEBOARD_FAB2_LIB.BASEBOARD_FAB2(SCH_1):TP_CPU0_RSVD_212
AL60 TP_CPU0_RSVD_211 RSVD<211> @BASEBOARD_FAB2_LIB.BASEBOARD_FAB2(SCH_1):TP_CPU0_RSVD_211
AL62 TP_CPU0_RSVD_210 RSVD<210> @BASEBOARD_FAB2_LIB.BASEBOARD_FAB2(SCH_1):TP_CPU0_RSVD_210
AM21 PVCCMCP_CPU0 RSVD<209> @BASEBOARD_FAB2_LIB.BASEBOARD_FAB2(SCH_1):PVCCMCP_CPU0
AM23 TP_CPU0_RSVD_208 RSVD<208> @BASEBOARD_FAB2_LIB.BASEBOARD_FAB2(SCH_1):TP_CPU0_RSVD_208
AM25 PVCCMCP_CPU0 RSVD<207> @BASEBOARD_FAB2_LIB.BASEBOARD_FAB2(SCH_1):PVCCMCP_CPU0
AM27 CLK_100M_CPU0_RC_REFCLK0_DP RSVD<206> @BASEBOARD_FAB2_LIB.BASEBOARD_FAB2(SCH_1):CLK_100M_CPU0_RC_REFCLK0_DP
AM59 TP_CPU0_RSVD_205 RSVD<205> @BASEBOARD_FAB2_LIB.BASEBOARD_FAB2(SCH_1):TP_CPU0_RSVD_205
AM61 TP_CPU0_RSVD_204 RSVD<204> @BASEBOARD_FAB2_LIB.BASEBOARD_FAB2(SCH_1):TP_CPU0_RSVD_204
AN18 PVCCMCP_CPU0 RSVD<203> @BASEBOARD_FAB2_LIB.BASEBOARD_FAB2(SCH_1):PVCCMCP_CPU0
AN22 PVCCMCP_CPU0 RSVD<202> @BASEBOARD_FAB2_LIB.BASEBOARD_FAB2(SCH_1):PVCCMCP_CPU0
AN24 PVCCMCP_CPU0 RSVD<201> @BASEBOARD_FAB2_LIB.BASEBOARD_FAB2(SCH_1):PVCCMCP_CPU0
AN26 PVCCMCP_CPU0 RSVD<200> @BASEBOARD_FAB2_LIB.BASEBOARD_FAB2(SCH_1):PVCCMCP_CPU0
AN60 TP_CPU0_RSVD_199 RSVD<199> @BASEBOARD_FAB2_LIB.BASEBOARD_FAB2(SCH_1):TP_CPU0_RSVD_199
AN62 TP_CPU0_RSVD_198 RSVD<198> @BASEBOARD_FAB2_LIB.BASEBOARD_FAB2(SCH_1):TP_CPU0_RSVD_198
AP23 PVCCMCP_CPU0 RSVD<197> @BASEBOARD_FAB2_LIB.BASEBOARD_FAB2(SCH_1):PVCCMCP_CPU0
AP25 PVCCMCP_CPU0 RSVD<196> @BASEBOARD_FAB2_LIB.BASEBOARD_FAB2(SCH_1):PVCCMCP_CPU0
AP27 CLK_100M_CPU0_RC_REFCLK0_DN RSVD<195> @BASEBOARD_FAB2_LIB.BASEBOARD_FAB2(SCH_1):CLK_100M_CPU0_RC_REFCLK0_DN
AP61 TP_CPU0_RSVD_194 RSVD<194> @BASEBOARD_FAB2_LIB.BASEBOARD_FAB2(SCH_1):TP_CPU0_RSVD_194
AF45 PD_CPU0_RSVD_TEST_1 TEST_1 @BASEBOARD_FAB2_LIB.BASEBOARD_FAB2(SCH_1):PD_CPU0_RSVD_TEST_1
AY13 TP_CPU0_RSVD_TEST_11 TEST_11 @BASEBOARD_FAB2_LIB.BASEBOARD_FAB2(SCH_1):TP_CPU0_RSVD_TEST_11
AG46 PD_CPU0_RSVD_TEST_2 TEST_2 @BASEBOARD_FAB2_LIB.BASEBOARD_FAB2(SCH_1):PD_CPU0_RSVD_TEST_2
AM13 TP_CPU0_RSVD_TEST_3 TEST_3 @BASEBOARD_FAB2_LIB.BASEBOARD_FAB2(SCH_1):TP_CPU0_RSVD_TEST_3
AN12 TP_CPU0_RSVD_TEST_4 TEST_4 @BASEBOARD_FAB2_LIB.BASEBOARD_FAB2(SCH_1):TP_CPU0_RSVD_TEST_4
AN14 TP_CPU0_RSVD_TEST_5 TEST_5 @BASEBOARD_FAB2_LIB.BASEBOARD_FAB2(SCH_1):TP_CPU0_RSVD_TEST_5


DRAWING: @BASEBOARD_FAB2_LIB.BASEBOARD_FAB2(SCH_1):PAGE23 

SKX_EXT_B_BGA1-IC,TBD  I172  U5D1
 J60 M_A_ACT_N DDR0_ACT_N @BASEBOARD_FAB2_LIB.BASEBOARD_FAB2(SCH_1):M_A_ACT_N
 B61 M_A_ALERT_N DDR0_ALERT_N @BASEBOARD_FAB2_LIB.BASEBOARD_FAB2(SCH_1):M_A_ALERT_N
 G54 M_A_BA<1> DDR0_BA<1> @BASEBOARD_FAB2_LIB.BASEBOARD_FAB2(SCH_1):M_A_BA(1)
 C52 M_A_BA<0> DDR0_BA<0> @BASEBOARD_FAB2_LIB.BASEBOARD_FAB2(SCH_1):M_A_BA(0)
 F63 M_A_BG<1> DDR0_BG<1> @BASEBOARD_FAB2_LIB.BASEBOARD_FAB2(SCH_1):M_A_BG(1)
 D61 M_A_BG<0> DDR0_BG<0> @BASEBOARD_FAB2_LIB.BASEBOARD_FAB2(SCH_1):M_A_BG(0)
 G46 M_A_C<2> DDR0_CID<2> @BASEBOARD_FAB2_LIB.BASEBOARD_FAB2(SCH_1):M_A_C(2)
 D63 M_A_CKE<3> DDR0_CKE<3> @BASEBOARD_FAB2_LIB.BASEBOARD_FAB2(SCH_1):M_A_CKE(3)
 B63 M_A_CKE<2> DDR0_CKE<2> @BASEBOARD_FAB2_LIB.BASEBOARD_FAB2(SCH_1):M_A_CKE(2)
 C64 M_A_CKE<1> DDR0_CKE<1> @BASEBOARD_FAB2_LIB.BASEBOARD_FAB2(SCH_1):M_A_CKE(1)
 C62 M_A_CKE<0> DDR0_CKE<0> @BASEBOARD_FAB2_LIB.BASEBOARD_FAB2(SCH_1):M_A_CKE(0)
 C56 M_A_CLK_DN<3> DDR0_CLK_DN<3> @BASEBOARD_FAB2_LIB.BASEBOARD_FAB2(SCH_1):M_A_CLK_DN(3)
 J56 M_A_CLK_DN<2> DDR0_CLK_DN<2> @BASEBOARD_FAB2_LIB.BASEBOARD_FAB2(SCH_1):M_A_CLK_DN(2)
 C54 M_A_CLK_DN<1> DDR0_CLK_DN<1> @BASEBOARD_FAB2_LIB.BASEBOARD_FAB2(SCH_1):M_A_CLK_DN(1)
 F55 M_A_CLK_DN<0> DDR0_CLK_DN<0> @BASEBOARD_FAB2_LIB.BASEBOARD_FAB2(SCH_1):M_A_CLK_DN(0)
 B57 M_A_CLK_DP<3> DDR0_CLK_DP<3> @BASEBOARD_FAB2_LIB.BASEBOARD_FAB2(SCH_1):M_A_CLK_DP(3)
 G56 M_A_CLK_DP<2> DDR0_CLK_DP<2> @BASEBOARD_FAB2_LIB.BASEBOARD_FAB2(SCH_1):M_A_CLK_DP(2)
 B55 M_A_CLK_DP<1> DDR0_CLK_DP<1> @BASEBOARD_FAB2_LIB.BASEBOARD_FAB2(SCH_1):M_A_CLK_DP(1)
 D55 M_A_CLK_DP<0> DDR0_CLK_DP<0> @BASEBOARD_FAB2_LIB.BASEBOARD_FAB2(SCH_1):M_A_CLK_DP(0)
 K45 M_A_CS_N<7> DDR0_CS_N<7> @BASEBOARD_FAB2_LIB.BASEBOARD_FAB2(SCH_1):M_A_CS_N(7)
 F45 M_A_CS_N<6> DDR0_CS_N<6> @BASEBOARD_FAB2_LIB.BASEBOARD_FAB2(SCH_1):M_A_CS_N(6)
 D49 M_A_CS_N<5> DDR0_CS_N<5> @BASEBOARD_FAB2_LIB.BASEBOARD_FAB2(SCH_1):M_A_CS_N(5)
 B51 M_A_CS_N<4> DDR0_CS_N<4> @BASEBOARD_FAB2_LIB.BASEBOARD_FAB2(SCH_1):M_A_CS_N(4)
 F47 M_A_CS_N<3> DDR0_CS_N<3> @BASEBOARD_FAB2_LIB.BASEBOARD_FAB2(SCH_1):M_A_CS_N(3)
 D47 M_A_CS_N<2> DDR0_CS_N<2> @BASEBOARD_FAB2_LIB.BASEBOARD_FAB2(SCH_1):M_A_CS_N(2)
 F49 M_A_CS_N<1> DDR0_CS_N<1> @BASEBOARD_FAB2_LIB.BASEBOARD_FAB2(SCH_1):M_A_CS_N(1)
 G52 M_A_CS_N<0> DDR0_CS_N<0> @BASEBOARD_FAB2_LIB.BASEBOARD_FAB2(SCH_1):M_A_CS_N(0)
 K23 M_A_DQ<63> DDR0_DQ<63> @BASEBOARD_FAB2_LIB.BASEBOARD_FAB2(SCH_1):M_A_DQ(63)
 H23 M_A_DQ<62> DDR0_DQ<62> @BASEBOARD_FAB2_LIB.BASEBOARD_FAB2(SCH_1):M_A_DQ(62)
 N26 M_A_DQ<61> DDR0_DQ<61> @BASEBOARD_FAB2_LIB.BASEBOARD_FAB2(SCH_1):M_A_DQ(61)
 L26 M_A_DQ<60> DDR0_DQ<60> @BASEBOARD_FAB2_LIB.BASEBOARD_FAB2(SCH_1):M_A_DQ(60)
 T23 M_A_DQ<59> DDR0_DQ<59> @BASEBOARD_FAB2_LIB.BASEBOARD_FAB2(SCH_1):M_A_DQ(59)
 P23 M_A_DQ<58> DDR0_DQ<58> @BASEBOARD_FAB2_LIB.BASEBOARD_FAB2(SCH_1):M_A_DQ(58)
 P25 M_A_DQ<57> DDR0_DQ<57> @BASEBOARD_FAB2_LIB.BASEBOARD_FAB2(SCH_1):M_A_DQ(57)
 K25 M_A_DQ<56> DDR0_DQ<56> @BASEBOARD_FAB2_LIB.BASEBOARD_FAB2(SCH_1):M_A_DQ(56)
 P29 M_A_DQ<55> DDR0_DQ<55> @BASEBOARD_FAB2_LIB.BASEBOARD_FAB2(SCH_1):M_A_DQ(55)
 K29 M_A_DQ<54> DDR0_DQ<54> @BASEBOARD_FAB2_LIB.BASEBOARD_FAB2(SCH_1):M_A_DQ(54)
 N32 M_A_DQ<53> DDR0_DQ<53> @BASEBOARD_FAB2_LIB.BASEBOARD_FAB2(SCH_1):M_A_DQ(53)
 L32 M_A_DQ<52> DDR0_DQ<52> @BASEBOARD_FAB2_LIB.BASEBOARD_FAB2(SCH_1):M_A_DQ(52)
 N28 M_A_DQ<51> DDR0_DQ<51> @BASEBOARD_FAB2_LIB.BASEBOARD_FAB2(SCH_1):M_A_DQ(51)
 L28 M_A_DQ<50> DDR0_DQ<50> @BASEBOARD_FAB2_LIB.BASEBOARD_FAB2(SCH_1):M_A_DQ(50)
 P31 M_A_DQ<49> DDR0_DQ<49> @BASEBOARD_FAB2_LIB.BASEBOARD_FAB2(SCH_1):M_A_DQ(49)
 K31 M_A_DQ<48> DDR0_DQ<48> @BASEBOARD_FAB2_LIB.BASEBOARD_FAB2(SCH_1):M_A_DQ(48)
 P35 M_A_DQ<47> DDR0_DQ<47> @BASEBOARD_FAB2_LIB.BASEBOARD_FAB2(SCH_1):M_A_DQ(47)
 K35 M_A_DQ<46> DDR0_DQ<46> @BASEBOARD_FAB2_LIB.BASEBOARD_FAB2(SCH_1):M_A_DQ(46)
 N38 M_A_DQ<45> DDR0_DQ<45> @BASEBOARD_FAB2_LIB.BASEBOARD_FAB2(SCH_1):M_A_DQ(45)
 L38 M_A_DQ<44> DDR0_DQ<44> @BASEBOARD_FAB2_LIB.BASEBOARD_FAB2(SCH_1):M_A_DQ(44)
 N34 M_A_DQ<43> DDR0_DQ<43> @BASEBOARD_FAB2_LIB.BASEBOARD_FAB2(SCH_1):M_A_DQ(43)
 L34 M_A_DQ<42> DDR0_DQ<42> @BASEBOARD_FAB2_LIB.BASEBOARD_FAB2(SCH_1):M_A_DQ(42)
 P37 M_A_DQ<41> DDR0_DQ<41> @BASEBOARD_FAB2_LIB.BASEBOARD_FAB2(SCH_1):M_A_DQ(41)
 K37 M_A_DQ<40> DDR0_DQ<40> @BASEBOARD_FAB2_LIB.BASEBOARD_FAB2(SCH_1):M_A_DQ(40)
 F39 M_A_DQ<39> DDR0_DQ<39> @BASEBOARD_FAB2_LIB.BASEBOARD_FAB2(SCH_1):M_A_DQ(39)
 B39 M_A_DQ<38> DDR0_DQ<38> @BASEBOARD_FAB2_LIB.BASEBOARD_FAB2(SCH_1):M_A_DQ(38)
 F41 M_A_DQ<37> DDR0_DQ<37> @BASEBOARD_FAB2_LIB.BASEBOARD_FAB2(SCH_1):M_A_DQ(37)
 E42 M_A_DQ<36> DDR0_DQ<36> @BASEBOARD_FAB2_LIB.BASEBOARD_FAB2(SCH_1):M_A_DQ(36)
 E38 M_A_DQ<35> DDR0_DQ<35> @BASEBOARD_FAB2_LIB.BASEBOARD_FAB2(SCH_1):M_A_DQ(35)
 C38 M_A_DQ<34> DDR0_DQ<34> @BASEBOARD_FAB2_LIB.BASEBOARD_FAB2(SCH_1):M_A_DQ(34)
 B41 M_A_DQ<33> DDR0_DQ<33> @BASEBOARD_FAB2_LIB.BASEBOARD_FAB2(SCH_1):M_A_DQ(33)
 C42 M_A_DQ<32> DDR0_DQ<32> @BASEBOARD_FAB2_LIB.BASEBOARD_FAB2(SCH_1):M_A_DQ(32)
 R74 M_A_DQ<31> DDR0_DQ<31> @BASEBOARD_FAB2_LIB.BASEBOARD_FAB2(SCH_1):M_A_DQ(31)
 L74 M_A_DQ<30> DDR0_DQ<30> @BASEBOARD_FAB2_LIB.BASEBOARD_FAB2(SCH_1):M_A_DQ(30)
 P77 M_A_DQ<29> DDR0_DQ<29> @BASEBOARD_FAB2_LIB.BASEBOARD_FAB2(SCH_1):M_A_DQ(29)
 M77 M_A_DQ<28> DDR0_DQ<28> @BASEBOARD_FAB2_LIB.BASEBOARD_FAB2(SCH_1):M_A_DQ(28)
 P73 M_A_DQ<27> DDR0_DQ<27> @BASEBOARD_FAB2_LIB.BASEBOARD_FAB2(SCH_1):M_A_DQ(27)
 M73 M_A_DQ<26> DDR0_DQ<26> @BASEBOARD_FAB2_LIB.BASEBOARD_FAB2(SCH_1):M_A_DQ(26)
 R76 M_A_DQ<25> DDR0_DQ<25> @BASEBOARD_FAB2_LIB.BASEBOARD_FAB2(SCH_1):M_A_DQ(25)
 L76 M_A_DQ<24> DDR0_DQ<24> @BASEBOARD_FAB2_LIB.BASEBOARD_FAB2(SCH_1):M_A_DQ(24)
 N80 M_A_DQ<23> DDR0_DQ<23> @BASEBOARD_FAB2_LIB.BASEBOARD_FAB2(SCH_1):M_A_DQ(23)
 R82 M_A_DQ<22> DDR0_DQ<22> @BASEBOARD_FAB2_LIB.BASEBOARD_FAB2(SCH_1):M_A_DQ(22)
 V79 M_A_DQ<21> DDR0_DQ<21> @BASEBOARD_FAB2_LIB.BASEBOARD_FAB2(SCH_1):M_A_DQ(21)
 W80 M_A_DQ<20> DDR0_DQ<20> @BASEBOARD_FAB2_LIB.BASEBOARD_FAB2(SCH_1):M_A_DQ(20)
 M81 M_A_DQ<19> DDR0_DQ<19> @BASEBOARD_FAB2_LIB.BASEBOARD_FAB2(SCH_1):M_A_DQ(19)
 N82 M_A_DQ<18> DDR0_DQ<18> @BASEBOARD_FAB2_LIB.BASEBOARD_FAB2(SCH_1):M_A_DQ(18)
 T79 M_A_DQ<17> DDR0_DQ<17> @BASEBOARD_FAB2_LIB.BASEBOARD_FAB2(SCH_1):M_A_DQ(17)
 V81 M_A_DQ<16> DDR0_DQ<16> @BASEBOARD_FAB2_LIB.BASEBOARD_FAB2(SCH_1):M_A_DQ(16)
 N84 M_A_DQ<15> DDR0_DQ<15> @BASEBOARD_FAB2_LIB.BASEBOARD_FAB2(SCH_1):M_A_DQ(15)
 N86 M_A_DQ<14> DDR0_DQ<14> @BASEBOARD_FAB2_LIB.BASEBOARD_FAB2(SCH_1):M_A_DQ(14)
AA84 M_A_DQ<13> DDR0_DQ<13> @BASEBOARD_FAB2_LIB.BASEBOARD_FAB2(SCH_1):M_A_DQ(13)
AA86 M_A_DQ<12> DDR0_DQ<12> @BASEBOARD_FAB2_LIB.BASEBOARD_FAB2(SCH_1):M_A_DQ(12)
 L84 M_A_DQ<11> DDR0_DQ<11> @BASEBOARD_FAB2_LIB.BASEBOARD_FAB2(SCH_1):M_A_DQ(11)
 L86 M_A_DQ<10> DDR0_DQ<10> @BASEBOARD_FAB2_LIB.BASEBOARD_FAB2(SCH_1):M_A_DQ(10)
 W84 M_A_DQ<9> DDR0_DQ<9> @BASEBOARD_FAB2_LIB.BASEBOARD_FAB2(SCH_1):M_A_DQ(9)
 W86 M_A_DQ<8> DDR0_DQ<8> @BASEBOARD_FAB2_LIB.BASEBOARD_FAB2(SCH_1):M_A_DQ(8)
AG84 M_A_DQ<7> DDR0_DQ<7> @BASEBOARD_FAB2_LIB.BASEBOARD_FAB2(SCH_1):M_A_DQ(7)
AG86 M_A_DQ<6> DDR0_DQ<6> @BASEBOARD_FAB2_LIB.BASEBOARD_FAB2(SCH_1):M_A_DQ(6)
AR84 M_A_DQ<5> DDR0_DQ<5> @BASEBOARD_FAB2_LIB.BASEBOARD_FAB2(SCH_1):M_A_DQ(5)
AR86 M_A_DQ<4> DDR0_DQ<4> @BASEBOARD_FAB2_LIB.BASEBOARD_FAB2(SCH_1):M_A_DQ(4)
AE84 M_A_DQ<3> DDR0_DQ<3> @BASEBOARD_FAB2_LIB.BASEBOARD_FAB2(SCH_1):M_A_DQ(3)
AE86 M_A_DQ<2> DDR0_DQ<2> @BASEBOARD_FAB2_LIB.BASEBOARD_FAB2(SCH_1):M_A_DQ(2)
AN84 M_A_DQ<1> DDR0_DQ<1> @BASEBOARD_FAB2_LIB.BASEBOARD_FAB2(SCH_1):M_A_DQ(1)
AN86 M_A_DQ<0> DDR0_DQ<0> @BASEBOARD_FAB2_LIB.BASEBOARD_FAB2(SCH_1):M_A_DQ(0)
AB67 M_A_DQS_DN<17> DDR0_DQS_DN<17> @BASEBOARD_FAB2_LIB.BASEBOARD_FAB2(SCH_1):M_A_DQS_DN(17)
 J24 M_A_DQS_DN<16> DDR0_DQS_DN<16> @BASEBOARD_FAB2_LIB.BASEBOARD_FAB2(SCH_1):M_A_DQS_DN(16)
 J30 M_A_DQS_DN<15> DDR0_DQS_DN<15> @BASEBOARD_FAB2_LIB.BASEBOARD_FAB2(SCH_1):M_A_DQS_DN(15)
 J36 M_A_DQS_DN<14> DDR0_DQS_DN<14> @BASEBOARD_FAB2_LIB.BASEBOARD_FAB2(SCH_1):M_A_DQS_DN(14)
 A40 M_A_DQS_DN<13> DDR0_DQS_DN<13> @BASEBOARD_FAB2_LIB.BASEBOARD_FAB2(SCH_1):M_A_DQS_DN(13)
 K75 M_A_DQS_DN<12> DDR0_DQS_DN<12> @BASEBOARD_FAB2_LIB.BASEBOARD_FAB2(SCH_1):M_A_DQS_DN(12)
 U82 M_A_DQS_DN<11> DDR0_DQS_DN<11> @BASEBOARD_FAB2_LIB.BASEBOARD_FAB2(SCH_1):M_A_DQS_DN(11)
 U84 M_A_DQS_DN<10> DDR0_DQS_DN<10> @BASEBOARD_FAB2_LIB.BASEBOARD_FAB2(SCH_1):M_A_DQS_DN(10)
AL84 M_A_DQS_DN<9> DDR0_DQS_DN<9> @BASEBOARD_FAB2_LIB.BASEBOARD_FAB2(SCH_1):M_A_DQS_DN(9)
AH67 M_A_DQS_DN<8> DDR0_DQS_DN<8> @BASEBOARD_FAB2_LIB.BASEBOARD_FAB2(SCH_1):M_A_DQS_DN(8)
 N24 M_A_DQS_DN<7> DDR0_DQS_DN<7> @BASEBOARD_FAB2_LIB.BASEBOARD_FAB2(SCH_1):M_A_DQS_DN(7)
 R30 M_A_DQS_DN<6> DDR0_DQS_DN<6> @BASEBOARD_FAB2_LIB.BASEBOARD_FAB2(SCH_1):M_A_DQS_DN(6)
 R36 M_A_DQS_DN<5> DDR0_DQS_DN<5> @BASEBOARD_FAB2_LIB.BASEBOARD_FAB2(SCH_1):M_A_DQS_DN(5)
 G40 M_A_DQS_DN<4> DDR0_DQS_DN<4> @BASEBOARD_FAB2_LIB.BASEBOARD_FAB2(SCH_1):M_A_DQS_DN(4)
 T75 M_A_DQS_DN<3> DDR0_DQS_DN<3> @BASEBOARD_FAB2_LIB.BASEBOARD_FAB2(SCH_1):M_A_DQS_DN(3)
 P79 M_A_DQS_DN<2> DDR0_DQS_DN<2> @BASEBOARD_FAB2_LIB.BASEBOARD_FAB2(SCH_1):M_A_DQS_DN(2)
 R84 M_A_DQS_DN<1> DDR0_DQS_DN<1> @BASEBOARD_FAB2_LIB.BASEBOARD_FAB2(SCH_1):M_A_DQS_DN(1)
AJ84 M_A_DQS_DN<0> DDR0_DQS_DN<0> @BASEBOARD_FAB2_LIB.BASEBOARD_FAB2(SCH_1):M_A_DQS_DN(0)
AD67 M_A_DQS_DP<17> DDR0_DQS_DP<17> @BASEBOARD_FAB2_LIB.BASEBOARD_FAB2(SCH_1):M_A_DQS_DP(17)
 L24 M_A_DQS_DP<16> DDR0_DQS_DP<16> @BASEBOARD_FAB2_LIB.BASEBOARD_FAB2(SCH_1):M_A_DQS_DP(16)
 L30 M_A_DQS_DP<15> DDR0_DQS_DP<15> @BASEBOARD_FAB2_LIB.BASEBOARD_FAB2(SCH_1):M_A_DQS_DP(15)
 L36 M_A_DQS_DP<14> DDR0_DQS_DP<14> @BASEBOARD_FAB2_LIB.BASEBOARD_FAB2(SCH_1):M_A_DQS_DP(14)
 C40 M_A_DQS_DP<13> DDR0_DQS_DP<13> @BASEBOARD_FAB2_LIB.BASEBOARD_FAB2(SCH_1):M_A_DQS_DP(13)
 M75 M_A_DQS_DP<12> DDR0_DQS_DP<12> @BASEBOARD_FAB2_LIB.BASEBOARD_FAB2(SCH_1):M_A_DQS_DP(12)
 T81 M_A_DQS_DP<11> DDR0_DQS_DP<11> @BASEBOARD_FAB2_LIB.BASEBOARD_FAB2(SCH_1):M_A_DQS_DP(11)
 V85 M_A_DQS_DP<10> DDR0_DQS_DP<10> @BASEBOARD_FAB2_LIB.BASEBOARD_FAB2(SCH_1):M_A_DQS_DP(10)
AM85 M_A_DQS_DP<9> DDR0_DQS_DP<9> @BASEBOARD_FAB2_LIB.BASEBOARD_FAB2(SCH_1):M_A_DQS_DP(9)
AF67 M_A_DQS_DP<8> DDR0_DQS_DP<8> @BASEBOARD_FAB2_LIB.BASEBOARD_FAB2(SCH_1):M_A_DQS_DP(8)
 R24 M_A_DQS_DP<7> DDR0_DQS_DP<7> @BASEBOARD_FAB2_LIB.BASEBOARD_FAB2(SCH_1):M_A_DQS_DP(7)
 N30 M_A_DQS_DP<6> DDR0_DQS_DP<6> @BASEBOARD_FAB2_LIB.BASEBOARD_FAB2(SCH_1):M_A_DQS_DP(6)
 N36 M_A_DQS_DP<5> DDR0_DQS_DP<5> @BASEBOARD_FAB2_LIB.BASEBOARD_FAB2(SCH_1):M_A_DQS_DP(5)
 E40 M_A_DQS_DP<4> DDR0_DQS_DP<4> @BASEBOARD_FAB2_LIB.BASEBOARD_FAB2(SCH_1):M_A_DQS_DP(4)
 P75 M_A_DQS_DP<3> DDR0_DQS_DP<3> @BASEBOARD_FAB2_LIB.BASEBOARD_FAB2(SCH_1):M_A_DQS_DP(3)
 R80 M_A_DQS_DP<2> DDR0_DQS_DP<2> @BASEBOARD_FAB2_LIB.BASEBOARD_FAB2(SCH_1):M_A_DQS_DP(2)
 P85 M_A_DQS_DP<1> DDR0_DQS_DP<1> @BASEBOARD_FAB2_LIB.BASEBOARD_FAB2(SCH_1):M_A_DQS_DP(1)
AH85 M_A_DQS_DP<0> DDR0_DQS_DP<0> @BASEBOARD_FAB2_LIB.BASEBOARD_FAB2(SCH_1):M_A_DQS_DP(0)
AG66 M_A_ECC<7> DDR0_ECC<7> @BASEBOARD_FAB2_LIB.BASEBOARD_FAB2(SCH_1):M_A_ECC(7)
AC66 M_A_ECC<6> DDR0_ECC<6> @BASEBOARD_FAB2_LIB.BASEBOARD_FAB2(SCH_1):M_A_ECC(6)
AF69 M_A_ECC<5> DDR0_ECC<5> @BASEBOARD_FAB2_LIB.BASEBOARD_FAB2(SCH_1):M_A_ECC(5)
AD69 M_A_ECC<4> DDR0_ECC<4> @BASEBOARD_FAB2_LIB.BASEBOARD_FAB2(SCH_1):M_A_ECC(4)
AF65 M_A_ECC<3> DDR0_ECC<3> @BASEBOARD_FAB2_LIB.BASEBOARD_FAB2(SCH_1):M_A_ECC(3)
AD65 M_A_ECC<2> DDR0_ECC<2> @BASEBOARD_FAB2_LIB.BASEBOARD_FAB2(SCH_1):M_A_ECC(2)
AG68 M_A_ECC<1> DDR0_ECC<1> @BASEBOARD_FAB2_LIB.BASEBOARD_FAB2(SCH_1):M_A_ECC(1)
AC68 M_A_ECC<0> DDR0_ECC<0> @BASEBOARD_FAB2_LIB.BASEBOARD_FAB2(SCH_1):M_A_ECC(0)
 K47 M_A_MA<17> DDR0_MA<17> @BASEBOARD_FAB2_LIB.BASEBOARD_FAB2(SCH_1):M_A_MA(17)
 D51 M_A_MA<16> DDR0_MA<16> @BASEBOARD_FAB2_LIB.BASEBOARD_FAB2(SCH_1):M_A_MA(16)
 K49 M_A_MA<15> DDR0_MA<15> @BASEBOARD_FAB2_LIB.BASEBOARD_FAB2(SCH_1):M_A_MA(15)
 F51 M_A_MA<14> DDR0_MA<14> @BASEBOARD_FAB2_LIB.BASEBOARD_FAB2(SCH_1):M_A_MA(14)
 J48 M_A_MA<13> DDR0_MA<13> @BASEBOARD_FAB2_LIB.BASEBOARD_FAB2(SCH_1):M_A_MA(13)
 J64 M_A_MA<12> DDR0_MA<12> @BASEBOARD_FAB2_LIB.BASEBOARD_FAB2(SCH_1):M_A_MA(12)
 G62 M_A_MA<11> DDR0_MA<11> @BASEBOARD_FAB2_LIB.BASEBOARD_FAB2(SCH_1):M_A_MA(11)
 J54 M_A_MA<10> DDR0_MA<10> @BASEBOARD_FAB2_LIB.BASEBOARD_FAB2(SCH_1):M_A_MA(10)
 F61 M_A_MA<9> DDR0_MA<9> @BASEBOARD_FAB2_LIB.BASEBOARD_FAB2(SCH_1):M_A_MA(9)
 C60 M_A_MA<8> DDR0_MA<8> @BASEBOARD_FAB2_LIB.BASEBOARD_FAB2(SCH_1):M_A_MA(8)
 G60 M_A_MA<7> DDR0_MA<7> @BASEBOARD_FAB2_LIB.BASEBOARD_FAB2(SCH_1):M_A_MA(7)
 D59 M_A_MA<6> DDR0_MA<6> @BASEBOARD_FAB2_LIB.BASEBOARD_FAB2(SCH_1):M_A_MA(6)
 F59 M_A_MA<5> DDR0_MA<5> @BASEBOARD_FAB2_LIB.BASEBOARD_FAB2(SCH_1):M_A_MA(5)
 G58 M_A_MA<4> DDR0_MA<4> @BASEBOARD_FAB2_LIB.BASEBOARD_FAB2(SCH_1):M_A_MA(4)
 C58 M_A_MA<3> DDR0_MA<3> @BASEBOARD_FAB2_LIB.BASEBOARD_FAB2(SCH_1):M_A_MA(3)
 D57 M_A_MA<2> DDR0_MA<2> @BASEBOARD_FAB2_LIB.BASEBOARD_FAB2(SCH_1):M_A_MA(2)
 F57 M_A_MA<1> DDR0_MA<1> @BASEBOARD_FAB2_LIB.BASEBOARD_FAB2(SCH_1):M_A_MA(1)
 F53 M_A_MA<0> DDR0_MA<0> @BASEBOARD_FAB2_LIB.BASEBOARD_FAB2(SCH_1):M_A_MA(0)
 G48 M_A_ODT<3> DDR0_ODT<3> @BASEBOARD_FAB2_LIB.BASEBOARD_FAB2(SCH_1):M_A_ODT(3)
 G50 M_A_ODT<2> DDR0_ODT<2> @BASEBOARD_FAB2_LIB.BASEBOARD_FAB2(SCH_1):M_A_ODT(2)
 C48 M_A_ODT<1> DDR0_ODT<1> @BASEBOARD_FAB2_LIB.BASEBOARD_FAB2(SCH_1):M_A_ODT(1)
 C50 M_A_ODT<0> DDR0_ODT<0> @BASEBOARD_FAB2_LIB.BASEBOARD_FAB2(SCH_1):M_A_ODT(0)
 D53 M_A_PAR DDR0_PAR @BASEBOARD_FAB2_LIB.BASEBOARD_FAB2(SCH_1):M_A_PAR


DRAWING: @BASEBOARD_FAB2_LIB.BASEBOARD_FAB2(SCH_1):PAGE24 

SKX_EXT_B_BGA1-IC,TBD  I172  U5D1
 T63 M_B_ACT_N DDR1_ACT_N @BASEBOARD_FAB2_LIB.BASEBOARD_FAB2(SCH_1):M_B_ACT_N
 W62 M_B_ALERT_N DDR1_ALERT_N @BASEBOARD_FAB2_LIB.BASEBOARD_FAB2(SCH_1):M_B_ALERT_N
 K55 M_B_BA<1> DDR1_BA<1> @BASEBOARD_FAB2_LIB.BASEBOARD_FAB2(SCH_1):M_B_BA(1)
 T53 M_B_BA<0> DDR1_BA<0> @BASEBOARD_FAB2_LIB.BASEBOARD_FAB2(SCH_1):M_B_BA(0)
 N60 M_B_BG<1> DDR1_BG<1> @BASEBOARD_FAB2_LIB.BASEBOARD_FAB2(SCH_1):M_B_BG(1)
 M61 M_B_BG<0> DDR1_BG<0> @BASEBOARD_FAB2_LIB.BASEBOARD_FAB2(SCH_1):M_B_BG(0)
 M47 M_B_C<2> DDR1_CID<2> @BASEBOARD_FAB2_LIB.BASEBOARD_FAB2(SCH_1):M_B_C(2)
 L64 M_B_CKE<3> DDR1_CKE<3> @BASEBOARD_FAB2_LIB.BASEBOARD_FAB2(SCH_1):M_B_CKE(3)
 K63 M_B_CKE<2> DDR1_CKE<2> @BASEBOARD_FAB2_LIB.BASEBOARD_FAB2(SCH_1):M_B_CKE(2)
 R64 M_B_CKE<1> DDR1_CKE<1> @BASEBOARD_FAB2_LIB.BASEBOARD_FAB2(SCH_1):M_B_CKE(1)
 N62 M_B_CKE<0> DDR1_CKE<0> @BASEBOARD_FAB2_LIB.BASEBOARD_FAB2(SCH_1):M_B_CKE(0)
 R56 M_B_CLK_DN<3> DDR1_CLK_DN<3> @BASEBOARD_FAB2_LIB.BASEBOARD_FAB2(SCH_1):M_B_CLK_DN(3)
 N56 M_B_CLK_DN<2> DDR1_CLK_DN<2> @BASEBOARD_FAB2_LIB.BASEBOARD_FAB2(SCH_1):M_B_CLK_DN(2)
 R54 M_B_CLK_DN<1> DDR1_CLK_DN<1> @BASEBOARD_FAB2_LIB.BASEBOARD_FAB2(SCH_1):M_B_CLK_DN(1)
 M53 M_B_CLK_DN<0> DDR1_CLK_DN<0> @BASEBOARD_FAB2_LIB.BASEBOARD_FAB2(SCH_1):M_B_CLK_DN(0)
 T57 M_B_CLK_DP<3> DDR1_CLK_DP<3> @BASEBOARD_FAB2_LIB.BASEBOARD_FAB2(SCH_1):M_B_CLK_DP(3)
 M57 M_B_CLK_DP<2> DDR1_CLK_DP<2> @BASEBOARD_FAB2_LIB.BASEBOARD_FAB2(SCH_1):M_B_CLK_DP(2)
 T55 M_B_CLK_DP<1> DDR1_CLK_DP<1> @BASEBOARD_FAB2_LIB.BASEBOARD_FAB2(SCH_1):M_B_CLK_DP(1)
 N54 M_B_CLK_DP<0> DDR1_CLK_DP<0> @BASEBOARD_FAB2_LIB.BASEBOARD_FAB2(SCH_1):M_B_CLK_DP(0)
 R46 M_B_CS_N<7> DDR1_CS_N<7> @BASEBOARD_FAB2_LIB.BASEBOARD_FAB2(SCH_1):M_B_CS_N(7)
 M45 M_B_CS_N<6> DDR1_CS_N<6> @BASEBOARD_FAB2_LIB.BASEBOARD_FAB2(SCH_1):M_B_CS_N(6)
 T49 M_B_CS_N<5> DDR1_CS_N<5> @BASEBOARD_FAB2_LIB.BASEBOARD_FAB2(SCH_1):M_B_CS_N(5)
 J50 M_B_CS_N<4> DDR1_CS_N<4> @BASEBOARD_FAB2_LIB.BASEBOARD_FAB2(SCH_1):M_B_CS_N(4)
 V47 M_B_CS_N<3> DDR1_CS_N<3> @BASEBOARD_FAB2_LIB.BASEBOARD_FAB2(SCH_1):M_B_CS_N(3)
 N46 M_B_CS_N<2> DDR1_CS_N<2> @BASEBOARD_FAB2_LIB.BASEBOARD_FAB2(SCH_1):M_B_CS_N(2)
 R50 M_B_CS_N<1> DDR1_CS_N<1> @BASEBOARD_FAB2_LIB.BASEBOARD_FAB2(SCH_1):M_B_CS_N(1)
 K51 M_B_CS_N<0> DDR1_CS_N<0> @BASEBOARD_FAB2_LIB.BASEBOARD_FAB2(SCH_1):M_B_CS_N(0)
AA26 M_B_DQ<63> DDR1_DQ<63> @BASEBOARD_FAB2_LIB.BASEBOARD_FAB2(SCH_1):M_B_DQ(63)
 U26 M_B_DQ<62> DDR1_DQ<62> @BASEBOARD_FAB2_LIB.BASEBOARD_FAB2(SCH_1):M_B_DQ(62)
 Y29 M_B_DQ<61> DDR1_DQ<61> @BASEBOARD_FAB2_LIB.BASEBOARD_FAB2(SCH_1):M_B_DQ(61)
 V29 M_B_DQ<60> DDR1_DQ<60> @BASEBOARD_FAB2_LIB.BASEBOARD_FAB2(SCH_1):M_B_DQ(60)
 Y25 M_B_DQ<59> DDR1_DQ<59> @BASEBOARD_FAB2_LIB.BASEBOARD_FAB2(SCH_1):M_B_DQ(59)
 V25 M_B_DQ<58> DDR1_DQ<58> @BASEBOARD_FAB2_LIB.BASEBOARD_FAB2(SCH_1):M_B_DQ(58)
AA28 M_B_DQ<57> DDR1_DQ<57> @BASEBOARD_FAB2_LIB.BASEBOARD_FAB2(SCH_1):M_B_DQ(57)
 U28 M_B_DQ<56> DDR1_DQ<56> @BASEBOARD_FAB2_LIB.BASEBOARD_FAB2(SCH_1):M_B_DQ(56)
 F27 M_B_DQ<55> DDR1_DQ<55> @BASEBOARD_FAB2_LIB.BASEBOARD_FAB2(SCH_1):M_B_DQ(55)
 B27 M_B_DQ<54> DDR1_DQ<54> @BASEBOARD_FAB2_LIB.BASEBOARD_FAB2(SCH_1):M_B_DQ(54)
 F29 M_B_DQ<53> DDR1_DQ<53> @BASEBOARD_FAB2_LIB.BASEBOARD_FAB2(SCH_1):M_B_DQ(53)
 E30 M_B_DQ<52> DDR1_DQ<52> @BASEBOARD_FAB2_LIB.BASEBOARD_FAB2(SCH_1):M_B_DQ(52)
 E26 M_B_DQ<51> DDR1_DQ<51> @BASEBOARD_FAB2_LIB.BASEBOARD_FAB2(SCH_1):M_B_DQ(51)
 C26 M_B_DQ<50> DDR1_DQ<50> @BASEBOARD_FAB2_LIB.BASEBOARD_FAB2(SCH_1):M_B_DQ(50)
 B29 M_B_DQ<49> DDR1_DQ<49> @BASEBOARD_FAB2_LIB.BASEBOARD_FAB2(SCH_1):M_B_DQ(49)
 C30 M_B_DQ<48> DDR1_DQ<48> @BASEBOARD_FAB2_LIB.BASEBOARD_FAB2(SCH_1):M_B_DQ(48)
 F33 M_B_DQ<47> DDR1_DQ<47> @BASEBOARD_FAB2_LIB.BASEBOARD_FAB2(SCH_1):M_B_DQ(47)
 B33 M_B_DQ<46> DDR1_DQ<46> @BASEBOARD_FAB2_LIB.BASEBOARD_FAB2(SCH_1):M_B_DQ(46)
 F35 M_B_DQ<45> DDR1_DQ<45> @BASEBOARD_FAB2_LIB.BASEBOARD_FAB2(SCH_1):M_B_DQ(45)
 E36 M_B_DQ<44> DDR1_DQ<44> @BASEBOARD_FAB2_LIB.BASEBOARD_FAB2(SCH_1):M_B_DQ(44)
 E32 M_B_DQ<43> DDR1_DQ<43> @BASEBOARD_FAB2_LIB.BASEBOARD_FAB2(SCH_1):M_B_DQ(43)
 C32 M_B_DQ<42> DDR1_DQ<42> @BASEBOARD_FAB2_LIB.BASEBOARD_FAB2(SCH_1):M_B_DQ(42)
 B35 M_B_DQ<41> DDR1_DQ<41> @BASEBOARD_FAB2_LIB.BASEBOARD_FAB2(SCH_1):M_B_DQ(41)
 C36 M_B_DQ<40> DDR1_DQ<40> @BASEBOARD_FAB2_LIB.BASEBOARD_FAB2(SCH_1):M_B_DQ(40)
 P41 M_B_DQ<39> DDR1_DQ<39> @BASEBOARD_FAB2_LIB.BASEBOARD_FAB2(SCH_1):M_B_DQ(39)
 K41 M_B_DQ<38> DDR1_DQ<38> @BASEBOARD_FAB2_LIB.BASEBOARD_FAB2(SCH_1):M_B_DQ(38)
 T43 M_B_DQ<37> DDR1_DQ<37> @BASEBOARD_FAB2_LIB.BASEBOARD_FAB2(SCH_1):M_B_DQ(37)
 P43 M_B_DQ<36> DDR1_DQ<36> @BASEBOARD_FAB2_LIB.BASEBOARD_FAB2(SCH_1):M_B_DQ(36)
 N40 M_B_DQ<35> DDR1_DQ<35> @BASEBOARD_FAB2_LIB.BASEBOARD_FAB2(SCH_1):M_B_DQ(35)
 L40 M_B_DQ<34> DDR1_DQ<34> @BASEBOARD_FAB2_LIB.BASEBOARD_FAB2(SCH_1):M_B_DQ(34)
 H43 M_B_DQ<33> DDR1_DQ<33> @BASEBOARD_FAB2_LIB.BASEBOARD_FAB2(SCH_1):M_B_DQ(33)
 K43 M_B_DQ<32> DDR1_DQ<32> @BASEBOARD_FAB2_LIB.BASEBOARD_FAB2(SCH_1):M_B_DQ(32)
 G72 M_B_DQ<31> DDR1_DQ<31> @BASEBOARD_FAB2_LIB.BASEBOARD_FAB2(SCH_1):M_B_DQ(31)
 C72 M_B_DQ<30> DDR1_DQ<30> @BASEBOARD_FAB2_LIB.BASEBOARD_FAB2(SCH_1):M_B_DQ(30)
 G74 M_B_DQ<29> DDR1_DQ<29> @BASEBOARD_FAB2_LIB.BASEBOARD_FAB2(SCH_1):M_B_DQ(29)
 F75 M_B_DQ<28> DDR1_DQ<28> @BASEBOARD_FAB2_LIB.BASEBOARD_FAB2(SCH_1):M_B_DQ(28)
 F71 M_B_DQ<27> DDR1_DQ<27> @BASEBOARD_FAB2_LIB.BASEBOARD_FAB2(SCH_1):M_B_DQ(27)
 D71 M_B_DQ<26> DDR1_DQ<26> @BASEBOARD_FAB2_LIB.BASEBOARD_FAB2(SCH_1):M_B_DQ(26)
 C74 M_B_DQ<25> DDR1_DQ<25> @BASEBOARD_FAB2_LIB.BASEBOARD_FAB2(SCH_1):M_B_DQ(25)
 D75 M_B_DQ<24> DDR1_DQ<24> @BASEBOARD_FAB2_LIB.BASEBOARD_FAB2(SCH_1):M_B_DQ(24)
 J78 M_B_DQ<23> DDR1_DQ<23> @BASEBOARD_FAB2_LIB.BASEBOARD_FAB2(SCH_1):M_B_DQ(23)
 E78 M_B_DQ<22> DDR1_DQ<22> @BASEBOARD_FAB2_LIB.BASEBOARD_FAB2(SCH_1):M_B_DQ(22)
 H81 M_B_DQ<21> DDR1_DQ<21> @BASEBOARD_FAB2_LIB.BASEBOARD_FAB2(SCH_1):M_B_DQ(21)
 F81 M_B_DQ<20> DDR1_DQ<20> @BASEBOARD_FAB2_LIB.BASEBOARD_FAB2(SCH_1):M_B_DQ(20)
 H77 M_B_DQ<19> DDR1_DQ<19> @BASEBOARD_FAB2_LIB.BASEBOARD_FAB2(SCH_1):M_B_DQ(19)
 F77 M_B_DQ<18> DDR1_DQ<18> @BASEBOARD_FAB2_LIB.BASEBOARD_FAB2(SCH_1):M_B_DQ(18)
 J80 M_B_DQ<17> DDR1_DQ<17> @BASEBOARD_FAB2_LIB.BASEBOARD_FAB2(SCH_1):M_B_DQ(17)
 E80 M_B_DQ<16> DDR1_DQ<16> @BASEBOARD_FAB2_LIB.BASEBOARD_FAB2(SCH_1):M_B_DQ(16)
AC80 M_B_DQ<15> DDR1_DQ<15> @BASEBOARD_FAB2_LIB.BASEBOARD_FAB2(SCH_1):M_B_DQ(15)
AE82 M_B_DQ<14> DDR1_DQ<14> @BASEBOARD_FAB2_LIB.BASEBOARD_FAB2(SCH_1):M_B_DQ(14)
AH79 M_B_DQ<13> DDR1_DQ<13> @BASEBOARD_FAB2_LIB.BASEBOARD_FAB2(SCH_1):M_B_DQ(13)
AJ80 M_B_DQ<12> DDR1_DQ<12> @BASEBOARD_FAB2_LIB.BASEBOARD_FAB2(SCH_1):M_B_DQ(12)
AB81 M_B_DQ<11> DDR1_DQ<11> @BASEBOARD_FAB2_LIB.BASEBOARD_FAB2(SCH_1):M_B_DQ(11)
AC82 M_B_DQ<10> DDR1_DQ<10> @BASEBOARD_FAB2_LIB.BASEBOARD_FAB2(SCH_1):M_B_DQ(10)
AF79 M_B_DQ<9> DDR1_DQ<9> @BASEBOARD_FAB2_LIB.BASEBOARD_FAB2(SCH_1):M_B_DQ(9)
AH81 M_B_DQ<8> DDR1_DQ<8> @BASEBOARD_FAB2_LIB.BASEBOARD_FAB2(SCH_1):M_B_DQ(8)
AN80 M_B_DQ<7> DDR1_DQ<7> @BASEBOARD_FAB2_LIB.BASEBOARD_FAB2(SCH_1):M_B_DQ(7)
AR82 M_B_DQ<6> DDR1_DQ<6> @BASEBOARD_FAB2_LIB.BASEBOARD_FAB2(SCH_1):M_B_DQ(6)
AV79 M_B_DQ<5> DDR1_DQ<5> @BASEBOARD_FAB2_LIB.BASEBOARD_FAB2(SCH_1):M_B_DQ(5)
AW80 M_B_DQ<4> DDR1_DQ<4> @BASEBOARD_FAB2_LIB.BASEBOARD_FAB2(SCH_1):M_B_DQ(4)
AM81 M_B_DQ<3> DDR1_DQ<3> @BASEBOARD_FAB2_LIB.BASEBOARD_FAB2(SCH_1):M_B_DQ(3)
AN82 M_B_DQ<2> DDR1_DQ<2> @BASEBOARD_FAB2_LIB.BASEBOARD_FAB2(SCH_1):M_B_DQ(2)
AT79 M_B_DQ<1> DDR1_DQ<1> @BASEBOARD_FAB2_LIB.BASEBOARD_FAB2(SCH_1):M_B_DQ(1)
AV81 M_B_DQ<0> DDR1_DQ<0> @BASEBOARD_FAB2_LIB.BASEBOARD_FAB2(SCH_1):M_B_DQ(0)
 G68 M_B_DQS_DN<17> DDR1_DQS_DN<17> @BASEBOARD_FAB2_LIB.BASEBOARD_FAB2(SCH_1):M_B_DQS_DN(17)
 T27 M_B_DQS_DN<16> DDR1_DQS_DN<16> @BASEBOARD_FAB2_LIB.BASEBOARD_FAB2(SCH_1):M_B_DQS_DN(16)
 A28 M_B_DQS_DN<15> DDR1_DQS_DN<15> @BASEBOARD_FAB2_LIB.BASEBOARD_FAB2(SCH_1):M_B_DQS_DN(15)
 A34 M_B_DQS_DN<14> DDR1_DQS_DN<14> @BASEBOARD_FAB2_LIB.BASEBOARD_FAB2(SCH_1):M_B_DQS_DN(14)
 J42 M_B_DQS_DN<13> DDR1_DQS_DN<13> @BASEBOARD_FAB2_LIB.BASEBOARD_FAB2(SCH_1):M_B_DQS_DN(13)
 B73 M_B_DQS_DN<12> DDR1_DQS_DN<12> @BASEBOARD_FAB2_LIB.BASEBOARD_FAB2(SCH_1):M_B_DQS_DN(12)
 D79 M_B_DQS_DN<11> DDR1_DQS_DN<11> @BASEBOARD_FAB2_LIB.BASEBOARD_FAB2(SCH_1):M_B_DQS_DN(11)
AG82 M_B_DQS_DN<10> DDR1_DQS_DN<10> @BASEBOARD_FAB2_LIB.BASEBOARD_FAB2(SCH_1):M_B_DQS_DN(10)
AU82 M_B_DQS_DN<9> DDR1_DQS_DN<9> @BASEBOARD_FAB2_LIB.BASEBOARD_FAB2(SCH_1):M_B_DQS_DN(9)
 N68 M_B_DQS_DN<8> DDR1_DQS_DN<8> @BASEBOARD_FAB2_LIB.BASEBOARD_FAB2(SCH_1):M_B_DQS_DN(8)
AB27 M_B_DQS_DN<7> DDR1_DQS_DN<7> @BASEBOARD_FAB2_LIB.BASEBOARD_FAB2(SCH_1):M_B_DQS_DN(7)
 G28 M_B_DQS_DN<6> DDR1_DQS_DN<6> @BASEBOARD_FAB2_LIB.BASEBOARD_FAB2(SCH_1):M_B_DQS_DN(6)
 G34 M_B_DQS_DN<5> DDR1_DQS_DN<5> @BASEBOARD_FAB2_LIB.BASEBOARD_FAB2(SCH_1):M_B_DQS_DN(5)
 N42 M_B_DQS_DN<4> DDR1_DQS_DN<4> @BASEBOARD_FAB2_LIB.BASEBOARD_FAB2(SCH_1):M_B_DQS_DN(4)
 H73 M_B_DQS_DN<3> DDR1_DQS_DN<3> @BASEBOARD_FAB2_LIB.BASEBOARD_FAB2(SCH_1):M_B_DQS_DN(3)
 K79 M_B_DQS_DN<2> DDR1_DQS_DN<2> @BASEBOARD_FAB2_LIB.BASEBOARD_FAB2(SCH_1):M_B_DQS_DN(2)
AD79 M_B_DQS_DN<1> DDR1_DQS_DN<1> @BASEBOARD_FAB2_LIB.BASEBOARD_FAB2(SCH_1):M_B_DQS_DN(1)
AP79 M_B_DQS_DN<0> DDR1_DQS_DN<0> @BASEBOARD_FAB2_LIB.BASEBOARD_FAB2(SCH_1):M_B_DQS_DN(0)
 J68 M_B_DQS_DP<17> DDR1_DQS_DP<17> @BASEBOARD_FAB2_LIB.BASEBOARD_FAB2(SCH_1):M_B_DQS_DP(17)
 V27 M_B_DQS_DP<16> DDR1_DQS_DP<16> @BASEBOARD_FAB2_LIB.BASEBOARD_FAB2(SCH_1):M_B_DQS_DP(16)
 C28 M_B_DQS_DP<15> DDR1_DQS_DP<15> @BASEBOARD_FAB2_LIB.BASEBOARD_FAB2(SCH_1):M_B_DQS_DP(15)
 C34 M_B_DQS_DP<14> DDR1_DQS_DP<14> @BASEBOARD_FAB2_LIB.BASEBOARD_FAB2(SCH_1):M_B_DQS_DP(14)
 L42 M_B_DQS_DP<13> DDR1_DQS_DP<13> @BASEBOARD_FAB2_LIB.BASEBOARD_FAB2(SCH_1):M_B_DQS_DP(13)
 D73 M_B_DQS_DP<12> DDR1_DQS_DP<12> @BASEBOARD_FAB2_LIB.BASEBOARD_FAB2(SCH_1):M_B_DQS_DP(12)
 F79 M_B_DQS_DP<11> DDR1_DQS_DP<11> @BASEBOARD_FAB2_LIB.BASEBOARD_FAB2(SCH_1):M_B_DQS_DP(11)
AF81 M_B_DQS_DP<10> DDR1_DQS_DP<10> @BASEBOARD_FAB2_LIB.BASEBOARD_FAB2(SCH_1):M_B_DQS_DP(10)
AT81 M_B_DQS_DP<9> DDR1_DQS_DP<9> @BASEBOARD_FAB2_LIB.BASEBOARD_FAB2(SCH_1):M_B_DQS_DP(9)
 L68 M_B_DQS_DP<8> DDR1_DQS_DP<8> @BASEBOARD_FAB2_LIB.BASEBOARD_FAB2(SCH_1):M_B_DQS_DP(8)
 Y27 M_B_DQS_DP<7> DDR1_DQS_DP<7> @BASEBOARD_FAB2_LIB.BASEBOARD_FAB2(SCH_1):M_B_DQS_DP(7)
 E28 M_B_DQS_DP<6> DDR1_DQS_DP<6> @BASEBOARD_FAB2_LIB.BASEBOARD_FAB2(SCH_1):M_B_DQS_DP(6)
 E34 M_B_DQS_DP<5> DDR1_DQS_DP<5> @BASEBOARD_FAB2_LIB.BASEBOARD_FAB2(SCH_1):M_B_DQS_DP(5)
 R42 M_B_DQS_DP<4> DDR1_DQS_DP<4> @BASEBOARD_FAB2_LIB.BASEBOARD_FAB2(SCH_1):M_B_DQS_DP(4)
 F73 M_B_DQS_DP<3> DDR1_DQS_DP<3> @BASEBOARD_FAB2_LIB.BASEBOARD_FAB2(SCH_1):M_B_DQS_DP(3)
 H79 M_B_DQS_DP<2> DDR1_DQS_DP<2> @BASEBOARD_FAB2_LIB.BASEBOARD_FAB2(SCH_1):M_B_DQS_DP(2)
AE80 M_B_DQS_DP<1> DDR1_DQS_DP<1> @BASEBOARD_FAB2_LIB.BASEBOARD_FAB2(SCH_1):M_B_DQS_DP(1)
AR80 M_B_DQS_DP<0> DDR1_DQS_DP<0> @BASEBOARD_FAB2_LIB.BASEBOARD_FAB2(SCH_1):M_B_DQS_DP(0)
 M67 M_B_ECC<7> DDR1_ECC<7> @BASEBOARD_FAB2_LIB.BASEBOARD_FAB2(SCH_1):M_B_ECC(7)
 H67 M_B_ECC<6> DDR1_ECC<6> @BASEBOARD_FAB2_LIB.BASEBOARD_FAB2(SCH_1):M_B_ECC(6)
 M69 M_B_ECC<5> DDR1_ECC<5> @BASEBOARD_FAB2_LIB.BASEBOARD_FAB2(SCH_1):M_B_ECC(5)
 L70 M_B_ECC<4> DDR1_ECC<4> @BASEBOARD_FAB2_LIB.BASEBOARD_FAB2(SCH_1):M_B_ECC(4)
 L66 M_B_ECC<3> DDR1_ECC<3> @BASEBOARD_FAB2_LIB.BASEBOARD_FAB2(SCH_1):M_B_ECC(3)
 J66 M_B_ECC<2> DDR1_ECC<2> @BASEBOARD_FAB2_LIB.BASEBOARD_FAB2(SCH_1):M_B_ECC(2)
 H69 M_B_ECC<1> DDR1_ECC<1> @BASEBOARD_FAB2_LIB.BASEBOARD_FAB2(SCH_1):M_B_ECC(1)
 J70 M_B_ECC<0> DDR1_ECC<0> @BASEBOARD_FAB2_LIB.BASEBOARD_FAB2(SCH_1):M_B_ECC(0)
 N48 M_B_MA<17> DDR1_MA<17> @BASEBOARD_FAB2_LIB.BASEBOARD_FAB2(SCH_1):M_B_MA(17)
 R52 M_B_MA<16> DDR1_MA<16> @BASEBOARD_FAB2_LIB.BASEBOARD_FAB2(SCH_1):M_B_MA(16)
 N52 M_B_MA<15> DDR1_MA<15> @BASEBOARD_FAB2_LIB.BASEBOARD_FAB2(SCH_1):M_B_MA(15)
 T51 M_B_MA<14> DDR1_MA<14> @BASEBOARD_FAB2_LIB.BASEBOARD_FAB2(SCH_1):M_B_MA(14)
 M51 M_B_MA<13> DDR1_MA<13> @BASEBOARD_FAB2_LIB.BASEBOARD_FAB2(SCH_1):M_B_MA(13)
 T61 M_B_MA<12> DDR1_MA<12> @BASEBOARD_FAB2_LIB.BASEBOARD_FAB2(SCH_1):M_B_MA(12)
 R60 M_B_MA<11> DDR1_MA<11> @BASEBOARD_FAB2_LIB.BASEBOARD_FAB2(SCH_1):M_B_MA(11)
 M55 M_B_MA<10> DDR1_MA<10> @BASEBOARD_FAB2_LIB.BASEBOARD_FAB2(SCH_1):M_B_MA(10)
 K59 M_B_MA<9> DDR1_MA<9> @BASEBOARD_FAB2_LIB.BASEBOARD_FAB2(SCH_1):M_B_MA(9)
 W60 M_B_MA<8> DDR1_MA<8> @BASEBOARD_FAB2_LIB.BASEBOARD_FAB2(SCH_1):M_B_MA(8)
 V61 M_B_MA<7> DDR1_MA<7> @BASEBOARD_FAB2_LIB.BASEBOARD_FAB2(SCH_1):M_B_MA(7)
 T59 M_B_MA<6> DDR1_MA<6> @BASEBOARD_FAB2_LIB.BASEBOARD_FAB2(SCH_1):M_B_MA(6)
 R58 M_B_MA<5> DDR1_MA<5> @BASEBOARD_FAB2_LIB.BASEBOARD_FAB2(SCH_1):M_B_MA(5)
 M59 M_B_MA<4> DDR1_MA<4> @BASEBOARD_FAB2_LIB.BASEBOARD_FAB2(SCH_1):M_B_MA(4)
 N58 M_B_MA<3> DDR1_MA<3> @BASEBOARD_FAB2_LIB.BASEBOARD_FAB2(SCH_1):M_B_MA(3)
 K57 M_B_MA<2> DDR1_MA<2> @BASEBOARD_FAB2_LIB.BASEBOARD_FAB2(SCH_1):M_B_MA(2)
 J58 M_B_MA<1> DDR1_MA<1> @BASEBOARD_FAB2_LIB.BASEBOARD_FAB2(SCH_1):M_B_MA(1)
 J52 M_B_MA<0> DDR1_MA<0> @BASEBOARD_FAB2_LIB.BASEBOARD_FAB2(SCH_1):M_B_MA(0)
 T47 M_B_ODT<3> DDR1_ODT<3> @BASEBOARD_FAB2_LIB.BASEBOARD_FAB2(SCH_1):M_B_ODT(3)
 M49 M_B_ODT<2> DDR1_ODT<2> @BASEBOARD_FAB2_LIB.BASEBOARD_FAB2(SCH_1):M_B_ODT(2)
 R48 M_B_ODT<1> DDR1_ODT<1> @BASEBOARD_FAB2_LIB.BASEBOARD_FAB2(SCH_1):M_B_ODT(1)
 N50 M_B_ODT<0> DDR1_ODT<0> @BASEBOARD_FAB2_LIB.BASEBOARD_FAB2(SCH_1):M_B_ODT(0)
 K53 M_B_PAR DDR1_PAR @BASEBOARD_FAB2_LIB.BASEBOARD_FAB2(SCH_1):M_B_PAR


DRAWING: @BASEBOARD_FAB2_LIB.BASEBOARD_FAB2(SCH_1):PAGE25 

SKX_EXT_B_BGA1-IC,TBD  I172  U5D1
AB61 M_C_ACT_N DDR2_ACT_N @BASEBOARD_FAB2_LIB.BASEBOARD_FAB2(SCH_1):M_C_ACT_N
AD61 M_C_ALERT_N DDR2_ALERT_N @BASEBOARD_FAB2_LIB.BASEBOARD_FAB2(SCH_1):M_C_ALERT_N
AE56 M_C_BA<1> DDR2_BA<1> @BASEBOARD_FAB2_LIB.BASEBOARD_FAB2(SCH_1):M_C_BA(1)
 W52 M_C_BA<0> DDR2_BA<0> @BASEBOARD_FAB2_LIB.BASEBOARD_FAB2(SCH_1):M_C_BA(0)
AE62 M_C_BG<1> DDR2_BG<1> @BASEBOARD_FAB2_LIB.BASEBOARD_FAB2(SCH_1):M_C_BG(1)
AA60 M_C_BG<0> DDR2_BG<0> @BASEBOARD_FAB2_LIB.BASEBOARD_FAB2(SCH_1):M_C_BG(0)
AB45 M_C_C<2> DDR2_CID<2> @BASEBOARD_FAB2_LIB.BASEBOARD_FAB2(SCH_1):M_C_C(2)
AB63 M_C_CKE<3> DDR2_CKE<3> @BASEBOARD_FAB2_LIB.BASEBOARD_FAB2(SCH_1):M_C_CKE(3)
 V63 M_C_CKE<2> DDR2_CKE<2> @BASEBOARD_FAB2_LIB.BASEBOARD_FAB2(SCH_1):M_C_CKE(2)
AD63 M_C_CKE<1> DDR2_CKE<1> @BASEBOARD_FAB2_LIB.BASEBOARD_FAB2(SCH_1):M_C_CKE(1)
AA62 M_C_CKE<0> DDR2_CKE<0> @BASEBOARD_FAB2_LIB.BASEBOARD_FAB2(SCH_1):M_C_CKE(0)
 W56 M_C_CLK_DN<3> DDR2_CLK_DN<3> @BASEBOARD_FAB2_LIB.BASEBOARD_FAB2(SCH_1):M_C_CLK_DN(3)
AA56 M_C_CLK_DN<2> DDR2_CLK_DN<2> @BASEBOARD_FAB2_LIB.BASEBOARD_FAB2(SCH_1):M_C_CLK_DN(2)
 W54 M_C_CLK_DN<1> DDR2_CLK_DN<1> @BASEBOARD_FAB2_LIB.BASEBOARD_FAB2(SCH_1):M_C_CLK_DN(1)
AA54 M_C_CLK_DN<0> DDR2_CLK_DN<0> @BASEBOARD_FAB2_LIB.BASEBOARD_FAB2(SCH_1):M_C_CLK_DN(0)
 V57 M_C_CLK_DP<3> DDR2_CLK_DP<3> @BASEBOARD_FAB2_LIB.BASEBOARD_FAB2(SCH_1):M_C_CLK_DP(3)
AB57 M_C_CLK_DP<2> DDR2_CLK_DP<2> @BASEBOARD_FAB2_LIB.BASEBOARD_FAB2(SCH_1):M_C_CLK_DP(2)
 V55 M_C_CLK_DP<1> DDR2_CLK_DP<1> @BASEBOARD_FAB2_LIB.BASEBOARD_FAB2(SCH_1):M_C_CLK_DP(1)
AB55 M_C_CLK_DP<0> DDR2_CLK_DP<0> @BASEBOARD_FAB2_LIB.BASEBOARD_FAB2(SCH_1):M_C_CLK_DP(0)
 V45 M_C_CS_N<7> DDR2_CS_N<7> @BASEBOARD_FAB2_LIB.BASEBOARD_FAB2(SCH_1):M_C_CS_N(7)
 T45 M_C_CS_N<6> DDR2_CS_N<6> @BASEBOARD_FAB2_LIB.BASEBOARD_FAB2(SCH_1):M_C_CS_N(6)
 W48 M_C_CS_N<5> DDR2_CS_N<5> @BASEBOARD_FAB2_LIB.BASEBOARD_FAB2(SCH_1):M_C_CS_N(5)
AB51 M_C_CS_N<4> DDR2_CS_N<4> @BASEBOARD_FAB2_LIB.BASEBOARD_FAB2(SCH_1):M_C_CS_N(4)
AA46 M_C_CS_N<3> DDR2_CS_N<3> @BASEBOARD_FAB2_LIB.BASEBOARD_FAB2(SCH_1):M_C_CS_N(3)
 W46 M_C_CS_N<2> DDR2_CS_N<2> @BASEBOARD_FAB2_LIB.BASEBOARD_FAB2(SCH_1):M_C_CS_N(2)
AB49 M_C_CS_N<1> DDR2_CS_N<1> @BASEBOARD_FAB2_LIB.BASEBOARD_FAB2(SCH_1):M_C_CS_N(1)
 V51 M_C_CS_N<0> DDR2_CS_N<0> @BASEBOARD_FAB2_LIB.BASEBOARD_FAB2(SCH_1):M_C_CS_N(0)
AH23 M_C_DQ<63> DDR2_DQ<63> @BASEBOARD_FAB2_LIB.BASEBOARD_FAB2(SCH_1):M_C_DQ(63)
AD23 M_C_DQ<62> DDR2_DQ<62> @BASEBOARD_FAB2_LIB.BASEBOARD_FAB2(SCH_1):M_C_DQ(62)
AG26 M_C_DQ<61> DDR2_DQ<61> @BASEBOARD_FAB2_LIB.BASEBOARD_FAB2(SCH_1):M_C_DQ(61)
AE26 M_C_DQ<60> DDR2_DQ<60> @BASEBOARD_FAB2_LIB.BASEBOARD_FAB2(SCH_1):M_C_DQ(60)
AG22 M_C_DQ<59> DDR2_DQ<59> @BASEBOARD_FAB2_LIB.BASEBOARD_FAB2(SCH_1):M_C_DQ(59)
AE22 M_C_DQ<58> DDR2_DQ<58> @BASEBOARD_FAB2_LIB.BASEBOARD_FAB2(SCH_1):M_C_DQ(58)
AH25 M_C_DQ<57> DDR2_DQ<57> @BASEBOARD_FAB2_LIB.BASEBOARD_FAB2(SCH_1):M_C_DQ(57)
AD25 M_C_DQ<56> DDR2_DQ<56> @BASEBOARD_FAB2_LIB.BASEBOARD_FAB2(SCH_1):M_C_DQ(56)
AH29 M_C_DQ<55> DDR2_DQ<55> @BASEBOARD_FAB2_LIB.BASEBOARD_FAB2(SCH_1):M_C_DQ(55)
AD29 M_C_DQ<54> DDR2_DQ<54> @BASEBOARD_FAB2_LIB.BASEBOARD_FAB2(SCH_1):M_C_DQ(54)
AG32 M_C_DQ<53> DDR2_DQ<53> @BASEBOARD_FAB2_LIB.BASEBOARD_FAB2(SCH_1):M_C_DQ(53)
AE32 M_C_DQ<52> DDR2_DQ<52> @BASEBOARD_FAB2_LIB.BASEBOARD_FAB2(SCH_1):M_C_DQ(52)
AG28 M_C_DQ<51> DDR2_DQ<51> @BASEBOARD_FAB2_LIB.BASEBOARD_FAB2(SCH_1):M_C_DQ(51)
AE28 M_C_DQ<50> DDR2_DQ<50> @BASEBOARD_FAB2_LIB.BASEBOARD_FAB2(SCH_1):M_C_DQ(50)
AH31 M_C_DQ<49> DDR2_DQ<49> @BASEBOARD_FAB2_LIB.BASEBOARD_FAB2(SCH_1):M_C_DQ(49)
AD31 M_C_DQ<48> DDR2_DQ<48> @BASEBOARD_FAB2_LIB.BASEBOARD_FAB2(SCH_1):M_C_DQ(48)
AA32 M_C_DQ<47> DDR2_DQ<47> @BASEBOARD_FAB2_LIB.BASEBOARD_FAB2(SCH_1):M_C_DQ(47)
 U32 M_C_DQ<46> DDR2_DQ<46> @BASEBOARD_FAB2_LIB.BASEBOARD_FAB2(SCH_1):M_C_DQ(46)
 Y35 M_C_DQ<45> DDR2_DQ<45> @BASEBOARD_FAB2_LIB.BASEBOARD_FAB2(SCH_1):M_C_DQ(45)
 V35 M_C_DQ<44> DDR2_DQ<44> @BASEBOARD_FAB2_LIB.BASEBOARD_FAB2(SCH_1):M_C_DQ(44)
 Y31 M_C_DQ<43> DDR2_DQ<43> @BASEBOARD_FAB2_LIB.BASEBOARD_FAB2(SCH_1):M_C_DQ(43)
 V31 M_C_DQ<42> DDR2_DQ<42> @BASEBOARD_FAB2_LIB.BASEBOARD_FAB2(SCH_1):M_C_DQ(42)
AA34 M_C_DQ<41> DDR2_DQ<41> @BASEBOARD_FAB2_LIB.BASEBOARD_FAB2(SCH_1):M_C_DQ(41)
 U34 M_C_DQ<40> DDR2_DQ<40> @BASEBOARD_FAB2_LIB.BASEBOARD_FAB2(SCH_1):M_C_DQ(40)
AA38 M_C_DQ<39> DDR2_DQ<39> @BASEBOARD_FAB2_LIB.BASEBOARD_FAB2(SCH_1):M_C_DQ(39)
 U38 M_C_DQ<38> DDR2_DQ<38> @BASEBOARD_FAB2_LIB.BASEBOARD_FAB2(SCH_1):M_C_DQ(38)
 Y41 M_C_DQ<37> DDR2_DQ<37> @BASEBOARD_FAB2_LIB.BASEBOARD_FAB2(SCH_1):M_C_DQ(37)
 V41 M_C_DQ<36> DDR2_DQ<36> @BASEBOARD_FAB2_LIB.BASEBOARD_FAB2(SCH_1):M_C_DQ(36)
 Y37 M_C_DQ<35> DDR2_DQ<35> @BASEBOARD_FAB2_LIB.BASEBOARD_FAB2(SCH_1):M_C_DQ(35)
 V37 M_C_DQ<34> DDR2_DQ<34> @BASEBOARD_FAB2_LIB.BASEBOARD_FAB2(SCH_1):M_C_DQ(34)
AA40 M_C_DQ<33> DDR2_DQ<33> @BASEBOARD_FAB2_LIB.BASEBOARD_FAB2(SCH_1):M_C_DQ(33)
 U40 M_C_DQ<32> DDR2_DQ<32> @BASEBOARD_FAB2_LIB.BASEBOARD_FAB2(SCH_1):M_C_DQ(32)
AT65 M_C_DQ<31> DDR2_DQ<31> @BASEBOARD_FAB2_LIB.BASEBOARD_FAB2(SCH_1):M_C_DQ(31)
AM65 M_C_DQ<30> DDR2_DQ<30> @BASEBOARD_FAB2_LIB.BASEBOARD_FAB2(SCH_1):M_C_DQ(30)
AR68 M_C_DQ<29> DDR2_DQ<29> @BASEBOARD_FAB2_LIB.BASEBOARD_FAB2(SCH_1):M_C_DQ(29)
AN68 M_C_DQ<28> DDR2_DQ<28> @BASEBOARD_FAB2_LIB.BASEBOARD_FAB2(SCH_1):M_C_DQ(28)
AR64 M_C_DQ<27> DDR2_DQ<27> @BASEBOARD_FAB2_LIB.BASEBOARD_FAB2(SCH_1):M_C_DQ(27)
AN64 M_C_DQ<26> DDR2_DQ<26> @BASEBOARD_FAB2_LIB.BASEBOARD_FAB2(SCH_1):M_C_DQ(26)
AT67 M_C_DQ<25> DDR2_DQ<25> @BASEBOARD_FAB2_LIB.BASEBOARD_FAB2(SCH_1):M_C_DQ(25)
AM67 M_C_DQ<24> DDR2_DQ<24> @BASEBOARD_FAB2_LIB.BASEBOARD_FAB2(SCH_1):M_C_DQ(24)
 V69 M_C_DQ<23> DDR2_DQ<23> @BASEBOARD_FAB2_LIB.BASEBOARD_FAB2(SCH_1):M_C_DQ(23)
 T71 M_C_DQ<22> DDR2_DQ<22> @BASEBOARD_FAB2_LIB.BASEBOARD_FAB2(SCH_1):M_C_DQ(22)
AB71 M_C_DQ<21> DDR2_DQ<21> @BASEBOARD_FAB2_LIB.BASEBOARD_FAB2(SCH_1):M_C_DQ(21)
AA72 M_C_DQ<20> DDR2_DQ<20> @BASEBOARD_FAB2_LIB.BASEBOARD_FAB2(SCH_1):M_C_DQ(20)
 T69 M_C_DQ<19> DDR2_DQ<19> @BASEBOARD_FAB2_LIB.BASEBOARD_FAB2(SCH_1):M_C_DQ(19)
 R70 M_C_DQ<18> DDR2_DQ<18> @BASEBOARD_FAB2_LIB.BASEBOARD_FAB2(SCH_1):M_C_DQ(18)
AA70 M_C_DQ<17> DDR2_DQ<17> @BASEBOARD_FAB2_LIB.BASEBOARD_FAB2(SCH_1):M_C_DQ(17)
 W72 M_C_DQ<16> DDR2_DQ<16> @BASEBOARD_FAB2_LIB.BASEBOARD_FAB2(SCH_1):M_C_DQ(16)
 Y75 M_C_DQ<15> DDR2_DQ<15> @BASEBOARD_FAB2_LIB.BASEBOARD_FAB2(SCH_1):M_C_DQ(15)
AB77 M_C_DQ<14> DDR2_DQ<14> @BASEBOARD_FAB2_LIB.BASEBOARD_FAB2(SCH_1):M_C_DQ(14)
AE74 M_C_DQ<13> DDR2_DQ<13> @BASEBOARD_FAB2_LIB.BASEBOARD_FAB2(SCH_1):M_C_DQ(13)
AF75 M_C_DQ<12> DDR2_DQ<12> @BASEBOARD_FAB2_LIB.BASEBOARD_FAB2(SCH_1):M_C_DQ(12)
 W76 M_C_DQ<11> DDR2_DQ<11> @BASEBOARD_FAB2_LIB.BASEBOARD_FAB2(SCH_1):M_C_DQ(11)
 Y77 M_C_DQ<10> DDR2_DQ<10> @BASEBOARD_FAB2_LIB.BASEBOARD_FAB2(SCH_1):M_C_DQ(10)
AC74 M_C_DQ<9> DDR2_DQ<9> @BASEBOARD_FAB2_LIB.BASEBOARD_FAB2(SCH_1):M_C_DQ(9)
AE76 M_C_DQ<8> DDR2_DQ<8> @BASEBOARD_FAB2_LIB.BASEBOARD_FAB2(SCH_1):M_C_DQ(8)
AK75 M_C_DQ<7> DDR2_DQ<7> @BASEBOARD_FAB2_LIB.BASEBOARD_FAB2(SCH_1):M_C_DQ(7)
AM77 M_C_DQ<6> DDR2_DQ<6> @BASEBOARD_FAB2_LIB.BASEBOARD_FAB2(SCH_1):M_C_DQ(6)
AR74 M_C_DQ<5> DDR2_DQ<5> @BASEBOARD_FAB2_LIB.BASEBOARD_FAB2(SCH_1):M_C_DQ(5)
AT75 M_C_DQ<4> DDR2_DQ<4> @BASEBOARD_FAB2_LIB.BASEBOARD_FAB2(SCH_1):M_C_DQ(4)
AJ76 M_C_DQ<3> DDR2_DQ<3> @BASEBOARD_FAB2_LIB.BASEBOARD_FAB2(SCH_1):M_C_DQ(3)
AK77 M_C_DQ<2> DDR2_DQ<2> @BASEBOARD_FAB2_LIB.BASEBOARD_FAB2(SCH_1):M_C_DQ(2)
AN74 M_C_DQ<1> DDR2_DQ<1> @BASEBOARD_FAB2_LIB.BASEBOARD_FAB2(SCH_1):M_C_DQ(1)
AR76 M_C_DQ<0> DDR2_DQ<0> @BASEBOARD_FAB2_LIB.BASEBOARD_FAB2(SCH_1):M_C_DQ(0)
AT71 M_C_DQS_DN<17> DDR2_DQS_DN<17> @BASEBOARD_FAB2_LIB.BASEBOARD_FAB2(SCH_1):M_C_DQS_DN(17)
AC24 M_C_DQS_DN<16> DDR2_DQS_DN<16> @BASEBOARD_FAB2_LIB.BASEBOARD_FAB2(SCH_1):M_C_DQS_DN(16)
AC30 M_C_DQS_DN<15> DDR2_DQS_DN<15> @BASEBOARD_FAB2_LIB.BASEBOARD_FAB2(SCH_1):M_C_DQS_DN(15)
 T33 M_C_DQS_DN<14> DDR2_DQS_DN<14> @BASEBOARD_FAB2_LIB.BASEBOARD_FAB2(SCH_1):M_C_DQS_DN(14)
 T39 M_C_DQS_DN<13> DDR2_DQS_DN<13> @BASEBOARD_FAB2_LIB.BASEBOARD_FAB2(SCH_1):M_C_DQS_DN(13)
AL66 M_C_DQS_DN<12> DDR2_DQS_DN<12> @BASEBOARD_FAB2_LIB.BASEBOARD_FAB2(SCH_1):M_C_DQS_DN(12)
 U72 M_C_DQS_DN<11> DDR2_DQS_DN<11> @BASEBOARD_FAB2_LIB.BASEBOARD_FAB2(SCH_1):M_C_DQS_DN(11)
AD77 M_C_DQS_DN<10> DDR2_DQS_DN<10> @BASEBOARD_FAB2_LIB.BASEBOARD_FAB2(SCH_1):M_C_DQS_DN(10)
AP77 M_C_DQS_DN<9> DDR2_DQS_DN<9> @BASEBOARD_FAB2_LIB.BASEBOARD_FAB2(SCH_1):M_C_DQS_DN(9)
BB71 M_C_DQS_DN<8> DDR2_DQS_DN<8> @BASEBOARD_FAB2_LIB.BASEBOARD_FAB2(SCH_1):M_C_DQS_DN(8)
AJ24 M_C_DQS_DN<7> DDR2_DQS_DN<7> @BASEBOARD_FAB2_LIB.BASEBOARD_FAB2(SCH_1):M_C_DQS_DN(7)
AJ30 M_C_DQS_DN<6> DDR2_DQS_DN<6> @BASEBOARD_FAB2_LIB.BASEBOARD_FAB2(SCH_1):M_C_DQS_DN(6)
AB33 M_C_DQS_DN<5> DDR2_DQS_DN<5> @BASEBOARD_FAB2_LIB.BASEBOARD_FAB2(SCH_1):M_C_DQS_DN(5)
AB39 M_C_DQS_DN<4> DDR2_DQS_DN<4> @BASEBOARD_FAB2_LIB.BASEBOARD_FAB2(SCH_1):M_C_DQS_DN(4)
AU66 M_C_DQS_DN<3> DDR2_DQS_DN<3> @BASEBOARD_FAB2_LIB.BASEBOARD_FAB2(SCH_1):M_C_DQS_DN(3)
 Y69 M_C_DQS_DN<2> DDR2_DQS_DN<2> @BASEBOARD_FAB2_LIB.BASEBOARD_FAB2(SCH_1):M_C_DQS_DN(2)
AA74 M_C_DQS_DN<1> DDR2_DQS_DN<1> @BASEBOARD_FAB2_LIB.BASEBOARD_FAB2(SCH_1):M_C_DQS_DN(1)
AL74 M_C_DQS_DN<0> DDR2_DQS_DN<0> @BASEBOARD_FAB2_LIB.BASEBOARD_FAB2(SCH_1):M_C_DQS_DN(0)
AV71 M_C_DQS_DP<17> DDR2_DQS_DP<17> @BASEBOARD_FAB2_LIB.BASEBOARD_FAB2(SCH_1):M_C_DQS_DP(17)
AE24 M_C_DQS_DP<16> DDR2_DQS_DP<16> @BASEBOARD_FAB2_LIB.BASEBOARD_FAB2(SCH_1):M_C_DQS_DP(16)
AE30 M_C_DQS_DP<15> DDR2_DQS_DP<15> @BASEBOARD_FAB2_LIB.BASEBOARD_FAB2(SCH_1):M_C_DQS_DP(15)
 V33 M_C_DQS_DP<14> DDR2_DQS_DP<14> @BASEBOARD_FAB2_LIB.BASEBOARD_FAB2(SCH_1):M_C_DQS_DP(14)
 V39 M_C_DQS_DP<13> DDR2_DQS_DP<13> @BASEBOARD_FAB2_LIB.BASEBOARD_FAB2(SCH_1):M_C_DQS_DP(13)
AN66 M_C_DQS_DP<12> DDR2_DQS_DP<12> @BASEBOARD_FAB2_LIB.BASEBOARD_FAB2(SCH_1):M_C_DQS_DP(12)
 V71 M_C_DQS_DP<11> DDR2_DQS_DP<11> @BASEBOARD_FAB2_LIB.BASEBOARD_FAB2(SCH_1):M_C_DQS_DP(11)
AC76 M_C_DQS_DP<10> DDR2_DQS_DP<10> @BASEBOARD_FAB2_LIB.BASEBOARD_FAB2(SCH_1):M_C_DQS_DP(10)
AN76 M_C_DQS_DP<9> DDR2_DQS_DP<9> @BASEBOARD_FAB2_LIB.BASEBOARD_FAB2(SCH_1):M_C_DQS_DP(9)
AY71 M_C_DQS_DP<8> DDR2_DQS_DP<8> @BASEBOARD_FAB2_LIB.BASEBOARD_FAB2(SCH_1):M_C_DQS_DP(8)
AG24 M_C_DQS_DP<7> DDR2_DQS_DP<7> @BASEBOARD_FAB2_LIB.BASEBOARD_FAB2(SCH_1):M_C_DQS_DP(7)
AG30 M_C_DQS_DP<6> DDR2_DQS_DP<6> @BASEBOARD_FAB2_LIB.BASEBOARD_FAB2(SCH_1):M_C_DQS_DP(6)
 Y33 M_C_DQS_DP<5> DDR2_DQS_DP<5> @BASEBOARD_FAB2_LIB.BASEBOARD_FAB2(SCH_1):M_C_DQS_DP(5)
 Y39 M_C_DQS_DP<4> DDR2_DQS_DP<4> @BASEBOARD_FAB2_LIB.BASEBOARD_FAB2(SCH_1):M_C_DQS_DP(4)
AR66 M_C_DQS_DP<3> DDR2_DQS_DP<3> @BASEBOARD_FAB2_LIB.BASEBOARD_FAB2(SCH_1):M_C_DQS_DP(3)
 W70 M_C_DQS_DP<2> DDR2_DQS_DP<2> @BASEBOARD_FAB2_LIB.BASEBOARD_FAB2(SCH_1):M_C_DQS_DP(2)
AB75 M_C_DQS_DP<1> DDR2_DQS_DP<1> @BASEBOARD_FAB2_LIB.BASEBOARD_FAB2(SCH_1):M_C_DQS_DP(1)
AM75 M_C_DQS_DP<0> DDR2_DQS_DP<0> @BASEBOARD_FAB2_LIB.BASEBOARD_FAB2(SCH_1):M_C_DQS_DP(0)
BA70 M_C_ECC<7> DDR2_ECC<7> @BASEBOARD_FAB2_LIB.BASEBOARD_FAB2(SCH_1):M_C_ECC(7)
AU70 M_C_ECC<6> DDR2_ECC<6> @BASEBOARD_FAB2_LIB.BASEBOARD_FAB2(SCH_1):M_C_ECC(6)
AY73 M_C_ECC<5> DDR2_ECC<5> @BASEBOARD_FAB2_LIB.BASEBOARD_FAB2(SCH_1):M_C_ECC(5)
AV73 M_C_ECC<4> DDR2_ECC<4> @BASEBOARD_FAB2_LIB.BASEBOARD_FAB2(SCH_1):M_C_ECC(4)
AY69 M_C_ECC<3> DDR2_ECC<3> @BASEBOARD_FAB2_LIB.BASEBOARD_FAB2(SCH_1):M_C_ECC(3)
AV69 M_C_ECC<2> DDR2_ECC<2> @BASEBOARD_FAB2_LIB.BASEBOARD_FAB2(SCH_1):M_C_ECC(2)
BA72 M_C_ECC<1> DDR2_ECC<1> @BASEBOARD_FAB2_LIB.BASEBOARD_FAB2(SCH_1):M_C_ECC(1)
AU72 M_C_ECC<0> DDR2_ECC<0> @BASEBOARD_FAB2_LIB.BASEBOARD_FAB2(SCH_1):M_C_ECC(0)
AC46 M_C_MA<17> DDR2_MA<17> @BASEBOARD_FAB2_LIB.BASEBOARD_FAB2(SCH_1):M_C_MA(17)
AA52 M_C_MA<16> DDR2_MA<16> @BASEBOARD_FAB2_LIB.BASEBOARD_FAB2(SCH_1):M_C_MA(16)
AE54 M_C_MA<15> DDR2_MA<15> @BASEBOARD_FAB2_LIB.BASEBOARD_FAB2(SCH_1):M_C_MA(15)
 W50 M_C_MA<14> DDR2_MA<14> @BASEBOARD_FAB2_LIB.BASEBOARD_FAB2(SCH_1):M_C_MA(14)
AD53 M_C_MA<13> DDR2_MA<13> @BASEBOARD_FAB2_LIB.BASEBOARD_FAB2(SCH_1):M_C_MA(13)
AG62 M_C_MA<12> DDR2_MA<12> @BASEBOARD_FAB2_LIB.BASEBOARD_FAB2(SCH_1):M_C_MA(12)
AG60 M_C_MA<11> DDR2_MA<11> @BASEBOARD_FAB2_LIB.BASEBOARD_FAB2(SCH_1):M_C_MA(11)
AD55 M_C_MA<10> DDR2_MA<10> @BASEBOARD_FAB2_LIB.BASEBOARD_FAB2(SCH_1):M_C_MA(10)
AG58 M_C_MA<9> DDR2_MA<9> @BASEBOARD_FAB2_LIB.BASEBOARD_FAB2(SCH_1):M_C_MA(9)
AD59 M_C_MA<8> DDR2_MA<8> @BASEBOARD_FAB2_LIB.BASEBOARD_FAB2(SCH_1):M_C_MA(8)
AE60 M_C_MA<7> DDR2_MA<7> @BASEBOARD_FAB2_LIB.BASEBOARD_FAB2(SCH_1):M_C_MA(7)
AB59 M_C_MA<6> DDR2_MA<6> @BASEBOARD_FAB2_LIB.BASEBOARD_FAB2(SCH_1):M_C_MA(6)
 V59 M_C_MA<5> DDR2_MA<5> @BASEBOARD_FAB2_LIB.BASEBOARD_FAB2(SCH_1):M_C_MA(5)
AA58 M_C_MA<4> DDR2_MA<4> @BASEBOARD_FAB2_LIB.BASEBOARD_FAB2(SCH_1):M_C_MA(4)
 W58 M_C_MA<3> DDR2_MA<3> @BASEBOARD_FAB2_LIB.BASEBOARD_FAB2(SCH_1):M_C_MA(3)
AD57 M_C_MA<2> DDR2_MA<2> @BASEBOARD_FAB2_LIB.BASEBOARD_FAB2(SCH_1):M_C_MA(2)
AE58 M_C_MA<1> DDR2_MA<1> @BASEBOARD_FAB2_LIB.BASEBOARD_FAB2(SCH_1):M_C_MA(1)
AB53 M_C_MA<0> DDR2_MA<0> @BASEBOARD_FAB2_LIB.BASEBOARD_FAB2(SCH_1):M_C_MA(0)
AB47 M_C_ODT<3> DDR2_ODT<3> @BASEBOARD_FAB2_LIB.BASEBOARD_FAB2(SCH_1):M_C_ODT(3)
 V49 M_C_ODT<2> DDR2_ODT<2> @BASEBOARD_FAB2_LIB.BASEBOARD_FAB2(SCH_1):M_C_ODT(2)
AA48 M_C_ODT<1> DDR2_ODT<1> @BASEBOARD_FAB2_LIB.BASEBOARD_FAB2(SCH_1):M_C_ODT(1)
AA50 M_C_ODT<0> DDR2_ODT<0> @BASEBOARD_FAB2_LIB.BASEBOARD_FAB2(SCH_1):M_C_ODT(0)
 V53 M_C_PAR DDR2_PAR @BASEBOARD_FAB2_LIB.BASEBOARD_FAB2(SCH_1):M_C_PAR


DRAWING: @BASEBOARD_FAB2_LIB.BASEBOARD_FAB2(SCH_1):PAGE26 

SKX_EXT_B_BGA1-IC,TBD  I172  U5D1
DW60 M_D_ACT_N DDR3_ACT_N @BASEBOARD_FAB2_LIB.BASEBOARD_FAB2(SCH_1):M_D_ACT_N
ED63 M_D_ALERT_N DDR3_ALERT_N @BASEBOARD_FAB2_LIB.BASEBOARD_FAB2(SCH_1):M_D_ALERT_N
EA54 M_D_BA<1> DDR3_BA<1> @BASEBOARD_FAB2_LIB.BASEBOARD_FAB2(SCH_1):M_D_BA(1)
EE52 M_D_BA<0> DDR3_BA<0> @BASEBOARD_FAB2_LIB.BASEBOARD_FAB2(SCH_1):M_D_BA(0)
DW62 M_D_BG<1> DDR3_BG<1> @BASEBOARD_FAB2_LIB.BASEBOARD_FAB2(SCH_1):M_D_BG(1)
ED61 M_D_BG<0> DDR3_BG<0> @BASEBOARD_FAB2_LIB.BASEBOARD_FAB2(SCH_1):M_D_BG(0)
DV47 M_D_C<2> DDR3_CID<2> @BASEBOARD_FAB2_LIB.BASEBOARD_FAB2(SCH_1):M_D_C(2)
EB63 M_D_CKE<3> DDR3_CKE<3> @BASEBOARD_FAB2_LIB.BASEBOARD_FAB2(SCH_1):M_D_CKE(3)
EA62 M_D_CKE<2> DDR3_CKE<2> @BASEBOARD_FAB2_LIB.BASEBOARD_FAB2(SCH_1):M_D_CKE(2)
EF63 M_D_CKE<1> DDR3_CKE<1> @BASEBOARD_FAB2_LIB.BASEBOARD_FAB2(SCH_1):M_D_CKE(1)
EE62 M_D_CKE<0> DDR3_CKE<0> @BASEBOARD_FAB2_LIB.BASEBOARD_FAB2(SCH_1):M_D_CKE(0)
EF57 M_D_CLK_DN<3> DDR3_CLK_DN<3> @BASEBOARD_FAB2_LIB.BASEBOARD_FAB2(SCH_1):M_D_CLK_DN(3)
DW56 M_D_CLK_DN<2> DDR3_CLK_DN<2> @BASEBOARD_FAB2_LIB.BASEBOARD_FAB2(SCH_1):M_D_CLK_DN(2)
EF55 M_D_CLK_DN<1> DDR3_CLK_DN<1> @BASEBOARD_FAB2_LIB.BASEBOARD_FAB2(SCH_1):M_D_CLK_DN(1)
ED55 M_D_CLK_DN<0> DDR3_CLK_DN<0> @BASEBOARD_FAB2_LIB.BASEBOARD_FAB2(SCH_1):M_D_CLK_DN(0)
EE56 M_D_CLK_DP<3> DDR3_CLK_DP<3> @BASEBOARD_FAB2_LIB.BASEBOARD_FAB2(SCH_1):M_D_CLK_DP(3)
EA56 M_D_CLK_DP<2> DDR3_CLK_DP<2> @BASEBOARD_FAB2_LIB.BASEBOARD_FAB2(SCH_1):M_D_CLK_DP(2)
EE54 M_D_CLK_DP<1> DDR3_CLK_DP<1> @BASEBOARD_FAB2_LIB.BASEBOARD_FAB2(SCH_1):M_D_CLK_DP(1)
EB55 M_D_CLK_DP<0> DDR3_CLK_DP<0> @BASEBOARD_FAB2_LIB.BASEBOARD_FAB2(SCH_1):M_D_CLK_DP(0)
EB45 M_D_CS_N<7> DDR3_CS_N<7> @BASEBOARD_FAB2_LIB.BASEBOARD_FAB2(SCH_1):M_D_CS_N(7)
DV45 M_D_CS_N<6> DDR3_CS_N<6> @BASEBOARD_FAB2_LIB.BASEBOARD_FAB2(SCH_1):M_D_CS_N(6)
EB49 M_D_CS_N<5> DDR3_CS_N<5> @BASEBOARD_FAB2_LIB.BASEBOARD_FAB2(SCH_1):M_D_CS_N(5)
EB51 M_D_CS_N<4> DDR3_CS_N<4> @BASEBOARD_FAB2_LIB.BASEBOARD_FAB2(SCH_1):M_D_CS_N(4)
EB47 M_D_CS_N<3> DDR3_CS_N<3> @BASEBOARD_FAB2_LIB.BASEBOARD_FAB2(SCH_1):M_D_CS_N(3)
ED47 M_D_CS_N<2> DDR3_CS_N<2> @BASEBOARD_FAB2_LIB.BASEBOARD_FAB2(SCH_1):M_D_CS_N(2)
ED49 M_D_CS_N<1> DDR3_CS_N<1> @BASEBOARD_FAB2_LIB.BASEBOARD_FAB2(SCH_1):M_D_CS_N(1)
EF51 M_D_CS_N<0> DDR3_CS_N<0> @BASEBOARD_FAB2_LIB.BASEBOARD_FAB2(SCH_1):M_D_CS_N(0)
DW22 M_D_DQ<63> DDR3_DQ<63> @BASEBOARD_FAB2_LIB.BASEBOARD_FAB2(SCH_1):M_D_DQ(63)
EC22 M_D_DQ<62> DDR3_DQ<62> @BASEBOARD_FAB2_LIB.BASEBOARD_FAB2(SCH_1):M_D_DQ(62)
DT25 M_D_DQ<61> DDR3_DQ<61> @BASEBOARD_FAB2_LIB.BASEBOARD_FAB2(SCH_1):M_D_DQ(61)
DP25 M_D_DQ<60> DDR3_DQ<60> @BASEBOARD_FAB2_LIB.BASEBOARD_FAB2(SCH_1):M_D_DQ(60)
EB21 M_D_DQ<59> DDR3_DQ<59> @BASEBOARD_FAB2_LIB.BASEBOARD_FAB2(SCH_1):M_D_DQ(59)
DY21 M_D_DQ<58> DDR3_DQ<58> @BASEBOARD_FAB2_LIB.BASEBOARD_FAB2(SCH_1):M_D_DQ(58)
DU24 M_D_DQ<57> DDR3_DQ<57> @BASEBOARD_FAB2_LIB.BASEBOARD_FAB2(SCH_1):M_D_DQ(57)
DN24 M_D_DQ<56> DDR3_DQ<56> @BASEBOARD_FAB2_LIB.BASEBOARD_FAB2(SCH_1):M_D_DQ(56)
DU28 M_D_DQ<55> DDR3_DQ<55> @BASEBOARD_FAB2_LIB.BASEBOARD_FAB2(SCH_1):M_D_DQ(55)
DN28 M_D_DQ<54> DDR3_DQ<54> @BASEBOARD_FAB2_LIB.BASEBOARD_FAB2(SCH_1):M_D_DQ(54)
DT31 M_D_DQ<53> DDR3_DQ<53> @BASEBOARD_FAB2_LIB.BASEBOARD_FAB2(SCH_1):M_D_DQ(53)
DP31 M_D_DQ<52> DDR3_DQ<52> @BASEBOARD_FAB2_LIB.BASEBOARD_FAB2(SCH_1):M_D_DQ(52)
DT27 M_D_DQ<51> DDR3_DQ<51> @BASEBOARD_FAB2_LIB.BASEBOARD_FAB2(SCH_1):M_D_DQ(51)
DP27 M_D_DQ<50> DDR3_DQ<50> @BASEBOARD_FAB2_LIB.BASEBOARD_FAB2(SCH_1):M_D_DQ(50)
DU30 M_D_DQ<49> DDR3_DQ<49> @BASEBOARD_FAB2_LIB.BASEBOARD_FAB2(SCH_1):M_D_DQ(49)
DN30 M_D_DQ<48> DDR3_DQ<48> @BASEBOARD_FAB2_LIB.BASEBOARD_FAB2(SCH_1):M_D_DQ(48)
DU34 M_D_DQ<47> DDR3_DQ<47> @BASEBOARD_FAB2_LIB.BASEBOARD_FAB2(SCH_1):M_D_DQ(47)
DN34 M_D_DQ<46> DDR3_DQ<46> @BASEBOARD_FAB2_LIB.BASEBOARD_FAB2(SCH_1):M_D_DQ(46)
DT37 M_D_DQ<45> DDR3_DQ<45> @BASEBOARD_FAB2_LIB.BASEBOARD_FAB2(SCH_1):M_D_DQ(45)
DP37 M_D_DQ<44> DDR3_DQ<44> @BASEBOARD_FAB2_LIB.BASEBOARD_FAB2(SCH_1):M_D_DQ(44)
DT33 M_D_DQ<43> DDR3_DQ<43> @BASEBOARD_FAB2_LIB.BASEBOARD_FAB2(SCH_1):M_D_DQ(43)
DP33 M_D_DQ<42> DDR3_DQ<42> @BASEBOARD_FAB2_LIB.BASEBOARD_FAB2(SCH_1):M_D_DQ(42)
DU36 M_D_DQ<41> DDR3_DQ<41> @BASEBOARD_FAB2_LIB.BASEBOARD_FAB2(SCH_1):M_D_DQ(41)
DN36 M_D_DQ<40> DDR3_DQ<40> @BASEBOARD_FAB2_LIB.BASEBOARD_FAB2(SCH_1):M_D_DQ(40)
ED37 M_D_DQ<39> DDR3_DQ<39> @BASEBOARD_FAB2_LIB.BASEBOARD_FAB2(SCH_1):M_D_DQ(39)
DY37 M_D_DQ<38> DDR3_DQ<38> @BASEBOARD_FAB2_LIB.BASEBOARD_FAB2(SCH_1):M_D_DQ(38)
EA40 M_D_DQ<37> DDR3_DQ<37> @BASEBOARD_FAB2_LIB.BASEBOARD_FAB2(SCH_1):M_D_DQ(37)
DY39 M_D_DQ<36> DDR3_DQ<36> @BASEBOARD_FAB2_LIB.BASEBOARD_FAB2(SCH_1):M_D_DQ(36)
EC36 M_D_DQ<35> DDR3_DQ<35> @BASEBOARD_FAB2_LIB.BASEBOARD_FAB2(SCH_1):M_D_DQ(35)
EA36 M_D_DQ<34> DDR3_DQ<34> @BASEBOARD_FAB2_LIB.BASEBOARD_FAB2(SCH_1):M_D_DQ(34)
ED39 M_D_DQ<33> DDR3_DQ<33> @BASEBOARD_FAB2_LIB.BASEBOARD_FAB2(SCH_1):M_D_DQ(33)
EC40 M_D_DQ<32> DDR3_DQ<32> @BASEBOARD_FAB2_LIB.BASEBOARD_FAB2(SCH_1):M_D_DQ(32)
DU74 M_D_DQ<31> DDR3_DQ<31> @BASEBOARD_FAB2_LIB.BASEBOARD_FAB2(SCH_1):M_D_DQ(31)
DN74 M_D_DQ<30> DDR3_DQ<30> @BASEBOARD_FAB2_LIB.BASEBOARD_FAB2(SCH_1):M_D_DQ(30)
DT77 M_D_DQ<29> DDR3_DQ<29> @BASEBOARD_FAB2_LIB.BASEBOARD_FAB2(SCH_1):M_D_DQ(29)
DP77 M_D_DQ<28> DDR3_DQ<28> @BASEBOARD_FAB2_LIB.BASEBOARD_FAB2(SCH_1):M_D_DQ(28)
DT73 M_D_DQ<27> DDR3_DQ<27> @BASEBOARD_FAB2_LIB.BASEBOARD_FAB2(SCH_1):M_D_DQ(27)
DP73 M_D_DQ<26> DDR3_DQ<26> @BASEBOARD_FAB2_LIB.BASEBOARD_FAB2(SCH_1):M_D_DQ(26)
DU76 M_D_DQ<25> DDR3_DQ<25> @BASEBOARD_FAB2_LIB.BASEBOARD_FAB2(SCH_1):M_D_DQ(25)
DN76 M_D_DQ<24> DDR3_DQ<24> @BASEBOARD_FAB2_LIB.BASEBOARD_FAB2(SCH_1):M_D_DQ(24)
DN82 M_D_DQ<23> DDR3_DQ<23> @BASEBOARD_FAB2_LIB.BASEBOARD_FAB2(SCH_1):M_D_DQ(23)
DR80 M_D_DQ<22> DDR3_DQ<22> @BASEBOARD_FAB2_LIB.BASEBOARD_FAB2(SCH_1):M_D_DQ(22)
DJ80 M_D_DQ<21> DDR3_DQ<21> @BASEBOARD_FAB2_LIB.BASEBOARD_FAB2(SCH_1):M_D_DQ(21)
DK79 M_D_DQ<20> DDR3_DQ<20> @BASEBOARD_FAB2_LIB.BASEBOARD_FAB2(SCH_1):M_D_DQ(20)
DR82 M_D_DQ<19> DDR3_DQ<19> @BASEBOARD_FAB2_LIB.BASEBOARD_FAB2(SCH_1):M_D_DQ(19)
DT81 M_D_DQ<18> DDR3_DQ<18> @BASEBOARD_FAB2_LIB.BASEBOARD_FAB2(SCH_1):M_D_DQ(18)
DK81 M_D_DQ<17> DDR3_DQ<17> @BASEBOARD_FAB2_LIB.BASEBOARD_FAB2(SCH_1):M_D_DQ(17)
DM79 M_D_DQ<16> DDR3_DQ<16> @BASEBOARD_FAB2_LIB.BASEBOARD_FAB2(SCH_1):M_D_DQ(16)
DV85 M_D_DQ<15> DDR3_DQ<15> @BASEBOARD_FAB2_LIB.BASEBOARD_FAB2(SCH_1):M_D_DQ(15)
DR84 M_D_DQ<14> DDR3_DQ<14> @BASEBOARD_FAB2_LIB.BASEBOARD_FAB2(SCH_1):M_D_DQ(14)
DE84 M_D_DQ<13> DDR3_DQ<13> @BASEBOARD_FAB2_LIB.BASEBOARD_FAB2(SCH_1):M_D_DQ(13)
DD85 M_D_DQ<12> DDR3_DQ<12> @BASEBOARD_FAB2_LIB.BASEBOARD_FAB2(SCH_1):M_D_DQ(12)
DY83 M_D_DQ<11> DDR3_DQ<11> @BASEBOARD_FAB2_LIB.BASEBOARD_FAB2(SCH_1):M_D_DQ(11)
DV83 M_D_DQ<10> DDR3_DQ<10> @BASEBOARD_FAB2_LIB.BASEBOARD_FAB2(SCH_1):M_D_DQ(10)
DH85 M_D_DQ<9> DDR3_DQ<9> @BASEBOARD_FAB2_LIB.BASEBOARD_FAB2(SCH_1):M_D_DQ(9)
DG84 M_D_DQ<8> DDR3_DQ<8> @BASEBOARD_FAB2_LIB.BASEBOARD_FAB2(SCH_1):M_D_DQ(8)
CW84 M_D_DQ<7> DDR3_DQ<7> @BASEBOARD_FAB2_LIB.BASEBOARD_FAB2(SCH_1):M_D_DQ(7)
CW86 M_D_DQ<6> DDR3_DQ<6> @BASEBOARD_FAB2_LIB.BASEBOARD_FAB2(SCH_1):M_D_DQ(6)
CL86 M_D_DQ<5> DDR3_DQ<5> @BASEBOARD_FAB2_LIB.BASEBOARD_FAB2(SCH_1):M_D_DQ(5)
CL84 M_D_DQ<4> DDR3_DQ<4> @BASEBOARD_FAB2_LIB.BASEBOARD_FAB2(SCH_1):M_D_DQ(4)
DA84 M_D_DQ<3> DDR3_DQ<3> @BASEBOARD_FAB2_LIB.BASEBOARD_FAB2(SCH_1):M_D_DQ(3)
DA86 M_D_DQ<2> DDR3_DQ<2> @BASEBOARD_FAB2_LIB.BASEBOARD_FAB2(SCH_1):M_D_DQ(2)
CN86 M_D_DQ<1> DDR3_DQ<1> @BASEBOARD_FAB2_LIB.BASEBOARD_FAB2(SCH_1):M_D_DQ(1)
CN84 M_D_DQ<0> DDR3_DQ<0> @BASEBOARD_FAB2_LIB.BASEBOARD_FAB2(SCH_1):M_D_DQ(0)
DB67 M_D_DQS_DN<17> DDR3_DQS_DN<17> @BASEBOARD_FAB2_LIB.BASEBOARD_FAB2(SCH_1):M_D_DQS_DN(17)
DM23 M_D_DQS_DN<16> DDR3_DQS_DN<16> @BASEBOARD_FAB2_LIB.BASEBOARD_FAB2(SCH_1):M_D_DQS_DN(16)
DM29 M_D_DQS_DN<15> DDR3_DQS_DN<15> @BASEBOARD_FAB2_LIB.BASEBOARD_FAB2(SCH_1):M_D_DQS_DN(15)
DP35 M_D_DQS_DN<14> DDR3_DQS_DN<14> @BASEBOARD_FAB2_LIB.BASEBOARD_FAB2(SCH_1):M_D_DQS_DN(14)
EA38 M_D_DQS_DN<13> DDR3_DQS_DN<13> @BASEBOARD_FAB2_LIB.BASEBOARD_FAB2(SCH_1):M_D_DQS_DN(13)
DP75 M_D_DQS_DN<12> DDR3_DQS_DN<12> @BASEBOARD_FAB2_LIB.BASEBOARD_FAB2(SCH_1):M_D_DQS_DN(12)
DN80 M_D_DQS_DN<11> DDR3_DQS_DN<11> @BASEBOARD_FAB2_LIB.BASEBOARD_FAB2(SCH_1):M_D_DQS_DN(11)
DM85 M_D_DQS_DN<10> DDR3_DQS_DN<10> @BASEBOARD_FAB2_LIB.BASEBOARD_FAB2(SCH_1):M_D_DQS_DN(10)
CR84 M_D_DQS_DN<9> DDR3_DQS_DN<9> @BASEBOARD_FAB2_LIB.BASEBOARD_FAB2(SCH_1):M_D_DQS_DN(9)
DF67 M_D_DQS_DN<8> DDR3_DQS_DN<8> @BASEBOARD_FAB2_LIB.BASEBOARD_FAB2(SCH_1):M_D_DQS_DN(8)
DV23 M_D_DQS_DN<7> DDR3_DQS_DN<7> @BASEBOARD_FAB2_LIB.BASEBOARD_FAB2(SCH_1):M_D_DQS_DN(7)
DV29 M_D_DQS_DN<6> DDR3_DQS_DN<6> @BASEBOARD_FAB2_LIB.BASEBOARD_FAB2(SCH_1):M_D_DQS_DN(6)
DV35 M_D_DQS_DN<5> DDR3_DQS_DN<5> @BASEBOARD_FAB2_LIB.BASEBOARD_FAB2(SCH_1):M_D_DQS_DN(5)
EE38 M_D_DQS_DN<4> DDR3_DQS_DN<4> @BASEBOARD_FAB2_LIB.BASEBOARD_FAB2(SCH_1):M_D_DQS_DN(4)
DV75 M_D_DQS_DN<3> DDR3_DQS_DN<3> @BASEBOARD_FAB2_LIB.BASEBOARD_FAB2(SCH_1):M_D_DQS_DN(3)
DL82 M_D_DQS_DN<2> DDR3_DQS_DN<2> @BASEBOARD_FAB2_LIB.BASEBOARD_FAB2(SCH_1):M_D_DQS_DN(2)
DN84 M_D_DQS_DN<1> DDR3_DQS_DN<1> @BASEBOARD_FAB2_LIB.BASEBOARD_FAB2(SCH_1):M_D_DQS_DN(1)
CU84 M_D_DQS_DN<0> DDR3_DQS_DN<0> @BASEBOARD_FAB2_LIB.BASEBOARD_FAB2(SCH_1):M_D_DQS_DN(0)
CY67 M_D_DQS_DP<17> DDR3_DQS_DP<17> @BASEBOARD_FAB2_LIB.BASEBOARD_FAB2(SCH_1):M_D_DQS_DP(17)
DP23 M_D_DQS_DP<16> DDR3_DQS_DP<16> @BASEBOARD_FAB2_LIB.BASEBOARD_FAB2(SCH_1):M_D_DQS_DP(16)
DP29 M_D_DQS_DP<15> DDR3_DQS_DP<15> @BASEBOARD_FAB2_LIB.BASEBOARD_FAB2(SCH_1):M_D_DQS_DP(15)
DM35 M_D_DQS_DP<14> DDR3_DQS_DP<14> @BASEBOARD_FAB2_LIB.BASEBOARD_FAB2(SCH_1):M_D_DQS_DP(14)
DW38 M_D_DQS_DP<13> DDR3_DQS_DP<13> @BASEBOARD_FAB2_LIB.BASEBOARD_FAB2(SCH_1):M_D_DQS_DP(13)
DM75 M_D_DQS_DP<12> DDR3_DQS_DP<12> @BASEBOARD_FAB2_LIB.BASEBOARD_FAB2(SCH_1):M_D_DQS_DP(12)
DP79 M_D_DQS_DP<11> DDR3_DQS_DP<11> @BASEBOARD_FAB2_LIB.BASEBOARD_FAB2(SCH_1):M_D_DQS_DP(11)
DL84 M_D_DQS_DP<10> DDR3_DQS_DP<10> @BASEBOARD_FAB2_LIB.BASEBOARD_FAB2(SCH_1):M_D_DQS_DP(10)
CP85 M_D_DQS_DP<9> DDR3_DQS_DP<9> @BASEBOARD_FAB2_LIB.BASEBOARD_FAB2(SCH_1):M_D_DQS_DP(9)
DD67 M_D_DQS_DP<8> DDR3_DQS_DP<8> @BASEBOARD_FAB2_LIB.BASEBOARD_FAB2(SCH_1):M_D_DQS_DP(8)
DT23 M_D_DQS_DP<7> DDR3_DQS_DP<7> @BASEBOARD_FAB2_LIB.BASEBOARD_FAB2(SCH_1):M_D_DQS_DP(7)
DT29 M_D_DQS_DP<6> DDR3_DQS_DP<6> @BASEBOARD_FAB2_LIB.BASEBOARD_FAB2(SCH_1):M_D_DQS_DP(6)
DT35 M_D_DQS_DP<5> DDR3_DQS_DP<5> @BASEBOARD_FAB2_LIB.BASEBOARD_FAB2(SCH_1):M_D_DQS_DP(5)
EC38 M_D_DQS_DP<4> DDR3_DQS_DP<4> @BASEBOARD_FAB2_LIB.BASEBOARD_FAB2(SCH_1):M_D_DQS_DP(4)
DT75 M_D_DQS_DP<3> DDR3_DQS_DP<3> @BASEBOARD_FAB2_LIB.BASEBOARD_FAB2(SCH_1):M_D_DQS_DP(3)
DM81 M_D_DQS_DP<2> DDR3_DQS_DP<2> @BASEBOARD_FAB2_LIB.BASEBOARD_FAB2(SCH_1):M_D_DQS_DP(2)
DP85 M_D_DQS_DP<1> DDR3_DQS_DP<1> @BASEBOARD_FAB2_LIB.BASEBOARD_FAB2(SCH_1):M_D_DQS_DP(1)
CV85 M_D_DQS_DP<0> DDR3_DQS_DP<0> @BASEBOARD_FAB2_LIB.BASEBOARD_FAB2(SCH_1):M_D_DQS_DP(0)
DE66 M_D_ECC<7> DDR3_ECC<7> @BASEBOARD_FAB2_LIB.BASEBOARD_FAB2(SCH_1):M_D_ECC(7)
DA66 M_D_ECC<6> DDR3_ECC<6> @BASEBOARD_FAB2_LIB.BASEBOARD_FAB2(SCH_1):M_D_ECC(6)
DD69 M_D_ECC<5> DDR3_ECC<5> @BASEBOARD_FAB2_LIB.BASEBOARD_FAB2(SCH_1):M_D_ECC(5)
DB69 M_D_ECC<4> DDR3_ECC<4> @BASEBOARD_FAB2_LIB.BASEBOARD_FAB2(SCH_1):M_D_ECC(4)
DD65 M_D_ECC<3> DDR3_ECC<3> @BASEBOARD_FAB2_LIB.BASEBOARD_FAB2(SCH_1):M_D_ECC(3)
DB65 M_D_ECC<2> DDR3_ECC<2> @BASEBOARD_FAB2_LIB.BASEBOARD_FAB2(SCH_1):M_D_ECC(2)
DE68 M_D_ECC<1> DDR3_ECC<1> @BASEBOARD_FAB2_LIB.BASEBOARD_FAB2(SCH_1):M_D_ECC(1)
DA68 M_D_ECC<0> DDR3_ECC<0> @BASEBOARD_FAB2_LIB.BASEBOARD_FAB2(SCH_1):M_D_ECC(0)
EA46 M_D_MA<17> DDR3_MA<17> @BASEBOARD_FAB2_LIB.BASEBOARD_FAB2(SCH_1):M_D_MA(17)
EA52 M_D_MA<16> DDR3_MA<16> @BASEBOARD_FAB2_LIB.BASEBOARD_FAB2(SCH_1):M_D_MA(16)
DV49 M_D_MA<15> DDR3_MA<15> @BASEBOARD_FAB2_LIB.BASEBOARD_FAB2(SCH_1):M_D_MA(15)
ED51 M_D_MA<14> DDR3_MA<14> @BASEBOARD_FAB2_LIB.BASEBOARD_FAB2(SCH_1):M_D_MA(14)
DW48 M_D_MA<13> DDR3_MA<13> @BASEBOARD_FAB2_LIB.BASEBOARD_FAB2(SCH_1):M_D_MA(13)
DT63 M_D_MA<12> DDR3_MA<12> @BASEBOARD_FAB2_LIB.BASEBOARD_FAB2(SCH_1):M_D_MA(12)
EB61 M_D_MA<11> DDR3_MA<11> @BASEBOARD_FAB2_LIB.BASEBOARD_FAB2(SCH_1):M_D_MA(11)
DW54 M_D_MA<10> DDR3_MA<10> @BASEBOARD_FAB2_LIB.BASEBOARD_FAB2(SCH_1):M_D_MA(10)
EF61 M_D_MA<9> DDR3_MA<9> @BASEBOARD_FAB2_LIB.BASEBOARD_FAB2(SCH_1):M_D_MA(9)
EB59 M_D_MA<8> DDR3_MA<8> @BASEBOARD_FAB2_LIB.BASEBOARD_FAB2(SCH_1):M_D_MA(8)
EA60 M_D_MA<7> DDR3_MA<7> @BASEBOARD_FAB2_LIB.BASEBOARD_FAB2(SCH_1):M_D_MA(7)
EE60 M_D_MA<6> DDR3_MA<6> @BASEBOARD_FAB2_LIB.BASEBOARD_FAB2(SCH_1):M_D_MA(6)
EA58 M_D_MA<5> DDR3_MA<5> @BASEBOARD_FAB2_LIB.BASEBOARD_FAB2(SCH_1):M_D_MA(5)
ED59 M_D_MA<4> DDR3_MA<4> @BASEBOARD_FAB2_LIB.BASEBOARD_FAB2(SCH_1):M_D_MA(4)
EB57 M_D_MA<3> DDR3_MA<3> @BASEBOARD_FAB2_LIB.BASEBOARD_FAB2(SCH_1):M_D_MA(3)
EE58 M_D_MA<2> DDR3_MA<2> @BASEBOARD_FAB2_LIB.BASEBOARD_FAB2(SCH_1):M_D_MA(2)
ED57 M_D_MA<1> DDR3_MA<1> @BASEBOARD_FAB2_LIB.BASEBOARD_FAB2(SCH_1):M_D_MA(1)
EB53 M_D_MA<0> DDR3_MA<0> @BASEBOARD_FAB2_LIB.BASEBOARD_FAB2(SCH_1):M_D_MA(0)
EA48 M_D_ODT<3> DDR3_ODT<3> @BASEBOARD_FAB2_LIB.BASEBOARD_FAB2(SCH_1):M_D_ODT(3)
EA50 M_D_ODT<2> DDR3_ODT<2> @BASEBOARD_FAB2_LIB.BASEBOARD_FAB2(SCH_1):M_D_ODT(2)
EE48 M_D_ODT<1> DDR3_ODT<1> @BASEBOARD_FAB2_LIB.BASEBOARD_FAB2(SCH_1):M_D_ODT(1)
EE50 M_D_ODT<0> DDR3_ODT<0> @BASEBOARD_FAB2_LIB.BASEBOARD_FAB2(SCH_1):M_D_ODT(0)
ED53 M_D_PAR DDR3_PAR @BASEBOARD_FAB2_LIB.BASEBOARD_FAB2(SCH_1):M_D_PAR


DRAWING: @BASEBOARD_FAB2_LIB.BASEBOARD_FAB2(SCH_1):PAGE27 

SKX_EXT_B_BGA1-IC,TBD  I172  U5D1
DR62 M_E_ACT_N DDR4_ACT_N @BASEBOARD_FAB2_LIB.BASEBOARD_FAB2(SCH_1):M_E_ACT_N
DT61 M_E_ALERT_N DDR4_ALERT_N @BASEBOARD_FAB2_LIB.BASEBOARD_FAB2(SCH_1):M_E_ALERT_N
DV55 M_E_BA<1> DDR4_BA<1> @BASEBOARD_FAB2_LIB.BASEBOARD_FAB2(SCH_1):M_E_BA(1)
DM53 M_E_BA<0> DDR4_BA<0> @BASEBOARD_FAB2_LIB.BASEBOARD_FAB2(SCH_1):M_E_BA(0)
DM61 M_E_BG<1> DDR4_BG<1> @BASEBOARD_FAB2_LIB.BASEBOARD_FAB2(SCH_1):M_E_BG(1)
DJ62 M_E_BG<0> DDR4_BG<0> @BASEBOARD_FAB2_LIB.BASEBOARD_FAB2(SCH_1):M_E_BG(0)
DT47 M_E_C<2> DDR4_CID<2> @BASEBOARD_FAB2_LIB.BASEBOARD_FAB2(SCH_1):M_E_C(2)
DR64 M_E_CKE<3> DDR4_CKE<3> @BASEBOARD_FAB2_LIB.BASEBOARD_FAB2(SCH_1):M_E_CKE(3)
DL64 M_E_CKE<2> DDR4_CKE<2> @BASEBOARD_FAB2_LIB.BASEBOARD_FAB2(SCH_1):M_E_CKE(2)
DN64 M_E_CKE<1> DDR4_CKE<1> @BASEBOARD_FAB2_LIB.BASEBOARD_FAB2(SCH_1):M_E_CKE(1)
DM63 M_E_CKE<0> DDR4_CKE<0> @BASEBOARD_FAB2_LIB.BASEBOARD_FAB2(SCH_1):M_E_CKE(0)
DT57 M_E_CLK_DN<3> DDR4_CLK_DN<3> @BASEBOARD_FAB2_LIB.BASEBOARD_FAB2(SCH_1):M_E_CLK_DN(3)
DM57 M_E_CLK_DN<2> DDR4_CLK_DN<2> @BASEBOARD_FAB2_LIB.BASEBOARD_FAB2(SCH_1):M_E_CLK_DN(2)
DR54 M_E_CLK_DN<1> DDR4_CLK_DN<1> @BASEBOARD_FAB2_LIB.BASEBOARD_FAB2(SCH_1):M_E_CLK_DN(1)
DM55 M_E_CLK_DN<0> DDR4_CLK_DN<0> @BASEBOARD_FAB2_LIB.BASEBOARD_FAB2(SCH_1):M_E_CLK_DN(0)
DR56 M_E_CLK_DP<3> DDR4_CLK_DP<3> @BASEBOARD_FAB2_LIB.BASEBOARD_FAB2(SCH_1):M_E_CLK_DP(3)
DN56 M_E_CLK_DP<2> DDR4_CLK_DP<2> @BASEBOARD_FAB2_LIB.BASEBOARD_FAB2(SCH_1):M_E_CLK_DP(2)
DT53 M_E_CLK_DP<1> DDR4_CLK_DP<1> @BASEBOARD_FAB2_LIB.BASEBOARD_FAB2(SCH_1):M_E_CLK_DP(1)
DN54 M_E_CLK_DP<0> DDR4_CLK_DP<0> @BASEBOARD_FAB2_LIB.BASEBOARD_FAB2(SCH_1):M_E_CLK_DP(0)
DN46 M_E_CS_N<7> DDR4_CS_N<7> @BASEBOARD_FAB2_LIB.BASEBOARD_FAB2(SCH_1):M_E_CS_N(7)
DT45 M_E_CS_N<6> DDR4_CS_N<6> @BASEBOARD_FAB2_LIB.BASEBOARD_FAB2(SCH_1):M_E_CS_N(6)
DM49 M_E_CS_N<5> DDR4_CS_N<5> @BASEBOARD_FAB2_LIB.BASEBOARD_FAB2(SCH_1):M_E_CS_N(5)
DW50 M_E_CS_N<4> DDR4_CS_N<4> @BASEBOARD_FAB2_LIB.BASEBOARD_FAB2(SCH_1):M_E_CS_N(4)
DK47 M_E_CS_N<3> DDR4_CS_N<3> @BASEBOARD_FAB2_LIB.BASEBOARD_FAB2(SCH_1):M_E_CS_N(3)
DR46 M_E_CS_N<2> DDR4_CS_N<2> @BASEBOARD_FAB2_LIB.BASEBOARD_FAB2(SCH_1):M_E_CS_N(2)
DN50 M_E_CS_N<1> DDR4_CS_N<1> @BASEBOARD_FAB2_LIB.BASEBOARD_FAB2(SCH_1):M_E_CS_N(1)
DV51 M_E_CS_N<0> DDR4_CS_N<0> @BASEBOARD_FAB2_LIB.BASEBOARD_FAB2(SCH_1):M_E_CS_N(0)
DK25 M_E_DQ<63> DDR4_DQ<63> @BASEBOARD_FAB2_LIB.BASEBOARD_FAB2(SCH_1):M_E_DQ(63)
DF25 M_E_DQ<62> DDR4_DQ<62> @BASEBOARD_FAB2_LIB.BASEBOARD_FAB2(SCH_1):M_E_DQ(62)
DJ28 M_E_DQ<61> DDR4_DQ<61> @BASEBOARD_FAB2_LIB.BASEBOARD_FAB2(SCH_1):M_E_DQ(61)
DG28 M_E_DQ<60> DDR4_DQ<60> @BASEBOARD_FAB2_LIB.BASEBOARD_FAB2(SCH_1):M_E_DQ(60)
DJ24 M_E_DQ<59> DDR4_DQ<59> @BASEBOARD_FAB2_LIB.BASEBOARD_FAB2(SCH_1):M_E_DQ(59)
DD25 M_E_DQ<58> DDR4_DQ<58> @BASEBOARD_FAB2_LIB.BASEBOARD_FAB2(SCH_1):M_E_DQ(58)
DK27 M_E_DQ<57> DDR4_DQ<57> @BASEBOARD_FAB2_LIB.BASEBOARD_FAB2(SCH_1):M_E_DQ(57)
DF27 M_E_DQ<56> DDR4_DQ<56> @BASEBOARD_FAB2_LIB.BASEBOARD_FAB2(SCH_1):M_E_DQ(56)
ED25 M_E_DQ<55> DDR4_DQ<55> @BASEBOARD_FAB2_LIB.BASEBOARD_FAB2(SCH_1):M_E_DQ(55)
DY25 M_E_DQ<54> DDR4_DQ<54> @BASEBOARD_FAB2_LIB.BASEBOARD_FAB2(SCH_1):M_E_DQ(54)
EA28 M_E_DQ<53> DDR4_DQ<53> @BASEBOARD_FAB2_LIB.BASEBOARD_FAB2(SCH_1):M_E_DQ(53)
DY27 M_E_DQ<52> DDR4_DQ<52> @BASEBOARD_FAB2_LIB.BASEBOARD_FAB2(SCH_1):M_E_DQ(52)
EC24 M_E_DQ<51> DDR4_DQ<51> @BASEBOARD_FAB2_LIB.BASEBOARD_FAB2(SCH_1):M_E_DQ(51)
EA24 M_E_DQ<50> DDR4_DQ<50> @BASEBOARD_FAB2_LIB.BASEBOARD_FAB2(SCH_1):M_E_DQ(50)
ED27 M_E_DQ<49> DDR4_DQ<49> @BASEBOARD_FAB2_LIB.BASEBOARD_FAB2(SCH_1):M_E_DQ(49)
EC28 M_E_DQ<48> DDR4_DQ<48> @BASEBOARD_FAB2_LIB.BASEBOARD_FAB2(SCH_1):M_E_DQ(48)
ED31 M_E_DQ<47> DDR4_DQ<47> @BASEBOARD_FAB2_LIB.BASEBOARD_FAB2(SCH_1):M_E_DQ(47)
DY31 M_E_DQ<46> DDR4_DQ<46> @BASEBOARD_FAB2_LIB.BASEBOARD_FAB2(SCH_1):M_E_DQ(46)
EA34 M_E_DQ<45> DDR4_DQ<45> @BASEBOARD_FAB2_LIB.BASEBOARD_FAB2(SCH_1):M_E_DQ(45)
DY33 M_E_DQ<44> DDR4_DQ<44> @BASEBOARD_FAB2_LIB.BASEBOARD_FAB2(SCH_1):M_E_DQ(44)
EC30 M_E_DQ<43> DDR4_DQ<43> @BASEBOARD_FAB2_LIB.BASEBOARD_FAB2(SCH_1):M_E_DQ(43)
EA30 M_E_DQ<42> DDR4_DQ<42> @BASEBOARD_FAB2_LIB.BASEBOARD_FAB2(SCH_1):M_E_DQ(42)
ED33 M_E_DQ<41> DDR4_DQ<41> @BASEBOARD_FAB2_LIB.BASEBOARD_FAB2(SCH_1):M_E_DQ(41)
EC34 M_E_DQ<40> DDR4_DQ<40> @BASEBOARD_FAB2_LIB.BASEBOARD_FAB2(SCH_1):M_E_DQ(40)
DU40 M_E_DQ<39> DDR4_DQ<39> @BASEBOARD_FAB2_LIB.BASEBOARD_FAB2(SCH_1):M_E_DQ(39)
DN40 M_E_DQ<38> DDR4_DQ<38> @BASEBOARD_FAB2_LIB.BASEBOARD_FAB2(SCH_1):M_E_DQ(38)
DN42 M_E_DQ<37> DDR4_DQ<37> @BASEBOARD_FAB2_LIB.BASEBOARD_FAB2(SCH_1):M_E_DQ(37)
DL42 M_E_DQ<36> DDR4_DQ<36> @BASEBOARD_FAB2_LIB.BASEBOARD_FAB2(SCH_1):M_E_DQ(36)
DT39 M_E_DQ<35> DDR4_DQ<35> @BASEBOARD_FAB2_LIB.BASEBOARD_FAB2(SCH_1):M_E_DQ(35)
DP39 M_E_DQ<34> DDR4_DQ<34> @BASEBOARD_FAB2_LIB.BASEBOARD_FAB2(SCH_1):M_E_DQ(34)
DW42 M_E_DQ<33> DDR4_DQ<33> @BASEBOARD_FAB2_LIB.BASEBOARD_FAB2(SCH_1):M_E_DQ(33)
DU42 M_E_DQ<32> DDR4_DQ<32> @BASEBOARD_FAB2_LIB.BASEBOARD_FAB2(SCH_1):M_E_DQ(32)
EE72 M_E_DQ<31> DDR4_DQ<31> @BASEBOARD_FAB2_LIB.BASEBOARD_FAB2(SCH_1):M_E_DQ(31)
EA72 M_E_DQ<30> DDR4_DQ<30> @BASEBOARD_FAB2_LIB.BASEBOARD_FAB2(SCH_1):M_E_DQ(30)
EB75 M_E_DQ<29> DDR4_DQ<29> @BASEBOARD_FAB2_LIB.BASEBOARD_FAB2(SCH_1):M_E_DQ(29)
EA74 M_E_DQ<28> DDR4_DQ<28> @BASEBOARD_FAB2_LIB.BASEBOARD_FAB2(SCH_1):M_E_DQ(28)
ED71 M_E_DQ<27> DDR4_DQ<27> @BASEBOARD_FAB2_LIB.BASEBOARD_FAB2(SCH_1):M_E_DQ(27)
EB71 M_E_DQ<26> DDR4_DQ<26> @BASEBOARD_FAB2_LIB.BASEBOARD_FAB2(SCH_1):M_E_DQ(26)
EE74 M_E_DQ<25> DDR4_DQ<25> @BASEBOARD_FAB2_LIB.BASEBOARD_FAB2(SCH_1):M_E_DQ(25)
ED75 M_E_DQ<24> DDR4_DQ<24> @BASEBOARD_FAB2_LIB.BASEBOARD_FAB2(SCH_1):M_E_DQ(24)
EC78 M_E_DQ<23> DDR4_DQ<23> @BASEBOARD_FAB2_LIB.BASEBOARD_FAB2(SCH_1):M_E_DQ(23)
DW78 M_E_DQ<22> DDR4_DQ<22> @BASEBOARD_FAB2_LIB.BASEBOARD_FAB2(SCH_1):M_E_DQ(22)
EB81 M_E_DQ<21> DDR4_DQ<21> @BASEBOARD_FAB2_LIB.BASEBOARD_FAB2(SCH_1):M_E_DQ(21)
DY81 M_E_DQ<20> DDR4_DQ<20> @BASEBOARD_FAB2_LIB.BASEBOARD_FAB2(SCH_1):M_E_DQ(20)
EB77 M_E_DQ<19> DDR4_DQ<19> @BASEBOARD_FAB2_LIB.BASEBOARD_FAB2(SCH_1):M_E_DQ(19)
DY77 M_E_DQ<18> DDR4_DQ<18> @BASEBOARD_FAB2_LIB.BASEBOARD_FAB2(SCH_1):M_E_DQ(18)
EC80 M_E_DQ<17> DDR4_DQ<17> @BASEBOARD_FAB2_LIB.BASEBOARD_FAB2(SCH_1):M_E_DQ(17)
DW80 M_E_DQ<16> DDR4_DQ<16> @BASEBOARD_FAB2_LIB.BASEBOARD_FAB2(SCH_1):M_E_DQ(16)
DE82 M_E_DQ<15> DDR4_DQ<15> @BASEBOARD_FAB2_LIB.BASEBOARD_FAB2(SCH_1):M_E_DQ(15)
DC82 M_E_DQ<14> DDR4_DQ<14> @BASEBOARD_FAB2_LIB.BASEBOARD_FAB2(SCH_1):M_E_DQ(14)
CW80 M_E_DQ<13> DDR4_DQ<13> @BASEBOARD_FAB2_LIB.BASEBOARD_FAB2(SCH_1):M_E_DQ(13)
CY79 M_E_DQ<12> DDR4_DQ<12> @BASEBOARD_FAB2_LIB.BASEBOARD_FAB2(SCH_1):M_E_DQ(12)
DF81 M_E_DQ<11> DDR4_DQ<11> @BASEBOARD_FAB2_LIB.BASEBOARD_FAB2(SCH_1):M_E_DQ(11)
DE80 M_E_DQ<10> DDR4_DQ<10> @BASEBOARD_FAB2_LIB.BASEBOARD_FAB2(SCH_1):M_E_DQ(10)
CY81 M_E_DQ<9> DDR4_DQ<9> @BASEBOARD_FAB2_LIB.BASEBOARD_FAB2(SCH_1):M_E_DQ(9)
DB79 M_E_DQ<8> DDR4_DQ<8> @BASEBOARD_FAB2_LIB.BASEBOARD_FAB2(SCH_1):M_E_DQ(8)
CN82 M_E_DQ<7> DDR4_DQ<7> @BASEBOARD_FAB2_LIB.BASEBOARD_FAB2(SCH_1):M_E_DQ(7)
CR80 M_E_DQ<6> DDR4_DQ<6> @BASEBOARD_FAB2_LIB.BASEBOARD_FAB2(SCH_1):M_E_DQ(6)
CJ80 M_E_DQ<5> DDR4_DQ<5> @BASEBOARD_FAB2_LIB.BASEBOARD_FAB2(SCH_1):M_E_DQ(5)
CK79 M_E_DQ<4> DDR4_DQ<4> @BASEBOARD_FAB2_LIB.BASEBOARD_FAB2(SCH_1):M_E_DQ(4)
CR82 M_E_DQ<3> DDR4_DQ<3> @BASEBOARD_FAB2_LIB.BASEBOARD_FAB2(SCH_1):M_E_DQ(3)
CT81 M_E_DQ<2> DDR4_DQ<2> @BASEBOARD_FAB2_LIB.BASEBOARD_FAB2(SCH_1):M_E_DQ(2)
CK81 M_E_DQ<1> DDR4_DQ<1> @BASEBOARD_FAB2_LIB.BASEBOARD_FAB2(SCH_1):M_E_DQ(1)
CM79 M_E_DQ<0> DDR4_DQ<0> @BASEBOARD_FAB2_LIB.BASEBOARD_FAB2(SCH_1):M_E_DQ(0)
DV67 M_E_DQS_DN<17> DDR4_DQS_DN<17> @BASEBOARD_FAB2_LIB.BASEBOARD_FAB2(SCH_1):M_E_DQS_DN(17)
DG26 M_E_DQS_DN<16> DDR4_DQS_DN<16> @BASEBOARD_FAB2_LIB.BASEBOARD_FAB2(SCH_1):M_E_DQS_DN(16)
EA26 M_E_DQS_DN<15> DDR4_DQS_DN<15> @BASEBOARD_FAB2_LIB.BASEBOARD_FAB2(SCH_1):M_E_DQS_DN(15)
EA32 M_E_DQS_DN<14> DDR4_DQS_DN<14> @BASEBOARD_FAB2_LIB.BASEBOARD_FAB2(SCH_1):M_E_DQS_DN(14)
DP41 M_E_DQS_DN<13> DDR4_DQS_DN<13> @BASEBOARD_FAB2_LIB.BASEBOARD_FAB2(SCH_1):M_E_DQS_DN(13)
EB73 M_E_DQS_DN<12> DDR4_DQS_DN<12> @BASEBOARD_FAB2_LIB.BASEBOARD_FAB2(SCH_1):M_E_DQS_DN(12)
DY79 M_E_DQS_DN<11> DDR4_DQS_DN<11> @BASEBOARD_FAB2_LIB.BASEBOARD_FAB2(SCH_1):M_E_DQS_DN(11)
DC80 M_E_DQS_DN<10> DDR4_DQS_DN<10> @BASEBOARD_FAB2_LIB.BASEBOARD_FAB2(SCH_1):M_E_DQS_DN(10)
CN80 M_E_DQS_DN<9> DDR4_DQS_DN<9> @BASEBOARD_FAB2_LIB.BASEBOARD_FAB2(SCH_1):M_E_DQS_DN(9)
EB67 M_E_DQS_DN<8> DDR4_DQS_DN<8> @BASEBOARD_FAB2_LIB.BASEBOARD_FAB2(SCH_1):M_E_DQS_DN(8)
DL26 M_E_DQS_DN<7> DDR4_DQS_DN<7> @BASEBOARD_FAB2_LIB.BASEBOARD_FAB2(SCH_1):M_E_DQS_DN(7)
EE26 M_E_DQS_DN<6> DDR4_DQS_DN<6> @BASEBOARD_FAB2_LIB.BASEBOARD_FAB2(SCH_1):M_E_DQS_DN(6)
EE32 M_E_DQS_DN<5> DDR4_DQS_DN<5> @BASEBOARD_FAB2_LIB.BASEBOARD_FAB2(SCH_1):M_E_DQS_DN(5)
DV41 M_E_DQS_DN<4> DDR4_DQS_DN<4> @BASEBOARD_FAB2_LIB.BASEBOARD_FAB2(SCH_1):M_E_DQS_DN(4)
EF73 M_E_DQS_DN<3> DDR4_DQS_DN<3> @BASEBOARD_FAB2_LIB.BASEBOARD_FAB2(SCH_1):M_E_DQS_DN(3)
ED79 M_E_DQS_DN<2> DDR4_DQS_DN<2> @BASEBOARD_FAB2_LIB.BASEBOARD_FAB2(SCH_1):M_E_DQS_DN(2)
DA82 M_E_DQS_DN<1> DDR4_DQS_DN<1> @BASEBOARD_FAB2_LIB.BASEBOARD_FAB2(SCH_1):M_E_DQS_DN(1)
CL82 M_E_DQS_DN<0> DDR4_DQS_DN<0> @BASEBOARD_FAB2_LIB.BASEBOARD_FAB2(SCH_1):M_E_DQS_DN(0)
DT67 M_E_DQS_DP<17> DDR4_DQS_DP<17> @BASEBOARD_FAB2_LIB.BASEBOARD_FAB2(SCH_1):M_E_DQS_DP(17)
DE26 M_E_DQS_DP<16> DDR4_DQS_DP<16> @BASEBOARD_FAB2_LIB.BASEBOARD_FAB2(SCH_1):M_E_DQS_DP(16)
DW26 M_E_DQS_DP<15> DDR4_DQS_DP<15> @BASEBOARD_FAB2_LIB.BASEBOARD_FAB2(SCH_1):M_E_DQS_DP(15)
DW32 M_E_DQS_DP<14> DDR4_DQS_DP<14> @BASEBOARD_FAB2_LIB.BASEBOARD_FAB2(SCH_1):M_E_DQS_DP(14)
DM41 M_E_DQS_DP<13> DDR4_DQS_DP<13> @BASEBOARD_FAB2_LIB.BASEBOARD_FAB2(SCH_1):M_E_DQS_DP(13)
DY73 M_E_DQS_DP<12> DDR4_DQS_DP<12> @BASEBOARD_FAB2_LIB.BASEBOARD_FAB2(SCH_1):M_E_DQS_DP(12)
DV79 M_E_DQS_DP<11> DDR4_DQS_DP<11> @BASEBOARD_FAB2_LIB.BASEBOARD_FAB2(SCH_1):M_E_DQS_DP(11)
DD79 M_E_DQS_DP<10> DDR4_DQS_DP<10> @BASEBOARD_FAB2_LIB.BASEBOARD_FAB2(SCH_1):M_E_DQS_DP(10)
CP79 M_E_DQS_DP<9> DDR4_DQS_DP<9> @BASEBOARD_FAB2_LIB.BASEBOARD_FAB2(SCH_1):M_E_DQS_DP(9)
DY67 M_E_DQS_DP<8> DDR4_DQS_DP<8> @BASEBOARD_FAB2_LIB.BASEBOARD_FAB2(SCH_1):M_E_DQS_DP(8)
DJ26 M_E_DQS_DP<7> DDR4_DQS_DP<7> @BASEBOARD_FAB2_LIB.BASEBOARD_FAB2(SCH_1):M_E_DQS_DP(7)
EC26 M_E_DQS_DP<6> DDR4_DQS_DP<6> @BASEBOARD_FAB2_LIB.BASEBOARD_FAB2(SCH_1):M_E_DQS_DP(6)
EC32 M_E_DQS_DP<5> DDR4_DQS_DP<5> @BASEBOARD_FAB2_LIB.BASEBOARD_FAB2(SCH_1):M_E_DQS_DP(5)
DT41 M_E_DQS_DP<4> DDR4_DQS_DP<4> @BASEBOARD_FAB2_LIB.BASEBOARD_FAB2(SCH_1):M_E_DQS_DP(4)
ED73 M_E_DQS_DP<3> DDR4_DQS_DP<3> @BASEBOARD_FAB2_LIB.BASEBOARD_FAB2(SCH_1):M_E_DQS_DP(3)
EB79 M_E_DQS_DP<2> DDR4_DQS_DP<2> @BASEBOARD_FAB2_LIB.BASEBOARD_FAB2(SCH_1):M_E_DQS_DP(2)
DB81 M_E_DQS_DP<1> DDR4_DQS_DP<1> @BASEBOARD_FAB2_LIB.BASEBOARD_FAB2(SCH_1):M_E_DQS_DP(1)
CM81 M_E_DQS_DP<0> DDR4_DQS_DP<0> @BASEBOARD_FAB2_LIB.BASEBOARD_FAB2(SCH_1):M_E_DQS_DP(0)
EA66 M_E_ECC<7> DDR4_ECC<7> @BASEBOARD_FAB2_LIB.BASEBOARD_FAB2(SCH_1):M_E_ECC(7)
DU66 M_E_ECC<6> DDR4_ECC<6> @BASEBOARD_FAB2_LIB.BASEBOARD_FAB2(SCH_1):M_E_ECC(6)
DV69 M_E_ECC<5> DDR4_ECC<5> @BASEBOARD_FAB2_LIB.BASEBOARD_FAB2(SCH_1):M_E_ECC(5)
DU68 M_E_ECC<4> DDR4_ECC<4> @BASEBOARD_FAB2_LIB.BASEBOARD_FAB2(SCH_1):M_E_ECC(4)
DY65 M_E_ECC<3> DDR4_ECC<3> @BASEBOARD_FAB2_LIB.BASEBOARD_FAB2(SCH_1):M_E_ECC(3)
DV65 M_E_ECC<2> DDR4_ECC<2> @BASEBOARD_FAB2_LIB.BASEBOARD_FAB2(SCH_1):M_E_ECC(2)
EA68 M_E_ECC<1> DDR4_ECC<1> @BASEBOARD_FAB2_LIB.BASEBOARD_FAB2(SCH_1):M_E_ECC(1)
DY69 M_E_ECC<0> DDR4_ECC<0> @BASEBOARD_FAB2_LIB.BASEBOARD_FAB2(SCH_1):M_E_ECC(0)
DR48 M_E_MA<17> DDR4_MA<17> @BASEBOARD_FAB2_LIB.BASEBOARD_FAB2(SCH_1):M_E_MA(17)
DN52 M_E_MA<16> DDR4_MA<16> @BASEBOARD_FAB2_LIB.BASEBOARD_FAB2(SCH_1):M_E_MA(16)
DR52 M_E_MA<15> DDR4_MA<15> @BASEBOARD_FAB2_LIB.BASEBOARD_FAB2(SCH_1):M_E_MA(15)
DM51 M_E_MA<14> DDR4_MA<14> @BASEBOARD_FAB2_LIB.BASEBOARD_FAB2(SCH_1):M_E_MA(14)
DT51 M_E_MA<13> DDR4_MA<13> @BASEBOARD_FAB2_LIB.BASEBOARD_FAB2(SCH_1):M_E_MA(13)
DN60 M_E_MA<12> DDR4_MA<12> @BASEBOARD_FAB2_LIB.BASEBOARD_FAB2(SCH_1):M_E_MA(12)
DR60 M_E_MA<11> DDR4_MA<11> @BASEBOARD_FAB2_LIB.BASEBOARD_FAB2(SCH_1):M_E_MA(11)
DT55 M_E_MA<10> DDR4_MA<10> @BASEBOARD_FAB2_LIB.BASEBOARD_FAB2(SCH_1):M_E_MA(10)
DV59 M_E_MA<9> DDR4_MA<9> @BASEBOARD_FAB2_LIB.BASEBOARD_FAB2(SCH_1):M_E_MA(9)
DJ60 M_E_MA<8> DDR4_MA<8> @BASEBOARD_FAB2_LIB.BASEBOARD_FAB2(SCH_1):M_E_MA(8)
DK61 M_E_MA<7> DDR4_MA<7> @BASEBOARD_FAB2_LIB.BASEBOARD_FAB2(SCH_1):M_E_MA(7)
DM59 M_E_MA<6> DDR4_MA<6> @BASEBOARD_FAB2_LIB.BASEBOARD_FAB2(SCH_1):M_E_MA(6)
DN58 M_E_MA<5> DDR4_MA<5> @BASEBOARD_FAB2_LIB.BASEBOARD_FAB2(SCH_1):M_E_MA(5)
DT59 M_E_MA<4> DDR4_MA<4> @BASEBOARD_FAB2_LIB.BASEBOARD_FAB2(SCH_1):M_E_MA(4)
DR58 M_E_MA<3> DDR4_MA<3> @BASEBOARD_FAB2_LIB.BASEBOARD_FAB2(SCH_1):M_E_MA(3)
DV57 M_E_MA<2> DDR4_MA<2> @BASEBOARD_FAB2_LIB.BASEBOARD_FAB2(SCH_1):M_E_MA(2)
DW58 M_E_MA<1> DDR4_MA<1> @BASEBOARD_FAB2_LIB.BASEBOARD_FAB2(SCH_1):M_E_MA(1)
DW52 M_E_MA<0> DDR4_MA<0> @BASEBOARD_FAB2_LIB.BASEBOARD_FAB2(SCH_1):M_E_MA(0)
DM47 M_E_ODT<3> DDR4_ODT<3> @BASEBOARD_FAB2_LIB.BASEBOARD_FAB2(SCH_1):M_E_ODT(3)
DT49 M_E_ODT<2> DDR4_ODT<2> @BASEBOARD_FAB2_LIB.BASEBOARD_FAB2(SCH_1):M_E_ODT(2)
DN48 M_E_ODT<1> DDR4_ODT<1> @BASEBOARD_FAB2_LIB.BASEBOARD_FAB2(SCH_1):M_E_ODT(1)
DR50 M_E_ODT<0> DDR4_ODT<0> @BASEBOARD_FAB2_LIB.BASEBOARD_FAB2(SCH_1):M_E_ODT(0)
DV53 M_E_PAR DDR4_PAR @BASEBOARD_FAB2_LIB.BASEBOARD_FAB2(SCH_1):M_E_PAR


DRAWING: @BASEBOARD_FAB2_LIB.BASEBOARD_FAB2(SCH_1):PAGE28 

SKX_EXT_B_BGA1-IC,TBD  I172  U5D1
DC62 M_F_ACT_N DDR5_ACT_N @BASEBOARD_FAB2_LIB.BASEBOARD_FAB2(SCH_1):M_F_ACT_N
DD61 M_F_ALERT_N DDR5_ALERT_N @BASEBOARD_FAB2_LIB.BASEBOARD_FAB2(SCH_1):M_F_ALERT_N
DC56 M_F_BA<1> DDR5_BA<1> @BASEBOARD_FAB2_LIB.BASEBOARD_FAB2(SCH_1):M_F_BA(1)
DJ52 M_F_BA<0> DDR5_BA<0> @BASEBOARD_FAB2_LIB.BASEBOARD_FAB2(SCH_1):M_F_BA(0)
DF61 M_F_BG<1> DDR5_BG<1> @BASEBOARD_FAB2_LIB.BASEBOARD_FAB2(SCH_1):M_F_BG(1)
DA62 M_F_BG<0> DDR5_BG<0> @BASEBOARD_FAB2_LIB.BASEBOARD_FAB2(SCH_1):M_F_BG(0)
DF45 M_F_C<2> DDR5_CID<2> @BASEBOARD_FAB2_LIB.BASEBOARD_FAB2(SCH_1):M_F_C(2)
DF63 M_F_CKE<3> DDR5_CKE<3> @BASEBOARD_FAB2_LIB.BASEBOARD_FAB2(SCH_1):M_F_CKE(3)
DK63 M_F_CKE<2> DDR5_CKE<2> @BASEBOARD_FAB2_LIB.BASEBOARD_FAB2(SCH_1):M_F_CKE(2)
DD63 M_F_CKE<1> DDR5_CKE<1> @BASEBOARD_FAB2_LIB.BASEBOARD_FAB2(SCH_1):M_F_CKE(1)
DG62 M_F_CKE<0> DDR5_CKE<0> @BASEBOARD_FAB2_LIB.BASEBOARD_FAB2(SCH_1):M_F_CKE(0)
DF57 M_F_CLK_DN<3> DDR5_CLK_DN<3> @BASEBOARD_FAB2_LIB.BASEBOARD_FAB2(SCH_1):M_F_CLK_DN(3)
DK57 M_F_CLK_DN<2> DDR5_CLK_DN<2> @BASEBOARD_FAB2_LIB.BASEBOARD_FAB2(SCH_1):M_F_CLK_DN(2)
DF55 M_F_CLK_DN<1> DDR5_CLK_DN<1> @BASEBOARD_FAB2_LIB.BASEBOARD_FAB2(SCH_1):M_F_CLK_DN(1)
DK55 M_F_CLK_DN<0> DDR5_CLK_DN<0> @BASEBOARD_FAB2_LIB.BASEBOARD_FAB2(SCH_1):M_F_CLK_DN(0)
DG56 M_F_CLK_DP<3> DDR5_CLK_DP<3> @BASEBOARD_FAB2_LIB.BASEBOARD_FAB2(SCH_1):M_F_CLK_DP(3)
DJ56 M_F_CLK_DP<2> DDR5_CLK_DP<2> @BASEBOARD_FAB2_LIB.BASEBOARD_FAB2(SCH_1):M_F_CLK_DP(2)
DG54 M_F_CLK_DP<1> DDR5_CLK_DP<1> @BASEBOARD_FAB2_LIB.BASEBOARD_FAB2(SCH_1):M_F_CLK_DP(1)
DJ54 M_F_CLK_DP<0> DDR5_CLK_DP<0> @BASEBOARD_FAB2_LIB.BASEBOARD_FAB2(SCH_1):M_F_CLK_DP(0)
DK45 M_F_CS_N<7> DDR5_CS_N<7> @BASEBOARD_FAB2_LIB.BASEBOARD_FAB2(SCH_1):M_F_CS_N(7)
DM45 M_F_CS_N<6> DDR5_CS_N<6> @BASEBOARD_FAB2_LIB.BASEBOARD_FAB2(SCH_1):M_F_CS_N(6)
DJ48 M_F_CS_N<5> DDR5_CS_N<5> @BASEBOARD_FAB2_LIB.BASEBOARD_FAB2(SCH_1):M_F_CS_N(5)
DF51 M_F_CS_N<4> DDR5_CS_N<4> @BASEBOARD_FAB2_LIB.BASEBOARD_FAB2(SCH_1):M_F_CS_N(4)
DG46 M_F_CS_N<3> DDR5_CS_N<3> @BASEBOARD_FAB2_LIB.BASEBOARD_FAB2(SCH_1):M_F_CS_N(3)
DJ46 M_F_CS_N<2> DDR5_CS_N<2> @BASEBOARD_FAB2_LIB.BASEBOARD_FAB2(SCH_1):M_F_CS_N(2)
DF49 M_F_CS_N<1> DDR5_CS_N<1> @BASEBOARD_FAB2_LIB.BASEBOARD_FAB2(SCH_1):M_F_CS_N(1)
DK51 M_F_CS_N<0> DDR5_CS_N<0> @BASEBOARD_FAB2_LIB.BASEBOARD_FAB2(SCH_1):M_F_CS_N(0)
DC28 M_F_DQ<63> DDR5_DQ<63> @BASEBOARD_FAB2_LIB.BASEBOARD_FAB2(SCH_1):M_F_DQ(63)
CW28 M_F_DQ<62> DDR5_DQ<62> @BASEBOARD_FAB2_LIB.BASEBOARD_FAB2(SCH_1):M_F_DQ(62)
DB31 M_F_DQ<61> DDR5_DQ<61> @BASEBOARD_FAB2_LIB.BASEBOARD_FAB2(SCH_1):M_F_DQ(61)
CY31 M_F_DQ<60> DDR5_DQ<60> @BASEBOARD_FAB2_LIB.BASEBOARD_FAB2(SCH_1):M_F_DQ(60)
DB27 M_F_DQ<59> DDR5_DQ<59> @BASEBOARD_FAB2_LIB.BASEBOARD_FAB2(SCH_1):M_F_DQ(59)
CY27 M_F_DQ<58> DDR5_DQ<58> @BASEBOARD_FAB2_LIB.BASEBOARD_FAB2(SCH_1):M_F_DQ(58)
DC30 M_F_DQ<57> DDR5_DQ<57> @BASEBOARD_FAB2_LIB.BASEBOARD_FAB2(SCH_1):M_F_DQ(57)
CW30 M_F_DQ<56> DDR5_DQ<56> @BASEBOARD_FAB2_LIB.BASEBOARD_FAB2(SCH_1):M_F_DQ(56)
DC34 M_F_DQ<55> DDR5_DQ<55> @BASEBOARD_FAB2_LIB.BASEBOARD_FAB2(SCH_1):M_F_DQ(55)
CW34 M_F_DQ<54> DDR5_DQ<54> @BASEBOARD_FAB2_LIB.BASEBOARD_FAB2(SCH_1):M_F_DQ(54)
DB37 M_F_DQ<53> DDR5_DQ<53> @BASEBOARD_FAB2_LIB.BASEBOARD_FAB2(SCH_1):M_F_DQ(53)
CY37 M_F_DQ<52> DDR5_DQ<52> @BASEBOARD_FAB2_LIB.BASEBOARD_FAB2(SCH_1):M_F_DQ(52)
DB33 M_F_DQ<51> DDR5_DQ<51> @BASEBOARD_FAB2_LIB.BASEBOARD_FAB2(SCH_1):M_F_DQ(51)
CY33 M_F_DQ<50> DDR5_DQ<50> @BASEBOARD_FAB2_LIB.BASEBOARD_FAB2(SCH_1):M_F_DQ(50)
DC36 M_F_DQ<49> DDR5_DQ<49> @BASEBOARD_FAB2_LIB.BASEBOARD_FAB2(SCH_1):M_F_DQ(49)
CW36 M_F_DQ<48> DDR5_DQ<48> @BASEBOARD_FAB2_LIB.BASEBOARD_FAB2(SCH_1):M_F_DQ(48)
DK31 M_F_DQ<47> DDR5_DQ<47> @BASEBOARD_FAB2_LIB.BASEBOARD_FAB2(SCH_1):M_F_DQ(47)
DF31 M_F_DQ<46> DDR5_DQ<46> @BASEBOARD_FAB2_LIB.BASEBOARD_FAB2(SCH_1):M_F_DQ(46)
DJ34 M_F_DQ<45> DDR5_DQ<45> @BASEBOARD_FAB2_LIB.BASEBOARD_FAB2(SCH_1):M_F_DQ(45)
DG34 M_F_DQ<44> DDR5_DQ<44> @BASEBOARD_FAB2_LIB.BASEBOARD_FAB2(SCH_1):M_F_DQ(44)
DJ30 M_F_DQ<43> DDR5_DQ<43> @BASEBOARD_FAB2_LIB.BASEBOARD_FAB2(SCH_1):M_F_DQ(43)
DG30 M_F_DQ<42> DDR5_DQ<42> @BASEBOARD_FAB2_LIB.BASEBOARD_FAB2(SCH_1):M_F_DQ(42)
DK33 M_F_DQ<41> DDR5_DQ<41> @BASEBOARD_FAB2_LIB.BASEBOARD_FAB2(SCH_1):M_F_DQ(41)
DF33 M_F_DQ<40> DDR5_DQ<40> @BASEBOARD_FAB2_LIB.BASEBOARD_FAB2(SCH_1):M_F_DQ(40)
DH39 M_F_DQ<39> DDR5_DQ<39> @BASEBOARD_FAB2_LIB.BASEBOARD_FAB2(SCH_1):M_F_DQ(39)
DD39 M_F_DQ<38> DDR5_DQ<38> @BASEBOARD_FAB2_LIB.BASEBOARD_FAB2(SCH_1):M_F_DQ(38)
DE42 M_F_DQ<37> DDR5_DQ<37> @BASEBOARD_FAB2_LIB.BASEBOARD_FAB2(SCH_1):M_F_DQ(37)
DA42 M_F_DQ<36> DDR5_DQ<36> @BASEBOARD_FAB2_LIB.BASEBOARD_FAB2(SCH_1):M_F_DQ(36)
DG38 M_F_DQ<35> DDR5_DQ<35> @BASEBOARD_FAB2_LIB.BASEBOARD_FAB2(SCH_1):M_F_DQ(35)
DE38 M_F_DQ<34> DDR5_DQ<34> @BASEBOARD_FAB2_LIB.BASEBOARD_FAB2(SCH_1):M_F_DQ(34)
DG42 M_F_DQ<33> DDR5_DQ<33> @BASEBOARD_FAB2_LIB.BASEBOARD_FAB2(SCH_1):M_F_DQ(33)
DD41 M_F_DQ<32> DDR5_DQ<32> @BASEBOARD_FAB2_LIB.BASEBOARD_FAB2(SCH_1):M_F_DQ(32)
CU64 M_F_DQ<31> DDR5_DQ<31> @BASEBOARD_FAB2_LIB.BASEBOARD_FAB2(SCH_1):M_F_DQ(31)
CN64 M_F_DQ<30> DDR5_DQ<30> @BASEBOARD_FAB2_LIB.BASEBOARD_FAB2(SCH_1):M_F_DQ(30)
CT67 M_F_DQ<29> DDR5_DQ<29> @BASEBOARD_FAB2_LIB.BASEBOARD_FAB2(SCH_1):M_F_DQ(29)
CP67 M_F_DQ<28> DDR5_DQ<28> @BASEBOARD_FAB2_LIB.BASEBOARD_FAB2(SCH_1):M_F_DQ(28)
CT63 M_F_DQ<27> DDR5_DQ<27> @BASEBOARD_FAB2_LIB.BASEBOARD_FAB2(SCH_1):M_F_DQ(27)
CP63 M_F_DQ<26> DDR5_DQ<26> @BASEBOARD_FAB2_LIB.BASEBOARD_FAB2(SCH_1):M_F_DQ(26)
CU66 M_F_DQ<25> DDR5_DQ<25> @BASEBOARD_FAB2_LIB.BASEBOARD_FAB2(SCH_1):M_F_DQ(25)
CN66 M_F_DQ<24> DDR5_DQ<24> @BASEBOARD_FAB2_LIB.BASEBOARD_FAB2(SCH_1):M_F_DQ(24)
DM71 M_F_DQ<23> DDR5_DQ<23> @BASEBOARD_FAB2_LIB.BASEBOARD_FAB2(SCH_1):M_F_DQ(23)
DK69 M_F_DQ<22> DDR5_DQ<22> @BASEBOARD_FAB2_LIB.BASEBOARD_FAB2(SCH_1):M_F_DQ(22)
DG72 M_F_DQ<21> DDR5_DQ<21> @BASEBOARD_FAB2_LIB.BASEBOARD_FAB2(SCH_1):M_F_DQ(21)
DF71 M_F_DQ<20> DDR5_DQ<20> @BASEBOARD_FAB2_LIB.BASEBOARD_FAB2(SCH_1):M_F_DQ(20)
DN70 M_F_DQ<19> DDR5_DQ<19> @BASEBOARD_FAB2_LIB.BASEBOARD_FAB2(SCH_1):M_F_DQ(19)
DM69 M_F_DQ<18> DDR5_DQ<18> @BASEBOARD_FAB2_LIB.BASEBOARD_FAB2(SCH_1):M_F_DQ(18)
DJ72 M_F_DQ<17> DDR5_DQ<17> @BASEBOARD_FAB2_LIB.BASEBOARD_FAB2(SCH_1):M_F_DQ(17)
DG70 M_F_DQ<16> DDR5_DQ<16> @BASEBOARD_FAB2_LIB.BASEBOARD_FAB2(SCH_1):M_F_DQ(16)
DH77 M_F_DQ<15> DDR5_DQ<15> @BASEBOARD_FAB2_LIB.BASEBOARD_FAB2(SCH_1):M_F_DQ(15)
DF77 M_F_DQ<14> DDR5_DQ<14> @BASEBOARD_FAB2_LIB.BASEBOARD_FAB2(SCH_1):M_F_DQ(14)
DB75 M_F_DQ<13> DDR5_DQ<13> @BASEBOARD_FAB2_LIB.BASEBOARD_FAB2(SCH_1):M_F_DQ(13)
DC74 M_F_DQ<12> DDR5_DQ<12> @BASEBOARD_FAB2_LIB.BASEBOARD_FAB2(SCH_1):M_F_DQ(12)
DJ76 M_F_DQ<11> DDR5_DQ<11> @BASEBOARD_FAB2_LIB.BASEBOARD_FAB2(SCH_1):M_F_DQ(11)
DH75 M_F_DQ<10> DDR5_DQ<10> @BASEBOARD_FAB2_LIB.BASEBOARD_FAB2(SCH_1):M_F_DQ(10)
DC76 M_F_DQ<9> DDR5_DQ<9> @BASEBOARD_FAB2_LIB.BASEBOARD_FAB2(SCH_1):M_F_DQ(9)
DE74 M_F_DQ<8> DDR5_DQ<8> @BASEBOARD_FAB2_LIB.BASEBOARD_FAB2(SCH_1):M_F_DQ(8)
CT77 M_F_DQ<7> DDR5_DQ<7> @BASEBOARD_FAB2_LIB.BASEBOARD_FAB2(SCH_1):M_F_DQ(7)
CV75 M_F_DQ<6> DDR5_DQ<6> @BASEBOARD_FAB2_LIB.BASEBOARD_FAB2(SCH_1):M_F_DQ(6)
CM75 M_F_DQ<5> DDR5_DQ<5> @BASEBOARD_FAB2_LIB.BASEBOARD_FAB2(SCH_1):M_F_DQ(5)
CN74 M_F_DQ<4> DDR5_DQ<4> @BASEBOARD_FAB2_LIB.BASEBOARD_FAB2(SCH_1):M_F_DQ(4)
CV77 M_F_DQ<3> DDR5_DQ<3> @BASEBOARD_FAB2_LIB.BASEBOARD_FAB2(SCH_1):M_F_DQ(3)
CW76 M_F_DQ<2> DDR5_DQ<2> @BASEBOARD_FAB2_LIB.BASEBOARD_FAB2(SCH_1):M_F_DQ(2)
CN76 M_F_DQ<1> DDR5_DQ<1> @BASEBOARD_FAB2_LIB.BASEBOARD_FAB2(SCH_1):M_F_DQ(1)
CR74 M_F_DQ<0> DDR5_DQ<0> @BASEBOARD_FAB2_LIB.BASEBOARD_FAB2(SCH_1):M_F_DQ(0)
CJ70 M_F_DQS_DN<17> DDR5_DQS_DN<17> @BASEBOARD_FAB2_LIB.BASEBOARD_FAB2(SCH_1):M_F_DQS_DN(17)
CY29 M_F_DQS_DN<16> DDR5_DQS_DN<16> @BASEBOARD_FAB2_LIB.BASEBOARD_FAB2(SCH_1):M_F_DQS_DN(16)
CY35 M_F_DQS_DN<15> DDR5_DQS_DN<15> @BASEBOARD_FAB2_LIB.BASEBOARD_FAB2(SCH_1):M_F_DQS_DN(15)
DG32 M_F_DQS_DN<14> DDR5_DQS_DN<14> @BASEBOARD_FAB2_LIB.BASEBOARD_FAB2(SCH_1):M_F_DQS_DN(14)
DE40 M_F_DQS_DN<13> DDR5_DQS_DN<13> @BASEBOARD_FAB2_LIB.BASEBOARD_FAB2(SCH_1):M_F_DQS_DN(13)
CP65 M_F_DQS_DN<12> DDR5_DQS_DN<12> @BASEBOARD_FAB2_LIB.BASEBOARD_FAB2(SCH_1):M_F_DQS_DN(12)
DJ70 M_F_DQS_DN<11> DDR5_DQS_DN<11> @BASEBOARD_FAB2_LIB.BASEBOARD_FAB2(SCH_1):M_F_DQS_DN(11)
DF75 M_F_DQS_DN<10> DDR5_DQS_DN<10> @BASEBOARD_FAB2_LIB.BASEBOARD_FAB2(SCH_1):M_F_DQS_DN(10)
CT75 M_F_DQS_DN<9> DDR5_DQS_DN<9> @BASEBOARD_FAB2_LIB.BASEBOARD_FAB2(SCH_1):M_F_DQS_DN(9)
CN70 M_F_DQS_DN<8> DDR5_DQS_DN<8> @BASEBOARD_FAB2_LIB.BASEBOARD_FAB2(SCH_1):M_F_DQS_DN(8)
DD29 M_F_DQS_DN<7> DDR5_DQS_DN<7> @BASEBOARD_FAB2_LIB.BASEBOARD_FAB2(SCH_1):M_F_DQS_DN(7)
DD35 M_F_DQS_DN<6> DDR5_DQS_DN<6> @BASEBOARD_FAB2_LIB.BASEBOARD_FAB2(SCH_1):M_F_DQS_DN(6)
DL32 M_F_DQS_DN<5> DDR5_DQS_DN<5> @BASEBOARD_FAB2_LIB.BASEBOARD_FAB2(SCH_1):M_F_DQS_DN(5)
DG40 M_F_DQS_DN<4> DDR5_DQS_DN<4> @BASEBOARD_FAB2_LIB.BASEBOARD_FAB2(SCH_1):M_F_DQS_DN(4)
CV65 M_F_DQS_DN<3> DDR5_DQS_DN<3> @BASEBOARD_FAB2_LIB.BASEBOARD_FAB2(SCH_1):M_F_DQS_DN(3)
DL72 M_F_DQS_DN<2> DDR5_DQS_DN<2> @BASEBOARD_FAB2_LIB.BASEBOARD_FAB2(SCH_1):M_F_DQS_DN(2)
DD77 M_F_DQS_DN<1> DDR5_DQS_DN<1> @BASEBOARD_FAB2_LIB.BASEBOARD_FAB2(SCH_1):M_F_DQS_DN(1)
CP77 M_F_DQS_DN<0> DDR5_DQS_DN<0> @BASEBOARD_FAB2_LIB.BASEBOARD_FAB2(SCH_1):M_F_DQS_DN(0)
CG70 M_F_DQS_DP<17> DDR5_DQS_DP<17> @BASEBOARD_FAB2_LIB.BASEBOARD_FAB2(SCH_1):M_F_DQS_DP(17)
CV29 M_F_DQS_DP<16> DDR5_DQS_DP<16> @BASEBOARD_FAB2_LIB.BASEBOARD_FAB2(SCH_1):M_F_DQS_DP(16)
CV35 M_F_DQS_DP<15> DDR5_DQS_DP<15> @BASEBOARD_FAB2_LIB.BASEBOARD_FAB2(SCH_1):M_F_DQS_DP(15)
DE32 M_F_DQS_DP<14> DDR5_DQS_DP<14> @BASEBOARD_FAB2_LIB.BASEBOARD_FAB2(SCH_1):M_F_DQS_DP(14)
DC40 M_F_DQS_DP<13> DDR5_DQS_DP<13> @BASEBOARD_FAB2_LIB.BASEBOARD_FAB2(SCH_1):M_F_DQS_DP(13)
CM65 M_F_DQS_DP<12> DDR5_DQS_DP<12> @BASEBOARD_FAB2_LIB.BASEBOARD_FAB2(SCH_1):M_F_DQS_DP(12)
DH69 M_F_DQS_DP<11> DDR5_DQS_DP<11> @BASEBOARD_FAB2_LIB.BASEBOARD_FAB2(SCH_1):M_F_DQS_DP(11)
DG74 M_F_DQS_DP<10> DDR5_DQS_DP<10> @BASEBOARD_FAB2_LIB.BASEBOARD_FAB2(SCH_1):M_F_DQS_DP(10)
CU74 M_F_DQS_DP<9> DDR5_DQS_DP<9> @BASEBOARD_FAB2_LIB.BASEBOARD_FAB2(SCH_1):M_F_DQS_DP(9)
CL70 M_F_DQS_DP<8> DDR5_DQS_DP<8> @BASEBOARD_FAB2_LIB.BASEBOARD_FAB2(SCH_1):M_F_DQS_DP(8)
DB29 M_F_DQS_DP<7> DDR5_DQS_DP<7> @BASEBOARD_FAB2_LIB.BASEBOARD_FAB2(SCH_1):M_F_DQS_DP(7)
DB35 M_F_DQS_DP<6> DDR5_DQS_DP<6> @BASEBOARD_FAB2_LIB.BASEBOARD_FAB2(SCH_1):M_F_DQS_DP(6)
DJ32 M_F_DQS_DP<5> DDR5_DQS_DP<5> @BASEBOARD_FAB2_LIB.BASEBOARD_FAB2(SCH_1):M_F_DQS_DP(5)
DJ40 M_F_DQS_DP<4> DDR5_DQS_DP<4> @BASEBOARD_FAB2_LIB.BASEBOARD_FAB2(SCH_1):M_F_DQS_DP(4)
CT65 M_F_DQS_DP<3> DDR5_DQS_DP<3> @BASEBOARD_FAB2_LIB.BASEBOARD_FAB2(SCH_1):M_F_DQS_DP(3)
DK71 M_F_DQS_DP<2> DDR5_DQS_DP<2> @BASEBOARD_FAB2_LIB.BASEBOARD_FAB2(SCH_1):M_F_DQS_DP(2)
DE76 M_F_DQS_DP<1> DDR5_DQS_DP<1> @BASEBOARD_FAB2_LIB.BASEBOARD_FAB2(SCH_1):M_F_DQS_DP(1)
CR76 M_F_DQS_DP<0> DDR5_DQS_DP<0> @BASEBOARD_FAB2_LIB.BASEBOARD_FAB2(SCH_1):M_F_DQS_DP(0)
CM69 M_F_ECC<7> DDR5_ECC<7> @BASEBOARD_FAB2_LIB.BASEBOARD_FAB2(SCH_1):M_F_ECC(7)
CH69 M_F_ECC<6> DDR5_ECC<6> @BASEBOARD_FAB2_LIB.BASEBOARD_FAB2(SCH_1):M_F_ECC(6)
CL72 M_F_ECC<5> DDR5_ECC<5> @BASEBOARD_FAB2_LIB.BASEBOARD_FAB2(SCH_1):M_F_ECC(5)
CJ72 M_F_ECC<4> DDR5_ECC<4> @BASEBOARD_FAB2_LIB.BASEBOARD_FAB2(SCH_1):M_F_ECC(4)
CL68 M_F_ECC<3> DDR5_ECC<3> @BASEBOARD_FAB2_LIB.BASEBOARD_FAB2(SCH_1):M_F_ECC(3)
CJ68 M_F_ECC<2> DDR5_ECC<2> @BASEBOARD_FAB2_LIB.BASEBOARD_FAB2(SCH_1):M_F_ECC(2)
CM71 M_F_ECC<1> DDR5_ECC<1> @BASEBOARD_FAB2_LIB.BASEBOARD_FAB2(SCH_1):M_F_ECC(1)
CH71 M_F_ECC<0> DDR5_ECC<0> @BASEBOARD_FAB2_LIB.BASEBOARD_FAB2(SCH_1):M_F_ECC(0)
DE46 M_F_MA<17> DDR5_MA<17> @BASEBOARD_FAB2_LIB.BASEBOARD_FAB2(SCH_1):M_F_MA(17)
DG52 M_F_MA<16> DDR5_MA<16> @BASEBOARD_FAB2_LIB.BASEBOARD_FAB2(SCH_1):M_F_MA(16)
DC54 M_F_MA<15> DDR5_MA<15> @BASEBOARD_FAB2_LIB.BASEBOARD_FAB2(SCH_1):M_F_MA(15)
DJ50 M_F_MA<14> DDR5_MA<14> @BASEBOARD_FAB2_LIB.BASEBOARD_FAB2(SCH_1):M_F_MA(14)
DD53 M_F_MA<13> DDR5_MA<13> @BASEBOARD_FAB2_LIB.BASEBOARD_FAB2(SCH_1):M_F_MA(13)
DG60 M_F_MA<12> DDR5_MA<12> @BASEBOARD_FAB2_LIB.BASEBOARD_FAB2(SCH_1):M_F_MA(12)
DA60 M_F_MA<11> DDR5_MA<11> @BASEBOARD_FAB2_LIB.BASEBOARD_FAB2(SCH_1):M_F_MA(11)
DD55 M_F_MA<10> DDR5_MA<10> @BASEBOARD_FAB2_LIB.BASEBOARD_FAB2(SCH_1):M_F_MA(10)
DA58 M_F_MA<9> DDR5_MA<9> @BASEBOARD_FAB2_LIB.BASEBOARD_FAB2(SCH_1):M_F_MA(9)
DD59 M_F_MA<8> DDR5_MA<8> @BASEBOARD_FAB2_LIB.BASEBOARD_FAB2(SCH_1):M_F_MA(8)
DC60 M_F_MA<7> DDR5_MA<7> @BASEBOARD_FAB2_LIB.BASEBOARD_FAB2(SCH_1):M_F_MA(7)
DK59 M_F_MA<6> DDR5_MA<6> @BASEBOARD_FAB2_LIB.BASEBOARD_FAB2(SCH_1):M_F_MA(6)
DF59 M_F_MA<5> DDR5_MA<5> @BASEBOARD_FAB2_LIB.BASEBOARD_FAB2(SCH_1):M_F_MA(5)
DJ58 M_F_MA<4> DDR5_MA<4> @BASEBOARD_FAB2_LIB.BASEBOARD_FAB2(SCH_1):M_F_MA(4)
DG58 M_F_MA<3> DDR5_MA<3> @BASEBOARD_FAB2_LIB.BASEBOARD_FAB2(SCH_1):M_F_MA(3)
DD57 M_F_MA<2> DDR5_MA<2> @BASEBOARD_FAB2_LIB.BASEBOARD_FAB2(SCH_1):M_F_MA(2)
DC58 M_F_MA<1> DDR5_MA<1> @BASEBOARD_FAB2_LIB.BASEBOARD_FAB2(SCH_1):M_F_MA(1)
DF53 M_F_MA<0> DDR5_MA<0> @BASEBOARD_FAB2_LIB.BASEBOARD_FAB2(SCH_1):M_F_MA(0)
DF47 M_F_ODT<3> DDR5_ODT<3> @BASEBOARD_FAB2_LIB.BASEBOARD_FAB2(SCH_1):M_F_ODT(3)
DK49 M_F_ODT<2> DDR5_ODT<2> @BASEBOARD_FAB2_LIB.BASEBOARD_FAB2(SCH_1):M_F_ODT(2)
DG48 M_F_ODT<1> DDR5_ODT<1> @BASEBOARD_FAB2_LIB.BASEBOARD_FAB2(SCH_1):M_F_ODT(1)
DG50 M_F_ODT<0> DDR5_ODT<0> @BASEBOARD_FAB2_LIB.BASEBOARD_FAB2(SCH_1):M_F_ODT(0)
DK53 M_F_PAR DDR5_PAR @BASEBOARD_FAB2_LIB.BASEBOARD_FAB2(SCH_1):M_F_PAR


DRAWING: @BASEBOARD_FAB2_LIB.BASEBOARD_FAB2(SCH_1):PAGE29 

SKX_EXT_B_BGA1-IC,TBD  I61  U5D1
BN22 SMB_HFI0_CPU0_LVC2_SCL CD_HFI0_I2CCLK @BASEBOARD_FAB2_LIB.BASEBOARD_FAB2(SCH_1):SMB_HFI0_CPU0_LVC2_SCL
BP23 SMB_HFI0_CPU0_LVC2_SDA CD_HFI0_I2CDAT @BASEBOARD_FAB2_LIB.BASEBOARD_FAB2(SCH_1):SMB_HFI0_CPU0_LVC2_SDA
BP19 IRQ_HFI0_CPU0_LVT2_N CD_HFI0_INT_N @BASEBOARD_FAB2_LIB.BASEBOARD_FAB2(SCH_1):IRQ_HFI0_CPU0_LVT2_N
BK21 LED_HFI0_CPU0_N CD_HFI0_LED_N @BASEBOARD_FAB2_LIB.BASEBOARD_FAB2(SCH_1):LED_HFI0_CPU0_N
BR20 FM_MODPRST_HFI0_CPU0_LVT2_N CD_HFI0_MODPRST_N @BASEBOARD_FAB2_LIB.BASEBOARD_FAB2(SCH_1):FM_MODPRST_HFI0_CPU0_LVT2_N
BN24 RST_HFI0_CPU0_LVT2_N CD_HFI0_RESET_N @BASEBOARD_FAB2_LIB.BASEBOARD_FAB2(SCH_1):RST_HFI0_CPU0_LVT2_N
BJ22 SMB_HFI1_CPU0_LVC2_SCL CD_HFI1_I2CCLK @BASEBOARD_FAB2_LIB.BASEBOARD_FAB2(SCH_1):SMB_HFI1_CPU0_LVC2_SCL
BH23 SMB_HFI1_CPU0_LVC2_SDA CD_HFI1_I2CDAT @BASEBOARD_FAB2_LIB.BASEBOARD_FAB2(SCH_1):SMB_HFI1_CPU0_LVC2_SDA
BM21 IRQ_HFI1_CPU0_LVT2_N CD_HFI1_INT_N @BASEBOARD_FAB2_LIB.BASEBOARD_FAB2(SCH_1):IRQ_HFI1_CPU0_LVT2_N
BM23 LED_HFI1_CPU0_N CD_HFI1_LED_N @BASEBOARD_FAB2_LIB.BASEBOARD_FAB2(SCH_1):LED_HFI1_CPU0_N
BT19 FM_MODPRST_HFI1_CPU0_LVT2_N CD_HFI1_MODPRST_N @BASEBOARD_FAB2_LIB.BASEBOARD_FAB2(SCH_1):FM_MODPRST_HFI1_CPU0_LVT2_N
BK23 RST_HFI1_CPU0_LVT2_N CD_HFI1_RESET_N @BASEBOARD_FAB2_LIB.BASEBOARD_FAB2(SCH_1):RST_HFI1_CPU0_LVT2_N
BE16 CLK_156M_OSC_CPU0_HFI_DN CD_HFI_REFCLK_DN @BASEBOARD_FAB2_LIB.BASEBOARD_FAB2(SCH_1):CLK_156M_OSC_CPU0_HFI_DN
BG16 CLK_156M_OSC_CPU0_HFI_DP CD_HFI_REFCLK_DP @BASEBOARD_FAB2_LIB.BASEBOARD_FAB2(SCH_1):CLK_156M_OSC_CPU0_HFI_DP
BU24 CLK_100M_CPU0_PE_REFCLK_DN CD_PE_REFCLK_DN @BASEBOARD_FAB2_LIB.BASEBOARD_FAB2(SCH_1):CLK_100M_CPU0_PE_REFCLK_DN
BW24 CLK_100M_CPU0_PE_REFCLK_DP CD_PE_REFCLK_DP @BASEBOARD_FAB2_LIB.BASEBOARD_FAB2(SCH_1):CLK_100M_CPU0_PE_REFCLK_DP
CF25 RST_CD_CPU0_POR_N CD_POR_N @BASEBOARD_FAB2_LIB.BASEBOARD_FAB2(SCH_1):RST_CD_CPU0_POR_N
CB23 JTAG_MCP_TCK CD_TCLK @BASEBOARD_FAB2_LIB.BASEBOARD_FAB2(SCH_1):JTAG_MCP_TCK
BY21 JTAG_MCP_CPU0_TDI CD_TDI @BASEBOARD_FAB2_LIB.BASEBOARD_FAB2(SCH_1):JTAG_MCP_CPU0_TDI
CC22 JTAG_MCP_CPU0_TDO CD_TDO @BASEBOARD_FAB2_LIB.BASEBOARD_FAB2(SCH_1):JTAG_MCP_CPU0_TDO
CE24 JTAG_MCP_TMS CD_TMS @BASEBOARD_FAB2_LIB.BASEBOARD_FAB2(SCH_1):JTAG_MCP_TMS
CD23 JTAG_MCP_TRST_N CD_TRST_N @BASEBOARD_FAB2_LIB.BASEBOARD_FAB2(SCH_1):JTAG_MCP_TRST_N
CT11 DMI_CPU0_PCH_RX_C_DN<3> DMI_RX_DN<3> @BASEBOARD_FAB2_LIB.BASEBOARD_FAB2(SCH_1):DMI_CPU0_PCH_RX_C_DN(3)
CR12 DMI_CPU0_PCH_RX_C_DN<2> DMI_RX_DN<2> @BASEBOARD_FAB2_LIB.BASEBOARD_FAB2(SCH_1):DMI_CPU0_PCH_RX_C_DN(2)
CM11 DMI_CPU0_PCH_RX_C_DN<1> DMI_RX_DN<1> @BASEBOARD_FAB2_LIB.BASEBOARD_FAB2(SCH_1):DMI_CPU0_PCH_RX_C_DN(1)
 CK9 DMI_CPU0_PCH_RX_C_DN<0> DMI_RX_DN<0> @BASEBOARD_FAB2_LIB.BASEBOARD_FAB2(SCH_1):DMI_CPU0_PCH_RX_C_DN(0)
CV11 DMI_CPU0_PCH_RX_C_DP<3> DMI_RX_DP<3> @BASEBOARD_FAB2_LIB.BASEBOARD_FAB2(SCH_1):DMI_CPU0_PCH_RX_C_DP(3)
CP11 DMI_CPU0_PCH_RX_C_DP<2> DMI_RX_DP<2> @BASEBOARD_FAB2_LIB.BASEBOARD_FAB2(SCH_1):DMI_CPU0_PCH_RX_C_DP(2)
CN10 DMI_CPU0_PCH_RX_C_DP<1> DMI_RX_DP<1> @BASEBOARD_FAB2_LIB.BASEBOARD_FAB2(SCH_1):DMI_CPU0_PCH_RX_C_DP(1)
CL10 DMI_CPU0_PCH_RX_C_DP<0> DMI_RX_DP<0> @BASEBOARD_FAB2_LIB.BASEBOARD_FAB2(SCH_1):DMI_CPU0_PCH_RX_C_DP(0)
 CP5 DMI_CPU0_PCH_TX_DN<3> DMI_TX_DN<3> @BASEBOARD_FAB2_LIB.BASEBOARD_FAB2(SCH_1):DMI_CPU0_PCH_TX_DN(3)
 CN4 DMI_CPU0_PCH_TX_DN<2> DMI_TX_DN<2> @BASEBOARD_FAB2_LIB.BASEBOARD_FAB2(SCH_1):DMI_CPU0_PCH_TX_DN(2)
 CJ4 DMI_CPU0_PCH_TX_DN<1> DMI_TX_DN<1> @BASEBOARD_FAB2_LIB.BASEBOARD_FAB2(SCH_1):DMI_CPU0_PCH_TX_DN(1)
 CG4 DMI_CPU0_PCH_TX_DN<0> DMI_TX_DN<0> @BASEBOARD_FAB2_LIB.BASEBOARD_FAB2(SCH_1):DMI_CPU0_PCH_TX_DN(0)
 CR4 DMI_CPU0_PCH_TX_DP<3> DMI_TX_DP<3> @BASEBOARD_FAB2_LIB.BASEBOARD_FAB2(SCH_1):DMI_CPU0_PCH_TX_DP(3)
 CM3 DMI_CPU0_PCH_TX_DP<2> DMI_TX_DP<2> @BASEBOARD_FAB2_LIB.BASEBOARD_FAB2(SCH_1):DMI_CPU0_PCH_TX_DP(2)
 CL4 DMI_CPU0_PCH_TX_DP<1> DMI_TX_DP<1> @BASEBOARD_FAB2_LIB.BASEBOARD_FAB2(SCH_1):DMI_CPU0_PCH_TX_DP(1)
 CH5 DMI_CPU0_PCH_TX_DP<0> DMI_TX_DP<0> @BASEBOARD_FAB2_LIB.BASEBOARD_FAB2(SCH_1):DMI_CPU0_PCH_TX_DP(0)
AR20 PVCCMCP_CPU0 RSVD<193> @BASEBOARD_FAB2_LIB.BASEBOARD_FAB2(SCH_1):PVCCMCP_CPU0
AR22 PVCCMCP_CPU0 RSVD<192> @BASEBOARD_FAB2_LIB.BASEBOARD_FAB2(SCH_1):PVCCMCP_CPU0
AR26 PVCCMCP_CPU0 RSVD<191> @BASEBOARD_FAB2_LIB.BASEBOARD_FAB2(SCH_1):PVCCMCP_CPU0
AR62 TP_CPU0_RSVD_190 RSVD<190> @BASEBOARD_FAB2_LIB.BASEBOARD_FAB2(SCH_1):TP_CPU0_RSVD_190
AT13 TP_CPU0_RSVD_189 RSVD<189> @BASEBOARD_FAB2_LIB.BASEBOARD_FAB2(SCH_1):TP_CPU0_RSVD_189
AT23 PVCCMCP_CPU0 RSVD<188> @BASEBOARD_FAB2_LIB.BASEBOARD_FAB2(SCH_1):PVCCMCP_CPU0
AT25 PVCCMCP_CPU0 RSVD<187> @BASEBOARD_FAB2_LIB.BASEBOARD_FAB2(SCH_1):PVCCMCP_CPU0
AV77 TP_CPU0_RSVD_186 RSVD<186> @BASEBOARD_FAB2_LIB.BASEBOARD_FAB2(SCH_1):TP_CPU0_RSVD_186
AW64 TP_CPU0_RSVD_184 RSVD<184> @BASEBOARD_FAB2_LIB.BASEBOARD_FAB2(SCH_1):TP_CPU0_RSVD_184
AW76 TP_CPU0_RSVD_183 RSVD<183> @BASEBOARD_FAB2_LIB.BASEBOARD_FAB2(SCH_1):TP_CPU0_RSVD_183
AY65 TP_CPU0_RSVD_182 RSVD<182> @BASEBOARD_FAB2_LIB.BASEBOARD_FAB2(SCH_1):TP_CPU0_RSVD_182
AY67 TP_CPU0_RSVD_181 RSVD<181> @BASEBOARD_FAB2_LIB.BASEBOARD_FAB2(SCH_1):TP_CPU0_RSVD_181
AY75 TP_CPU0_RSVD_180 RSVD<180> @BASEBOARD_FAB2_LIB.BASEBOARD_FAB2(SCH_1):TP_CPU0_RSVD_180
AY77 TP_CPU0_RSVD_179 RSVD<179> @BASEBOARD_FAB2_LIB.BASEBOARD_FAB2(SCH_1):TP_CPU0_RSVD_179
BA14 TP_CPU0_RSVD_178 RSVD<178> @BASEBOARD_FAB2_LIB.BASEBOARD_FAB2(SCH_1):TP_CPU0_RSVD_178
BA16 TP_CPU0_RSVD_177 RSVD<177> @BASEBOARD_FAB2_LIB.BASEBOARD_FAB2(SCH_1):TP_CPU0_RSVD_177
BA18 TP_CPU0_RSVD_176 RSVD<176> @BASEBOARD_FAB2_LIB.BASEBOARD_FAB2(SCH_1):TP_CPU0_RSVD_176
BA22 TP_CPU0_RSVD_175 RSVD<175> @BASEBOARD_FAB2_LIB.BASEBOARD_FAB2(SCH_1):TP_CPU0_RSVD_175
BA64 TP_CPU0_RSVD_174 RSVD<174> @BASEBOARD_FAB2_LIB.BASEBOARD_FAB2(SCH_1):TP_CPU0_RSVD_174
BA66 TP_CPU0_RSVD_173 RSVD<173> @BASEBOARD_FAB2_LIB.BASEBOARD_FAB2(SCH_1):TP_CPU0_RSVD_173
BA76 TP_CPU0_RSVD_172 RSVD<172> @BASEBOARD_FAB2_LIB.BASEBOARD_FAB2(SCH_1):TP_CPU0_RSVD_172


DRAWING: @BASEBOARD_FAB2_LIB.BASEBOARD_FAB2(SCH_1):PAGE30 

SKX_EXT_B_BGA1-IC,TBD  I84  U5D1
DU16 P3E_CPU0_PE1_PCH_RXN<15> PE1_RX_DN<15> @BASEBOARD_FAB2_LIB.BASEBOARD_FAB2(SCH_1):P3E_CPU0_PE1_PCH_RXN(15)
DY15 P3E_CPU0_PE1_PCH_RXN<14> PE1_RX_DN<14> @BASEBOARD_FAB2_LIB.BASEBOARD_FAB2(SCH_1):P3E_CPU0_PE1_PCH_RXN(14)
DW14 P3E_CPU0_PE1_PCH_RXN<13> PE1_RX_DN<13> @BASEBOARD_FAB2_LIB.BASEBOARD_FAB2(SCH_1):P3E_CPU0_PE1_PCH_RXN(13)
DV13 P3E_CPU0_PE1_PCH_RXN<12> PE1_RX_DN<12> @BASEBOARD_FAB2_LIB.BASEBOARD_FAB2(SCH_1):P3E_CPU0_PE1_PCH_RXN(12)
DT13 P3E_CPU0_PE1_PCH_RXN<11> PE1_RX_DN<11> @BASEBOARD_FAB2_LIB.BASEBOARD_FAB2(SCH_1):P3E_CPU0_PE1_PCH_RXN(11)
DT11 P3E_CPU0_PE1_PCH_RXN<10> PE1_RX_DN<10> @BASEBOARD_FAB2_LIB.BASEBOARD_FAB2(SCH_1):P3E_CPU0_PE1_PCH_RXN(10)
DP11 P3E_CPU0_PE1_PCH_RXN<9> PE1_RX_DN<9> @BASEBOARD_FAB2_LIB.BASEBOARD_FAB2(SCH_1):P3E_CPU0_PE1_PCH_RXN(9)
DM11 P3E_CPU0_PE1_PCH_RXN<8> PE1_RX_DN<8> @BASEBOARD_FAB2_LIB.BASEBOARD_FAB2(SCH_1):P3E_CPU0_PE1_PCH_RXN(8)
 DM9 P3E_CPU0_PE1_SS_RXN<7> PE1_RX_DN<7> @BASEBOARD_FAB2_LIB.BASEBOARD_FAB2(SCH_1):P3E_CPU0_PE1_SS_RXN(7)
 DK9 P3E_CPU0_PE1_SS_RXN<6> PE1_RX_DN<6> @BASEBOARD_FAB2_LIB.BASEBOARD_FAB2(SCH_1):P3E_CPU0_PE1_SS_RXN(6)
 DH9 P3E_CPU0_PE1_SS_RXN<5> PE1_RX_DN<5> @BASEBOARD_FAB2_LIB.BASEBOARD_FAB2(SCH_1):P3E_CPU0_PE1_SS_RXN(5)
DE10 P3E_CPU0_PE1_SS_RXN<4> PE1_RX_DN<4> @BASEBOARD_FAB2_LIB.BASEBOARD_FAB2(SCH_1):P3E_CPU0_PE1_SS_RXN(4)
DC10 P3E_CPU0_PE1_SS_RXN<3> PE1_RX_DN<3> @BASEBOARD_FAB2_LIB.BASEBOARD_FAB2(SCH_1):P3E_CPU0_PE1_SS_RXN(3)
 DC8 P3E_CPU0_PE1_SS_RXN<2> PE1_RX_DN<2> @BASEBOARD_FAB2_LIB.BASEBOARD_FAB2(SCH_1):P3E_CPU0_PE1_SS_RXN(2)
 DA8 P3E_CPU0_PE1_SS_RXN<1> PE1_RX_DN<1> @BASEBOARD_FAB2_LIB.BASEBOARD_FAB2(SCH_1):P3E_CPU0_PE1_SS_RXN(1)
 CW8 P3E_CPU0_PE1_SS_RXN<0> PE1_RX_DN<0> @BASEBOARD_FAB2_LIB.BASEBOARD_FAB2(SCH_1):P3E_CPU0_PE1_SS_RXN(0)
DT15 P3E_CPU0_PE1_PCH_RXP<15> PE1_RX_DP<15> @BASEBOARD_FAB2_LIB.BASEBOARD_FAB2(SCH_1):P3E_CPU0_PE1_PCH_RXP(15)
DV15 P3E_CPU0_PE1_PCH_RXP<14> PE1_RX_DP<14> @BASEBOARD_FAB2_LIB.BASEBOARD_FAB2(SCH_1):P3E_CPU0_PE1_PCH_RXP(14)
DY13 P3E_CPU0_PE1_PCH_RXP<13> PE1_RX_DP<13> @BASEBOARD_FAB2_LIB.BASEBOARD_FAB2(SCH_1):P3E_CPU0_PE1_PCH_RXP(13)
DU12 P3E_CPU0_PE1_PCH_RXP<12> PE1_RX_DP<12> @BASEBOARD_FAB2_LIB.BASEBOARD_FAB2(SCH_1):P3E_CPU0_PE1_PCH_RXP(12)
DP13 P3E_CPU0_PE1_PCH_RXP<11> PE1_RX_DP<11> @BASEBOARD_FAB2_LIB.BASEBOARD_FAB2(SCH_1):P3E_CPU0_PE1_PCH_RXP(11)
DR12 P3E_CPU0_PE1_PCH_RXP<10> PE1_RX_DP<10> @BASEBOARD_FAB2_LIB.BASEBOARD_FAB2(SCH_1):P3E_CPU0_PE1_PCH_RXP(10)
DN10 P3E_CPU0_PE1_PCH_RXP<9> PE1_RX_DP<9> @BASEBOARD_FAB2_LIB.BASEBOARD_FAB2(SCH_1):P3E_CPU0_PE1_PCH_RXP(9)
DK11 P3E_CPU0_PE1_PCH_RXP<8> PE1_RX_DP<8> @BASEBOARD_FAB2_LIB.BASEBOARD_FAB2(SCH_1):P3E_CPU0_PE1_PCH_RXP(8)
DL10 P3E_CPU0_PE1_SS_RXP<7> PE1_RX_DP<7> @BASEBOARD_FAB2_LIB.BASEBOARD_FAB2(SCH_1):P3E_CPU0_PE1_SS_RXP(7)
 DJ8 P3E_CPU0_PE1_SS_RXP<6> PE1_RX_DP<6> @BASEBOARD_FAB2_LIB.BASEBOARD_FAB2(SCH_1):P3E_CPU0_PE1_SS_RXP(6)
 DF9 P3E_CPU0_PE1_SS_RXP<5> PE1_RX_DP<5> @BASEBOARD_FAB2_LIB.BASEBOARD_FAB2(SCH_1):P3E_CPU0_PE1_SS_RXP(5)
 DD9 P3E_CPU0_PE1_SS_RXP<4> PE1_RX_DP<4> @BASEBOARD_FAB2_LIB.BASEBOARD_FAB2(SCH_1):P3E_CPU0_PE1_SS_RXP(4)
DA10 P3E_CPU0_PE1_SS_RXP<3> PE1_RX_DP<3> @BASEBOARD_FAB2_LIB.BASEBOARD_FAB2(SCH_1):P3E_CPU0_PE1_SS_RXP(3)
 DB9 P3E_CPU0_PE1_SS_RXP<2> PE1_RX_DP<2> @BASEBOARD_FAB2_LIB.BASEBOARD_FAB2(SCH_1):P3E_CPU0_PE1_SS_RXP(2)
 CY7 P3E_CPU0_PE1_SS_RXP<1> PE1_RX_DP<1> @BASEBOARD_FAB2_LIB.BASEBOARD_FAB2(SCH_1):P3E_CPU0_PE1_SS_RXP(1)
 CU8 P3E_CPU0_PE1_SS_RXP<0> PE1_RX_DP<0> @BASEBOARD_FAB2_LIB.BASEBOARD_FAB2(SCH_1):P3E_CPU0_PE1_SS_RXP(0)
 ED9 P3E_CPU0_PE1_PCH_TXN<15> PE1_TX_DN<15> @BASEBOARD_FAB2_LIB.BASEBOARD_FAB2(SCH_1):P3E_CPU0_PE1_PCH_TXN(15)
 EA8 P3E_CPU0_PE1_PCH_TXN<14> PE1_TX_DN<14> @BASEBOARD_FAB2_LIB.BASEBOARD_FAB2(SCH_1):P3E_CPU0_PE1_PCH_TXN(14)
 DY7 P3E_CPU0_PE1_PCH_TXN<13> PE1_TX_DN<13> @BASEBOARD_FAB2_LIB.BASEBOARD_FAB2(SCH_1):P3E_CPU0_PE1_PCH_TXN(13)
 DV7 P3E_CPU0_PE1_PCH_TXN<12> PE1_TX_DN<12> @BASEBOARD_FAB2_LIB.BASEBOARD_FAB2(SCH_1):P3E_CPU0_PE1_PCH_TXN(12)
 DU6 P3E_CPU0_PE1_PCH_TXN<11> PE1_TX_DN<11> @BASEBOARD_FAB2_LIB.BASEBOARD_FAB2(SCH_1):P3E_CPU0_PE1_PCH_TXN(11)
 DW4 P3E_CPU0_PE1_PCH_TXN<10> PE1_TX_DN<10> @BASEBOARD_FAB2_LIB.BASEBOARD_FAB2(SCH_1):P3E_CPU0_PE1_PCH_TXN(10)
 DV3 P3E_CPU0_PE1_PCH_TXN<9> PE1_TX_DN<9> @BASEBOARD_FAB2_LIB.BASEBOARD_FAB2(SCH_1):P3E_CPU0_PE1_PCH_TXN(9)
 DT5 P3E_CPU0_PE1_PCH_TXN<8> PE1_TX_DN<8> @BASEBOARD_FAB2_LIB.BASEBOARD_FAB2(SCH_1):P3E_CPU0_PE1_PCH_TXN(8)
 DN4 P3E_CPU0_PE1_SS_TXN<7> PE1_TX_DN<7> @BASEBOARD_FAB2_LIB.BASEBOARD_FAB2(SCH_1):P3E_CPU0_PE1_SS_TXN(7)
 DM3 P3E_CPU0_PE1_SS_TXN<6> PE1_TX_DN<6> @BASEBOARD_FAB2_LIB.BASEBOARD_FAB2(SCH_1):P3E_CPU0_PE1_SS_TXN(6)
 DK3 P3E_CPU0_PE1_SS_TXN<5> PE1_TX_DN<5> @BASEBOARD_FAB2_LIB.BASEBOARD_FAB2(SCH_1):P3E_CPU0_PE1_SS_TXN(5)
 DG4 P3E_CPU0_PE1_SS_TXN<4> PE1_TX_DN<4> @BASEBOARD_FAB2_LIB.BASEBOARD_FAB2(SCH_1):P3E_CPU0_PE1_SS_TXN(4)
 DE4 P3E_CPU0_PE1_SS_TXN<3> PE1_TX_DN<3> @BASEBOARD_FAB2_LIB.BASEBOARD_FAB2(SCH_1):P3E_CPU0_PE1_SS_TXN(3)
 DE2 P3E_CPU0_PE1_SS_TXN<2> PE1_TX_DN<2> @BASEBOARD_FAB2_LIB.BASEBOARD_FAB2(SCH_1):P3E_CPU0_PE1_SS_TXN(2)
 DC2 P3E_CPU0_PE1_SS_TXN<1> PE1_TX_DN<1> @BASEBOARD_FAB2_LIB.BASEBOARD_FAB2(SCH_1):P3E_CPU0_PE1_SS_TXN(1)
 DA2 P3E_CPU0_PE1_SS_TXN<0> PE1_TX_DN<0> @BASEBOARD_FAB2_LIB.BASEBOARD_FAB2(SCH_1):P3E_CPU0_PE1_SS_TXN(0)
 EC8 P3E_CPU0_PE1_PCH_TXP<15> PE1_TX_DP<15> @BASEBOARD_FAB2_LIB.BASEBOARD_FAB2(SCH_1):P3E_CPU0_PE1_PCH_TXP(15)
 EB7 P3E_CPU0_PE1_PCH_TXP<14> PE1_TX_DP<14> @BASEBOARD_FAB2_LIB.BASEBOARD_FAB2(SCH_1):P3E_CPU0_PE1_PCH_TXP(14)
 DW6 P3E_CPU0_PE1_PCH_TXP<13> PE1_TX_DP<13> @BASEBOARD_FAB2_LIB.BASEBOARD_FAB2(SCH_1):P3E_CPU0_PE1_PCH_TXP(13)
 DT7 P3E_CPU0_PE1_PCH_TXP<12> PE1_TX_DP<12> @BASEBOARD_FAB2_LIB.BASEBOARD_FAB2(SCH_1):P3E_CPU0_PE1_PCH_TXP(12)
 DV5 P3E_CPU0_PE1_PCH_TXP<11> PE1_TX_DP<11> @BASEBOARD_FAB2_LIB.BASEBOARD_FAB2(SCH_1):P3E_CPU0_PE1_PCH_TXP(11)
 DU4 P3E_CPU0_PE1_PCH_TXP<10> PE1_TX_DP<10> @BASEBOARD_FAB2_LIB.BASEBOARD_FAB2(SCH_1):P3E_CPU0_PE1_PCH_TXP(10)
 DU2 P3E_CPU0_PE1_PCH_TXP<9> PE1_TX_DP<9> @BASEBOARD_FAB2_LIB.BASEBOARD_FAB2(SCH_1):P3E_CPU0_PE1_PCH_TXP(9)
 DR4 P3E_CPU0_PE1_PCH_TXP<8> PE1_TX_DP<8> @BASEBOARD_FAB2_LIB.BASEBOARD_FAB2(SCH_1):P3E_CPU0_PE1_PCH_TXP(8)
 DP3 P3E_CPU0_PE1_SS_TXP<7> PE1_TX_DP<7> @BASEBOARD_FAB2_LIB.BASEBOARD_FAB2(SCH_1):P3E_CPU0_PE1_SS_TXP(7)
 DL2 P3E_CPU0_PE1_SS_TXP<6> PE1_TX_DP<6> @BASEBOARD_FAB2_LIB.BASEBOARD_FAB2(SCH_1):P3E_CPU0_PE1_SS_TXP(6)
 DH3 P3E_CPU0_PE1_SS_TXP<5> PE1_TX_DP<5> @BASEBOARD_FAB2_LIB.BASEBOARD_FAB2(SCH_1):P3E_CPU0_PE1_SS_TXP(5)
 DF3 P3E_CPU0_PE1_SS_TXP<4> PE1_TX_DP<4> @BASEBOARD_FAB2_LIB.BASEBOARD_FAB2(SCH_1):P3E_CPU0_PE1_SS_TXP(4)
 DC4 P3E_CPU0_PE1_SS_TXP<3> PE1_TX_DP<3> @BASEBOARD_FAB2_LIB.BASEBOARD_FAB2(SCH_1):P3E_CPU0_PE1_SS_TXP(3)
 DD3 P3E_CPU0_PE1_SS_TXP<2> PE1_TX_DP<2> @BASEBOARD_FAB2_LIB.BASEBOARD_FAB2(SCH_1):P3E_CPU0_PE1_SS_TXP(2)
 DB1 P3E_CPU0_PE1_SS_TXP<1> PE1_TX_DP<1> @BASEBOARD_FAB2_LIB.BASEBOARD_FAB2(SCH_1):P3E_CPU0_PE1_SS_TXP(1)
 CW2 P3E_CPU0_PE1_SS_TXP<0> PE1_TX_DP<0> @BASEBOARD_FAB2_LIB.BASEBOARD_FAB2(SCH_1):P3E_CPU0_PE1_SS_TXP(0)


DRAWING: @BASEBOARD_FAB2_LIB.BASEBOARD_FAB2(SCH_1):PAGE31 

SKX_EXT_B_BGA1-IC,TBD  I106  U5D1
 BK9 P3E_CPU0_PE2_SS_RXN<15> PE2_RX_DN<15> @BASEBOARD_FAB2_LIB.BASEBOARD_FAB2(SCH_1):P3E_CPU0_PE2_SS_RXN(15)
 BL8 P3E_CPU0_PE2_SS_RXN<14> PE2_RX_DN<14> @BASEBOARD_FAB2_LIB.BASEBOARD_FAB2(SCH_1):P3E_CPU0_PE2_SS_RXN(14)
 BN8 P3E_CPU0_PE2_SS_RXN<13> PE2_RX_DN<13> @BASEBOARD_FAB2_LIB.BASEBOARD_FAB2(SCH_1):P3E_CPU0_PE2_SS_RXN(13)
 BR8 P3E_CPU0_PE2_SS_RXN<12> PE2_RX_DN<12> @BASEBOARD_FAB2_LIB.BASEBOARD_FAB2(SCH_1):P3E_CPU0_PE2_SS_RXN(12)
 BT7 P3E_CPU0_PE2_SS_RXN<11> PE2_RX_DN<11> @BASEBOARD_FAB2_LIB.BASEBOARD_FAB2(SCH_1):P3E_CPU0_PE2_SS_RXN(11)
 BV7 P3E_CPU0_PE2_SS_RXN<10> PE2_RX_DN<10> @BASEBOARD_FAB2_LIB.BASEBOARD_FAB2(SCH_1):P3E_CPU0_PE2_SS_RXN(10)
 BY7 P3E_CPU0_PE2_SS_RXN<9> PE2_RX_DN<9> @BASEBOARD_FAB2_LIB.BASEBOARD_FAB2(SCH_1):P3E_CPU0_PE2_SS_RXN(9)
 BY9 P3E_CPU0_PE2_SS_RXN<8> PE2_RX_DN<8> @BASEBOARD_FAB2_LIB.BASEBOARD_FAB2(SCH_1):P3E_CPU0_PE2_SS_RXN(8)
 CE8 P3E_CPU0_PE2_SS_RXN<7> PE2_RX_DN<7> @BASEBOARD_FAB2_LIB.BASEBOARD_FAB2(SCH_1):P3E_CPU0_PE2_SS_RXN(7)
 CE6 P3E_CPU0_PE2_SS_RXN<6> PE2_RX_DN<6> @BASEBOARD_FAB2_LIB.BASEBOARD_FAB2(SCH_1):P3E_CPU0_PE2_SS_RXN(6)
 CG8 P3E_CPU0_PE2_SS_RXN<5> PE2_RX_DN<5> @BASEBOARD_FAB2_LIB.BASEBOARD_FAB2(SCH_1):P3E_CPU0_PE2_SS_RXN(5)
 CK7 P3E_CPU0_PE2_SS_RXN<4> PE2_RX_DN<4> @BASEBOARD_FAB2_LIB.BASEBOARD_FAB2(SCH_1):P3E_CPU0_PE2_SS_RXN(4)
 CM7 P3E_CPU0_PE2_SS_RXN<3> PE2_RX_DN<3> @BASEBOARD_FAB2_LIB.BASEBOARD_FAB2(SCH_1):P3E_CPU0_PE2_SS_RXN(3)
 CP7 P3E_CPU0_PE2_SS_RXN<2> PE2_RX_DN<2> @BASEBOARD_FAB2_LIB.BASEBOARD_FAB2(SCH_1):P3E_CPU0_PE2_SS_RXN(2)
 CP9 P3E_CPU0_PE2_SS_RXN<1> PE2_RX_DN<1> @BASEBOARD_FAB2_LIB.BASEBOARD_FAB2(SCH_1):P3E_CPU0_PE2_SS_RXN(1)
 CT9 P3E_CPU0_PE2_SS_RXN<0> PE2_RX_DN<0> @BASEBOARD_FAB2_LIB.BASEBOARD_FAB2(SCH_1):P3E_CPU0_PE2_SS_RXN(0)
BJ10 P3E_CPU0_PE2_SS_RXP<15> PE2_RX_DP<15> @BASEBOARD_FAB2_LIB.BASEBOARD_FAB2(SCH_1):P3E_CPU0_PE2_SS_RXP(15)
 BJ8 P3E_CPU0_PE2_SS_RXP<14> PE2_RX_DP<14> @BASEBOARD_FAB2_LIB.BASEBOARD_FAB2(SCH_1):P3E_CPU0_PE2_SS_RXP(14)
 BM7 P3E_CPU0_PE2_SS_RXP<13> PE2_RX_DP<13> @BASEBOARD_FAB2_LIB.BASEBOARD_FAB2(SCH_1):P3E_CPU0_PE2_SS_RXP(13)
 BP9 P3E_CPU0_PE2_SS_RXP<12> PE2_RX_DP<12> @BASEBOARD_FAB2_LIB.BASEBOARD_FAB2(SCH_1):P3E_CPU0_PE2_SS_RXP(12)
 BP7 P3E_CPU0_PE2_SS_RXP<11> PE2_RX_DP<11> @BASEBOARD_FAB2_LIB.BASEBOARD_FAB2(SCH_1):P3E_CPU0_PE2_SS_RXP(11)
 BU6 P3E_CPU0_PE2_SS_RXP<10> PE2_RX_DP<10> @BASEBOARD_FAB2_LIB.BASEBOARD_FAB2(SCH_1):P3E_CPU0_PE2_SS_RXP(10)
 BW8 P3E_CPU0_PE2_SS_RXP<9> PE2_RX_DP<9> @BASEBOARD_FAB2_LIB.BASEBOARD_FAB2(SCH_1):P3E_CPU0_PE2_SS_RXP(9)
 BV9 P3E_CPU0_PE2_SS_RXP<8> PE2_RX_DP<8> @BASEBOARD_FAB2_LIB.BASEBOARD_FAB2(SCH_1):P3E_CPU0_PE2_SS_RXP(8)
 CC8 P3E_CPU0_PE2_SS_RXP<7> PE2_RX_DP<7> @BASEBOARD_FAB2_LIB.BASEBOARD_FAB2(SCH_1):P3E_CPU0_PE2_SS_RXP(7)
 CD7 P3E_CPU0_PE2_SS_RXP<6> PE2_RX_DP<6> @BASEBOARD_FAB2_LIB.BASEBOARD_FAB2(SCH_1):P3E_CPU0_PE2_SS_RXP(6)
 CF7 P3E_CPU0_PE2_SS_RXP<5> PE2_RX_DP<5> @BASEBOARD_FAB2_LIB.BASEBOARD_FAB2(SCH_1):P3E_CPU0_PE2_SS_RXP(5)
 CH7 P3E_CPU0_PE2_SS_RXP<4> PE2_RX_DP<4> @BASEBOARD_FAB2_LIB.BASEBOARD_FAB2(SCH_1):P3E_CPU0_PE2_SS_RXP(4)
 CL6 P3E_CPU0_PE2_SS_RXP<3> PE2_RX_DP<3> @BASEBOARD_FAB2_LIB.BASEBOARD_FAB2(SCH_1):P3E_CPU0_PE2_SS_RXP(3)
 CN8 P3E_CPU0_PE2_SS_RXP<2> PE2_RX_DP<2> @BASEBOARD_FAB2_LIB.BASEBOARD_FAB2(SCH_1):P3E_CPU0_PE2_SS_RXP(2)
 CM9 P3E_CPU0_PE2_SS_RXP<1> PE2_RX_DP<1> @BASEBOARD_FAB2_LIB.BASEBOARD_FAB2(SCH_1):P3E_CPU0_PE2_SS_RXP(1)
 CR8 P3E_CPU0_PE2_SS_RXP<0> PE2_RX_DP<0> @BASEBOARD_FAB2_LIB.BASEBOARD_FAB2(SCH_1):P3E_CPU0_PE2_SS_RXP(0)
 BM5 P3E_CPU0_PE2_SS_TXN<15> PE2_TX_DN<15> @BASEBOARD_FAB2_LIB.BASEBOARD_FAB2(SCH_1):P3E_CPU0_PE2_SS_TXN(15)
 BL4 P3E_CPU0_PE2_SS_TXN<14> PE2_TX_DN<14> @BASEBOARD_FAB2_LIB.BASEBOARD_FAB2(SCH_1):P3E_CPU0_PE2_SS_TXN(14)
 BP5 P3E_CPU0_PE2_SS_TXN<13> PE2_TX_DN<13> @BASEBOARD_FAB2_LIB.BASEBOARD_FAB2(SCH_1):P3E_CPU0_PE2_SS_TXN(13)
 BU4 P3E_CPU0_PE2_SS_TXN<12> PE2_TX_DN<12> @BASEBOARD_FAB2_LIB.BASEBOARD_FAB2(SCH_1):P3E_CPU0_PE2_SS_TXN(12)
 BW4 P3E_CPU0_PE2_SS_TXN<11> PE2_TX_DN<11> @BASEBOARD_FAB2_LIB.BASEBOARD_FAB2(SCH_1):P3E_CPU0_PE2_SS_TXN(11)
 CA4 P3E_CPU0_PE2_SS_TXN<10> PE2_TX_DN<10> @BASEBOARD_FAB2_LIB.BASEBOARD_FAB2(SCH_1):P3E_CPU0_PE2_SS_TXN(10)
 CB3 P3E_CPU0_PE2_SS_TXN<9> PE2_TX_DN<9> @BASEBOARD_FAB2_LIB.BASEBOARD_FAB2(SCH_1):P3E_CPU0_PE2_SS_TXN(9)
 CC2 P3E_CPU0_PE2_SS_TXN<8> PE2_TX_DN<8> @BASEBOARD_FAB2_LIB.BASEBOARD_FAB2(SCH_1):P3E_CPU0_PE2_SS_TXN(8)
 CF3 P3E_CPU0_PE2_SS_TXN<7> PE2_TX_DN<7> @BASEBOARD_FAB2_LIB.BASEBOARD_FAB2(SCH_1):P3E_CPU0_PE2_SS_TXN(7)
 CG2 P3E_CPU0_PE2_SS_TXN<6> PE2_TX_DN<6> @BASEBOARD_FAB2_LIB.BASEBOARD_FAB2(SCH_1):P3E_CPU0_PE2_SS_TXN(6)
 CL2 P3E_CPU0_PE2_SS_TXN<5> PE2_TX_DN<5> @BASEBOARD_FAB2_LIB.BASEBOARD_FAB2(SCH_1):P3E_CPU0_PE2_SS_TXN(5)
 CM1 P3E_CPU0_PE2_SS_TXN<4> PE2_TX_DN<4> @BASEBOARD_FAB2_LIB.BASEBOARD_FAB2(SCH_1):P3E_CPU0_PE2_SS_TXN(4)
 CT3 P3E_CPU0_PE2_SS_TXN<3> PE2_TX_DN<3> @BASEBOARD_FAB2_LIB.BASEBOARD_FAB2(SCH_1):P3E_CPU0_PE2_SS_TXN(3)
 CT1 P3E_CPU0_PE2_SS_TXN<2> PE2_TX_DN<2> @BASEBOARD_FAB2_LIB.BASEBOARD_FAB2(SCH_1):P3E_CPU0_PE2_SS_TXN(2)
 CV3 P3E_CPU0_PE2_SS_TXN<1> PE2_TX_DN<1> @BASEBOARD_FAB2_LIB.BASEBOARD_FAB2(SCH_1):P3E_CPU0_PE2_SS_TXN(1)
 CY3 P3E_CPU0_PE2_SS_TXN<0> PE2_TX_DN<0> @BASEBOARD_FAB2_LIB.BASEBOARD_FAB2(SCH_1):P3E_CPU0_PE2_SS_TXN(0)
 BK5 P3E_CPU0_PE2_SS_TXP<15> PE2_TX_DP<15> @BASEBOARD_FAB2_LIB.BASEBOARD_FAB2(SCH_1):P3E_CPU0_PE2_SS_TXP(15)
 BM3 P3E_CPU0_PE2_SS_TXP<14> PE2_TX_DP<14> @BASEBOARD_FAB2_LIB.BASEBOARD_FAB2(SCH_1):P3E_CPU0_PE2_SS_TXP(14)
 BN4 P3E_CPU0_PE2_SS_TXP<13> PE2_TX_DP<13> @BASEBOARD_FAB2_LIB.BASEBOARD_FAB2(SCH_1):P3E_CPU0_PE2_SS_TXP(13)
 BR4 P3E_CPU0_PE2_SS_TXP<12> PE2_TX_DP<12> @BASEBOARD_FAB2_LIB.BASEBOARD_FAB2(SCH_1):P3E_CPU0_PE2_SS_TXP(12)
 BV3 P3E_CPU0_PE2_SS_TXP<11> PE2_TX_DP<11> @BASEBOARD_FAB2_LIB.BASEBOARD_FAB2(SCH_1):P3E_CPU0_PE2_SS_TXP(11)
 BY5 P3E_CPU0_PE2_SS_TXP<10> PE2_TX_DP<10> @BASEBOARD_FAB2_LIB.BASEBOARD_FAB2(SCH_1):P3E_CPU0_PE2_SS_TXP(10)
 BY3 P3E_CPU0_PE2_SS_TXP<9> PE2_TX_DP<9> @BASEBOARD_FAB2_LIB.BASEBOARD_FAB2(SCH_1):P3E_CPU0_PE2_SS_TXP(9)
 CD3 P3E_CPU0_PE2_SS_TXP<8> PE2_TX_DP<8> @BASEBOARD_FAB2_LIB.BASEBOARD_FAB2(SCH_1):P3E_CPU0_PE2_SS_TXP(8)
 CE4 P3E_CPU0_PE2_SS_TXP<7> PE2_TX_DP<7> @BASEBOARD_FAB2_LIB.BASEBOARD_FAB2(SCH_1):P3E_CPU0_PE2_SS_TXP(7)
 CE2 P3E_CPU0_PE2_SS_TXP<6> PE2_TX_DP<6> @BASEBOARD_FAB2_LIB.BASEBOARD_FAB2(SCH_1):P3E_CPU0_PE2_SS_TXP(6)
 CK3 P3E_CPU0_PE2_SS_TXP<5> PE2_TX_DP<5> @BASEBOARD_FAB2_LIB.BASEBOARD_FAB2(SCH_1):P3E_CPU0_PE2_SS_TXP(5)
 CK1 P3E_CPU0_PE2_SS_TXP<4> PE2_TX_DP<4> @BASEBOARD_FAB2_LIB.BASEBOARD_FAB2(SCH_1):P3E_CPU0_PE2_SS_TXP(4)
 CP3 P3E_CPU0_PE2_SS_TXP<3> PE2_TX_DP<3> @BASEBOARD_FAB2_LIB.BASEBOARD_FAB2(SCH_1):P3E_CPU0_PE2_SS_TXP(3)
 CR2 P3E_CPU0_PE2_SS_TXP<2> PE2_TX_DP<2> @BASEBOARD_FAB2_LIB.BASEBOARD_FAB2(SCH_1):P3E_CPU0_PE2_SS_TXP(2)
 CU2 P3E_CPU0_PE2_SS_TXP<1> PE2_TX_DP<1> @BASEBOARD_FAB2_LIB.BASEBOARD_FAB2(SCH_1):P3E_CPU0_PE2_SS_TXP(1)
 CW4 P3E_CPU0_PE2_SS_TXP<0> PE2_TX_DP<0> @BASEBOARD_FAB2_LIB.BASEBOARD_FAB2(SCH_1):P3E_CPU0_PE2_SS_TXP(0)


DRAWING: @BASEBOARD_FAB2_LIB.BASEBOARD_FAB2(SCH_1):PAGE32 

SKX_EXT_B_BGA1-IC,TBD  I89  U5D1
 CV9 P3E_CPU0_PE3_OCP_RXN<15> PE3_RX_DN<15> @BASEBOARD_FAB2_LIB.BASEBOARD_FAB2(SCH_1):P3E_CPU0_PE3_OCP_RXN(15)
CY11 P3E_CPU0_PE3_OCP_RXN<14> PE3_RX_DN<14> @BASEBOARD_FAB2_LIB.BASEBOARD_FAB2(SCH_1):P3E_CPU0_PE3_OCP_RXN(14)
DB11 P3E_CPU0_PE3_OCP_RXN<13> PE3_RX_DN<13> @BASEBOARD_FAB2_LIB.BASEBOARD_FAB2(SCH_1):P3E_CPU0_PE3_OCP_RXN(13)
DD13 P3E_CPU0_PE3_OCP_RXN<12> PE3_RX_DN<12> @BASEBOARD_FAB2_LIB.BASEBOARD_FAB2(SCH_1):P3E_CPU0_PE3_OCP_RXN(12)
DG10 P3E_CPU0_PE3_OCP_RXN<11> PE3_RX_DN<11> @BASEBOARD_FAB2_LIB.BASEBOARD_FAB2(SCH_1):P3E_CPU0_PE3_OCP_RXN(11)
DG12 P3E_CPU0_PE3_OCP_RXN<10> PE3_RX_DN<10> @BASEBOARD_FAB2_LIB.BASEBOARD_FAB2(SCH_1):P3E_CPU0_PE3_OCP_RXN(10)
DJ12 P3E_CPU0_PE3_OCP_RXN<9> PE3_RX_DN<9> @BASEBOARD_FAB2_LIB.BASEBOARD_FAB2(SCH_1):P3E_CPU0_PE3_OCP_RXN(9)
DL12 P3E_CPU0_PE3_OCP_RXN<8> PE3_RX_DN<8> @BASEBOARD_FAB2_LIB.BASEBOARD_FAB2(SCH_1):P3E_CPU0_PE3_OCP_RXN(8)
DL14 P3E_CPU0_PE3_OCP_RXN<7> PE3_RX_DN<7> @BASEBOARD_FAB2_LIB.BASEBOARD_FAB2(SCH_1):P3E_CPU0_PE3_OCP_RXN(7)
DN14 P3E_CPU0_PE3_OCP_RXN<6> PE3_RX_DN<6> @BASEBOARD_FAB2_LIB.BASEBOARD_FAB2(SCH_1):P3E_CPU0_PE3_OCP_RXN(6)
DR14 P3E_CPU0_PE3_OCP_RXN<5> PE3_RX_DN<5> @BASEBOARD_FAB2_LIB.BASEBOARD_FAB2(SCH_1):P3E_CPU0_PE3_OCP_RXN(5)
DR16 P3E_CPU0_PE3_OCP_RXN<4> PE3_RX_DN<4> @BASEBOARD_FAB2_LIB.BASEBOARD_FAB2(SCH_1):P3E_CPU0_PE3_OCP_RXN(4)
DT19 P3E_CPU0_PE3_OCP_RXN<3> PE3_RX_DN<3> @BASEBOARD_FAB2_LIB.BASEBOARD_FAB2(SCH_1):P3E_CPU0_PE3_OCP_RXN(3)
DW16 P3E_CPU0_PE3_OCP_RXN<2> PE3_RX_DN<2> @BASEBOARD_FAB2_LIB.BASEBOARD_FAB2(SCH_1):P3E_CPU0_PE3_OCP_RXN(2)
DW18 P3E_CPU0_PE3_OCP_RXN<1> PE3_RX_DN<1> @BASEBOARD_FAB2_LIB.BASEBOARD_FAB2(SCH_1):P3E_CPU0_PE3_OCP_RXN(1)
EA18 P3E_CPU0_PE3_OCP_RXN<0> PE3_RX_DN<0> @BASEBOARD_FAB2_LIB.BASEBOARD_FAB2(SCH_1):P3E_CPU0_PE3_OCP_RXN(0)
CU10 P3E_CPU0_PE3_OCP_RXP<15> PE3_RX_DP<15> @BASEBOARD_FAB2_LIB.BASEBOARD_FAB2(SCH_1):P3E_CPU0_PE3_OCP_RXP(15)
CW10 P3E_CPU0_PE3_OCP_RXP<14> PE3_RX_DP<14> @BASEBOARD_FAB2_LIB.BASEBOARD_FAB2(SCH_1):P3E_CPU0_PE3_OCP_RXP(14)
DA12 P3E_CPU0_PE3_OCP_RXP<13> PE3_RX_DP<13> @BASEBOARD_FAB2_LIB.BASEBOARD_FAB2(SCH_1):P3E_CPU0_PE3_OCP_RXP(13)
DC12 P3E_CPU0_PE3_OCP_RXP<12> PE3_RX_DP<12> @BASEBOARD_FAB2_LIB.BASEBOARD_FAB2(SCH_1):P3E_CPU0_PE3_OCP_RXP(12)
DF11 P3E_CPU0_PE3_OCP_RXP<11> PE3_RX_DP<11> @BASEBOARD_FAB2_LIB.BASEBOARD_FAB2(SCH_1):P3E_CPU0_PE3_OCP_RXP(11)
DE12 P3E_CPU0_PE3_OCP_RXP<10> PE3_RX_DP<10> @BASEBOARD_FAB2_LIB.BASEBOARD_FAB2(SCH_1):P3E_CPU0_PE3_OCP_RXP(10)
DH11 P3E_CPU0_PE3_OCP_RXP<9> PE3_RX_DP<9> @BASEBOARD_FAB2_LIB.BASEBOARD_FAB2(SCH_1):P3E_CPU0_PE3_OCP_RXP(9)
DK13 P3E_CPU0_PE3_OCP_RXP<8> PE3_RX_DP<8> @BASEBOARD_FAB2_LIB.BASEBOARD_FAB2(SCH_1):P3E_CPU0_PE3_OCP_RXP(8)
DJ14 P3E_CPU0_PE3_OCP_RXP<7> PE3_RX_DP<7> @BASEBOARD_FAB2_LIB.BASEBOARD_FAB2(SCH_1):P3E_CPU0_PE3_OCP_RXP(7)
DM13 P3E_CPU0_PE3_OCP_RXP<6> PE3_RX_DP<6> @BASEBOARD_FAB2_LIB.BASEBOARD_FAB2(SCH_1):P3E_CPU0_PE3_OCP_RXP(6)
DP15 P3E_CPU0_PE3_OCP_RXP<5> PE3_RX_DP<5> @BASEBOARD_FAB2_LIB.BASEBOARD_FAB2(SCH_1):P3E_CPU0_PE3_OCP_RXP(5)
DN16 P3E_CPU0_PE3_OCP_RXP<4> PE3_RX_DP<4> @BASEBOARD_FAB2_LIB.BASEBOARD_FAB2(SCH_1):P3E_CPU0_PE3_OCP_RXP(4)
DR18 P3E_CPU0_PE3_OCP_RXP<3> PE3_RX_DP<3> @BASEBOARD_FAB2_LIB.BASEBOARD_FAB2(SCH_1):P3E_CPU0_PE3_OCP_RXP(3)
DV17 P3E_CPU0_PE3_OCP_RXP<2> PE3_RX_DP<2> @BASEBOARD_FAB2_LIB.BASEBOARD_FAB2(SCH_1):P3E_CPU0_PE3_OCP_RXP(2)
DU18 P3E_CPU0_PE3_OCP_RXP<1> PE3_RX_DP<1> @BASEBOARD_FAB2_LIB.BASEBOARD_FAB2(SCH_1):P3E_CPU0_PE3_OCP_RXP(1)
DY17 P3E_CPU0_PE3_OCP_RXP<0> PE3_RX_DP<0> @BASEBOARD_FAB2_LIB.BASEBOARD_FAB2(SCH_1):P3E_CPU0_PE3_OCP_RXP(0)
 CY5 P3E_CPU0_PE3_OCP_TXN<15> PE3_TX_DN<15> @BASEBOARD_FAB2_LIB.BASEBOARD_FAB2(SCH_1):P3E_CPU0_PE3_OCP_TXN(15)
 DB5 P3E_CPU0_PE3_OCP_TXN<14> PE3_TX_DN<14> @BASEBOARD_FAB2_LIB.BASEBOARD_FAB2(SCH_1):P3E_CPU0_PE3_OCP_TXN(14)
 DD5 P3E_CPU0_PE3_OCP_TXN<13> PE3_TX_DN<13> @BASEBOARD_FAB2_LIB.BASEBOARD_FAB2(SCH_1):P3E_CPU0_PE3_OCP_TXN(13)
 DJ6 P3E_CPU0_PE3_OCP_TXN<12> PE3_TX_DN<12> @BASEBOARD_FAB2_LIB.BASEBOARD_FAB2(SCH_1):P3E_CPU0_PE3_OCP_TXN(12)
 DJ4 P3E_CPU0_PE3_OCP_TXN<11> PE3_TX_DN<11> @BASEBOARD_FAB2_LIB.BASEBOARD_FAB2(SCH_1):P3E_CPU0_PE3_OCP_TXN(11)
 DL6 P3E_CPU0_PE3_OCP_TXN<10> PE3_TX_DN<10> @BASEBOARD_FAB2_LIB.BASEBOARD_FAB2(SCH_1):P3E_CPU0_PE3_OCP_TXN(10)
 DP5 P3E_CPU0_PE3_OCP_TXN<9> PE3_TX_DN<9> @BASEBOARD_FAB2_LIB.BASEBOARD_FAB2(SCH_1):P3E_CPU0_PE3_OCP_TXN(9)
 DM7 P3E_CPU0_PE3_OCP_TXN<8> PE3_TX_DN<8> @BASEBOARD_FAB2_LIB.BASEBOARD_FAB2(SCH_1):P3E_CPU0_PE3_OCP_TXN(8)
 DR8 P3E_CPU0_PE3_OCP_TXN<7> PE3_TX_DN<7> @BASEBOARD_FAB2_LIB.BASEBOARD_FAB2(SCH_1):P3E_CPU0_PE3_OCP_TXN(7)
 DU8 P3E_CPU0_PE3_OCP_TXN<6> PE3_TX_DN<6> @BASEBOARD_FAB2_LIB.BASEBOARD_FAB2(SCH_1):P3E_CPU0_PE3_OCP_TXN(6)
DW10 P3E_CPU0_PE3_OCP_TXN<5> PE3_TX_DN<5> @BASEBOARD_FAB2_LIB.BASEBOARD_FAB2(SCH_1):P3E_CPU0_PE3_OCP_TXN(5)
 EB9 P3E_CPU0_PE3_OCP_TXN<4> PE3_TX_DN<4> @BASEBOARD_FAB2_LIB.BASEBOARD_FAB2(SCH_1):P3E_CPU0_PE3_OCP_TXN(4)
DY11 P3E_CPU0_PE3_OCP_TXN<3> PE3_TX_DN<3> @BASEBOARD_FAB2_LIB.BASEBOARD_FAB2(SCH_1):P3E_CPU0_PE3_OCP_TXN(3)
EC12 P3E_CPU0_PE3_OCP_TXN<2> PE3_TX_DN<2> @BASEBOARD_FAB2_LIB.BASEBOARD_FAB2(SCH_1):P3E_CPU0_PE3_OCP_TXN(2)
EE12 P3E_CPU0_PE3_OCP_TXN<1> PE3_TX_DN<1> @BASEBOARD_FAB2_LIB.BASEBOARD_FAB2(SCH_1):P3E_CPU0_PE3_OCP_TXN(1)
EE14 P3E_CPU0_PE3_OCP_TXN<0> PE3_TX_DN<0> @BASEBOARD_FAB2_LIB.BASEBOARD_FAB2(SCH_1):P3E_CPU0_PE3_OCP_TXN(0)
 CV5 P3E_CPU0_PE3_OCP_TXP<15> PE3_TX_DP<15> @BASEBOARD_FAB2_LIB.BASEBOARD_FAB2(SCH_1):P3E_CPU0_PE3_OCP_TXP(15)
 DA4 P3E_CPU0_PE3_OCP_TXP<14> PE3_TX_DP<14> @BASEBOARD_FAB2_LIB.BASEBOARD_FAB2(SCH_1):P3E_CPU0_PE3_OCP_TXP(14)
 DC6 P3E_CPU0_PE3_OCP_TXP<13> PE3_TX_DP<13> @BASEBOARD_FAB2_LIB.BASEBOARD_FAB2(SCH_1):P3E_CPU0_PE3_OCP_TXP(13)
 DG6 P3E_CPU0_PE3_OCP_TXP<12> PE3_TX_DP<12> @BASEBOARD_FAB2_LIB.BASEBOARD_FAB2(SCH_1):P3E_CPU0_PE3_OCP_TXP(12)
 DH5 P3E_CPU0_PE3_OCP_TXP<11> PE3_TX_DP<11> @BASEBOARD_FAB2_LIB.BASEBOARD_FAB2(SCH_1):P3E_CPU0_PE3_OCP_TXP(11)
 DK5 P3E_CPU0_PE3_OCP_TXP<10> PE3_TX_DP<10> @BASEBOARD_FAB2_LIB.BASEBOARD_FAB2(SCH_1):P3E_CPU0_PE3_OCP_TXP(10)
 DM5 P3E_CPU0_PE3_OCP_TXP<9> PE3_TX_DP<9> @BASEBOARD_FAB2_LIB.BASEBOARD_FAB2(SCH_1):P3E_CPU0_PE3_OCP_TXP(9)
 DN6 P3E_CPU0_PE3_OCP_TXP<8> PE3_TX_DP<8> @BASEBOARD_FAB2_LIB.BASEBOARD_FAB2(SCH_1):P3E_CPU0_PE3_OCP_TXP(8)
 DP7 P3E_CPU0_PE3_OCP_TXP<7> PE3_TX_DP<7> @BASEBOARD_FAB2_LIB.BASEBOARD_FAB2(SCH_1):P3E_CPU0_PE3_OCP_TXP(7)
 DT9 P3E_CPU0_PE3_OCP_TXP<6> PE3_TX_DP<6> @BASEBOARD_FAB2_LIB.BASEBOARD_FAB2(SCH_1):P3E_CPU0_PE3_OCP_TXP(6)
 DV9 P3E_CPU0_PE3_OCP_TXP<5> PE3_TX_DP<5> @BASEBOARD_FAB2_LIB.BASEBOARD_FAB2(SCH_1):P3E_CPU0_PE3_OCP_TXP(5)
 DY9 P3E_CPU0_PE3_OCP_TXP<4> PE3_TX_DP<4> @BASEBOARD_FAB2_LIB.BASEBOARD_FAB2(SCH_1):P3E_CPU0_PE3_OCP_TXP(4)
EA10 P3E_CPU0_PE3_OCP_TXP<3> PE3_TX_DP<3> @BASEBOARD_FAB2_LIB.BASEBOARD_FAB2(SCH_1):P3E_CPU0_PE3_OCP_TXP(3)
EB11 P3E_CPU0_PE3_OCP_TXP<2> PE3_TX_DP<2> @BASEBOARD_FAB2_LIB.BASEBOARD_FAB2(SCH_1):P3E_CPU0_PE3_OCP_TXP(2)
ED13 P3E_CPU0_PE3_OCP_TXP<1> PE3_TX_DP<1> @BASEBOARD_FAB2_LIB.BASEBOARD_FAB2(SCH_1):P3E_CPU0_PE3_OCP_TXP(1)
EC14 P3E_CPU0_PE3_OCP_TXP<0> PE3_TX_DP<0> @BASEBOARD_FAB2_LIB.BASEBOARD_FAB2(SCH_1):P3E_CPU0_PE3_OCP_TXP(0)


DRAWING: @BASEBOARD_FAB2_LIB.BASEBOARD_FAB2(SCH_1):PAGE33 

SKX_EXT_B_BGA1-IC,TBD  I86  U5D1
BB11 UPI_CPU1_CPU0_P0P0_DN<0> UPI0_RX_DN<19> @BASEBOARD_FAB2_LIB.BASEBOARD_FAB2(SCH_1):UPI_CPU1_CPU0_P0P0_DN(0)
 BD9 UPI_CPU1_CPU0_P0P0_DN<1> UPI0_RX_DN<18> @BASEBOARD_FAB2_LIB.BASEBOARD_FAB2(SCH_1):UPI_CPU1_CPU0_P0P0_DN(1)
 AY9 UPI_CPU1_CPU0_P0P0_DN<2> UPI0_RX_DN<17> @BASEBOARD_FAB2_LIB.BASEBOARD_FAB2(SCH_1):UPI_CPU1_CPU0_P0P0_DN(2)
 AW8 UPI_CPU1_CPU0_P0P0_DN<3> UPI0_RX_DN<16> @BASEBOARD_FAB2_LIB.BASEBOARD_FAB2(SCH_1):UPI_CPU1_CPU0_P0P0_DN(3)
 BD7 UPI_CPU1_CPU0_P0P0_DN<4> UPI0_RX_DN<15> @BASEBOARD_FAB2_LIB.BASEBOARD_FAB2(SCH_1):UPI_CPU1_CPU0_P0P0_DN(4)
 BC6 UPI_CPU1_CPU0_P0P0_DN<5> UPI0_RX_DN<14> @BASEBOARD_FAB2_LIB.BASEBOARD_FAB2(SCH_1):UPI_CPU1_CPU0_P0P0_DN(5)
 BA8 UPI_CPU1_CPU0_P0P0_DN<6> UPI0_RX_DN<13> @BASEBOARD_FAB2_LIB.BASEBOARD_FAB2(SCH_1):UPI_CPU1_CPU0_P0P0_DN(6)
AU10 UPI_CPU1_CPU0_P0P0_DN<7> UPI0_RX_DN<12> @BASEBOARD_FAB2_LIB.BASEBOARD_FAB2(SCH_1):UPI_CPU1_CPU0_P0P0_DN(7)
 AR8 UPI_CPU1_CPU0_P0P0_DN<8> UPI0_RX_DN<11> @BASEBOARD_FAB2_LIB.BASEBOARD_FAB2(SCH_1):UPI_CPU1_CPU0_P0P0_DN(8)
 AP7 UPI_CPU1_CPU0_P0P0_DN<9> UPI0_RX_DN<10> @BASEBOARD_FAB2_LIB.BASEBOARD_FAB2(SCH_1):UPI_CPU1_CPU0_P0P0_DN(9)
 AM9 UPI_CPU1_CPU0_P0P0_DN<10> UPI0_RX_DN<9> @BASEBOARD_FAB2_LIB.BASEBOARD_FAB2(SCH_1):UPI_CPU1_CPU0_P0P0_DN(10)
 AK7 UPI_CPU1_CPU0_P0P0_DN<11> UPI0_RX_DN<8> @BASEBOARD_FAB2_LIB.BASEBOARD_FAB2(SCH_1):UPI_CPU1_CPU0_P0P0_DN(11)
 AL6 UPI_CPU1_CPU0_P0P0_DN<12> UPI0_RX_DN<7> @BASEBOARD_FAB2_LIB.BASEBOARD_FAB2(SCH_1):UPI_CPU1_CPU0_P0P0_DN(12)
 AJ6 UPI_CPU1_CPU0_P0P0_DN<13> UPI0_RX_DN<6> @BASEBOARD_FAB2_LIB.BASEBOARD_FAB2(SCH_1):UPI_CPU1_CPU0_P0P0_DN(13)
 AG8 UPI_CPU1_CPU0_P0P0_DN<14> UPI0_RX_DN<5> @BASEBOARD_FAB2_LIB.BASEBOARD_FAB2(SCH_1):UPI_CPU1_CPU0_P0P0_DN(14)
 AE6 UPI_CPU1_CPU0_P0P0_DN<15> UPI0_RX_DN<4> @BASEBOARD_FAB2_LIB.BASEBOARD_FAB2(SCH_1):UPI_CPU1_CPU0_P0P0_DN(15)
 AD5 UPI_CPU1_CPU0_P0P0_DN<16> UPI0_RX_DN<3> @BASEBOARD_FAB2_LIB.BASEBOARD_FAB2(SCH_1):UPI_CPU1_CPU0_P0P0_DN(16)
 AB7 UPI_CPU1_CPU0_P0P0_DN<17> UPI0_RX_DN<2> @BASEBOARD_FAB2_LIB.BASEBOARD_FAB2(SCH_1):UPI_CPU1_CPU0_P0P0_DN(17)
 AA8 UPI_CPU1_CPU0_P0P0_DN<18> UPI0_RX_DN<1> @BASEBOARD_FAB2_LIB.BASEBOARD_FAB2(SCH_1):UPI_CPU1_CPU0_P0P0_DN(18)
AC10 UPI_CPU1_CPU0_P0P0_DN<19> UPI0_RX_DN<0> @BASEBOARD_FAB2_LIB.BASEBOARD_FAB2(SCH_1):UPI_CPU1_CPU0_P0P0_DN(19)
BA10 UPI_CPU1_CPU0_P0P0_DP<0> UPI0_RX_DP<19> @BASEBOARD_FAB2_LIB.BASEBOARD_FAB2(SCH_1):UPI_CPU1_CPU0_P0P0_DP(0)
BC10 UPI_CPU1_CPU0_P0P0_DP<1> UPI0_RX_DP<18> @BASEBOARD_FAB2_LIB.BASEBOARD_FAB2(SCH_1):UPI_CPU1_CPU0_P0P0_DP(1)
 BB9 UPI_CPU1_CPU0_P0P0_DP<2> UPI0_RX_DP<17> @BASEBOARD_FAB2_LIB.BASEBOARD_FAB2(SCH_1):UPI_CPU1_CPU0_P0P0_DP(2)
 AV9 UPI_CPU1_CPU0_P0P0_DP<3> UPI0_RX_DP<16> @BASEBOARD_FAB2_LIB.BASEBOARD_FAB2(SCH_1):UPI_CPU1_CPU0_P0P0_DP(3)
 BF7 UPI_CPU1_CPU0_P0P0_DP<4> UPI0_RX_DP<15> @BASEBOARD_FAB2_LIB.BASEBOARD_FAB2(SCH_1):UPI_CPU1_CPU0_P0P0_DP(4)
 BB7 UPI_CPU1_CPU0_P0P0_DP<5> UPI0_RX_DP<14> @BASEBOARD_FAB2_LIB.BASEBOARD_FAB2(SCH_1):UPI_CPU1_CPU0_P0P0_DP(5)
 AY7 UPI_CPU1_CPU0_P0P0_DP<6> UPI0_RX_DP<13> @BASEBOARD_FAB2_LIB.BASEBOARD_FAB2(SCH_1):UPI_CPU1_CPU0_P0P0_DP(6)
 AT9 UPI_CPU1_CPU0_P0P0_DP<7> UPI0_RX_DP<12> @BASEBOARD_FAB2_LIB.BASEBOARD_FAB2(SCH_1):UPI_CPU1_CPU0_P0P0_DP(7)
 AU8 UPI_CPU1_CPU0_P0P0_DP<8> UPI0_RX_DP<11> @BASEBOARD_FAB2_LIB.BASEBOARD_FAB2(SCH_1):UPI_CPU1_CPU0_P0P0_DP(8)
 AN8 UPI_CPU1_CPU0_P0P0_DP<9> UPI0_RX_DP<10> @BASEBOARD_FAB2_LIB.BASEBOARD_FAB2(SCH_1):UPI_CPU1_CPU0_P0P0_DP(9)
 AL8 UPI_CPU1_CPU0_P0P0_DP<10> UPI0_RX_DP<9> @BASEBOARD_FAB2_LIB.BASEBOARD_FAB2(SCH_1):UPI_CPU1_CPU0_P0P0_DP(10)
 AM7 UPI_CPU1_CPU0_P0P0_DP<11> UPI0_RX_DP<8> @BASEBOARD_FAB2_LIB.BASEBOARD_FAB2(SCH_1):UPI_CPU1_CPU0_P0P0_DP(11)
 AK5 UPI_CPU1_CPU0_P0P0_DP<12> UPI0_RX_DP<7> @BASEBOARD_FAB2_LIB.BASEBOARD_FAB2(SCH_1):UPI_CPU1_CPU0_P0P0_DP(12)
 AH7 UPI_CPU1_CPU0_P0P0_DP<13> UPI0_RX_DP<6> @BASEBOARD_FAB2_LIB.BASEBOARD_FAB2(SCH_1):UPI_CPU1_CPU0_P0P0_DP(13)
 AF7 UPI_CPU1_CPU0_P0P0_DP<14> UPI0_RX_DP<5> @BASEBOARD_FAB2_LIB.BASEBOARD_FAB2(SCH_1):UPI_CPU1_CPU0_P0P0_DP(14)
 AG6 UPI_CPU1_CPU0_P0P0_DP<15> UPI0_RX_DP<4> @BASEBOARD_FAB2_LIB.BASEBOARD_FAB2(SCH_1):UPI_CPU1_CPU0_P0P0_DP(15)
 AC6 UPI_CPU1_CPU0_P0P0_DP<16> UPI0_RX_DP<3> @BASEBOARD_FAB2_LIB.BASEBOARD_FAB2(SCH_1):UPI_CPU1_CPU0_P0P0_DP(16)
 AA6 UPI_CPU1_CPU0_P0P0_DP<17> UPI0_RX_DP<2> @BASEBOARD_FAB2_LIB.BASEBOARD_FAB2(SCH_1):UPI_CPU1_CPU0_P0P0_DP(17)
 AC8 UPI_CPU1_CPU0_P0P0_DP<18> UPI0_RX_DP<1> @BASEBOARD_FAB2_LIB.BASEBOARD_FAB2(SCH_1):UPI_CPU1_CPU0_P0P0_DP(18)
 AB9 UPI_CPU1_CPU0_P0P0_DP<19> UPI0_RX_DP<0> @BASEBOARD_FAB2_LIB.BASEBOARD_FAB2(SCH_1):UPI_CPU1_CPU0_P0P0_DP(19)
 BG4 UPI_CPU0_CPU1_P0P0_DN<0> UPI0_TX_DN<19> @BASEBOARD_FAB2_LIB.BASEBOARD_FAB2(SCH_1):UPI_CPU0_CPU1_P0P0_DN(0)
 BF3 UPI_CPU0_CPU1_P0P0_DN<1> UPI0_TX_DN<18> @BASEBOARD_FAB2_LIB.BASEBOARD_FAB2(SCH_1):UPI_CPU0_CPU1_P0P0_DN(1)
 BB3 UPI_CPU0_CPU1_P0P0_DN<2> UPI0_TX_DN<17> @BASEBOARD_FAB2_LIB.BASEBOARD_FAB2(SCH_1):UPI_CPU0_CPU1_P0P0_DN(2)
 BA4 UPI_CPU0_CPU1_P0P0_DN<3> UPI0_TX_DN<16> @BASEBOARD_FAB2_LIB.BASEBOARD_FAB2(SCH_1):UPI_CPU0_CPU1_P0P0_DN(3)
 AV5 UPI_CPU0_CPU1_P0P0_DN<4> UPI0_TX_DN<15> @BASEBOARD_FAB2_LIB.BASEBOARD_FAB2(SCH_1):UPI_CPU0_CPU1_P0P0_DN(4)
 AU4 UPI_CPU0_CPU1_P0P0_DN<5> UPI0_TX_DN<14> @BASEBOARD_FAB2_LIB.BASEBOARD_FAB2(SCH_1):UPI_CPU0_CPU1_P0P0_DN(5)
 AT3 UPI_CPU0_CPU1_P0P0_DN<6> UPI0_TX_DN<13> @BASEBOARD_FAB2_LIB.BASEBOARD_FAB2(SCH_1):UPI_CPU0_CPU1_P0P0_DN(6)
 AT1 UPI_CPU0_CPU1_P0P0_DN<7> UPI0_TX_DN<12> @BASEBOARD_FAB2_LIB.BASEBOARD_FAB2(SCH_1):UPI_CPU0_CPU1_P0P0_DN(7)
 AN4 UPI_CPU0_CPU1_P0P0_DN<8> UPI0_TX_DN<11> @BASEBOARD_FAB2_LIB.BASEBOARD_FAB2(SCH_1):UPI_CPU0_CPU1_P0P0_DN(8)
 AM3 UPI_CPU0_CPU1_P0P0_DN<9> UPI0_TX_DN<10> @BASEBOARD_FAB2_LIB.BASEBOARD_FAB2(SCH_1):UPI_CPU0_CPU1_P0P0_DN(9)
 AL2 UPI_CPU0_CPU1_P0P0_DN<10> UPI0_TX_DN<9> @BASEBOARD_FAB2_LIB.BASEBOARD_FAB2(SCH_1):UPI_CPU0_CPU1_P0P0_DN(10)
 AH3 UPI_CPU0_CPU1_P0P0_DN<11> UPI0_TX_DN<8> @BASEBOARD_FAB2_LIB.BASEBOARD_FAB2(SCH_1):UPI_CPU0_CPU1_P0P0_DN(11)
 AE2 UPI_CPU0_CPU1_P0P0_DN<12> UPI0_TX_DN<7> @BASEBOARD_FAB2_LIB.BASEBOARD_FAB2(SCH_1):UPI_CPU0_CPU1_P0P0_DN(12)
 AG4 UPI_CPU0_CPU1_P0P0_DN<13> UPI0_TX_DN<6> @BASEBOARD_FAB2_LIB.BASEBOARD_FAB2(SCH_1):UPI_CPU0_CPU1_P0P0_DN(13)
 AC2 UPI_CPU0_CPU1_P0P0_DN<14> UPI0_TX_DN<5> @BASEBOARD_FAB2_LIB.BASEBOARD_FAB2(SCH_1):UPI_CPU0_CPU1_P0P0_DN(14)
 AB3 UPI_CPU0_CPU1_P0P0_DN<15> UPI0_TX_DN<4> @BASEBOARD_FAB2_LIB.BASEBOARD_FAB2(SCH_1):UPI_CPU0_CPU1_P0P0_DN(15)
  Y1 UPI_CPU0_CPU1_P0P0_DN<16> UPI0_TX_DN<3> @BASEBOARD_FAB2_LIB.BASEBOARD_FAB2(SCH_1):UPI_CPU0_CPU1_P0P0_DN(16)
  V3 UPI_CPU0_CPU1_P0P0_DN<17> UPI0_TX_DN<2> @BASEBOARD_FAB2_LIB.BASEBOARD_FAB2(SCH_1):UPI_CPU0_CPU1_P0P0_DN(17)
  P1 UPI_CPU0_CPU1_P0P0_DN<18> UPI0_TX_DN<1> @BASEBOARD_FAB2_LIB.BASEBOARD_FAB2(SCH_1):UPI_CPU0_CPU1_P0P0_DN(18)
  N2 UPI_CPU0_CPU1_P0P0_DN<19> UPI0_TX_DN<0> @BASEBOARD_FAB2_LIB.BASEBOARD_FAB2(SCH_1):UPI_CPU0_CPU1_P0P0_DN(19)
 BH3 UPI_CPU0_CPU1_P0P0_DP<0> UPI0_TX_DP<19> @BASEBOARD_FAB2_LIB.BASEBOARD_FAB2(SCH_1):UPI_CPU0_CPU1_P0P0_DP(0)
 BD3 UPI_CPU0_CPU1_P0P0_DP<1> UPI0_TX_DP<18> @BASEBOARD_FAB2_LIB.BASEBOARD_FAB2(SCH_1):UPI_CPU0_CPU1_P0P0_DP(1)
 BC2 UPI_CPU0_CPU1_P0P0_DP<2> UPI0_TX_DP<17> @BASEBOARD_FAB2_LIB.BASEBOARD_FAB2(SCH_1):UPI_CPU0_CPU1_P0P0_DP(2)
 AY3 UPI_CPU0_CPU1_P0P0_DP<3> UPI0_TX_DP<16> @BASEBOARD_FAB2_LIB.BASEBOARD_FAB2(SCH_1):UPI_CPU0_CPU1_P0P0_DP(3)
 AW4 UPI_CPU0_CPU1_P0P0_DP<4> UPI0_TX_DP<15> @BASEBOARD_FAB2_LIB.BASEBOARD_FAB2(SCH_1):UPI_CPU0_CPU1_P0P0_DP(4)
 AR4 UPI_CPU0_CPU1_P0P0_DP<5> UPI0_TX_DP<14> @BASEBOARD_FAB2_LIB.BASEBOARD_FAB2(SCH_1):UPI_CPU0_CPU1_P0P0_DP(5)
 AR2 UPI_CPU0_CPU1_P0P0_DP<6> UPI0_TX_DP<13> @BASEBOARD_FAB2_LIB.BASEBOARD_FAB2(SCH_1):UPI_CPU0_CPU1_P0P0_DP(6)
 AP1 UPI_CPU0_CPU1_P0P0_DP<7> UPI0_TX_DP<12> @BASEBOARD_FAB2_LIB.BASEBOARD_FAB2(SCH_1):UPI_CPU0_CPU1_P0P0_DP(7)
 AP3 UPI_CPU0_CPU1_P0P0_DP<8> UPI0_TX_DP<11> @BASEBOARD_FAB2_LIB.BASEBOARD_FAB2(SCH_1):UPI_CPU0_CPU1_P0P0_DP(8)
 AK3 UPI_CPU0_CPU1_P0P0_DP<9> UPI0_TX_DP<10> @BASEBOARD_FAB2_LIB.BASEBOARD_FAB2(SCH_1):UPI_CPU0_CPU1_P0P0_DP(9)
 AK1 UPI_CPU0_CPU1_P0P0_DP<10> UPI0_TX_DP<9> @BASEBOARD_FAB2_LIB.BASEBOARD_FAB2(SCH_1):UPI_CPU0_CPU1_P0P0_DP(10)
 AJ2 UPI_CPU0_CPU1_P0P0_DP<11> UPI0_TX_DP<8> @BASEBOARD_FAB2_LIB.BASEBOARD_FAB2(SCH_1):UPI_CPU0_CPU1_P0P0_DP(11)
 AG2 UPI_CPU0_CPU1_P0P0_DP<12> UPI0_TX_DP<7> @BASEBOARD_FAB2_LIB.BASEBOARD_FAB2(SCH_1):UPI_CPU0_CPU1_P0P0_DP(12)
 AF3 UPI_CPU0_CPU1_P0P0_DP<13> UPI0_TX_DP<6> @BASEBOARD_FAB2_LIB.BASEBOARD_FAB2(SCH_1):UPI_CPU0_CPU1_P0P0_DP(13)
 AD1 UPI_CPU0_CPU1_P0P0_DP<14> UPI0_TX_DP<5> @BASEBOARD_FAB2_LIB.BASEBOARD_FAB2(SCH_1):UPI_CPU0_CPU1_P0P0_DP(14)
 AA2 UPI_CPU0_CPU1_P0P0_DP<15> UPI0_TX_DP<4> @BASEBOARD_FAB2_LIB.BASEBOARD_FAB2(SCH_1):UPI_CPU0_CPU1_P0P0_DP(15)
  W2 UPI_CPU0_CPU1_P0P0_DP<16> UPI0_TX_DP<3> @BASEBOARD_FAB2_LIB.BASEBOARD_FAB2(SCH_1):UPI_CPU0_CPU1_P0P0_DP(16)
  Y3 UPI_CPU0_CPU1_P0P0_DP<17> UPI0_TX_DP<2> @BASEBOARD_FAB2_LIB.BASEBOARD_FAB2(SCH_1):UPI_CPU0_CPU1_P0P0_DP(17)
  T1 UPI_CPU0_CPU1_P0P0_DP<18> UPI0_TX_DP<1> @BASEBOARD_FAB2_LIB.BASEBOARD_FAB2(SCH_1):UPI_CPU0_CPU1_P0P0_DP(18)
  M1 UPI_CPU0_CPU1_P0P0_DP<19> UPI0_TX_DP<0> @BASEBOARD_FAB2_LIB.BASEBOARD_FAB2(SCH_1):UPI_CPU0_CPU1_P0P0_DP(19)


DRAWING: @BASEBOARD_FAB2_LIB.BASEBOARD_FAB2(SCH_1):PAGE34 

SKX_EXT_B_BGA1-IC,TBD  I86  U5D1
AB19 UPI_CPU1_CPU0_P1P1_DN<0> UPI1_RX_DN<19> @BASEBOARD_FAB2_LIB.BASEBOARD_FAB2(SCH_1):UPI_CPU1_CPU0_P1P1_DN(0)
 Y21 UPI_CPU1_CPU0_P1P1_DN<1> UPI1_RX_DN<18> @BASEBOARD_FAB2_LIB.BASEBOARD_FAB2(SCH_1):UPI_CPU1_CPU0_P1P1_DN(1)
 V19 UPI_CPU1_CPU0_P1P1_DN<2> UPI1_RX_DN<17> @BASEBOARD_FAB2_LIB.BASEBOARD_FAB2(SCH_1):UPI_CPU1_CPU0_P1P1_DN(2)
 P21 UPI_CPU1_CPU0_P1P1_DN<3> UPI1_RX_DN<16> @BASEBOARD_FAB2_LIB.BASEBOARD_FAB2(SCH_1):UPI_CPU1_CPU0_P1P1_DN(3)
 U18 UPI_CPU1_CPU0_P1P1_DN<4> UPI1_RX_DN<15> @BASEBOARD_FAB2_LIB.BASEBOARD_FAB2(SCH_1):UPI_CPU1_CPU0_P1P1_DN(4)
 R20 UPI_CPU1_CPU0_P1P1_DN<5> UPI1_RX_DN<14> @BASEBOARD_FAB2_LIB.BASEBOARD_FAB2(SCH_1):UPI_CPU1_CPU0_P1P1_DN(5)
 W18 UPI_CPU1_CPU0_P1P1_DN<6> UPI1_RX_DN<13> @BASEBOARD_FAB2_LIB.BASEBOARD_FAB2(SCH_1):UPI_CPU1_CPU0_P1P1_DN(6)
 U16 UPI_CPU1_CPU0_P1P1_DN<7> UPI1_RX_DN<12> @BASEBOARD_FAB2_LIB.BASEBOARD_FAB2(SCH_1):UPI_CPU1_CPU0_P1P1_DN(7)
 P17 UPI_CPU1_CPU0_P1P1_DN<8> UPI1_RX_DN<11> @BASEBOARD_FAB2_LIB.BASEBOARD_FAB2(SCH_1):UPI_CPU1_CPU0_P1P1_DN(8)
 R16 UPI_CPU1_CPU0_P1P1_DN<9> UPI1_RX_DN<10> @BASEBOARD_FAB2_LIB.BASEBOARD_FAB2(SCH_1):UPI_CPU1_CPU0_P1P1_DN(9)
 R12 UPI_CPU1_CPU0_P1P1_DN<10> UPI1_RX_DN<9> @BASEBOARD_FAB2_LIB.BASEBOARD_FAB2(SCH_1):UPI_CPU1_CPU0_P1P1_DN(10)
 N14 UPI_CPU1_CPU0_P1P1_DN<11> UPI1_RX_DN<8> @BASEBOARD_FAB2_LIB.BASEBOARD_FAB2(SCH_1):UPI_CPU1_CPU0_P1P1_DN(11)
 L12 UPI_CPU1_CPU0_P1P1_DN<12> UPI1_RX_DN<7> @BASEBOARD_FAB2_LIB.BASEBOARD_FAB2(SCH_1):UPI_CPU1_CPU0_P1P1_DN(12)
 U12 UPI_CPU1_CPU0_P1P1_DN<13> UPI1_RX_DN<6> @BASEBOARD_FAB2_LIB.BASEBOARD_FAB2(SCH_1):UPI_CPU1_CPU0_P1P1_DN(13)
 R10 UPI_CPU1_CPU0_P1P1_DN<14> UPI1_RX_DN<5> @BASEBOARD_FAB2_LIB.BASEBOARD_FAB2(SCH_1):UPI_CPU1_CPU0_P1P1_DN(14)
  P9 UPI_CPU1_CPU0_P1P1_DN<15> UPI1_RX_DN<4> @BASEBOARD_FAB2_LIB.BASEBOARD_FAB2(SCH_1):UPI_CPU1_CPU0_P1P1_DN(15)
  T9 UPI_CPU1_CPU0_P1P1_DN<16> UPI1_RX_DN<3> @BASEBOARD_FAB2_LIB.BASEBOARD_FAB2(SCH_1):UPI_CPU1_CPU0_P1P1_DN(16)
  V7 UPI_CPU1_CPU0_P1P1_DN<17> UPI1_RX_DN<2> @BASEBOARD_FAB2_LIB.BASEBOARD_FAB2(SCH_1):UPI_CPU1_CPU0_P1P1_DN(17)
  P7 UPI_CPU1_CPU0_P1P1_DN<18> UPI1_RX_DN<1> @BASEBOARD_FAB2_LIB.BASEBOARD_FAB2(SCH_1):UPI_CPU1_CPU0_P1P1_DN(18)
  T5 UPI_CPU1_CPU0_P1P1_DN<19> UPI1_RX_DN<0> @BASEBOARD_FAB2_LIB.BASEBOARD_FAB2(SCH_1):UPI_CPU1_CPU0_P1P1_DN(19)
AA20 UPI_CPU1_CPU0_P1P1_DP<0> UPI1_RX_DP<19> @BASEBOARD_FAB2_LIB.BASEBOARD_FAB2(SCH_1):UPI_CPU1_CPU0_P1P1_DP(0)
 W20 UPI_CPU1_CPU0_P1P1_DP<1> UPI1_RX_DP<18> @BASEBOARD_FAB2_LIB.BASEBOARD_FAB2(SCH_1):UPI_CPU1_CPU0_P1P1_DP(1)
 Y19 UPI_CPU1_CPU0_P1P1_DP<2> UPI1_RX_DP<17> @BASEBOARD_FAB2_LIB.BASEBOARD_FAB2(SCH_1):UPI_CPU1_CPU0_P1P1_DP(2)
 T21 UPI_CPU1_CPU0_P1P1_DP<3> UPI1_RX_DP<16> @BASEBOARD_FAB2_LIB.BASEBOARD_FAB2(SCH_1):UPI_CPU1_CPU0_P1P1_DP(3)
 T19 UPI_CPU1_CPU0_P1P1_DP<4> UPI1_RX_DP<15> @BASEBOARD_FAB2_LIB.BASEBOARD_FAB2(SCH_1):UPI_CPU1_CPU0_P1P1_DP(4)
 P19 UPI_CPU1_CPU0_P1P1_DP<5> UPI1_RX_DP<14> @BASEBOARD_FAB2_LIB.BASEBOARD_FAB2(SCH_1):UPI_CPU1_CPU0_P1P1_DP(5)
 V17 UPI_CPU1_CPU0_P1P1_DP<6> UPI1_RX_DP<13> @BASEBOARD_FAB2_LIB.BASEBOARD_FAB2(SCH_1):UPI_CPU1_CPU0_P1P1_DP(6)
 W16 UPI_CPU1_CPU0_P1P1_DP<7> UPI1_RX_DP<12> @BASEBOARD_FAB2_LIB.BASEBOARD_FAB2(SCH_1):UPI_CPU1_CPU0_P1P1_DP(7)
 N16 UPI_CPU1_CPU0_P1P1_DP<8> UPI1_RX_DP<11> @BASEBOARD_FAB2_LIB.BASEBOARD_FAB2(SCH_1):UPI_CPU1_CPU0_P1P1_DP(8)
 T15 UPI_CPU1_CPU0_P1P1_DP<9> UPI1_RX_DP<10> @BASEBOARD_FAB2_LIB.BASEBOARD_FAB2(SCH_1):UPI_CPU1_CPU0_P1P1_DP(9)
 P13 UPI_CPU1_CPU0_P1P1_DP<10> UPI1_RX_DP<9> @BASEBOARD_FAB2_LIB.BASEBOARD_FAB2(SCH_1):UPI_CPU1_CPU0_P1P1_DP(10)
 M13 UPI_CPU1_CPU0_P1P1_DP<11> UPI1_RX_DP<8> @BASEBOARD_FAB2_LIB.BASEBOARD_FAB2(SCH_1):UPI_CPU1_CPU0_P1P1_DP(11)
 N12 UPI_CPU1_CPU0_P1P1_DP<12> UPI1_RX_DP<7> @BASEBOARD_FAB2_LIB.BASEBOARD_FAB2(SCH_1):UPI_CPU1_CPU0_P1P1_DP(12)
 T11 UPI_CPU1_CPU0_P1P1_DP<13> UPI1_RX_DP<6> @BASEBOARD_FAB2_LIB.BASEBOARD_FAB2(SCH_1):UPI_CPU1_CPU0_P1P1_DP(13)
 U10 UPI_CPU1_CPU0_P1P1_DP<14> UPI1_RX_DP<5> @BASEBOARD_FAB2_LIB.BASEBOARD_FAB2(SCH_1):UPI_CPU1_CPU0_P1P1_DP(14)
 N10 UPI_CPU1_CPU0_P1P1_DP<15> UPI1_RX_DP<4> @BASEBOARD_FAB2_LIB.BASEBOARD_FAB2(SCH_1):UPI_CPU1_CPU0_P1P1_DP(15)
  R8 UPI_CPU1_CPU0_P1P1_DP<16> UPI1_RX_DP<3> @BASEBOARD_FAB2_LIB.BASEBOARD_FAB2(SCH_1):UPI_CPU1_CPU0_P1P1_DP(16)
  U8 UPI_CPU1_CPU0_P1P1_DP<17> UPI1_RX_DP<2> @BASEBOARD_FAB2_LIB.BASEBOARD_FAB2(SCH_1):UPI_CPU1_CPU0_P1P1_DP(17)
  T7 UPI_CPU1_CPU0_P1P1_DP<18> UPI1_RX_DP<1> @BASEBOARD_FAB2_LIB.BASEBOARD_FAB2(SCH_1):UPI_CPU1_CPU0_P1P1_DP(18)
  R6 UPI_CPU1_CPU0_P1P1_DP<19> UPI1_RX_DP<0> @BASEBOARD_FAB2_LIB.BASEBOARD_FAB2(SCH_1):UPI_CPU1_CPU0_P1P1_DP(19)
 H21 UPI_CPU0_CPU1_P1P1_DN<0> UPI1_TX_DN<19> @BASEBOARD_FAB2_LIB.BASEBOARD_FAB2(SCH_1):UPI_CPU0_CPU1_P1P1_DN(0)
 F21 UPI_CPU0_CPU1_P1P1_DN<1> UPI1_TX_DN<18> @BASEBOARD_FAB2_LIB.BASEBOARD_FAB2(SCH_1):UPI_CPU0_CPU1_P1P1_DN(1)
 J20 UPI_CPU0_CPU1_P1P1_DN<2> UPI1_TX_DN<17> @BASEBOARD_FAB2_LIB.BASEBOARD_FAB2(SCH_1):UPI_CPU0_CPU1_P1P1_DN(2)
 G18 UPI_CPU0_CPU1_P1P1_DN<3> UPI1_TX_DN<16> @BASEBOARD_FAB2_LIB.BASEBOARD_FAB2(SCH_1):UPI_CPU0_CPU1_P1P1_DN(3)
 K19 UPI_CPU0_CPU1_P1P1_DN<4> UPI1_TX_DN<15> @BASEBOARD_FAB2_LIB.BASEBOARD_FAB2(SCH_1):UPI_CPU0_CPU1_P1P1_DN(4)
 H17 UPI_CPU0_CPU1_P1P1_DN<5> UPI1_TX_DN<14> @BASEBOARD_FAB2_LIB.BASEBOARD_FAB2(SCH_1):UPI_CPU0_CPU1_P1P1_DN(5)
 F15 UPI_CPU0_CPU1_P1P1_DN<6> UPI1_TX_DN<13> @BASEBOARD_FAB2_LIB.BASEBOARD_FAB2(SCH_1):UPI_CPU0_CPU1_P1P1_DN(6)
 D15 UPI_CPU0_CPU1_P1P1_DN<7> UPI1_TX_DN<12> @BASEBOARD_FAB2_LIB.BASEBOARD_FAB2(SCH_1):UPI_CPU0_CPU1_P1P1_DN(7)
 G14 UPI_CPU0_CPU1_P1P1_DN<8> UPI1_TX_DN<11> @BASEBOARD_FAB2_LIB.BASEBOARD_FAB2(SCH_1):UPI_CPU0_CPU1_P1P1_DN(8)
 E12 UPI_CPU0_CPU1_P1P1_DN<9> UPI1_TX_DN<10> @BASEBOARD_FAB2_LIB.BASEBOARD_FAB2(SCH_1):UPI_CPU0_CPU1_P1P1_DN(9)
 G10 UPI_CPU0_CPU1_P1P1_DN<10> UPI1_TX_DN<9> @BASEBOARD_FAB2_LIB.BASEBOARD_FAB2(SCH_1):UPI_CPU0_CPU1_P1P1_DN(10)
 F11 UPI_CPU0_CPU1_P1P1_DN<11> UPI1_TX_DN<8> @BASEBOARD_FAB2_LIB.BASEBOARD_FAB2(SCH_1):UPI_CPU0_CPU1_P1P1_DN(11)
  D9 UPI_CPU0_CPU1_P1P1_DN<12> UPI1_TX_DN<7> @BASEBOARD_FAB2_LIB.BASEBOARD_FAB2(SCH_1):UPI_CPU0_CPU1_P1P1_DN(12)
  K9 UPI_CPU0_CPU1_P1P1_DN<13> UPI1_TX_DN<6> @BASEBOARD_FAB2_LIB.BASEBOARD_FAB2(SCH_1):UPI_CPU0_CPU1_P1P1_DN(13)
  H7 UPI_CPU0_CPU1_P1P1_DN<14> UPI1_TX_DN<5> @BASEBOARD_FAB2_LIB.BASEBOARD_FAB2(SCH_1):UPI_CPU0_CPU1_P1P1_DN(14)
  G6 UPI_CPU0_CPU1_P1P1_DN<15> UPI1_TX_DN<4> @BASEBOARD_FAB2_LIB.BASEBOARD_FAB2(SCH_1):UPI_CPU0_CPU1_P1P1_DN(15)
  J6 UPI_CPU0_CPU1_P1P1_DN<16> UPI1_TX_DN<3> @BASEBOARD_FAB2_LIB.BASEBOARD_FAB2(SCH_1):UPI_CPU0_CPU1_P1P1_DN(16)
  K5 UPI_CPU0_CPU1_P1P1_DN<17> UPI1_TX_DN<2> @BASEBOARD_FAB2_LIB.BASEBOARD_FAB2(SCH_1):UPI_CPU0_CPU1_P1P1_DN(17)
  L4 UPI_CPU0_CPU1_P1P1_DN<18> UPI1_TX_DN<1> @BASEBOARD_FAB2_LIB.BASEBOARD_FAB2(SCH_1):UPI_CPU0_CPU1_P1P1_DN(18)
  M3 UPI_CPU0_CPU1_P1P1_DN<19> UPI1_TX_DN<0> @BASEBOARD_FAB2_LIB.BASEBOARD_FAB2(SCH_1):UPI_CPU0_CPU1_P1P1_DN(19)
 K21 UPI_CPU0_CPU1_P1P1_DP<0> UPI1_TX_DP<19> @BASEBOARD_FAB2_LIB.BASEBOARD_FAB2(SCH_1):UPI_CPU0_CPU1_P1P1_DP(0)
 G20 UPI_CPU0_CPU1_P1P1_DP<1> UPI1_TX_DP<18> @BASEBOARD_FAB2_LIB.BASEBOARD_FAB2(SCH_1):UPI_CPU0_CPU1_P1P1_DP(1)
 H19 UPI_CPU0_CPU1_P1P1_DP<2> UPI1_TX_DP<17> @BASEBOARD_FAB2_LIB.BASEBOARD_FAB2(SCH_1):UPI_CPU0_CPU1_P1P1_DP(2)
 J18 UPI_CPU0_CPU1_P1P1_DP<3> UPI1_TX_DP<16> @BASEBOARD_FAB2_LIB.BASEBOARD_FAB2(SCH_1):UPI_CPU0_CPU1_P1P1_DP(3)
 L18 UPI_CPU0_CPU1_P1P1_DP<4> UPI1_TX_DP<15> @BASEBOARD_FAB2_LIB.BASEBOARD_FAB2(SCH_1):UPI_CPU0_CPU1_P1P1_DP(4)
 G16 UPI_CPU0_CPU1_P1P1_DP<5> UPI1_TX_DP<14> @BASEBOARD_FAB2_LIB.BASEBOARD_FAB2(SCH_1):UPI_CPU0_CPU1_P1P1_DP(5)
 H15 UPI_CPU0_CPU1_P1P1_DP<6> UPI1_TX_DP<13> @BASEBOARD_FAB2_LIB.BASEBOARD_FAB2(SCH_1):UPI_CPU0_CPU1_P1P1_DP(6)
 E14 UPI_CPU0_CPU1_P1P1_DP<7> UPI1_TX_DP<12> @BASEBOARD_FAB2_LIB.BASEBOARD_FAB2(SCH_1):UPI_CPU0_CPU1_P1P1_DP(7)
 F13 UPI_CPU0_CPU1_P1P1_DP<8> UPI1_TX_DP<11> @BASEBOARD_FAB2_LIB.BASEBOARD_FAB2(SCH_1):UPI_CPU0_CPU1_P1P1_DP(8)
 G12 UPI_CPU0_CPU1_P1P1_DP<9> UPI1_TX_DP<10> @BASEBOARD_FAB2_LIB.BASEBOARD_FAB2(SCH_1):UPI_CPU0_CPU1_P1P1_DP(9)
  H9 UPI_CPU0_CPU1_P1P1_DP<10> UPI1_TX_DP<9> @BASEBOARD_FAB2_LIB.BASEBOARD_FAB2(SCH_1):UPI_CPU0_CPU1_P1P1_DP(10)
 E10 UPI_CPU0_CPU1_P1P1_DP<11> UPI1_TX_DP<8> @BASEBOARD_FAB2_LIB.BASEBOARD_FAB2(SCH_1):UPI_CPU0_CPU1_P1P1_DP(11)
  F9 UPI_CPU0_CPU1_P1P1_DP<12> UPI1_TX_DP<7> @BASEBOARD_FAB2_LIB.BASEBOARD_FAB2(SCH_1):UPI_CPU0_CPU1_P1P1_DP(12)
  J8 UPI_CPU0_CPU1_P1P1_DP<13> UPI1_TX_DP<6> @BASEBOARD_FAB2_LIB.BASEBOARD_FAB2(SCH_1):UPI_CPU0_CPU1_P1P1_DP(13)
  K7 UPI_CPU0_CPU1_P1P1_DP<14> UPI1_TX_DP<5> @BASEBOARD_FAB2_LIB.BASEBOARD_FAB2(SCH_1):UPI_CPU0_CPU1_P1P1_DP(14)
  F7 UPI_CPU0_CPU1_P1P1_DP<15> UPI1_TX_DP<4> @BASEBOARD_FAB2_LIB.BASEBOARD_FAB2(SCH_1):UPI_CPU0_CPU1_P1P1_DP(15)
  H5 UPI_CPU0_CPU1_P1P1_DP<16> UPI1_TX_DP<3> @BASEBOARD_FAB2_LIB.BASEBOARD_FAB2(SCH_1):UPI_CPU0_CPU1_P1P1_DP(16)
  M5 UPI_CPU0_CPU1_P1P1_DP<17> UPI1_TX_DP<2> @BASEBOARD_FAB2_LIB.BASEBOARD_FAB2(SCH_1):UPI_CPU0_CPU1_P1P1_DP(17)
  K3 UPI_CPU0_CPU1_P1P1_DP<18> UPI1_TX_DP<1> @BASEBOARD_FAB2_LIB.BASEBOARD_FAB2(SCH_1):UPI_CPU0_CPU1_P1P1_DP(18)
  P3 UPI_CPU0_CPU1_P1P1_DP<19> UPI1_TX_DP<0> @BASEBOARD_FAB2_LIB.BASEBOARD_FAB2(SCH_1):UPI_CPU0_CPU1_P1P1_DP(19)


DRAWING: @BASEBOARD_FAB2_LIB.BASEBOARD_FAB2(SCH_1):PAGE35 

SKX_EXT_B_BGA1-IC,TBD  I3  U5D1
BY17    GND UPI2_RX_DN<19> @BASEBOARD_FAB2_LIB.BASEBOARD_FAB2(SCH_1):GND
CB15    GND UPI2_RX_DN<18> @BASEBOARD_FAB2_LIB.BASEBOARD_FAB2(SCH_1):GND
CF17    GND UPI2_RX_DN<17> @BASEBOARD_FAB2_LIB.BASEBOARD_FAB2(SCH_1):GND
CD15    GND UPI2_RX_DN<16> @BASEBOARD_FAB2_LIB.BASEBOARD_FAB2(SCH_1):GND
CE16    GND UPI2_RX_DN<15> @BASEBOARD_FAB2_LIB.BASEBOARD_FAB2(SCH_1):GND
CH17    GND UPI2_RX_DN<14> @BASEBOARD_FAB2_LIB.BASEBOARD_FAB2(SCH_1):GND
CJ18    GND UPI2_RX_DN<13> @BASEBOARD_FAB2_LIB.BASEBOARD_FAB2(SCH_1):GND
CL16    GND UPI2_RX_DN<12> @BASEBOARD_FAB2_LIB.BASEBOARD_FAB2(SCH_1):GND
CP21    GND UPI2_RX_DN<11> @BASEBOARD_FAB2_LIB.BASEBOARD_FAB2(SCH_1):GND
CN20    GND UPI2_RX_DN<10> @BASEBOARD_FAB2_LIB.BASEBOARD_FAB2(SCH_1):GND
CR18    GND UPI2_RX_DN<9> @BASEBOARD_FAB2_LIB.BASEBOARD_FAB2(SCH_1):GND
CT21    GND UPI2_RX_DN<8> @BASEBOARD_FAB2_LIB.BASEBOARD_FAB2(SCH_1):GND
CV19    GND UPI2_RX_DN<7> @BASEBOARD_FAB2_LIB.BASEBOARD_FAB2(SCH_1):GND
CW20    GND UPI2_RX_DN<6> @BASEBOARD_FAB2_LIB.BASEBOARD_FAB2(SCH_1):GND
DA20    GND UPI2_RX_DN<5> @BASEBOARD_FAB2_LIB.BASEBOARD_FAB2(SCH_1):GND
DD19    GND UPI2_RX_DN<4> @BASEBOARD_FAB2_LIB.BASEBOARD_FAB2(SCH_1):GND
DB21    GND UPI2_RX_DN<3> @BASEBOARD_FAB2_LIB.BASEBOARD_FAB2(SCH_1):GND
DC22    GND UPI2_RX_DN<2> @BASEBOARD_FAB2_LIB.BASEBOARD_FAB2(SCH_1):GND
DE22    GND UPI2_RX_DN<1> @BASEBOARD_FAB2_LIB.BASEBOARD_FAB2(SCH_1):GND
DF23    GND UPI2_RX_DN<0> @BASEBOARD_FAB2_LIB.BASEBOARD_FAB2(SCH_1):GND
CA16    GND UPI2_RX_DP<19> @BASEBOARD_FAB2_LIB.BASEBOARD_FAB2(SCH_1):GND
BY15    GND UPI2_RX_DP<18> @BASEBOARD_FAB2_LIB.BASEBOARD_FAB2(SCH_1):GND
CD17    GND UPI2_RX_DP<17> @BASEBOARD_FAB2_LIB.BASEBOARD_FAB2(SCH_1):GND
CC14    GND UPI2_RX_DP<16> @BASEBOARD_FAB2_LIB.BASEBOARD_FAB2(SCH_1):GND
CF15    GND UPI2_RX_DP<15> @BASEBOARD_FAB2_LIB.BASEBOARD_FAB2(SCH_1):GND
CG16    GND UPI2_RX_DP<14> @BASEBOARD_FAB2_LIB.BASEBOARD_FAB2(SCH_1):GND
CK17    GND UPI2_RX_DP<13> @BASEBOARD_FAB2_LIB.BASEBOARD_FAB2(SCH_1):GND
CJ16    GND UPI2_RX_DP<12> @BASEBOARD_FAB2_LIB.BASEBOARD_FAB2(SCH_1):GND
CM21    GND UPI2_RX_DP<11> @BASEBOARD_FAB2_LIB.BASEBOARD_FAB2(SCH_1):GND
CP19    GND UPI2_RX_DP<10> @BASEBOARD_FAB2_LIB.BASEBOARD_FAB2(SCH_1):GND
CN18    GND UPI2_RX_DP<9> @BASEBOARD_FAB2_LIB.BASEBOARD_FAB2(SCH_1):GND
CR20    GND UPI2_RX_DP<8> @BASEBOARD_FAB2_LIB.BASEBOARD_FAB2(SCH_1):GND
CW18    GND UPI2_RX_DP<7> @BASEBOARD_FAB2_LIB.BASEBOARD_FAB2(SCH_1):GND
CU20    GND UPI2_RX_DP<6> @BASEBOARD_FAB2_LIB.BASEBOARD_FAB2(SCH_1):GND
CY19    GND UPI2_RX_DP<5> @BASEBOARD_FAB2_LIB.BASEBOARD_FAB2(SCH_1):GND
DB19    GND UPI2_RX_DP<4> @BASEBOARD_FAB2_LIB.BASEBOARD_FAB2(SCH_1):GND
DC20    GND UPI2_RX_DP<3> @BASEBOARD_FAB2_LIB.BASEBOARD_FAB2(SCH_1):GND
DA22    GND UPI2_RX_DP<2> @BASEBOARD_FAB2_LIB.BASEBOARD_FAB2(SCH_1):GND
DD21    GND UPI2_RX_DP<1> @BASEBOARD_FAB2_LIB.BASEBOARD_FAB2(SCH_1):GND
DG22    GND UPI2_RX_DP<0> @BASEBOARD_FAB2_LIB.BASEBOARD_FAB2(SCH_1):GND
CC12 TP_CPU0_UPI2_RSVD_DT21 UPI2_TX_DN<19> @BASEBOARD_FAB2_LIB.BASEBOARD_FAB2(SCH_1):TP_CPU0_UPI2_RSVD_DT21
CC10 TP_CPU0_UPI2_RSVD_DM21 UPI2_TX_DN<18> @BASEBOARD_FAB2_LIB.BASEBOARD_FAB2(SCH_1):TP_CPU0_UPI2_RSVD_DM21
CE12 TP_CPU0_UPI2_RSVD_DL20 UPI2_TX_DN<17> @BASEBOARD_FAB2_LIB.BASEBOARD_FAB2(SCH_1):TP_CPU0_UPI2_RSVD_DL20
CH11 TP_CPU0_UPI2_RSVD_DG20 UPI2_TX_DN<16> @BASEBOARD_FAB2_LIB.BASEBOARD_FAB2(SCH_1):TP_CPU0_UPI2_RSVD_DG20
CF13 TP_CPU0_UPI2_RSVD_DH19 UPI2_TX_DN<15> @BASEBOARD_FAB2_LIB.BASEBOARD_FAB2(SCH_1):TP_CPU0_UPI2_RSVD_DH19
CJ14 TP_CPU0_UPI2_RSVD_DK17 UPI2_TX_DN<14> @BASEBOARD_FAB2_LIB.BASEBOARD_FAB2(SCH_1):TP_CPU0_UPI2_RSVD_DK17
CM13 TP_CPU0_UPI2_RSVD_DG18 UPI2_TX_DN<13> @BASEBOARD_FAB2_LIB.BASEBOARD_FAB2(SCH_1):TP_CPU0_UPI2_RSVD_DG18
CU14 TP_CPU0_UPI2_RSVD_DD17 UPI2_TX_DN<12> @BASEBOARD_FAB2_LIB.BASEBOARD_FAB2(SCH_1):TP_CPU0_UPI2_RSVD_DD17
CW14 TP_CPU0_UPI2_RSVD_DF15 UPI2_TX_DN<11> @BASEBOARD_FAB2_LIB.BASEBOARD_FAB2(SCH_1):TP_CPU0_UPI2_RSVD_DF15
DA16 TP_CPU0_UPI2_RSVD_DC16 UPI2_TX_DN<10> @BASEBOARD_FAB2_LIB.BASEBOARD_FAB2(SCH_1):TP_CPU0_UPI2_RSVD_DC16
DC16 TP_CPU0_UPI2_RSVD_DA16 UPI2_TX_DN<9> @BASEBOARD_FAB2_LIB.BASEBOARD_FAB2(SCH_1):TP_CPU0_UPI2_RSVD_DA16
DF15 TP_CPU0_UPI2_RSVD_CW14 UPI2_TX_DN<8> @BASEBOARD_FAB2_LIB.BASEBOARD_FAB2(SCH_1):TP_CPU0_UPI2_RSVD_CW14
DD17 TP_CPU0_UPI2_RSVD_CU14 UPI2_TX_DN<7> @BASEBOARD_FAB2_LIB.BASEBOARD_FAB2(SCH_1):TP_CPU0_UPI2_RSVD_CU14
DG18 TP_CPU0_UPI2_RSVD_CM13 UPI2_TX_DN<6> @BASEBOARD_FAB2_LIB.BASEBOARD_FAB2(SCH_1):TP_CPU0_UPI2_RSVD_CM13
DK17 TP_CPU0_UPI2_RSVD_CJ14 UPI2_TX_DN<5> @BASEBOARD_FAB2_LIB.BASEBOARD_FAB2(SCH_1):TP_CPU0_UPI2_RSVD_CJ14
DH19 TP_CPU0_UPI2_RSVD_CF13 UPI2_TX_DN<4> @BASEBOARD_FAB2_LIB.BASEBOARD_FAB2(SCH_1):TP_CPU0_UPI2_RSVD_CF13
DG20 TP_CPU0_UPI2_RSVD_CH11 UPI2_TX_DN<3> @BASEBOARD_FAB2_LIB.BASEBOARD_FAB2(SCH_1):TP_CPU0_UPI2_RSVD_CH11
DL20 TP_CPU0_UPI2_RSVD_CE12 UPI2_TX_DN<2> @BASEBOARD_FAB2_LIB.BASEBOARD_FAB2(SCH_1):TP_CPU0_UPI2_RSVD_CE12
DM21 TP_CPU0_UPI2_RSVD_CC10 UPI2_TX_DN<1> @BASEBOARD_FAB2_LIB.BASEBOARD_FAB2(SCH_1):TP_CPU0_UPI2_RSVD_CC10
DT21 TP_CPU0_UPI2_RSVD_CC12 UPI2_TX_DN<0> @BASEBOARD_FAB2_LIB.BASEBOARD_FAB2(SCH_1):TP_CPU0_UPI2_RSVD_CC12
CA12 TP_CPU0_UPI2_RSVD_DP21 UPI2_TX_DP<19> @BASEBOARD_FAB2_LIB.BASEBOARD_FAB2(SCH_1):TP_CPU0_UPI2_RSVD_DP21
CB11 TP_CPU0_UPI2_RSVD_DN20 UPI2_TX_DP<18> @BASEBOARD_FAB2_LIB.BASEBOARD_FAB2(SCH_1):TP_CPU0_UPI2_RSVD_DN20
CD11 TP_CPU0_UPI2_RSVD_DK19 UPI2_TX_DP<17> @BASEBOARD_FAB2_LIB.BASEBOARD_FAB2(SCH_1):TP_CPU0_UPI2_RSVD_DK19
CF11 TP_CPU0_UPI2_RSVD_DJ20 UPI2_TX_DP<16> @BASEBOARD_FAB2_LIB.BASEBOARD_FAB2(SCH_1):TP_CPU0_UPI2_RSVD_DJ20
CG12 TP_CPU0_UPI2_RSVD_DJ18 UPI2_TX_DP<15> @BASEBOARD_FAB2_LIB.BASEBOARD_FAB2(SCH_1):TP_CPU0_UPI2_RSVD_DJ18
CH13 TP_CPU0_UPI2_RSVD_DH17 UPI2_TX_DP<14> @BASEBOARD_FAB2_LIB.BASEBOARD_FAB2(SCH_1):TP_CPU0_UPI2_RSVD_DH17
CK13 TP_CPU0_UPI2_RSVD_DF17 UPI2_TX_DP<13> @BASEBOARD_FAB2_LIB.BASEBOARD_FAB2(SCH_1):TP_CPU0_UPI2_RSVD_DF17
CR14 TP_CPU0_UPI2_RSVD_DE16 UPI2_TX_DP<12> @BASEBOARD_FAB2_LIB.BASEBOARD_FAB2(SCH_1):TP_CPU0_UPI2_RSVD_DE16
CV13 TP_CPU0_UPI2_RSVD_DD15 UPI2_TX_DP<11> @BASEBOARD_FAB2_LIB.BASEBOARD_FAB2(SCH_1):TP_CPU0_UPI2_RSVD_DD15
CW16 TP_CPU0_UPI2_RSVD_DB15 UPI2_TX_DP<10> @BASEBOARD_FAB2_LIB.BASEBOARD_FAB2(SCH_1):TP_CPU0_UPI2_RSVD_DB15
DB15 TP_CPU0_UPI2_RSVD_CW16 UPI2_TX_DP<9> @BASEBOARD_FAB2_LIB.BASEBOARD_FAB2(SCH_1):TP_CPU0_UPI2_RSVD_CW16
DD15 TP_CPU0_UPI2_RSVD_CV13 UPI2_TX_DP<8> @BASEBOARD_FAB2_LIB.BASEBOARD_FAB2(SCH_1):TP_CPU0_UPI2_RSVD_CV13
DE16 TP_CPU0_UPI2_RSVD_CR14 UPI2_TX_DP<7> @BASEBOARD_FAB2_LIB.BASEBOARD_FAB2(SCH_1):TP_CPU0_UPI2_RSVD_CR14
DF17 TP_CPU0_UPI2_RSVD_CK13 UPI2_TX_DP<6> @BASEBOARD_FAB2_LIB.BASEBOARD_FAB2(SCH_1):TP_CPU0_UPI2_RSVD_CK13
DH17 TP_CPU0_UPI2_RSVD_CH13 UPI2_TX_DP<5> @BASEBOARD_FAB2_LIB.BASEBOARD_FAB2(SCH_1):TP_CPU0_UPI2_RSVD_CH13
DJ18 TP_CPU0_UPI2_RSVD_CG12 UPI2_TX_DP<4> @BASEBOARD_FAB2_LIB.BASEBOARD_FAB2(SCH_1):TP_CPU0_UPI2_RSVD_CG12
DJ20 TP_CPU0_UPI2_RSVD_CF11 UPI2_TX_DP<3> @BASEBOARD_FAB2_LIB.BASEBOARD_FAB2(SCH_1):TP_CPU0_UPI2_RSVD_CF11
DK19 TP_CPU0_UPI2_RSVD_CD11 UPI2_TX_DP<2> @BASEBOARD_FAB2_LIB.BASEBOARD_FAB2(SCH_1):TP_CPU0_UPI2_RSVD_CD11
DN20 TP_CPU0_UPI2_RSVD_CB11 UPI2_TX_DP<1> @BASEBOARD_FAB2_LIB.BASEBOARD_FAB2(SCH_1):TP_CPU0_UPI2_RSVD_CB11
DP21 TP_CPU0_UPI2_RSVD_CA12 UPI2_TX_DP<0> @BASEBOARD_FAB2_LIB.BASEBOARD_FAB2(SCH_1):TP_CPU0_UPI2_RSVD_CA12


DRAWING: @BASEBOARD_FAB2_LIB.BASEBOARD_FAB2(SCH_1):PAGE36 

SKX_EXT_B_BGA1-IC,TBD  I15  U5D1
AY83 TP_CPU0_RSVD_255 RSVD<255> @BASEBOARD_FAB2_LIB.BASEBOARD_FAB2(SCH_1):TP_CPU0_RSVD_255
BA78 TP_CPU0_RSVD_171 RSVD<171> @BASEBOARD_FAB2_LIB.BASEBOARD_FAB2(SCH_1):TP_CPU0_RSVD_171
BA82 TP_CPU0_RSVD_170 RSVD<170> @BASEBOARD_FAB2_LIB.BASEBOARD_FAB2(SCH_1):TP_CPU0_RSVD_170
BB13 TP_CPU0_RSVD_169 RSVD<169> @BASEBOARD_FAB2_LIB.BASEBOARD_FAB2(SCH_1):TP_CPU0_RSVD_169
BB15 TP_CPU0_RSVD_168 RSVD<168> @BASEBOARD_FAB2_LIB.BASEBOARD_FAB2(SCH_1):TP_CPU0_RSVD_168
BB17 TP_CPU0_RSVD_167 RSVD<167> @BASEBOARD_FAB2_LIB.BASEBOARD_FAB2(SCH_1):TP_CPU0_RSVD_167
BB21 TP_CPU0_RSVD_166 RSVD<166> @BASEBOARD_FAB2_LIB.BASEBOARD_FAB2(SCH_1):TP_CPU0_RSVD_166
BB25 CLK_100M_CPU0_RC_REFCLK1_DN RSVD<165> @BASEBOARD_FAB2_LIB.BASEBOARD_FAB2(SCH_1):CLK_100M_CPU0_RC_REFCLK1_DN
BB65 TP_CPU0_RSVD_164 RSVD<164> @BASEBOARD_FAB2_LIB.BASEBOARD_FAB2(SCH_1):TP_CPU0_RSVD_164
BB67 TP_CPU0_RSVD_163 RSVD<163> @BASEBOARD_FAB2_LIB.BASEBOARD_FAB2(SCH_1):TP_CPU0_RSVD_163
BC14 TP_CPU0_RSVD_162 RSVD<162> @BASEBOARD_FAB2_LIB.BASEBOARD_FAB2(SCH_1):TP_CPU0_RSVD_162
BC18 TP_CPU0_RSVD_161 RSVD<161> @BASEBOARD_FAB2_LIB.BASEBOARD_FAB2(SCH_1):TP_CPU0_RSVD_161
BC20 TP_CPU0_RSVD_160 RSVD<160> @BASEBOARD_FAB2_LIB.BASEBOARD_FAB2(SCH_1):TP_CPU0_RSVD_160
BC22 TP_CPU0_RSVD_159 RSVD<159> @BASEBOARD_FAB2_LIB.BASEBOARD_FAB2(SCH_1):TP_CPU0_RSVD_159
BC64 TP_CPU0_RSVD_158 RSVD<158> @BASEBOARD_FAB2_LIB.BASEBOARD_FAB2(SCH_1):TP_CPU0_RSVD_158
BC66 TP_CPU0_RSVD_157 RSVD<157> @BASEBOARD_FAB2_LIB.BASEBOARD_FAB2(SCH_1):TP_CPU0_RSVD_157
BC68 TP_CPU0_RSVD_156 RSVD<156> @BASEBOARD_FAB2_LIB.BASEBOARD_FAB2(SCH_1):TP_CPU0_RSVD_156
BD17 TP_CPU0_RSVD_155 RSVD<155> @BASEBOARD_FAB2_LIB.BASEBOARD_FAB2(SCH_1):TP_CPU0_RSVD_155
BD19 TP_CPU0_RSVD_154 RSVD<154> @BASEBOARD_FAB2_LIB.BASEBOARD_FAB2(SCH_1):TP_CPU0_RSVD_154
BD25 CLK_100M_CPU0_RC_REFCLK1_DP RSVD<153> @BASEBOARD_FAB2_LIB.BASEBOARD_FAB2(SCH_1):CLK_100M_CPU0_RC_REFCLK1_DP
BD65 TP_CPU0_RSVD_152 RSVD<152> @BASEBOARD_FAB2_LIB.BASEBOARD_FAB2(SCH_1):TP_CPU0_RSVD_152
BD67 TP_CPU0_RSVD_151 RSVD<151> @BASEBOARD_FAB2_LIB.BASEBOARD_FAB2(SCH_1):TP_CPU0_RSVD_151
BD69 TP_CPU0_RSVD_150 RSVD<150> @BASEBOARD_FAB2_LIB.BASEBOARD_FAB2(SCH_1):TP_CPU0_RSVD_150
BE18 TP_CPU0_RSVD_149 RSVD<149> @BASEBOARD_FAB2_LIB.BASEBOARD_FAB2(SCH_1):TP_CPU0_RSVD_149
BE20 TP_CPU0_RSVD_148 RSVD<148> @BASEBOARD_FAB2_LIB.BASEBOARD_FAB2(SCH_1):TP_CPU0_RSVD_148
BE22 TP_CPU0_RSVD_147 RSVD<147> @BASEBOARD_FAB2_LIB.BASEBOARD_FAB2(SCH_1):TP_CPU0_RSVD_147
BF21 TP_CPU0_RSVD_146 RSVD<146> @BASEBOARD_FAB2_LIB.BASEBOARD_FAB2(SCH_1):TP_CPU0_RSVD_146
BG18 TP_CPU0_RSVD_145 RSVD<145> @BASEBOARD_FAB2_LIB.BASEBOARD_FAB2(SCH_1):TP_CPU0_RSVD_145
BG20 TP_CPU0_RSVD_144 RSVD<144> @BASEBOARD_FAB2_LIB.BASEBOARD_FAB2(SCH_1):TP_CPU0_RSVD_144
BH19 PVCCMCP_CPU0 RSVD<143> @BASEBOARD_FAB2_LIB.BASEBOARD_FAB2(SCH_1):PVCCMCP_CPU0
BJ16 PVCCMCP_CPU0 RSVD<142> @BASEBOARD_FAB2_LIB.BASEBOARD_FAB2(SCH_1):PVCCMCP_CPU0
BJ18 PVCCMCP_CPU0 RSVD<141> @BASEBOARD_FAB2_LIB.BASEBOARD_FAB2(SCH_1):PVCCMCP_CPU0
BJ20 PVCCMCP_CPU0 RSVD<140> @BASEBOARD_FAB2_LIB.BASEBOARD_FAB2(SCH_1):PVCCMCP_CPU0
BK17 PVCCMCP_CPU0 RSVD<139> @BASEBOARD_FAB2_LIB.BASEBOARD_FAB2(SCH_1):PVCCMCP_CPU0
BL18 PVCCIOMCP_CPU0 RSVD<138> @BASEBOARD_FAB2_LIB.BASEBOARD_FAB2(SCH_1):PVCCIOMCP_CPU0
BL20 PVCCMCP_CPU0 RSVD<137> @BASEBOARD_FAB2_LIB.BASEBOARD_FAB2(SCH_1):PVCCMCP_CPU0
BM17 PVCCIOMCP_CPU0 RSVD<136> @BASEBOARD_FAB2_LIB.BASEBOARD_FAB2(SCH_1):PVCCIOMCP_CPU0
BM19 PVCCMCP_CPU0 RSVD<135> @BASEBOARD_FAB2_LIB.BASEBOARD_FAB2(SCH_1):PVCCMCP_CPU0
BN18 PVCCIOMCP_CPU0 RSVD<134> @BASEBOARD_FAB2_LIB.BASEBOARD_FAB2(SCH_1):PVCCIOMCP_CPU0
BP17 PVCCIOMCP_CPU0 RSVD<133> @BASEBOARD_FAB2_LIB.BASEBOARD_FAB2(SCH_1):PVCCIOMCP_CPU0
BP21 PVCCMCP_CPU0 RSVD<132> @BASEBOARD_FAB2_LIB.BASEBOARD_FAB2(SCH_1):PVCCMCP_CPU0
BR22 PVCCMCP_CPU0 RSVD<131> @BASEBOARD_FAB2_LIB.BASEBOARD_FAB2(SCH_1):PVCCMCP_CPU0
BR24 PVCCMCP_CPU0 RSVD<130> @BASEBOARD_FAB2_LIB.BASEBOARD_FAB2(SCH_1):PVCCMCP_CPU0
BU18 PVCCIOMCP_CPU0 RSVD<129> @BASEBOARD_FAB2_LIB.BASEBOARD_FAB2(SCH_1):PVCCIOMCP_CPU0
BU20 PVCCMCP_CPU0 RSVD<128> @BASEBOARD_FAB2_LIB.BASEBOARD_FAB2(SCH_1):PVCCMCP_CPU0
BU22 PVCCMCP_CPU0 RSVD<127> @BASEBOARD_FAB2_LIB.BASEBOARD_FAB2(SCH_1):PVCCMCP_CPU0
BV19 PVCCMCP_CPU0 RSVD<126> @BASEBOARD_FAB2_LIB.BASEBOARD_FAB2(SCH_1):PVCCMCP_CPU0
BV21 PVCCMCP_CPU0 RSVD<125> @BASEBOARD_FAB2_LIB.BASEBOARD_FAB2(SCH_1):PVCCMCP_CPU0
BV23 TP_CPU0_RSVD_124 RSVD<124> @BASEBOARD_FAB2_LIB.BASEBOARD_FAB2(SCH_1):TP_CPU0_RSVD_124
BW10 TP_CPU0_RSVD_123 RSVD<123> @BASEBOARD_FAB2_LIB.BASEBOARD_FAB2(SCH_1):TP_CPU0_RSVD_123
BW20 PVCCMCP_CPU0 RSVD<122> @BASEBOARD_FAB2_LIB.BASEBOARD_FAB2(SCH_1):PVCCMCP_CPU0
BW22 TP_CPU0_RSVD_121 RSVD<121> @BASEBOARD_FAB2_LIB.BASEBOARD_FAB2(SCH_1):TP_CPU0_RSVD_121
BY19 PVCCMCP_CPU0 RSVD<120> @BASEBOARD_FAB2_LIB.BASEBOARD_FAB2(SCH_1):PVCCMCP_CPU0
BY25 TP_CPU0_RSVD_119 RSVD<119> @BASEBOARD_FAB2_LIB.BASEBOARD_FAB2(SCH_1):TP_CPU0_RSVD_119
CA22 PVCCMCP_CPU0 RSVD<118> @BASEBOARD_FAB2_LIB.BASEBOARD_FAB2(SCH_1):PVCCMCP_CPU0
CA24 TP_CPU0_RSVD_117 RSVD<117> @BASEBOARD_FAB2_LIB.BASEBOARD_FAB2(SCH_1):TP_CPU0_RSVD_117
CB19 PVCCMCP_CPU0 RSVD<116> @BASEBOARD_FAB2_LIB.BASEBOARD_FAB2(SCH_1):PVCCMCP_CPU0
CB21 PVCCMCP_CPU0 RSVD<115> @BASEBOARD_FAB2_LIB.BASEBOARD_FAB2(SCH_1):PVCCMCP_CPU0
CB25 TP_CPU0_RSVD_114 RSVD<114> @BASEBOARD_FAB2_LIB.BASEBOARD_FAB2(SCH_1):TP_CPU0_RSVD_114
 CB5 TP_CPU0_RSVD_113 RSVD<113> @BASEBOARD_FAB2_LIB.BASEBOARD_FAB2(SCH_1):TP_CPU0_RSVD_113
CC20 PVCCMCP_CPU0 RSVD<112> @BASEBOARD_FAB2_LIB.BASEBOARD_FAB2(SCH_1):PVCCMCP_CPU0
 CC6 TP_CPU0_RSVD_111 RSVD<111> @BASEBOARD_FAB2_LIB.BASEBOARD_FAB2(SCH_1):TP_CPU0_RSVD_111
CD19 PVCCMCP_CPU0 RSVD<110> @BASEBOARD_FAB2_LIB.BASEBOARD_FAB2(SCH_1):PVCCMCP_CPU0
CD21 PVCCMCP_CPU0 RSVD<109> @BASEBOARD_FAB2_LIB.BASEBOARD_FAB2(SCH_1):PVCCMCP_CPU0
CD25 TP_CPU0_RSVD_108 RSVD<108> @BASEBOARD_FAB2_LIB.BASEBOARD_FAB2(SCH_1):TP_CPU0_RSVD_108
CE22 PVCCMCP_CPU0 RSVD<107> @BASEBOARD_FAB2_LIB.BASEBOARD_FAB2(SCH_1):PVCCMCP_CPU0
CE78 TP_CPU0_RSVD_106 RSVD<106> @BASEBOARD_FAB2_LIB.BASEBOARD_FAB2(SCH_1):TP_CPU0_RSVD_106
CE80 TP_CPU0_RSVD_105 RSVD<105> @BASEBOARD_FAB2_LIB.BASEBOARD_FAB2(SCH_1):TP_CPU0_RSVD_105
CF19 PVCCMCP_CPU0 RSVD<104> @BASEBOARD_FAB2_LIB.BASEBOARD_FAB2(SCH_1):PVCCMCP_CPU0
CF21 PVCCMCP_CPU0 RSVD<103> @BASEBOARD_FAB2_LIB.BASEBOARD_FAB2(SCH_1):PVCCMCP_CPU0
CF23 PVCCMCP_CPU0 RSVD<102> @BASEBOARD_FAB2_LIB.BASEBOARD_FAB2(SCH_1):PVCCMCP_CPU0
CF79 TP_CPU0_RSVD_101 RSVD<101> @BASEBOARD_FAB2_LIB.BASEBOARD_FAB2(SCH_1):TP_CPU0_RSVD_101
CF81 TP_CPU0_RSVD_100 RSVD<100> @BASEBOARD_FAB2_LIB.BASEBOARD_FAB2(SCH_1):TP_CPU0_RSVD_100
CG10 TP_CPU0_RSVD_99 RSVD<99> @BASEBOARD_FAB2_LIB.BASEBOARD_FAB2(SCH_1):TP_CPU0_RSVD_99
CG20 PVCCMCP_CPU0 RSVD<98> @BASEBOARD_FAB2_LIB.BASEBOARD_FAB2(SCH_1):PVCCMCP_CPU0
CG24 TP_CPU0_RSVD_97 RSVD<97> @BASEBOARD_FAB2_LIB.BASEBOARD_FAB2(SCH_1):TP_CPU0_RSVD_97
CG26 PVCCMCP_CPU0 RSVD<96> @BASEBOARD_FAB2_LIB.BASEBOARD_FAB2(SCH_1):PVCCMCP_CPU0
CG78 TP_CPU0_RSVD_95 RSVD<95> @BASEBOARD_FAB2_LIB.BASEBOARD_FAB2(SCH_1):TP_CPU0_RSVD_95
CG82 TP_CPU0_RSVD_94 RSVD<94> @BASEBOARD_FAB2_LIB.BASEBOARD_FAB2(SCH_1):TP_CPU0_RSVD_94
CH21 PVCCMCP_CPU0 RSVD<93> @BASEBOARD_FAB2_LIB.BASEBOARD_FAB2(SCH_1):PVCCMCP_CPU0
CH23 PVCCMCP_CPU0 RSVD<92> @BASEBOARD_FAB2_LIB.BASEBOARD_FAB2(SCH_1):PVCCMCP_CPU0

SKX_EXT_B_BGA1-IC,TBD  I16  U5D1
CH25 TP_CPU0_RSVD_91 RSVD<91> @BASEBOARD_FAB2_LIB.BASEBOARD_FAB2(SCH_1):TP_CPU0_RSVD_91
CH77 TP_CPU0_RSVD_90 RSVD<90> @BASEBOARD_FAB2_LIB.BASEBOARD_FAB2(SCH_1):TP_CPU0_RSVD_90
CJ20 PVCCMCP_CPU0 RSVD<89> @BASEBOARD_FAB2_LIB.BASEBOARD_FAB2(SCH_1):PVCCMCP_CPU0
CJ22 PVCCMCP_CPU0 RSVD<88> @BASEBOARD_FAB2_LIB.BASEBOARD_FAB2(SCH_1):PVCCMCP_CPU0
CJ24 PVCCMCP_CPU0 RSVD<87> @BASEBOARD_FAB2_LIB.BASEBOARD_FAB2(SCH_1):PVCCMCP_CPU0
CJ26 PVCCMCP_CPU0 RSVD<86> @BASEBOARD_FAB2_LIB.BASEBOARD_FAB2(SCH_1):PVCCMCP_CPU0
CK19 TP_CPU0_RSVD_85 RSVD<85> @BASEBOARD_FAB2_LIB.BASEBOARD_FAB2(SCH_1):TP_CPU0_RSVD_85
CK23 PVCCMCP_CPU0 RSVD<84> @BASEBOARD_FAB2_LIB.BASEBOARD_FAB2(SCH_1):PVCCMCP_CPU0
CK25 PVCCMCP_CPU0 RSVD<83> @BASEBOARD_FAB2_LIB.BASEBOARD_FAB2(SCH_1):PVCCMCP_CPU0
CK77 TP_CPU0_RSVD_82 RSVD<82> @BASEBOARD_FAB2_LIB.BASEBOARD_FAB2(SCH_1):TP_CPU0_RSVD_82
CL24 PVCCMCP_CPU0 RSVD<81> @BASEBOARD_FAB2_LIB.BASEBOARD_FAB2(SCH_1):PVCCMCP_CPU0
AW22 TP_CPU0_TEST_10 TEST_10 @BASEBOARD_FAB2_LIB.BASEBOARD_FAB2(SCH_1):TP_CPU0_TEST_10
AR16 TP_CPU0_TEST_6 TEST_6 @BASEBOARD_FAB2_LIB.BASEBOARD_FAB2(SCH_1):TP_CPU0_TEST_6
AU18 TP_CPU0_TEST_7 TEST_7 @BASEBOARD_FAB2_LIB.BASEBOARD_FAB2(SCH_1):TP_CPU0_TEST_7
AW16 TP_CPU0_TEST_8 TEST_8 @BASEBOARD_FAB2_LIB.BASEBOARD_FAB2(SCH_1):TP_CPU0_TEST_8
AW20 TP_CPU0_TEST_9 TEST_9 @BASEBOARD_FAB2_LIB.BASEBOARD_FAB2(SCH_1):TP_CPU0_TEST_9


DRAWING: @BASEBOARD_FAB2_LIB.BASEBOARD_FAB2(SCH_1):PAGE37 

RES_0402-249,0.1%,1/16W,CHIP,GA  I303  R5D5
   1 VSENSE_PMAX_CPU0      A @BASEBOARD_FAB2_LIB.BASEBOARD_FAB2(SCH_1):VSENSE_PMAX_CPU0
   2    GND      B @BASEBOARD_FAB2_LIB.BASEBOARD_FAB2(SCH_1):GND

RES_0603-100.0K,1%,1/10W,CHIP,A  I309  R5P1
   1 PVCCIN_CPU0      A @BASEBOARD_FAB2_LIB.BASEBOARD_FAB2(SCH_1):PVCCIN_CPU0
   2 VSENSE_VCCINR2PMAX_CPU0      B @BASEBOARD_FAB2_LIB.BASEBOARD_FAB2(SCH_1):VSENSE_VCCINR2PMAX_CPU0

SKX_EXT_B_BGA1-IC,TBD  I310  U5D1
AF43 PVCCIN_CPU0 VCCIN<267> @BASEBOARD_FAB2_LIB.BASEBOARD_FAB2(SCH_1):PVCCIN_CPU0
AG38 PVCCIN_CPU0 VCCIN<266> @BASEBOARD_FAB2_LIB.BASEBOARD_FAB2(SCH_1):PVCCIN_CPU0
AG40 PVCCIN_CPU0 VCCIN<265> @BASEBOARD_FAB2_LIB.BASEBOARD_FAB2(SCH_1):PVCCIN_CPU0
AG42 PVCCIN_CPU0 VCCIN<264> @BASEBOARD_FAB2_LIB.BASEBOARD_FAB2(SCH_1):PVCCIN_CPU0
AH37 PVCCIN_CPU0 VCCIN<263> @BASEBOARD_FAB2_LIB.BASEBOARD_FAB2(SCH_1):PVCCIN_CPU0
AH39 PVCCIN_CPU0 VCCIN<262> @BASEBOARD_FAB2_LIB.BASEBOARD_FAB2(SCH_1):PVCCIN_CPU0
AH41 PVCCIN_CPU0 VCCIN<261> @BASEBOARD_FAB2_LIB.BASEBOARD_FAB2(SCH_1):PVCCIN_CPU0
AJ36 PVCCIN_CPU0 VCCIN<260> @BASEBOARD_FAB2_LIB.BASEBOARD_FAB2(SCH_1):PVCCIN_CPU0
AK35 PVCCIN_CPU0 VCCIN<259> @BASEBOARD_FAB2_LIB.BASEBOARD_FAB2(SCH_1):PVCCIN_CPU0
AK45 PVCCIN_CPU0 VCCIN<258> @BASEBOARD_FAB2_LIB.BASEBOARD_FAB2(SCH_1):PVCCIN_CPU0
AK47 PVCCIN_CPU0 VCCIN<257> @BASEBOARD_FAB2_LIB.BASEBOARD_FAB2(SCH_1):PVCCIN_CPU0
AK49 PVCCIN_CPU0 VCCIN<256> @BASEBOARD_FAB2_LIB.BASEBOARD_FAB2(SCH_1):PVCCIN_CPU0
AK51 PVCCIN_CPU0 VCCIN<255> @BASEBOARD_FAB2_LIB.BASEBOARD_FAB2(SCH_1):PVCCIN_CPU0
AK53 PVCCIN_CPU0 VCCIN<254> @BASEBOARD_FAB2_LIB.BASEBOARD_FAB2(SCH_1):PVCCIN_CPU0
AL34 PVCCIN_CPU0 VCCIN<253> @BASEBOARD_FAB2_LIB.BASEBOARD_FAB2(SCH_1):PVCCIN_CPU0
AL46 PVCCIN_CPU0 VCCIN<252> @BASEBOARD_FAB2_LIB.BASEBOARD_FAB2(SCH_1):PVCCIN_CPU0
AL48 PVCCIN_CPU0 VCCIN<251> @BASEBOARD_FAB2_LIB.BASEBOARD_FAB2(SCH_1):PVCCIN_CPU0
AL50 PVCCIN_CPU0 VCCIN<250> @BASEBOARD_FAB2_LIB.BASEBOARD_FAB2(SCH_1):PVCCIN_CPU0
AL52 PVCCIN_CPU0 VCCIN<249> @BASEBOARD_FAB2_LIB.BASEBOARD_FAB2(SCH_1):PVCCIN_CPU0
AL54 PVCCIN_CPU0 VCCIN<248> @BASEBOARD_FAB2_LIB.BASEBOARD_FAB2(SCH_1):PVCCIN_CPU0
AM33 PVCCIN_CPU0 VCCIN<247> @BASEBOARD_FAB2_LIB.BASEBOARD_FAB2(SCH_1):PVCCIN_CPU0
AM53 PVCCIN_CPU0 VCCIN<246> @BASEBOARD_FAB2_LIB.BASEBOARD_FAB2(SCH_1):PVCCIN_CPU0
AM55 PVCCIN_CPU0 VCCIN<245> @BASEBOARD_FAB2_LIB.BASEBOARD_FAB2(SCH_1):PVCCIN_CPU0
AN32 PVCCIN_CPU0 VCCIN<244> @BASEBOARD_FAB2_LIB.BASEBOARD_FAB2(SCH_1):PVCCIN_CPU0
AN54 PVCCIN_CPU0 VCCIN<243> @BASEBOARD_FAB2_LIB.BASEBOARD_FAB2(SCH_1):PVCCIN_CPU0
AN56 PVCCIN_CPU0 VCCIN<242> @BASEBOARD_FAB2_LIB.BASEBOARD_FAB2(SCH_1):PVCCIN_CPU0
AP55 PVCCIN_CPU0 VCCIN<241> @BASEBOARD_FAB2_LIB.BASEBOARD_FAB2(SCH_1):PVCCIN_CPU0
AP57 PVCCIN_CPU0 VCCIN<240> @BASEBOARD_FAB2_LIB.BASEBOARD_FAB2(SCH_1):PVCCIN_CPU0
AR56 PVCCIN_CPU0 VCCIN<239> @BASEBOARD_FAB2_LIB.BASEBOARD_FAB2(SCH_1):PVCCIN_CPU0
AR58 PVCCIN_CPU0 VCCIN<238> @BASEBOARD_FAB2_LIB.BASEBOARD_FAB2(SCH_1):PVCCIN_CPU0
AT57 PVCCIN_CPU0 VCCIN<237> @BASEBOARD_FAB2_LIB.BASEBOARD_FAB2(SCH_1):PVCCIN_CPU0
AT59 PVCCIN_CPU0 VCCIN<236> @BASEBOARD_FAB2_LIB.BASEBOARD_FAB2(SCH_1):PVCCIN_CPU0
AU58 PVCCIN_CPU0 VCCIN<235> @BASEBOARD_FAB2_LIB.BASEBOARD_FAB2(SCH_1):PVCCIN_CPU0
AU60 PVCCIN_CPU0 VCCIN<234> @BASEBOARD_FAB2_LIB.BASEBOARD_FAB2(SCH_1):PVCCIN_CPU0
AV59 PVCCIN_CPU0 VCCIN<233> @BASEBOARD_FAB2_LIB.BASEBOARD_FAB2(SCH_1):PVCCIN_CPU0
AV61 PVCCIN_CPU0 VCCIN<232> @BASEBOARD_FAB2_LIB.BASEBOARD_FAB2(SCH_1):PVCCIN_CPU0
AW60 PVCCIN_CPU0 VCCIN<231> @BASEBOARD_FAB2_LIB.BASEBOARD_FAB2(SCH_1):PVCCIN_CPU0
AY61 PVCCIN_CPU0 VCCIN<230> @BASEBOARD_FAB2_LIB.BASEBOARD_FAB2(SCH_1):PVCCIN_CPU0
BA60 PVCCIN_CPU0 VCCIN<229> @BASEBOARD_FAB2_LIB.BASEBOARD_FAB2(SCH_1):PVCCIN_CPU0
BB61 PVCCIN_CPU0 VCCIN<228> @BASEBOARD_FAB2_LIB.BASEBOARD_FAB2(SCH_1):PVCCIN_CPU0
BB85 PVCCIN_CPU0 VCCIN<227> @BASEBOARD_FAB2_LIB.BASEBOARD_FAB2(SCH_1):PVCCIN_CPU0
BC60 PVCCIN_CPU0 VCCIN<226> @BASEBOARD_FAB2_LIB.BASEBOARD_FAB2(SCH_1):PVCCIN_CPU0
BC62 PVCCIN_CPU0 VCCIN<225> @BASEBOARD_FAB2_LIB.BASEBOARD_FAB2(SCH_1):PVCCIN_CPU0
BC84 PVCCIN_CPU0 VCCIN<224> @BASEBOARD_FAB2_LIB.BASEBOARD_FAB2(SCH_1):PVCCIN_CPU0
BD61 PVCCIN_CPU0 VCCIN<223> @BASEBOARD_FAB2_LIB.BASEBOARD_FAB2(SCH_1):PVCCIN_CPU0
BD73 PVCCIN_CPU0 VCCIN<222> @BASEBOARD_FAB2_LIB.BASEBOARD_FAB2(SCH_1):PVCCIN_CPU0
BD75 PVCCIN_CPU0 VCCIN<221> @BASEBOARD_FAB2_LIB.BASEBOARD_FAB2(SCH_1):PVCCIN_CPU0
BD77 PVCCIN_CPU0 VCCIN<220> @BASEBOARD_FAB2_LIB.BASEBOARD_FAB2(SCH_1):PVCCIN_CPU0
BD79 PVCCIN_CPU0 VCCIN<219> @BASEBOARD_FAB2_LIB.BASEBOARD_FAB2(SCH_1):PVCCIN_CPU0
BD81 PVCCIN_CPU0 VCCIN<218> @BASEBOARD_FAB2_LIB.BASEBOARD_FAB2(SCH_1):PVCCIN_CPU0
BD83 PVCCIN_CPU0 VCCIN<217> @BASEBOARD_FAB2_LIB.BASEBOARD_FAB2(SCH_1):PVCCIN_CPU0
BD85 PVCCIN_CPU0 VCCIN<216> @BASEBOARD_FAB2_LIB.BASEBOARD_FAB2(SCH_1):PVCCIN_CPU0
BE60 PVCCIN_CPU0 VCCIN<215> @BASEBOARD_FAB2_LIB.BASEBOARD_FAB2(SCH_1):PVCCIN_CPU0
BE62 PVCCIN_CPU0 VCCIN<214> @BASEBOARD_FAB2_LIB.BASEBOARD_FAB2(SCH_1):PVCCIN_CPU0
BE72 PVCCIN_CPU0 VCCIN<213> @BASEBOARD_FAB2_LIB.BASEBOARD_FAB2(SCH_1):PVCCIN_CPU0
BE74 PVCCIN_CPU0 VCCIN<212> @BASEBOARD_FAB2_LIB.BASEBOARD_FAB2(SCH_1):PVCCIN_CPU0
BE76 PVCCIN_CPU0 VCCIN<211> @BASEBOARD_FAB2_LIB.BASEBOARD_FAB2(SCH_1):PVCCIN_CPU0
BE78 PVCCIN_CPU0 VCCIN<210> @BASEBOARD_FAB2_LIB.BASEBOARD_FAB2(SCH_1):PVCCIN_CPU0
BE80 PVCCIN_CPU0 VCCIN<209> @BASEBOARD_FAB2_LIB.BASEBOARD_FAB2(SCH_1):PVCCIN_CPU0
BE82 PVCCIN_CPU0 VCCIN<208> @BASEBOARD_FAB2_LIB.BASEBOARD_FAB2(SCH_1):PVCCIN_CPU0
BE84 PVCCIN_CPU0 VCCIN<207> @BASEBOARD_FAB2_LIB.BASEBOARD_FAB2(SCH_1):PVCCIN_CPU0
BF61 PVCCIN_CPU0 VCCIN<206> @BASEBOARD_FAB2_LIB.BASEBOARD_FAB2(SCH_1):PVCCIN_CPU0
BF73 PVCCIN_CPU0 VCCIN<205> @BASEBOARD_FAB2_LIB.BASEBOARD_FAB2(SCH_1):PVCCIN_CPU0
BF75 PVCCIN_CPU0 VCCIN<204> @BASEBOARD_FAB2_LIB.BASEBOARD_FAB2(SCH_1):PVCCIN_CPU0
BF77 PVCCIN_CPU0 VCCIN<203> @BASEBOARD_FAB2_LIB.BASEBOARD_FAB2(SCH_1):PVCCIN_CPU0
BF79 PVCCIN_CPU0 VCCIN<202> @BASEBOARD_FAB2_LIB.BASEBOARD_FAB2(SCH_1):PVCCIN_CPU0
BF81 PVCCIN_CPU0 VCCIN<201> @BASEBOARD_FAB2_LIB.BASEBOARD_FAB2(SCH_1):PVCCIN_CPU0
BF83 PVCCIN_CPU0 VCCIN<200> @BASEBOARD_FAB2_LIB.BASEBOARD_FAB2(SCH_1):PVCCIN_CPU0
BF85 PVCCIN_CPU0 VCCIN<199> @BASEBOARD_FAB2_LIB.BASEBOARD_FAB2(SCH_1):PVCCIN_CPU0
BG60 PVCCIN_CPU0 VCCIN<198> @BASEBOARD_FAB2_LIB.BASEBOARD_FAB2(SCH_1):PVCCIN_CPU0
BG62 PVCCIN_CPU0 VCCIN<197> @BASEBOARD_FAB2_LIB.BASEBOARD_FAB2(SCH_1):PVCCIN_CPU0
BG64 PVCCIN_CPU0 VCCIN<196> @BASEBOARD_FAB2_LIB.BASEBOARD_FAB2(SCH_1):PVCCIN_CPU0
BG66 PVCCIN_CPU0 VCCIN<195> @BASEBOARD_FAB2_LIB.BASEBOARD_FAB2(SCH_1):PVCCIN_CPU0
BG68 PVCCIN_CPU0 VCCIN<194> @BASEBOARD_FAB2_LIB.BASEBOARD_FAB2(SCH_1):PVCCIN_CPU0
BG70 PVCCIN_CPU0 VCCIN<193> @BASEBOARD_FAB2_LIB.BASEBOARD_FAB2(SCH_1):PVCCIN_CPU0
BG84 PVCCIN_CPU0 VCCIN<192> @BASEBOARD_FAB2_LIB.BASEBOARD_FAB2(SCH_1):PVCCIN_CPU0
BH61 PVCCIN_CPU0 VCCIN<191> @BASEBOARD_FAB2_LIB.BASEBOARD_FAB2(SCH_1):PVCCIN_CPU0
BH63 PVCCIN_CPU0 VCCIN<190> @BASEBOARD_FAB2_LIB.BASEBOARD_FAB2(SCH_1):PVCCIN_CPU0
BH65 PVCCIN_CPU0 VCCIN<189> @BASEBOARD_FAB2_LIB.BASEBOARD_FAB2(SCH_1):PVCCIN_CPU0
BH67 PVCCIN_CPU0 VCCIN<188> @BASEBOARD_FAB2_LIB.BASEBOARD_FAB2(SCH_1):PVCCIN_CPU0
BH69 PVCCIN_CPU0 VCCIN<187> @BASEBOARD_FAB2_LIB.BASEBOARD_FAB2(SCH_1):PVCCIN_CPU0
BH71 PVCCIN_CPU0 VCCIN<186> @BASEBOARD_FAB2_LIB.BASEBOARD_FAB2(SCH_1):PVCCIN_CPU0
BH73 PVCCIN_CPU0 VCCIN<185> @BASEBOARD_FAB2_LIB.BASEBOARD_FAB2(SCH_1):PVCCIN_CPU0
BH75 PVCCIN_CPU0 VCCIN<184> @BASEBOARD_FAB2_LIB.BASEBOARD_FAB2(SCH_1):PVCCIN_CPU0
BH77 PVCCIN_CPU0 VCCIN<183> @BASEBOARD_FAB2_LIB.BASEBOARD_FAB2(SCH_1):PVCCIN_CPU0
BH79 PVCCIN_CPU0 VCCIN<182> @BASEBOARD_FAB2_LIB.BASEBOARD_FAB2(SCH_1):PVCCIN_CPU0
BH81 PVCCIN_CPU0 VCCIN<181> @BASEBOARD_FAB2_LIB.BASEBOARD_FAB2(SCH_1):PVCCIN_CPU0
BH83 PVCCIN_CPU0 VCCIN<180> @BASEBOARD_FAB2_LIB.BASEBOARD_FAB2(SCH_1):PVCCIN_CPU0
BJ60 PVCCIN_CPU0 VCCIN<179> @BASEBOARD_FAB2_LIB.BASEBOARD_FAB2(SCH_1):PVCCIN_CPU0
BJ62 PVCCIN_CPU0 VCCIN<178> @BASEBOARD_FAB2_LIB.BASEBOARD_FAB2(SCH_1):PVCCIN_CPU0
BJ64 PVCCIN_CPU0 VCCIN<177> @BASEBOARD_FAB2_LIB.BASEBOARD_FAB2(SCH_1):PVCCIN_CPU0
BJ66 PVCCIN_CPU0 VCCIN<176> @BASEBOARD_FAB2_LIB.BASEBOARD_FAB2(SCH_1):PVCCIN_CPU0
BJ68 PVCCIN_CPU0 VCCIN<175> @BASEBOARD_FAB2_LIB.BASEBOARD_FAB2(SCH_1):PVCCIN_CPU0
BJ70 PVCCIN_CPU0 VCCIN<174> @BASEBOARD_FAB2_LIB.BASEBOARD_FAB2(SCH_1):PVCCIN_CPU0
BJ72 PVCCIN_CPU0 VCCIN<173> @BASEBOARD_FAB2_LIB.BASEBOARD_FAB2(SCH_1):PVCCIN_CPU0
BJ74 PVCCIN_CPU0 VCCIN<172> @BASEBOARD_FAB2_LIB.BASEBOARD_FAB2(SCH_1):PVCCIN_CPU0
BJ76 PVCCIN_CPU0 VCCIN<171> @BASEBOARD_FAB2_LIB.BASEBOARD_FAB2(SCH_1):PVCCIN_CPU0
BJ78 PVCCIN_CPU0 VCCIN<170> @BASEBOARD_FAB2_LIB.BASEBOARD_FAB2(SCH_1):PVCCIN_CPU0
BJ80 PVCCIN_CPU0 VCCIN<169> @BASEBOARD_FAB2_LIB.BASEBOARD_FAB2(SCH_1):PVCCIN_CPU0
BJ82 PVCCIN_CPU0 VCCIN<168> @BASEBOARD_FAB2_LIB.BASEBOARD_FAB2(SCH_1):PVCCIN_CPU0
BJ84 PVCCIN_CPU0 VCCIN<167> @BASEBOARD_FAB2_LIB.BASEBOARD_FAB2(SCH_1):PVCCIN_CPU0
BK61 PVCCIN_CPU0 VCCIN<166> @BASEBOARD_FAB2_LIB.BASEBOARD_FAB2(SCH_1):PVCCIN_CPU0
BK63 PVCCIN_CPU0 VCCIN<165> @BASEBOARD_FAB2_LIB.BASEBOARD_FAB2(SCH_1):PVCCIN_CPU0
BK65 PVCCIN_CPU0 VCCIN<164> @BASEBOARD_FAB2_LIB.BASEBOARD_FAB2(SCH_1):PVCCIN_CPU0
BK67 PVCCIN_CPU0 VCCIN<163> @BASEBOARD_FAB2_LIB.BASEBOARD_FAB2(SCH_1):PVCCIN_CPU0
BK69 PVCCIN_CPU0 VCCIN<162> @BASEBOARD_FAB2_LIB.BASEBOARD_FAB2(SCH_1):PVCCIN_CPU0
BK71 PVCCIN_CPU0 VCCIN<161> @BASEBOARD_FAB2_LIB.BASEBOARD_FAB2(SCH_1):PVCCIN_CPU0
BK73 PVCCIN_CPU0 VCCIN<160> @BASEBOARD_FAB2_LIB.BASEBOARD_FAB2(SCH_1):PVCCIN_CPU0
BK75 PVCCIN_CPU0 VCCIN<159> @BASEBOARD_FAB2_LIB.BASEBOARD_FAB2(SCH_1):PVCCIN_CPU0
BK77 PVCCIN_CPU0 VCCIN<158> @BASEBOARD_FAB2_LIB.BASEBOARD_FAB2(SCH_1):PVCCIN_CPU0
BK79 PVCCIN_CPU0 VCCIN<157> @BASEBOARD_FAB2_LIB.BASEBOARD_FAB2(SCH_1):PVCCIN_CPU0
BK81 PVCCIN_CPU0 VCCIN<156> @BASEBOARD_FAB2_LIB.BASEBOARD_FAB2(SCH_1):PVCCIN_CPU0
BK83 PVCCIN_CPU0 VCCIN<155> @BASEBOARD_FAB2_LIB.BASEBOARD_FAB2(SCH_1):PVCCIN_CPU0
BL60 PVCCIN_CPU0 VCCIN<154> @BASEBOARD_FAB2_LIB.BASEBOARD_FAB2(SCH_1):PVCCIN_CPU0
BL62 PVCCIN_CPU0 VCCIN<153> @BASEBOARD_FAB2_LIB.BASEBOARD_FAB2(SCH_1):PVCCIN_CPU0
BL84 PVCCIN_CPU0 VCCIN<152> @BASEBOARD_FAB2_LIB.BASEBOARD_FAB2(SCH_1):PVCCIN_CPU0
BM61 PVCCIN_CPU0 VCCIN<151> @BASEBOARD_FAB2_LIB.BASEBOARD_FAB2(SCH_1):PVCCIN_CPU0
BM63 PVCCIN_CPU0 VCCIN<150> @BASEBOARD_FAB2_LIB.BASEBOARD_FAB2(SCH_1):PVCCIN_CPU0
BM65 PVCCIN_CPU0 VCCIN<149> @BASEBOARD_FAB2_LIB.BASEBOARD_FAB2(SCH_1):PVCCIN_CPU0
BM67 PVCCIN_CPU0 VCCIN<148> @BASEBOARD_FAB2_LIB.BASEBOARD_FAB2(SCH_1):PVCCIN_CPU0
BM69 PVCCIN_CPU0 VCCIN<147> @BASEBOARD_FAB2_LIB.BASEBOARD_FAB2(SCH_1):PVCCIN_CPU0
BM71 PVCCIN_CPU0 VCCIN<146> @BASEBOARD_FAB2_LIB.BASEBOARD_FAB2(SCH_1):PVCCIN_CPU0
BM73 PVCCIN_CPU0 VCCIN<145> @BASEBOARD_FAB2_LIB.BASEBOARD_FAB2(SCH_1):PVCCIN_CPU0
BM75 PVCCIN_CPU0 VCCIN<144> @BASEBOARD_FAB2_LIB.BASEBOARD_FAB2(SCH_1):PVCCIN_CPU0
BM77 PVCCIN_CPU0 VCCIN<143> @BASEBOARD_FAB2_LIB.BASEBOARD_FAB2(SCH_1):PVCCIN_CPU0
BM79 PVCCIN_CPU0 VCCIN<142> @BASEBOARD_FAB2_LIB.BASEBOARD_FAB2(SCH_1):PVCCIN_CPU0
BM81 PVCCIN_CPU0 VCCIN<141> @BASEBOARD_FAB2_LIB.BASEBOARD_FAB2(SCH_1):PVCCIN_CPU0
BM83 PVCCIN_CPU0 VCCIN<140> @BASEBOARD_FAB2_LIB.BASEBOARD_FAB2(SCH_1):PVCCIN_CPU0
BN60 PVCCIN_CPU0 VCCIN<139> @BASEBOARD_FAB2_LIB.BASEBOARD_FAB2(SCH_1):PVCCIN_CPU0
BN62 PVCCIN_CPU0 VCCIN<138> @BASEBOARD_FAB2_LIB.BASEBOARD_FAB2(SCH_1):PVCCIN_CPU0
BN64 PVCCIN_CPU0 VCCIN<137> @BASEBOARD_FAB2_LIB.BASEBOARD_FAB2(SCH_1):PVCCIN_CPU0
BN66 PVCCIN_CPU0 VCCIN<136> @BASEBOARD_FAB2_LIB.BASEBOARD_FAB2(SCH_1):PVCCIN_CPU0
BN68 PVCCIN_CPU0 VCCIN<135> @BASEBOARD_FAB2_LIB.BASEBOARD_FAB2(SCH_1):PVCCIN_CPU0
BN70 PVCCIN_CPU0 VCCIN<134> @BASEBOARD_FAB2_LIB.BASEBOARD_FAB2(SCH_1):PVCCIN_CPU0
BN72 PVCCIN_CPU0 VCCIN<133> @BASEBOARD_FAB2_LIB.BASEBOARD_FAB2(SCH_1):PVCCIN_CPU0
BN74 PVCCIN_CPU0 VCCIN<132> @BASEBOARD_FAB2_LIB.BASEBOARD_FAB2(SCH_1):PVCCIN_CPU0
BN76 PVCCIN_CPU0 VCCIN<131> @BASEBOARD_FAB2_LIB.BASEBOARD_FAB2(SCH_1):PVCCIN_CPU0
BN78 PVCCIN_CPU0 VCCIN<130> @BASEBOARD_FAB2_LIB.BASEBOARD_FAB2(SCH_1):PVCCIN_CPU0

SKX_EXT_B_BGA1-IC,TBD  I311  U5D1
BN80 PVCCIN_CPU0 VCCIN<129> @BASEBOARD_FAB2_LIB.BASEBOARD_FAB2(SCH_1):PVCCIN_CPU0
BN82 PVCCIN_CPU0 VCCIN<128> @BASEBOARD_FAB2_LIB.BASEBOARD_FAB2(SCH_1):PVCCIN_CPU0
BN84 PVCCIN_CPU0 VCCIN<127> @BASEBOARD_FAB2_LIB.BASEBOARD_FAB2(SCH_1):PVCCIN_CPU0
BP61 PVCCIN_CPU0 VCCIN<126> @BASEBOARD_FAB2_LIB.BASEBOARD_FAB2(SCH_1):PVCCIN_CPU0
BP63 PVCCIN_CPU0 VCCIN<125> @BASEBOARD_FAB2_LIB.BASEBOARD_FAB2(SCH_1):PVCCIN_CPU0
BP65 PVCCIN_CPU0 VCCIN<124> @BASEBOARD_FAB2_LIB.BASEBOARD_FAB2(SCH_1):PVCCIN_CPU0
BP67 PVCCIN_CPU0 VCCIN<123> @BASEBOARD_FAB2_LIB.BASEBOARD_FAB2(SCH_1):PVCCIN_CPU0
BP69 PVCCIN_CPU0 VCCIN<122> @BASEBOARD_FAB2_LIB.BASEBOARD_FAB2(SCH_1):PVCCIN_CPU0
BP71 PVCCIN_CPU0 VCCIN<121> @BASEBOARD_FAB2_LIB.BASEBOARD_FAB2(SCH_1):PVCCIN_CPU0
BP73 PVCCIN_CPU0 VCCIN<120> @BASEBOARD_FAB2_LIB.BASEBOARD_FAB2(SCH_1):PVCCIN_CPU0
BP75 PVCCIN_CPU0 VCCIN<119> @BASEBOARD_FAB2_LIB.BASEBOARD_FAB2(SCH_1):PVCCIN_CPU0
BP77 PVCCIN_CPU0 VCCIN<118> @BASEBOARD_FAB2_LIB.BASEBOARD_FAB2(SCH_1):PVCCIN_CPU0
BP79 PVCCIN_CPU0 VCCIN<117> @BASEBOARD_FAB2_LIB.BASEBOARD_FAB2(SCH_1):PVCCIN_CPU0
BP81 PVCCIN_CPU0 VCCIN<116> @BASEBOARD_FAB2_LIB.BASEBOARD_FAB2(SCH_1):PVCCIN_CPU0
BP83 PVCCIN_CPU0 VCCIN<115> @BASEBOARD_FAB2_LIB.BASEBOARD_FAB2(SCH_1):PVCCIN_CPU0
BR60 PVCCIN_CPU0 VCCIN<114> @BASEBOARD_FAB2_LIB.BASEBOARD_FAB2(SCH_1):PVCCIN_CPU0
BR62 PVCCIN_CPU0 VCCIN<113> @BASEBOARD_FAB2_LIB.BASEBOARD_FAB2(SCH_1):PVCCIN_CPU0
BR84 PVCCIN_CPU0 VCCIN<112> @BASEBOARD_FAB2_LIB.BASEBOARD_FAB2(SCH_1):PVCCIN_CPU0
BT61 PVCCIN_CPU0 VCCIN<111> @BASEBOARD_FAB2_LIB.BASEBOARD_FAB2(SCH_1):PVCCIN_CPU0
BT63 PVCCIN_CPU0 VCCIN<110> @BASEBOARD_FAB2_LIB.BASEBOARD_FAB2(SCH_1):PVCCIN_CPU0
BT65 PVCCIN_CPU0 VCCIN<109> @BASEBOARD_FAB2_LIB.BASEBOARD_FAB2(SCH_1):PVCCIN_CPU0
BT67 PVCCIN_CPU0 VCCIN<108> @BASEBOARD_FAB2_LIB.BASEBOARD_FAB2(SCH_1):PVCCIN_CPU0
BT69 PVCCIN_CPU0 VCCIN<107> @BASEBOARD_FAB2_LIB.BASEBOARD_FAB2(SCH_1):PVCCIN_CPU0
BT71 PVCCIN_CPU0 VCCIN<106> @BASEBOARD_FAB2_LIB.BASEBOARD_FAB2(SCH_1):PVCCIN_CPU0
BT73 PVCCIN_CPU0 VCCIN<105> @BASEBOARD_FAB2_LIB.BASEBOARD_FAB2(SCH_1):PVCCIN_CPU0
BT75 PVCCIN_CPU0 VCCIN<104> @BASEBOARD_FAB2_LIB.BASEBOARD_FAB2(SCH_1):PVCCIN_CPU0
BT77 PVCCIN_CPU0 VCCIN<103> @BASEBOARD_FAB2_LIB.BASEBOARD_FAB2(SCH_1):PVCCIN_CPU0
BT79 PVCCIN_CPU0 VCCIN<102> @BASEBOARD_FAB2_LIB.BASEBOARD_FAB2(SCH_1):PVCCIN_CPU0
BT81 PVCCIN_CPU0 VCCIN<101> @BASEBOARD_FAB2_LIB.BASEBOARD_FAB2(SCH_1):PVCCIN_CPU0
BT83 PVCCIN_CPU0 VCCIN<100> @BASEBOARD_FAB2_LIB.BASEBOARD_FAB2(SCH_1):PVCCIN_CPU0
BU60 PVCCIN_CPU0 VCCIN<99> @BASEBOARD_FAB2_LIB.BASEBOARD_FAB2(SCH_1):PVCCIN_CPU0
BU62 PVCCIN_CPU0 VCCIN<98> @BASEBOARD_FAB2_LIB.BASEBOARD_FAB2(SCH_1):PVCCIN_CPU0
BU64 PVCCIN_CPU0 VCCIN<97> @BASEBOARD_FAB2_LIB.BASEBOARD_FAB2(SCH_1):PVCCIN_CPU0
BU66 PVCCIN_CPU0 VCCIN<96> @BASEBOARD_FAB2_LIB.BASEBOARD_FAB2(SCH_1):PVCCIN_CPU0
BU68 PVCCIN_CPU0 VCCIN<95> @BASEBOARD_FAB2_LIB.BASEBOARD_FAB2(SCH_1):PVCCIN_CPU0
BU70 PVCCIN_CPU0 VCCIN<94> @BASEBOARD_FAB2_LIB.BASEBOARD_FAB2(SCH_1):PVCCIN_CPU0
BU72 PVCCIN_CPU0 VCCIN<93> @BASEBOARD_FAB2_LIB.BASEBOARD_FAB2(SCH_1):PVCCIN_CPU0
BU74 PVCCIN_CPU0 VCCIN<92> @BASEBOARD_FAB2_LIB.BASEBOARD_FAB2(SCH_1):PVCCIN_CPU0
BU76 PVCCIN_CPU0 VCCIN<91> @BASEBOARD_FAB2_LIB.BASEBOARD_FAB2(SCH_1):PVCCIN_CPU0
BU78 PVCCIN_CPU0 VCCIN<90> @BASEBOARD_FAB2_LIB.BASEBOARD_FAB2(SCH_1):PVCCIN_CPU0
BU80 PVCCIN_CPU0 VCCIN<89> @BASEBOARD_FAB2_LIB.BASEBOARD_FAB2(SCH_1):PVCCIN_CPU0
BU82 PVCCIN_CPU0 VCCIN<88> @BASEBOARD_FAB2_LIB.BASEBOARD_FAB2(SCH_1):PVCCIN_CPU0
BU84 PVCCIN_CPU0 VCCIN<87> @BASEBOARD_FAB2_LIB.BASEBOARD_FAB2(SCH_1):PVCCIN_CPU0
BV61 PVCCIN_CPU0 VCCIN<86> @BASEBOARD_FAB2_LIB.BASEBOARD_FAB2(SCH_1):PVCCIN_CPU0
BV63 PVCCIN_CPU0 VCCIN<85> @BASEBOARD_FAB2_LIB.BASEBOARD_FAB2(SCH_1):PVCCIN_CPU0
BV65 PVCCIN_CPU0 VCCIN<84> @BASEBOARD_FAB2_LIB.BASEBOARD_FAB2(SCH_1):PVCCIN_CPU0
BV67 PVCCIN_CPU0 VCCIN<83> @BASEBOARD_FAB2_LIB.BASEBOARD_FAB2(SCH_1):PVCCIN_CPU0
BV69 PVCCIN_CPU0 VCCIN<82> @BASEBOARD_FAB2_LIB.BASEBOARD_FAB2(SCH_1):PVCCIN_CPU0
BV71 PVCCIN_CPU0 VCCIN<81> @BASEBOARD_FAB2_LIB.BASEBOARD_FAB2(SCH_1):PVCCIN_CPU0
BV73 PVCCIN_CPU0 VCCIN<80> @BASEBOARD_FAB2_LIB.BASEBOARD_FAB2(SCH_1):PVCCIN_CPU0
BV75 PVCCIN_CPU0 VCCIN<79> @BASEBOARD_FAB2_LIB.BASEBOARD_FAB2(SCH_1):PVCCIN_CPU0
BV77 PVCCIN_CPU0 VCCIN<78> @BASEBOARD_FAB2_LIB.BASEBOARD_FAB2(SCH_1):PVCCIN_CPU0
BV79 PVCCIN_CPU0 VCCIN<77> @BASEBOARD_FAB2_LIB.BASEBOARD_FAB2(SCH_1):PVCCIN_CPU0
BV81 PVCCIN_CPU0 VCCIN<76> @BASEBOARD_FAB2_LIB.BASEBOARD_FAB2(SCH_1):PVCCIN_CPU0
BV83 PVCCIN_CPU0 VCCIN<75> @BASEBOARD_FAB2_LIB.BASEBOARD_FAB2(SCH_1):PVCCIN_CPU0
BW60 PVCCIN_CPU0 VCCIN<74> @BASEBOARD_FAB2_LIB.BASEBOARD_FAB2(SCH_1):PVCCIN_CPU0
BW62 PVCCIN_CPU0 VCCIN<73> @BASEBOARD_FAB2_LIB.BASEBOARD_FAB2(SCH_1):PVCCIN_CPU0
BW64 PVCCIN_CPU0 VCCIN<72> @BASEBOARD_FAB2_LIB.BASEBOARD_FAB2(SCH_1):PVCCIN_CPU0
BW66 PVCCIN_CPU0 VCCIN<71> @BASEBOARD_FAB2_LIB.BASEBOARD_FAB2(SCH_1):PVCCIN_CPU0
BW68 PVCCIN_CPU0 VCCIN<70> @BASEBOARD_FAB2_LIB.BASEBOARD_FAB2(SCH_1):PVCCIN_CPU0
BW70 PVCCIN_CPU0 VCCIN<69> @BASEBOARD_FAB2_LIB.BASEBOARD_FAB2(SCH_1):PVCCIN_CPU0
BW84 PVCCIN_CPU0 VCCIN<68> @BASEBOARD_FAB2_LIB.BASEBOARD_FAB2(SCH_1):PVCCIN_CPU0
BY61 PVCCIN_CPU0 VCCIN<67> @BASEBOARD_FAB2_LIB.BASEBOARD_FAB2(SCH_1):PVCCIN_CPU0
BY73 PVCCIN_CPU0 VCCIN<66> @BASEBOARD_FAB2_LIB.BASEBOARD_FAB2(SCH_1):PVCCIN_CPU0
BY75 PVCCIN_CPU0 VCCIN<65> @BASEBOARD_FAB2_LIB.BASEBOARD_FAB2(SCH_1):PVCCIN_CPU0
BY77 PVCCIN_CPU0 VCCIN<64> @BASEBOARD_FAB2_LIB.BASEBOARD_FAB2(SCH_1):PVCCIN_CPU0
BY79 PVCCIN_CPU0 VCCIN<63> @BASEBOARD_FAB2_LIB.BASEBOARD_FAB2(SCH_1):PVCCIN_CPU0
BY81 PVCCIN_CPU0 VCCIN<62> @BASEBOARD_FAB2_LIB.BASEBOARD_FAB2(SCH_1):PVCCIN_CPU0
BY83 PVCCIN_CPU0 VCCIN<61> @BASEBOARD_FAB2_LIB.BASEBOARD_FAB2(SCH_1):PVCCIN_CPU0
CA60 PVCCIN_CPU0 VCCIN<60> @BASEBOARD_FAB2_LIB.BASEBOARD_FAB2(SCH_1):PVCCIN_CPU0
CA62 PVCCIN_CPU0 VCCIN<59> @BASEBOARD_FAB2_LIB.BASEBOARD_FAB2(SCH_1):PVCCIN_CPU0
CA72 PVCCIN_CPU0 VCCIN<58> @BASEBOARD_FAB2_LIB.BASEBOARD_FAB2(SCH_1):PVCCIN_CPU0
CA74 PVCCIN_CPU0 VCCIN<57> @BASEBOARD_FAB2_LIB.BASEBOARD_FAB2(SCH_1):PVCCIN_CPU0
CA76 PVCCIN_CPU0 VCCIN<56> @BASEBOARD_FAB2_LIB.BASEBOARD_FAB2(SCH_1):PVCCIN_CPU0
CA78 PVCCIN_CPU0 VCCIN<55> @BASEBOARD_FAB2_LIB.BASEBOARD_FAB2(SCH_1):PVCCIN_CPU0
CA80 PVCCIN_CPU0 VCCIN<54> @BASEBOARD_FAB2_LIB.BASEBOARD_FAB2(SCH_1):PVCCIN_CPU0
CA82 PVCCIN_CPU0 VCCIN<53> @BASEBOARD_FAB2_LIB.BASEBOARD_FAB2(SCH_1):PVCCIN_CPU0
CA84 PVCCIN_CPU0 VCCIN<52> @BASEBOARD_FAB2_LIB.BASEBOARD_FAB2(SCH_1):PVCCIN_CPU0
CB61 PVCCIN_CPU0 VCCIN<51> @BASEBOARD_FAB2_LIB.BASEBOARD_FAB2(SCH_1):PVCCIN_CPU0
CB73 PVCCIN_CPU0 VCCIN<50> @BASEBOARD_FAB2_LIB.BASEBOARD_FAB2(SCH_1):PVCCIN_CPU0
CB75 PVCCIN_CPU0 VCCIN<49> @BASEBOARD_FAB2_LIB.BASEBOARD_FAB2(SCH_1):PVCCIN_CPU0
CB77 PVCCIN_CPU0 VCCIN<48> @BASEBOARD_FAB2_LIB.BASEBOARD_FAB2(SCH_1):PVCCIN_CPU0
CB79 PVCCIN_CPU0 VCCIN<47> @BASEBOARD_FAB2_LIB.BASEBOARD_FAB2(SCH_1):PVCCIN_CPU0
CB81 PVCCIN_CPU0 VCCIN<46> @BASEBOARD_FAB2_LIB.BASEBOARD_FAB2(SCH_1):PVCCIN_CPU0
CB83 PVCCIN_CPU0 VCCIN<45> @BASEBOARD_FAB2_LIB.BASEBOARD_FAB2(SCH_1):PVCCIN_CPU0
CC60 PVCCIN_CPU0 VCCIN<44> @BASEBOARD_FAB2_LIB.BASEBOARD_FAB2(SCH_1):PVCCIN_CPU0
CC62 PVCCIN_CPU0 VCCIN<43> @BASEBOARD_FAB2_LIB.BASEBOARD_FAB2(SCH_1):PVCCIN_CPU0
CC84 PVCCIN_CPU0 VCCIN<42> @BASEBOARD_FAB2_LIB.BASEBOARD_FAB2(SCH_1):PVCCIN_CPU0
CD61 PVCCIN_CPU0 VCCIN<41> @BASEBOARD_FAB2_LIB.BASEBOARD_FAB2(SCH_1):PVCCIN_CPU0
CD83 PVCCIN_CPU0 VCCIN<40> @BASEBOARD_FAB2_LIB.BASEBOARD_FAB2(SCH_1):PVCCIN_CPU0
CD85 PVCCIN_CPU0 VCCIN<39> @BASEBOARD_FAB2_LIB.BASEBOARD_FAB2(SCH_1):PVCCIN_CPU0
CE60 PVCCIN_CPU0 VCCIN<38> @BASEBOARD_FAB2_LIB.BASEBOARD_FAB2(SCH_1):PVCCIN_CPU0
CE84 PVCCIN_CPU0 VCCIN<37> @BASEBOARD_FAB2_LIB.BASEBOARD_FAB2(SCH_1):PVCCIN_CPU0
CF61 PVCCIN_CPU0 VCCIN<36> @BASEBOARD_FAB2_LIB.BASEBOARD_FAB2(SCH_1):PVCCIN_CPU0
CF85 PVCCIN_CPU0 VCCIN<35> @BASEBOARD_FAB2_LIB.BASEBOARD_FAB2(SCH_1):PVCCIN_CPU0
CG60 PVCCIN_CPU0 VCCIN<34> @BASEBOARD_FAB2_LIB.BASEBOARD_FAB2(SCH_1):PVCCIN_CPU0
CG84 PVCCIN_CPU0 VCCIN<33> @BASEBOARD_FAB2_LIB.BASEBOARD_FAB2(SCH_1):PVCCIN_CPU0
CH61 PVCCIN_CPU0 VCCIN<32> @BASEBOARD_FAB2_LIB.BASEBOARD_FAB2(SCH_1):PVCCIN_CPU0
CH85 PVCCIN_CPU0 VCCIN<31> @BASEBOARD_FAB2_LIB.BASEBOARD_FAB2(SCH_1):PVCCIN_CPU0
CJ60 PVCCIN_CPU0 VCCIN<30> @BASEBOARD_FAB2_LIB.BASEBOARD_FAB2(SCH_1):PVCCIN_CPU0
CK59 PVCCIN_CPU0 VCCIN<29> @BASEBOARD_FAB2_LIB.BASEBOARD_FAB2(SCH_1):PVCCIN_CPU0
CK61 PVCCIN_CPU0 VCCIN<28> @BASEBOARD_FAB2_LIB.BASEBOARD_FAB2(SCH_1):PVCCIN_CPU0
CL58 PVCCIN_CPU0 VCCIN<27> @BASEBOARD_FAB2_LIB.BASEBOARD_FAB2(SCH_1):PVCCIN_CPU0
CL60 PVCCIN_CPU0 VCCIN<26> @BASEBOARD_FAB2_LIB.BASEBOARD_FAB2(SCH_1):PVCCIN_CPU0
CM57 PVCCIN_CPU0 VCCIN<25> @BASEBOARD_FAB2_LIB.BASEBOARD_FAB2(SCH_1):PVCCIN_CPU0
CM59 PVCCIN_CPU0 VCCIN<24> @BASEBOARD_FAB2_LIB.BASEBOARD_FAB2(SCH_1):PVCCIN_CPU0
CN56 PVCCIN_CPU0 VCCIN<23> @BASEBOARD_FAB2_LIB.BASEBOARD_FAB2(SCH_1):PVCCIN_CPU0
CN58 PVCCIN_CPU0 VCCIN<22> @BASEBOARD_FAB2_LIB.BASEBOARD_FAB2(SCH_1):PVCCIN_CPU0
CP33 PVCCIN_CPU0 VCCIN<21> @BASEBOARD_FAB2_LIB.BASEBOARD_FAB2(SCH_1):PVCCIN_CPU0
CP55 PVCCIN_CPU0 VCCIN<20> @BASEBOARD_FAB2_LIB.BASEBOARD_FAB2(SCH_1):PVCCIN_CPU0
CP57 PVCCIN_CPU0 VCCIN<19> @BASEBOARD_FAB2_LIB.BASEBOARD_FAB2(SCH_1):PVCCIN_CPU0
CR34 PVCCIN_CPU0 VCCIN<18> @BASEBOARD_FAB2_LIB.BASEBOARD_FAB2(SCH_1):PVCCIN_CPU0
CR54 PVCCIN_CPU0 VCCIN<17> @BASEBOARD_FAB2_LIB.BASEBOARD_FAB2(SCH_1):PVCCIN_CPU0
CR56 PVCCIN_CPU0 VCCIN<16> @BASEBOARD_FAB2_LIB.BASEBOARD_FAB2(SCH_1):PVCCIN_CPU0
CT37 PVCCIN_CPU0 VCCIN<15> @BASEBOARD_FAB2_LIB.BASEBOARD_FAB2(SCH_1):PVCCIN_CPU0
CT39 PVCCIN_CPU0 VCCIN<14> @BASEBOARD_FAB2_LIB.BASEBOARD_FAB2(SCH_1):PVCCIN_CPU0
CT41 PVCCIN_CPU0 VCCIN<13> @BASEBOARD_FAB2_LIB.BASEBOARD_FAB2(SCH_1):PVCCIN_CPU0
CT53 PVCCIN_CPU0 VCCIN<12> @BASEBOARD_FAB2_LIB.BASEBOARD_FAB2(SCH_1):PVCCIN_CPU0
CT55 PVCCIN_CPU0 VCCIN<11> @BASEBOARD_FAB2_LIB.BASEBOARD_FAB2(SCH_1):PVCCIN_CPU0
CU38 PVCCIN_CPU0 VCCIN<10> @BASEBOARD_FAB2_LIB.BASEBOARD_FAB2(SCH_1):PVCCIN_CPU0
CU40 PVCCIN_CPU0 VCCIN<9> @BASEBOARD_FAB2_LIB.BASEBOARD_FAB2(SCH_1):PVCCIN_CPU0
CU42 PVCCIN_CPU0 VCCIN<8> @BASEBOARD_FAB2_LIB.BASEBOARD_FAB2(SCH_1):PVCCIN_CPU0
CU52 PVCCIN_CPU0 VCCIN<7> @BASEBOARD_FAB2_LIB.BASEBOARD_FAB2(SCH_1):PVCCIN_CPU0
CU54 PVCCIN_CPU0 VCCIN<6> @BASEBOARD_FAB2_LIB.BASEBOARD_FAB2(SCH_1):PVCCIN_CPU0
CV51 PVCCIN_CPU0 VCCIN<5> @BASEBOARD_FAB2_LIB.BASEBOARD_FAB2(SCH_1):PVCCIN_CPU0
CW46 PVCCIN_CPU0 VCCIN<4> @BASEBOARD_FAB2_LIB.BASEBOARD_FAB2(SCH_1):PVCCIN_CPU0
CW48 PVCCIN_CPU0 VCCIN<3> @BASEBOARD_FAB2_LIB.BASEBOARD_FAB2(SCH_1):PVCCIN_CPU0
CW50 PVCCIN_CPU0 VCCIN<2> @BASEBOARD_FAB2_LIB.BASEBOARD_FAB2(SCH_1):PVCCIN_CPU0
CY47 PVCCIN_CPU0 VCCIN<1> @BASEBOARD_FAB2_LIB.BASEBOARD_FAB2(SCH_1):PVCCIN_CPU0
CY49 PVCCIN_CPU0 VCCIN<0> @BASEBOARD_FAB2_LIB.BASEBOARD_FAB2(SCH_1):PVCCIN_CPU0
AV85 VSENSE_VCCINR2PMAX_CPU0 VCCINPMAX<1> @BASEBOARD_FAB2_LIB.BASEBOARD_FAB2(SCH_1):VSENSE_VCCINR2PMAX_CPU0
AW86 VSENSE_VCCINR2PMAX_CPU0 VCCINPMAX<0> @BASEBOARD_FAB2_LIB.BASEBOARD_FAB2(SCH_1):VSENSE_VCCINR2PMAX_CPU0
BA86 VSENSE_PVCCIN_CPU0_SKT_VSEN VCCIN_SENSE @BASEBOARD_FAB2_LIB.BASEBOARD_FAB2(SCH_1):VSENSE_PVCCIN_CPU0_SKT_VSEN
AD41 VSENSE_PMAX_CPU0 VSENSEPMAX @BASEBOARD_FAB2_LIB.BASEBOARD_FAB2(SCH_1):VSENSE_PMAX_CPU0
AY85 VSENSE_PVCCIN_CPU0_SKT_VRTN VSS_VCCIN_SENSE @BASEBOARD_FAB2_LIB.BASEBOARD_FAB2(SCH_1):VSENSE_PVCCIN_CPU0_SKT_VRTN

RES_0402-10.0,1%,1/16W,EMPTY,GA  I312  R5D6
   1 PVCCIO_CPU0      A @BASEBOARD_FAB2_LIB.BASEBOARD_FAB2(SCH_1):PVCCIO_CPU0
   2 VSENSE_PMAX_CPU0      B @BASEBOARD_FAB2_LIB.BASEBOARD_FAB2(SCH_1):VSENSE_PMAX_CPU0


DRAWING: @BASEBOARD_FAB2_LIB.BASEBOARD_FAB2(SCH_1):PAGE38 

CAP_0603LF-10UF,4V,20%,X6S,E15A  I19  C6D1
   1 P1V8_MCP_CPU0      A @BASEBOARD_FAB2_LIB.BASEBOARD_FAB2(SCH_1):P1V8_MCP_CPU0
   2    GND      B @BASEBOARD_FAB2_LIB.BASEBOARD_FAB2(SCH_1):GND

SKX_EXT_B_BGA1-IC,TBD  I33  U5D1
 B47 PVDDQ_ABC VCCD012<51> @BASEBOARD_FAB2_LIB.BASEBOARD_FAB2(SCH_1):PVDDQ_ABC
 C46 PVDDQ_ABC VCCD012<50> @BASEBOARD_FAB2_LIB.BASEBOARD_FAB2(SCH_1):PVDDQ_ABC
 D45 PVDDQ_ABC VCCD012<49> @BASEBOARD_FAB2_LIB.BASEBOARD_FAB2(SCH_1):PVDDQ_ABC
AF63 PVDDQ_ABC VCCD012<48> @BASEBOARD_FAB2_LIB.BASEBOARD_FAB2(SCH_1):PVDDQ_ABC
AF61 PVDDQ_ABC VCCD012<47> @BASEBOARD_FAB2_LIB.BASEBOARD_FAB2(SCH_1):PVDDQ_ABC
AF59 PVDDQ_ABC VCCD012<46> @BASEBOARD_FAB2_LIB.BASEBOARD_FAB2(SCH_1):PVDDQ_ABC
AF57 PVDDQ_ABC VCCD012<45> @BASEBOARD_FAB2_LIB.BASEBOARD_FAB2(SCH_1):PVDDQ_ABC
AF55 PVDDQ_ABC VCCD012<44> @BASEBOARD_FAB2_LIB.BASEBOARD_FAB2(SCH_1):PVDDQ_ABC
AD45 PVDDQ_ABC VCCD012<43> @BASEBOARD_FAB2_LIB.BASEBOARD_FAB2(SCH_1):PVDDQ_ABC
 Y63 PVDDQ_ABC VCCD012<42> @BASEBOARD_FAB2_LIB.BASEBOARD_FAB2(SCH_1):PVDDQ_ABC
 Y61 PVDDQ_ABC VCCD012<41> @BASEBOARD_FAB2_LIB.BASEBOARD_FAB2(SCH_1):PVDDQ_ABC
 Y59 PVDDQ_ABC VCCD012<40> @BASEBOARD_FAB2_LIB.BASEBOARD_FAB2(SCH_1):PVDDQ_ABC
 Y57 PVDDQ_ABC VCCD012<39> @BASEBOARD_FAB2_LIB.BASEBOARD_FAB2(SCH_1):PVDDQ_ABC
 Y55 PVDDQ_ABC VCCD012<38> @BASEBOARD_FAB2_LIB.BASEBOARD_FAB2(SCH_1):PVDDQ_ABC
 Y53 PVDDQ_ABC VCCD012<37> @BASEBOARD_FAB2_LIB.BASEBOARD_FAB2(SCH_1):PVDDQ_ABC
 Y51 PVDDQ_ABC VCCD012<36> @BASEBOARD_FAB2_LIB.BASEBOARD_FAB2(SCH_1):PVDDQ_ABC
 Y49 PVDDQ_ABC VCCD012<35> @BASEBOARD_FAB2_LIB.BASEBOARD_FAB2(SCH_1):PVDDQ_ABC
 Y47 PVDDQ_ABC VCCD012<34> @BASEBOARD_FAB2_LIB.BASEBOARD_FAB2(SCH_1):PVDDQ_ABC
 Y45 PVDDQ_ABC VCCD012<33> @BASEBOARD_FAB2_LIB.BASEBOARD_FAB2(SCH_1):PVDDQ_ABC
 W64 PVDDQ_ABC VCCD012<32> @BASEBOARD_FAB2_LIB.BASEBOARD_FAB2(SCH_1):PVDDQ_ABC
 U62 PVDDQ_ABC VCCD012<31> @BASEBOARD_FAB2_LIB.BASEBOARD_FAB2(SCH_1):PVDDQ_ABC
 U60 PVDDQ_ABC VCCD012<30> @BASEBOARD_FAB2_LIB.BASEBOARD_FAB2(SCH_1):PVDDQ_ABC
 U58 PVDDQ_ABC VCCD012<29> @BASEBOARD_FAB2_LIB.BASEBOARD_FAB2(SCH_1):PVDDQ_ABC
 U56 PVDDQ_ABC VCCD012<28> @BASEBOARD_FAB2_LIB.BASEBOARD_FAB2(SCH_1):PVDDQ_ABC
 U54 PVDDQ_ABC VCCD012<27> @BASEBOARD_FAB2_LIB.BASEBOARD_FAB2(SCH_1):PVDDQ_ABC
 U52 PVDDQ_ABC VCCD012<26> @BASEBOARD_FAB2_LIB.BASEBOARD_FAB2(SCH_1):PVDDQ_ABC
 U50 PVDDQ_ABC VCCD012<25> @BASEBOARD_FAB2_LIB.BASEBOARD_FAB2(SCH_1):PVDDQ_ABC
 U48 PVDDQ_ABC VCCD012<24> @BASEBOARD_FAB2_LIB.BASEBOARD_FAB2(SCH_1):PVDDQ_ABC
 U46 PVDDQ_ABC VCCD012<23> @BASEBOARD_FAB2_LIB.BASEBOARD_FAB2(SCH_1):PVDDQ_ABC
 N64 PVDDQ_ABC VCCD012<22> @BASEBOARD_FAB2_LIB.BASEBOARD_FAB2(SCH_1):PVDDQ_ABC
 L62 PVDDQ_ABC VCCD012<21> @BASEBOARD_FAB2_LIB.BASEBOARD_FAB2(SCH_1):PVDDQ_ABC
 L60 PVDDQ_ABC VCCD012<20> @BASEBOARD_FAB2_LIB.BASEBOARD_FAB2(SCH_1):PVDDQ_ABC
 L58 PVDDQ_ABC VCCD012<19> @BASEBOARD_FAB2_LIB.BASEBOARD_FAB2(SCH_1):PVDDQ_ABC
 L56 PVDDQ_ABC VCCD012<18> @BASEBOARD_FAB2_LIB.BASEBOARD_FAB2(SCH_1):PVDDQ_ABC
 L54 PVDDQ_ABC VCCD012<17> @BASEBOARD_FAB2_LIB.BASEBOARD_FAB2(SCH_1):PVDDQ_ABC
 L52 PVDDQ_ABC VCCD012<16> @BASEBOARD_FAB2_LIB.BASEBOARD_FAB2(SCH_1):PVDDQ_ABC
 L50 PVDDQ_ABC VCCD012<15> @BASEBOARD_FAB2_LIB.BASEBOARD_FAB2(SCH_1):PVDDQ_ABC
 L48 PVDDQ_ABC VCCD012<14> @BASEBOARD_FAB2_LIB.BASEBOARD_FAB2(SCH_1):PVDDQ_ABC
 L46 PVDDQ_ABC VCCD012<13> @BASEBOARD_FAB2_LIB.BASEBOARD_FAB2(SCH_1):PVDDQ_ABC
 E64 PVDDQ_ABC VCCD012<12> @BASEBOARD_FAB2_LIB.BASEBOARD_FAB2(SCH_1):PVDDQ_ABC
 E62 PVDDQ_ABC VCCD012<11> @BASEBOARD_FAB2_LIB.BASEBOARD_FAB2(SCH_1):PVDDQ_ABC
 E60 PVDDQ_ABC VCCD012<10> @BASEBOARD_FAB2_LIB.BASEBOARD_FAB2(SCH_1):PVDDQ_ABC
 E58 PVDDQ_ABC VCCD012<9> @BASEBOARD_FAB2_LIB.BASEBOARD_FAB2(SCH_1):PVDDQ_ABC
 E56 PVDDQ_ABC VCCD012<8> @BASEBOARD_FAB2_LIB.BASEBOARD_FAB2(SCH_1):PVDDQ_ABC
 E54 PVDDQ_ABC VCCD012<7> @BASEBOARD_FAB2_LIB.BASEBOARD_FAB2(SCH_1):PVDDQ_ABC
 E52 PVDDQ_ABC VCCD012<6> @BASEBOARD_FAB2_LIB.BASEBOARD_FAB2(SCH_1):PVDDQ_ABC
 E50 PVDDQ_ABC VCCD012<5> @BASEBOARD_FAB2_LIB.BASEBOARD_FAB2(SCH_1):PVDDQ_ABC
 E48 PVDDQ_ABC VCCD012<4> @BASEBOARD_FAB2_LIB.BASEBOARD_FAB2(SCH_1):PVDDQ_ABC
 E46 PVDDQ_ABC VCCD012<3> @BASEBOARD_FAB2_LIB.BASEBOARD_FAB2(SCH_1):PVDDQ_ABC
 B59 PVDDQ_ABC VCCD012<2> @BASEBOARD_FAB2_LIB.BASEBOARD_FAB2(SCH_1):PVDDQ_ABC
 B53 PVDDQ_ABC VCCD012<1> @BASEBOARD_FAB2_LIB.BASEBOARD_FAB2(SCH_1):PVDDQ_ABC
 B49 PVDDQ_ABC VCCD012<0> @BASEBOARD_FAB2_LIB.BASEBOARD_FAB2(SCH_1):PVDDQ_ABC
EE44 PVDDQ_DEF VCCD345<50> @BASEBOARD_FAB2_LIB.BASEBOARD_FAB2(SCH_1):PVDDQ_DEF
EF45 PVDDQ_DEF VCCD345<49> @BASEBOARD_FAB2_LIB.BASEBOARD_FAB2(SCH_1):PVDDQ_DEF
DB53 PVDDQ_DEF VCCD345<48> @BASEBOARD_FAB2_LIB.BASEBOARD_FAB2(SCH_1):PVDDQ_DEF
DB55 PVDDQ_DEF VCCD345<47> @BASEBOARD_FAB2_LIB.BASEBOARD_FAB2(SCH_1):PVDDQ_DEF
DB57 PVDDQ_DEF VCCD345<46> @BASEBOARD_FAB2_LIB.BASEBOARD_FAB2(SCH_1):PVDDQ_DEF
DB59 PVDDQ_DEF VCCD345<45> @BASEBOARD_FAB2_LIB.BASEBOARD_FAB2(SCH_1):PVDDQ_DEF
DB61 PVDDQ_DEF VCCD345<44> @BASEBOARD_FAB2_LIB.BASEBOARD_FAB2(SCH_1):PVDDQ_DEF
DB63 PVDDQ_DEF VCCD345<43> @BASEBOARD_FAB2_LIB.BASEBOARD_FAB2(SCH_1):PVDDQ_DEF
DD45 PVDDQ_DEF VCCD345<42> @BASEBOARD_FAB2_LIB.BASEBOARD_FAB2(SCH_1):PVDDQ_DEF
DH45 PVDDQ_DEF VCCD345<41> @BASEBOARD_FAB2_LIB.BASEBOARD_FAB2(SCH_1):PVDDQ_DEF
DH47 PVDDQ_DEF VCCD345<40> @BASEBOARD_FAB2_LIB.BASEBOARD_FAB2(SCH_1):PVDDQ_DEF
DH49 PVDDQ_DEF VCCD345<39> @BASEBOARD_FAB2_LIB.BASEBOARD_FAB2(SCH_1):PVDDQ_DEF
DH51 PVDDQ_DEF VCCD345<38> @BASEBOARD_FAB2_LIB.BASEBOARD_FAB2(SCH_1):PVDDQ_DEF
DH53 PVDDQ_DEF VCCD345<37> @BASEBOARD_FAB2_LIB.BASEBOARD_FAB2(SCH_1):PVDDQ_DEF
DH55 PVDDQ_DEF VCCD345<36> @BASEBOARD_FAB2_LIB.BASEBOARD_FAB2(SCH_1):PVDDQ_DEF
DH57 PVDDQ_DEF VCCD345<35> @BASEBOARD_FAB2_LIB.BASEBOARD_FAB2(SCH_1):PVDDQ_DEF
DH59 PVDDQ_DEF VCCD345<34> @BASEBOARD_FAB2_LIB.BASEBOARD_FAB2(SCH_1):PVDDQ_DEF
DH61 PVDDQ_DEF VCCD345<33> @BASEBOARD_FAB2_LIB.BASEBOARD_FAB2(SCH_1):PVDDQ_DEF
DH63 PVDDQ_DEF VCCD345<32> @BASEBOARD_FAB2_LIB.BASEBOARD_FAB2(SCH_1):PVDDQ_DEF
DJ64 PVDDQ_DEF VCCD345<31> @BASEBOARD_FAB2_LIB.BASEBOARD_FAB2(SCH_1):PVDDQ_DEF
DL46 PVDDQ_DEF VCCD345<30> @BASEBOARD_FAB2_LIB.BASEBOARD_FAB2(SCH_1):PVDDQ_DEF
DL48 PVDDQ_DEF VCCD345<29> @BASEBOARD_FAB2_LIB.BASEBOARD_FAB2(SCH_1):PVDDQ_DEF
DL50 PVDDQ_DEF VCCD345<28> @BASEBOARD_FAB2_LIB.BASEBOARD_FAB2(SCH_1):PVDDQ_DEF
DL52 PVDDQ_DEF VCCD345<27> @BASEBOARD_FAB2_LIB.BASEBOARD_FAB2(SCH_1):PVDDQ_DEF
DL54 PVDDQ_DEF VCCD345<26> @BASEBOARD_FAB2_LIB.BASEBOARD_FAB2(SCH_1):PVDDQ_DEF
DL56 PVDDQ_DEF VCCD345<25> @BASEBOARD_FAB2_LIB.BASEBOARD_FAB2(SCH_1):PVDDQ_DEF
DL58 PVDDQ_DEF VCCD345<24> @BASEBOARD_FAB2_LIB.BASEBOARD_FAB2(SCH_1):PVDDQ_DEF
DL60 PVDDQ_DEF VCCD345<23> @BASEBOARD_FAB2_LIB.BASEBOARD_FAB2(SCH_1):PVDDQ_DEF
DL62 PVDDQ_DEF VCCD345<22> @BASEBOARD_FAB2_LIB.BASEBOARD_FAB2(SCH_1):PVDDQ_DEF
DU46 PVDDQ_DEF VCCD345<21> @BASEBOARD_FAB2_LIB.BASEBOARD_FAB2(SCH_1):PVDDQ_DEF
DU48 PVDDQ_DEF VCCD345<20> @BASEBOARD_FAB2_LIB.BASEBOARD_FAB2(SCH_1):PVDDQ_DEF
DU50 PVDDQ_DEF VCCD345<19> @BASEBOARD_FAB2_LIB.BASEBOARD_FAB2(SCH_1):PVDDQ_DEF
DU52 PVDDQ_DEF VCCD345<18> @BASEBOARD_FAB2_LIB.BASEBOARD_FAB2(SCH_1):PVDDQ_DEF
DU54 PVDDQ_DEF VCCD345<17> @BASEBOARD_FAB2_LIB.BASEBOARD_FAB2(SCH_1):PVDDQ_DEF
DU56 PVDDQ_DEF VCCD345<16> @BASEBOARD_FAB2_LIB.BASEBOARD_FAB2(SCH_1):PVDDQ_DEF
DU58 PVDDQ_DEF VCCD345<15> @BASEBOARD_FAB2_LIB.BASEBOARD_FAB2(SCH_1):PVDDQ_DEF
DU60 PVDDQ_DEF VCCD345<14> @BASEBOARD_FAB2_LIB.BASEBOARD_FAB2(SCH_1):PVDDQ_DEF
DU62 PVDDQ_DEF VCCD345<13> @BASEBOARD_FAB2_LIB.BASEBOARD_FAB2(SCH_1):PVDDQ_DEF
DU64 PVDDQ_DEF VCCD345<12> @BASEBOARD_FAB2_LIB.BASEBOARD_FAB2(SCH_1):PVDDQ_DEF
EC46 PVDDQ_DEF VCCD345<11> @BASEBOARD_FAB2_LIB.BASEBOARD_FAB2(SCH_1):PVDDQ_DEF
EC48 PVDDQ_DEF VCCD345<10> @BASEBOARD_FAB2_LIB.BASEBOARD_FAB2(SCH_1):PVDDQ_DEF
EC50 PVDDQ_DEF VCCD345<9> @BASEBOARD_FAB2_LIB.BASEBOARD_FAB2(SCH_1):PVDDQ_DEF
EC52 PVDDQ_DEF VCCD345<8> @BASEBOARD_FAB2_LIB.BASEBOARD_FAB2(SCH_1):PVDDQ_DEF
EC54 PVDDQ_DEF VCCD345<7> @BASEBOARD_FAB2_LIB.BASEBOARD_FAB2(SCH_1):PVDDQ_DEF
EC56 PVDDQ_DEF VCCD345<6> @BASEBOARD_FAB2_LIB.BASEBOARD_FAB2(SCH_1):PVDDQ_DEF
EC58 PVDDQ_DEF VCCD345<5> @BASEBOARD_FAB2_LIB.BASEBOARD_FAB2(SCH_1):PVDDQ_DEF
EC60 PVDDQ_DEF VCCD345<4> @BASEBOARD_FAB2_LIB.BASEBOARD_FAB2(SCH_1):PVDDQ_DEF
EC62 PVDDQ_DEF VCCD345<3> @BASEBOARD_FAB2_LIB.BASEBOARD_FAB2(SCH_1):PVDDQ_DEF
EF49 PVDDQ_DEF VCCD345<2> @BASEBOARD_FAB2_LIB.BASEBOARD_FAB2(SCH_1):PVDDQ_DEF
EF53 PVDDQ_DEF VCCD345<1> @BASEBOARD_FAB2_LIB.BASEBOARD_FAB2(SCH_1):PVDDQ_DEF
EF59 PVDDQ_DEF VCCD345<0> @BASEBOARD_FAB2_LIB.BASEBOARD_FAB2(SCH_1):PVDDQ_DEF

SKX_EXT_B_BGA1-IC,TBD  I34  U5D1
BY27 P1V8_MCP_CPU0 CD_VCCIN<3> @BASEBOARD_FAB2_LIB.BASEBOARD_FAB2(SCH_1):P1V8_MCP_CPU0
BV27 P1V8_MCP_CPU0 CD_VCCIN<2> @BASEBOARD_FAB2_LIB.BASEBOARD_FAB2(SCH_1):P1V8_MCP_CPU0
BU26 P1V8_MCP_CPU0 CD_VCCIN<1> @BASEBOARD_FAB2_LIB.BASEBOARD_FAB2(SCH_1):P1V8_MCP_CPU0
BT27 P1V8_MCP_CPU0 CD_VCCIN<0> @BASEBOARD_FAB2_LIB.BASEBOARD_FAB2(SCH_1):P1V8_MCP_CPU0
BM11 PVCCIOMCP_CPU0 CD_VCCP<15> @BASEBOARD_FAB2_LIB.BASEBOARD_FAB2(SCH_1):PVCCIOMCP_CPU0
BN12 PVCCIOMCP_CPU0 CD_VCCP<14> @BASEBOARD_FAB2_LIB.BASEBOARD_FAB2(SCH_1):PVCCIOMCP_CPU0
BN14 PVCCIOMCP_CPU0 CD_VCCP<13> @BASEBOARD_FAB2_LIB.BASEBOARD_FAB2(SCH_1):PVCCIOMCP_CPU0
BP11 PVCCIOMCP_CPU0 CD_VCCP<12> @BASEBOARD_FAB2_LIB.BASEBOARD_FAB2(SCH_1):PVCCIOMCP_CPU0
BP13 PVCCIOMCP_CPU0 CD_VCCP<11> @BASEBOARD_FAB2_LIB.BASEBOARD_FAB2(SCH_1):PVCCIOMCP_CPU0
BP15 PVCCIOMCP_CPU0 CD_VCCP<10> @BASEBOARD_FAB2_LIB.BASEBOARD_FAB2(SCH_1):PVCCIOMCP_CPU0
BR12 PVCCIOMCP_CPU0 CD_VCCP<9> @BASEBOARD_FAB2_LIB.BASEBOARD_FAB2(SCH_1):PVCCIOMCP_CPU0
BR14 PVCCIOMCP_CPU0 CD_VCCP<8> @BASEBOARD_FAB2_LIB.BASEBOARD_FAB2(SCH_1):PVCCIOMCP_CPU0
BT11 PVCCIOMCP_CPU0 CD_VCCP<7> @BASEBOARD_FAB2_LIB.BASEBOARD_FAB2(SCH_1):PVCCIOMCP_CPU0
BT13 PVCCIOMCP_CPU0 CD_VCCP<6> @BASEBOARD_FAB2_LIB.BASEBOARD_FAB2(SCH_1):PVCCIOMCP_CPU0
BT15 PVCCIOMCP_CPU0 CD_VCCP<5> @BASEBOARD_FAB2_LIB.BASEBOARD_FAB2(SCH_1):PVCCIOMCP_CPU0
BU12 PVCCIOMCP_CPU0 CD_VCCP<4> @BASEBOARD_FAB2_LIB.BASEBOARD_FAB2(SCH_1):PVCCIOMCP_CPU0
BU14 PVCCIOMCP_CPU0 CD_VCCP<3> @BASEBOARD_FAB2_LIB.BASEBOARD_FAB2(SCH_1):PVCCIOMCP_CPU0
BV11 PVCCIOMCP_CPU0 CD_VCCP<2> @BASEBOARD_FAB2_LIB.BASEBOARD_FAB2(SCH_1):PVCCIOMCP_CPU0
BV13 PVCCIOMCP_CPU0 CD_VCCP<1> @BASEBOARD_FAB2_LIB.BASEBOARD_FAB2(SCH_1):PVCCIOMCP_CPU0
BV15 PVCCIOMCP_CPU0 CD_VCCP<0> @BASEBOARD_FAB2_LIB.BASEBOARD_FAB2(SCH_1):PVCCIOMCP_CPU0
BD13 PVCCMCP_CPU0 CD_VCC_CORE<12> @BASEBOARD_FAB2_LIB.BASEBOARD_FAB2(SCH_1):PVCCMCP_CPU0
BE12 PVCCMCP_CPU0 CD_VCC_CORE<11> @BASEBOARD_FAB2_LIB.BASEBOARD_FAB2(SCH_1):PVCCMCP_CPU0
BE14 PVCCMCP_CPU0 CD_VCC_CORE<10> @BASEBOARD_FAB2_LIB.BASEBOARD_FAB2(SCH_1):PVCCMCP_CPU0
BF11 PVCCMCP_CPU0 CD_VCC_CORE<9> @BASEBOARD_FAB2_LIB.BASEBOARD_FAB2(SCH_1):PVCCMCP_CPU0
BF13 PVCCMCP_CPU0 CD_VCC_CORE<8> @BASEBOARD_FAB2_LIB.BASEBOARD_FAB2(SCH_1):PVCCMCP_CPU0
BG12 PVCCMCP_CPU0 CD_VCC_CORE<7> @BASEBOARD_FAB2_LIB.BASEBOARD_FAB2(SCH_1):PVCCMCP_CPU0
BG14 PVCCMCP_CPU0 CD_VCC_CORE<6> @BASEBOARD_FAB2_LIB.BASEBOARD_FAB2(SCH_1):PVCCMCP_CPU0
BH13 PVCCMCP_CPU0 CD_VCC_CORE<5> @BASEBOARD_FAB2_LIB.BASEBOARD_FAB2(SCH_1):PVCCMCP_CPU0
BJ12 PVCCMCP_CPU0 CD_VCC_CORE<4> @BASEBOARD_FAB2_LIB.BASEBOARD_FAB2(SCH_1):PVCCMCP_CPU0
BJ14 PVCCMCP_CPU0 CD_VCC_CORE<3> @BASEBOARD_FAB2_LIB.BASEBOARD_FAB2(SCH_1):PVCCMCP_CPU0
BK13 PVCCMCP_CPU0 CD_VCC_CORE<2> @BASEBOARD_FAB2_LIB.BASEBOARD_FAB2(SCH_1):PVCCMCP_CPU0
BK15 PVCCMCP_CPU0 CD_VCC_CORE<1> @BASEBOARD_FAB2_LIB.BASEBOARD_FAB2(SCH_1):PVCCMCP_CPU0
BL14 PVCCMCP_CPU0 CD_VCC_CORE<0> @BASEBOARD_FAB2_LIB.BASEBOARD_FAB2(SCH_1):PVCCMCP_CPU0
  A8 PVPP_ABC CD_VPP<3> @BASEBOARD_FAB2_LIB.BASEBOARD_FAB2(SCH_1):PVPP_ABC
 A10 PVPP_ABC CD_VPP<2> @BASEBOARD_FAB2_LIB.BASEBOARD_FAB2(SCH_1):PVPP_ABC
 A12 PVPP_ABC CD_VPP<1> @BASEBOARD_FAB2_LIB.BASEBOARD_FAB2(SCH_1):PVPP_ABC
 B11 PVPP_ABC CD_VPP<0> @BASEBOARD_FAB2_LIB.BASEBOARD_FAB2(SCH_1):PVPP_ABC
CY55 P3V3_STBY  VCC33 @BASEBOARD_FAB2_LIB.BASEBOARD_FAB2(SCH_1):P3V3_STBY
AR28 PVCCIO_CPU0 VCCIO<104> @BASEBOARD_FAB2_LIB.BASEBOARD_FAB2(SCH_1):PVCCIO_CPU0
AL28 PVCCIO_CPU0 VCCIO<103> @BASEBOARD_FAB2_LIB.BASEBOARD_FAB2(SCH_1):PVCCIO_CPU0
AM29 PVCCIO_CPU0 VCCIO<102> @BASEBOARD_FAB2_LIB.BASEBOARD_FAB2(SCH_1):PVCCIO_CPU0
AG34 PVCCIO_CPU0 VCCIO<101> @BASEBOARD_FAB2_LIB.BASEBOARD_FAB2(SCH_1):PVCCIO_CPU0
AE34 PVCCIO_CPU0 VCCIO<100> @BASEBOARD_FAB2_LIB.BASEBOARD_FAB2(SCH_1):PVCCIO_CPU0
AD35 PVCCIO_CPU0 VCCIO<99> @BASEBOARD_FAB2_LIB.BASEBOARD_FAB2(SCH_1):PVCCIO_CPU0
AF35 PVCCIO_CPU0 VCCIO<98> @BASEBOARD_FAB2_LIB.BASEBOARD_FAB2(SCH_1):PVCCIO_CPU0
AC36 PVCCIO_CPU0 VCCIO<97> @BASEBOARD_FAB2_LIB.BASEBOARD_FAB2(SCH_1):PVCCIO_CPU0
AD37 PVCCIO_CPU0 VCCIO<96> @BASEBOARD_FAB2_LIB.BASEBOARD_FAB2(SCH_1):PVCCIO_CPU0
AE36 PVCCIO_CPU0 VCCIO<95> @BASEBOARD_FAB2_LIB.BASEBOARD_FAB2(SCH_1):PVCCIO_CPU0
BF27 PVCCIO_CPU0 VCCIO<94> @BASEBOARD_FAB2_LIB.BASEBOARD_FAB2(SCH_1):PVCCIO_CPU0
BG26 PVCCIO_CPU0 VCCIO<93> @BASEBOARD_FAB2_LIB.BASEBOARD_FAB2(SCH_1):PVCCIO_CPU0
BH25 PVCCIO_CPU0 VCCIO<92> @BASEBOARD_FAB2_LIB.BASEBOARD_FAB2(SCH_1):PVCCIO_CPU0
BH27 PVCCIO_CPU0 VCCIO<91> @BASEBOARD_FAB2_LIB.BASEBOARD_FAB2(SCH_1):PVCCIO_CPU0
BJ26 PVCCIO_CPU0 VCCIO<90> @BASEBOARD_FAB2_LIB.BASEBOARD_FAB2(SCH_1):PVCCIO_CPU0
BK25 PVCCIO_CPU0 VCCIO<89> @BASEBOARD_FAB2_LIB.BASEBOARD_FAB2(SCH_1):PVCCIO_CPU0
BK27 PVCCIO_CPU0 VCCIO<88> @BASEBOARD_FAB2_LIB.BASEBOARD_FAB2(SCH_1):PVCCIO_CPU0
BL26 PVCCIO_CPU0 VCCIO<87> @BASEBOARD_FAB2_LIB.BASEBOARD_FAB2(SCH_1):PVCCIO_CPU0
BM27 PVCCIO_CPU0 VCCIO<86> @BASEBOARD_FAB2_LIB.BASEBOARD_FAB2(SCH_1):PVCCIO_CPU0
CH27 PVCCIO_CPU0 VCCIO<85> @BASEBOARD_FAB2_LIB.BASEBOARD_FAB2(SCH_1):PVCCIO_CPU0
CJ28 PVCCIO_CPU0 VCCIO<84> @BASEBOARD_FAB2_LIB.BASEBOARD_FAB2(SCH_1):PVCCIO_CPU0
CC26 PVCCIO_CPU0 VCCIO<83> @BASEBOARD_FAB2_LIB.BASEBOARD_FAB2(SCH_1):PVCCIO_CPU0
CD27 PVCCIO_CPU0 VCCIO<82> @BASEBOARD_FAB2_LIB.BASEBOARD_FAB2(SCH_1):PVCCIO_CPU0
CF27 PVCCIO_CPU0 VCCIO<81> @BASEBOARD_FAB2_LIB.BASEBOARD_FAB2(SCH_1):PVCCIO_CPU0
AV27 PVCCIO_CPU0 VCCIO<80> @BASEBOARD_FAB2_LIB.BASEBOARD_FAB2(SCH_1):PVCCIO_CPU0
AW26 PVCCIO_CPU0 VCCIO<79> @BASEBOARD_FAB2_LIB.BASEBOARD_FAB2(SCH_1):PVCCIO_CPU0
AY27 PVCCIO_CPU0 VCCIO<78> @BASEBOARD_FAB2_LIB.BASEBOARD_FAB2(SCH_1):PVCCIO_CPU0
BA26 PVCCIO_CPU0 VCCIO<77> @BASEBOARD_FAB2_LIB.BASEBOARD_FAB2(SCH_1):PVCCIO_CPU0
BB27 PVCCIO_CPU0 VCCIO<76> @BASEBOARD_FAB2_LIB.BASEBOARD_FAB2(SCH_1):PVCCIO_CPU0
BC26 PVCCIO_CPU0 VCCIO<75> @BASEBOARD_FAB2_LIB.BASEBOARD_FAB2(SCH_1):PVCCIO_CPU0
 W10 PVCCIO_CPU0 VCCIO<74> @BASEBOARD_FAB2_LIB.BASEBOARD_FAB2(SCH_1):PVCCIO_CPU0
 N18 PVCCIO_CPU0 VCCIO<73> @BASEBOARD_FAB2_LIB.BASEBOARD_FAB2(SCH_1):PVCCIO_CPU0
  M9 PVCCIO_CPU0 VCCIO<72> @BASEBOARD_FAB2_LIB.BASEBOARD_FAB2(SCH_1):PVCCIO_CPU0
  M7 PVCCIO_CPU0 VCCIO<71> @BASEBOARD_FAB2_LIB.BASEBOARD_FAB2(SCH_1):PVCCIO_CPU0
 K15 PVCCIO_CPU0 VCCIO<70> @BASEBOARD_FAB2_LIB.BASEBOARD_FAB2(SCH_1):PVCCIO_CPU0
  J2 PVCCIO_CPU0 VCCIO<69> @BASEBOARD_FAB2_LIB.BASEBOARD_FAB2(SCH_1):PVCCIO_CPU0
EB15 PVCCIO_CPU0 VCCIO<68> @BASEBOARD_FAB2_LIB.BASEBOARD_FAB2(SCH_1):PVCCIO_CPU0
EA12 PVCCIO_CPU0 VCCIO<67> @BASEBOARD_FAB2_LIB.BASEBOARD_FAB2(SCH_1):PVCCIO_CPU0
DU20 PVCCIO_CPU0 VCCIO<66> @BASEBOARD_FAB2_LIB.BASEBOARD_FAB2(SCH_1):PVCCIO_CPU0
 DR2 PVCCIO_CPU0 VCCIO<65> @BASEBOARD_FAB2_LIB.BASEBOARD_FAB2(SCH_1):PVCCIO_CPU0
DR10 PVCCIO_CPU0 VCCIO<64> @BASEBOARD_FAB2_LIB.BASEBOARD_FAB2(SCH_1):PVCCIO_CPU0
DP19 PVCCIO_CPU0 VCCIO<63> @BASEBOARD_FAB2_LIB.BASEBOARD_FAB2(SCH_1):PVCCIO_CPU0
 DN8 PVCCIO_CPU0 VCCIO<62> @BASEBOARD_FAB2_LIB.BASEBOARD_FAB2(SCH_1):PVCCIO_CPU0
DM17 PVCCIO_CPU0 VCCIO<61> @BASEBOARD_FAB2_LIB.BASEBOARD_FAB2(SCH_1):PVCCIO_CPU0
DJ16 PVCCIO_CPU0 VCCIO<60> @BASEBOARD_FAB2_LIB.BASEBOARD_FAB2(SCH_1):PVCCIO_CPU0
 H13 PVCCIO_CPU0 VCCIO<59> @BASEBOARD_FAB2_LIB.BASEBOARD_FAB2(SCH_1):PVCCIO_CPU0
 J10 PVCCIO_CPU0 VCCIO<58> @BASEBOARD_FAB2_LIB.BASEBOARD_FAB2(SCH_1):PVCCIO_CPU0
 L14 PVCCIO_CPU0 VCCIO<57> @BASEBOARD_FAB2_LIB.BASEBOARD_FAB2(SCH_1):PVCCIO_CPU0
 L16 PVCCIO_CPU0 VCCIO<56> @BASEBOARD_FAB2_LIB.BASEBOARD_FAB2(SCH_1):PVCCIO_CPU0
 DH7 PVCCIO_CPU0 VCCIO<55> @BASEBOARD_FAB2_LIB.BASEBOARD_FAB2(SCH_1):PVCCIO_CPU0
 DG8 PVCCIO_CPU0 VCCIO<54> @BASEBOARD_FAB2_LIB.BASEBOARD_FAB2(SCH_1):PVCCIO_CPU0
 M11 PVCCIO_CPU0 VCCIO<53> @BASEBOARD_FAB2_LIB.BASEBOARD_FAB2(SCH_1):PVCCIO_CPU0
 M21 PVCCIO_CPU0 VCCIO<52> @BASEBOARD_FAB2_LIB.BASEBOARD_FAB2(SCH_1):PVCCIO_CPU0
  P5 PVCCIO_CPU0 VCCIO<51> @BASEBOARD_FAB2_LIB.BASEBOARD_FAB2(SCH_1):PVCCIO_CPU0
  T3 PVCCIO_CPU0 VCCIO<50> @BASEBOARD_FAB2_LIB.BASEBOARD_FAB2(SCH_1):PVCCIO_CPU0
 U14 PVCCIO_CPU0 VCCIO<49> @BASEBOARD_FAB2_LIB.BASEBOARD_FAB2(SCH_1):PVCCIO_CPU0
DF21 PVCCIO_CPU0 VCCIO<48> @BASEBOARD_FAB2_LIB.BASEBOARD_FAB2(SCH_1):PVCCIO_CPU0
  W4 PVCCIO_CPU0 VCCIO<47> @BASEBOARD_FAB2_LIB.BASEBOARD_FAB2(SCH_1):PVCCIO_CPU0
  W6 PVCCIO_CPU0 VCCIO<46> @BASEBOARD_FAB2_LIB.BASEBOARD_FAB2(SCH_1):PVCCIO_CPU0
AA10 PVCCIO_CPU0 VCCIO<45> @BASEBOARD_FAB2_LIB.BASEBOARD_FAB2(SCH_1):PVCCIO_CPU0
AC20 PVCCIO_CPU0 VCCIO<44> @BASEBOARD_FAB2_LIB.BASEBOARD_FAB2(SCH_1):PVCCIO_CPU0
 AC4 PVCCIO_CPU0 VCCIO<43> @BASEBOARD_FAB2_LIB.BASEBOARD_FAB2(SCH_1):PVCCIO_CPU0
 AH9 PVCCIO_CPU0 VCCIO<42> @BASEBOARD_FAB2_LIB.BASEBOARD_FAB2(SCH_1):PVCCIO_CPU0
DF13 PVCCIO_CPU0 VCCIO<41> @BASEBOARD_FAB2_LIB.BASEBOARD_FAB2(SCH_1):PVCCIO_CPU0
AN10 PVCCIO_CPU0 VCCIO<40> @BASEBOARD_FAB2_LIB.BASEBOARD_FAB2(SCH_1):PVCCIO_CPU0
 DD7 PVCCIO_CPU0 VCCIO<39> @BASEBOARD_FAB2_LIB.BASEBOARD_FAB2(SCH_1):PVCCIO_CPU0
AT11 PVCCIO_CPU0 VCCIO<38> @BASEBOARD_FAB2_LIB.BASEBOARD_FAB2(SCH_1):PVCCIO_CPU0
 AW6 PVCCIO_CPU0 VCCIO<37> @BASEBOARD_FAB2_LIB.BASEBOARD_FAB2(SCH_1):PVCCIO_CPU0
AY11 PVCCIO_CPU0 VCCIO<36> @BASEBOARD_FAB2_LIB.BASEBOARD_FAB2(SCH_1):PVCCIO_CPU0
BA24 PVCCIO_CPU0 VCCIO<35> @BASEBOARD_FAB2_LIB.BASEBOARD_FAB2(SCH_1):PVCCIO_CPU0
 BB5 PVCCIO_CPU0 VCCIO<34> @BASEBOARD_FAB2_LIB.BASEBOARD_FAB2(SCH_1):PVCCIO_CPU0
DA14 PVCCIO_CPU0 VCCIO<33> @BASEBOARD_FAB2_LIB.BASEBOARD_FAB2(SCH_1):PVCCIO_CPU0
BF23 PVCCIO_CPU0 VCCIO<32> @BASEBOARD_FAB2_LIB.BASEBOARD_FAB2(SCH_1):PVCCIO_CPU0
BJ24 PVCCIO_CPU0 VCCIO<31> @BASEBOARD_FAB2_LIB.BASEBOARD_FAB2(SCH_1):PVCCIO_CPU0
BP25 PVCCIO_CPU0 VCCIO<30> @BASEBOARD_FAB2_LIB.BASEBOARD_FAB2(SCH_1):PVCCIO_CPU0
CB13 PVCCIO_CPU0 VCCIO<29> @BASEBOARD_FAB2_LIB.BASEBOARD_FAB2(SCH_1):PVCCIO_CPU0
CB17 PVCCIO_CPU0 VCCIO<28> @BASEBOARD_FAB2_LIB.BASEBOARD_FAB2(SCH_1):PVCCIO_CPU0
 CD9 PVCCIO_CPU0 VCCIO<27> @BASEBOARD_FAB2_LIB.BASEBOARD_FAB2(SCH_1):PVCCIO_CPU0
CE18 PVCCIO_CPU0 VCCIO<26> @BASEBOARD_FAB2_LIB.BASEBOARD_FAB2(SCH_1):PVCCIO_CPU0
  D7 PVCCIO_CPU0 VCCIO<25> @BASEBOARD_FAB2_LIB.BASEBOARD_FAB2(SCH_1):PVCCIO_CPU0
 CH9 PVCCIO_CPU0 VCCIO<24> @BASEBOARD_FAB2_LIB.BASEBOARD_FAB2(SCH_1):PVCCIO_CPU0
 CV7 PVCCIO_CPU0 VCCIO<23> @BASEBOARD_FAB2_LIB.BASEBOARD_FAB2(SCH_1):PVCCIO_CPU0
 CK5 PVCCIO_CPU0 VCCIO<22> @BASEBOARD_FAB2_LIB.BASEBOARD_FAB2(SCH_1):PVCCIO_CPU0
CL12 PVCCIO_CPU0 VCCIO<21> @BASEBOARD_FAB2_LIB.BASEBOARD_FAB2(SCH_1):PVCCIO_CPU0
CM15 PVCCIO_CPU0 VCCIO<20> @BASEBOARD_FAB2_LIB.BASEBOARD_FAB2(SCH_1):PVCCIO_CPU0
CB65 PVSA_CPU0 VCCSA<25> @BASEBOARD_FAB2_LIB.BASEBOARD_FAB2(SCH_1):PVSA_CPU0
CB67 PVSA_CPU0 VCCSA<24> @BASEBOARD_FAB2_LIB.BASEBOARD_FAB2(SCH_1):PVSA_CPU0
CB69 PVSA_CPU0 VCCSA<23> @BASEBOARD_FAB2_LIB.BASEBOARD_FAB2(SCH_1):PVSA_CPU0
CC66 PVSA_CPU0 VCCSA<22> @BASEBOARD_FAB2_LIB.BASEBOARD_FAB2(SCH_1):PVSA_CPU0
CC68 PVSA_CPU0 VCCSA<21> @BASEBOARD_FAB2_LIB.BASEBOARD_FAB2(SCH_1):PVSA_CPU0
CC70 PVSA_CPU0 VCCSA<20> @BASEBOARD_FAB2_LIB.BASEBOARD_FAB2(SCH_1):PVSA_CPU0
CD65 PVSA_CPU0 VCCSA<19> @BASEBOARD_FAB2_LIB.BASEBOARD_FAB2(SCH_1):PVSA_CPU0
CD67 PVSA_CPU0 VCCSA<18> @BASEBOARD_FAB2_LIB.BASEBOARD_FAB2(SCH_1):PVSA_CPU0
CD69 PVSA_CPU0 VCCSA<17> @BASEBOARD_FAB2_LIB.BASEBOARD_FAB2(SCH_1):PVSA_CPU0
CD71 PVSA_CPU0 VCCSA<16> @BASEBOARD_FAB2_LIB.BASEBOARD_FAB2(SCH_1):PVSA_CPU0
CE64 PVSA_CPU0 VCCSA<15> @BASEBOARD_FAB2_LIB.BASEBOARD_FAB2(SCH_1):PVSA_CPU0
CE66 PVSA_CPU0 VCCSA<14> @BASEBOARD_FAB2_LIB.BASEBOARD_FAB2(SCH_1):PVSA_CPU0
CE68 PVSA_CPU0 VCCSA<13> @BASEBOARD_FAB2_LIB.BASEBOARD_FAB2(SCH_1):PVSA_CPU0
CE72 PVSA_CPU0 VCCSA<12> @BASEBOARD_FAB2_LIB.BASEBOARD_FAB2(SCH_1):PVSA_CPU0
CE74 PVSA_CPU0 VCCSA<11> @BASEBOARD_FAB2_LIB.BASEBOARD_FAB2(SCH_1):PVSA_CPU0
CF65 PVSA_CPU0 VCCSA<10> @BASEBOARD_FAB2_LIB.BASEBOARD_FAB2(SCH_1):PVSA_CPU0
CF67 PVSA_CPU0 VCCSA<9> @BASEBOARD_FAB2_LIB.BASEBOARD_FAB2(SCH_1):PVSA_CPU0
CF73 PVSA_CPU0 VCCSA<8> @BASEBOARD_FAB2_LIB.BASEBOARD_FAB2(SCH_1):PVSA_CPU0
CF75 PVSA_CPU0 VCCSA<7> @BASEBOARD_FAB2_LIB.BASEBOARD_FAB2(SCH_1):PVSA_CPU0
CG64 PVSA_CPU0 VCCSA<6> @BASEBOARD_FAB2_LIB.BASEBOARD_FAB2(SCH_1):PVSA_CPU0
CG66 PVSA_CPU0 VCCSA<5> @BASEBOARD_FAB2_LIB.BASEBOARD_FAB2(SCH_1):PVSA_CPU0
CG74 PVSA_CPU0 VCCSA<4> @BASEBOARD_FAB2_LIB.BASEBOARD_FAB2(SCH_1):PVSA_CPU0
CH65 PVSA_CPU0 VCCSA<3> @BASEBOARD_FAB2_LIB.BASEBOARD_FAB2(SCH_1):PVSA_CPU0
CH75 PVSA_CPU0 VCCSA<2> @BASEBOARD_FAB2_LIB.BASEBOARD_FAB2(SCH_1):PVSA_CPU0
CJ64 PVSA_CPU0 VCCSA<1> @BASEBOARD_FAB2_LIB.BASEBOARD_FAB2(SCH_1):PVSA_CPU0
CJ66 PVSA_CPU0 VCCSA<0> @BASEBOARD_FAB2_LIB.BASEBOARD_FAB2(SCH_1):PVSA_CPU0


DRAWING: @BASEBOARD_FAB2_LIB.BASEBOARD_FAB2(SCH_1):PAGE39 

SKX_EXT_B_BGA1-IC,TBD  I127  U5D1
BT17 VSENSE_PVCCIOMCP_CPU0_SKT_VSEN CD_VCCP_SENSE<1> @BASEBOARD_FAB2_LIB.BASEBOARD_FAB2(SCH_1):VSENSE_PVCCIOMCP_CPU0_SKT_VSEN
BU16 VSENSE_PVCCIOMCP_CPU0_SKT_VRTN CD_VCCP_SENSE<0> @BASEBOARD_FAB2_LIB.BASEBOARD_FAB2(SCH_1):VSENSE_PVCCIOMCP_CPU0_SKT_VRTN
BN16 VSENSE_PVCCMCP_CPU0_SKT_VSEN CD_VCC_CORE_SENSE @BASEBOARD_FAB2_LIB.BASEBOARD_FAB2(SCH_1):VSENSE_PVCCMCP_CPU0_SKT_VSEN
BL16 VSENSE_PVCCMCP_CPU0_SKT_VRTN CD_VSS_VCC_CORE_SENSE @BASEBOARD_FAB2_LIB.BASEBOARD_FAB2(SCH_1):VSENSE_PVCCMCP_CPU0_SKT_VRTN
CL26 PVCCMCP_CPU0 RSVD<80> @BASEBOARD_FAB2_LIB.BASEBOARD_FAB2(SCH_1):PVCCMCP_CPU0
CM23 PVCCMCP_CPU0 RSVD<79> @BASEBOARD_FAB2_LIB.BASEBOARD_FAB2(SCH_1):PVCCMCP_CPU0
CM25 PVCCMCP_CPU0 RSVD<78> @BASEBOARD_FAB2_LIB.BASEBOARD_FAB2(SCH_1):PVCCMCP_CPU0
CN22 TP_CPU0_KTI2_AMONV RSVD<77> @BASEBOARD_FAB2_LIB.BASEBOARD_FAB2(SCH_1):TP_CPU0_KTI2_AMONV
CN24 PVCCMCP_CPU0 RSVD<76> @BASEBOARD_FAB2_LIB.BASEBOARD_FAB2(SCH_1):PVCCMCP_CPU0
CN28 PD_CPU0_MCP01_DMON RSVD<75> @BASEBOARD_FAB2_LIB.BASEBOARD_FAB2(SCH_1):PD_CPU0_MCP01_DMON
CP23 PVCCMCP_CPU0 RSVD<74> @BASEBOARD_FAB2_LIB.BASEBOARD_FAB2(SCH_1):PVCCMCP_CPU0
CP31 TP_CPU0_RSVD_73 RSVD<73> @BASEBOARD_FAB2_LIB.BASEBOARD_FAB2(SCH_1):TP_CPU0_RSVD_73
CR60 TP_CPU0_RSVD_72 RSVD<72> @BASEBOARD_FAB2_LIB.BASEBOARD_FAB2(SCH_1):TP_CPU0_RSVD_72
CT23 PVCCMCP_CPU0 RSVD<71> @BASEBOARD_FAB2_LIB.BASEBOARD_FAB2(SCH_1):PVCCMCP_CPU0
 CT5 TP_CPU0_RSVD_70 RSVD<70> @BASEBOARD_FAB2_LIB.BASEBOARD_FAB2(SCH_1):TP_CPU0_RSVD_70
CT69 TP_CPU0_RSVD_69 RSVD<69> @BASEBOARD_FAB2_LIB.BASEBOARD_FAB2(SCH_1):TP_CPU0_RSVD_69
CU24 PVCCMCP_CPU0 RSVD<68> @BASEBOARD_FAB2_LIB.BASEBOARD_FAB2(SCH_1):PVCCMCP_CPU0
 CU6 TP_CPU0_RSVD_67 RSVD<67> @BASEBOARD_FAB2_LIB.BASEBOARD_FAB2(SCH_1):TP_CPU0_RSVD_67
CU60 TP_CPU0_RSVD_66 RSVD<66> @BASEBOARD_FAB2_LIB.BASEBOARD_FAB2(SCH_1):TP_CPU0_RSVD_66
CV23 PVCCMCP_CPU0 RSVD<65> @BASEBOARD_FAB2_LIB.BASEBOARD_FAB2(SCH_1):PVCCMCP_CPU0
CV69 TP_CPU0_RSVD_64 RSVD<64> @BASEBOARD_FAB2_LIB.BASEBOARD_FAB2(SCH_1):TP_CPU0_RSVD_64
CW22 TP_CPU0_KTI2_DFX_DN RSVD<63> @BASEBOARD_FAB2_LIB.BASEBOARD_FAB2(SCH_1):TP_CPU0_KTI2_DFX_DN
CW24 PVCCMCP_CPU0 RSVD<62> @BASEBOARD_FAB2_LIB.BASEBOARD_FAB2(SCH_1):PVCCMCP_CPU0
CW60 TP_CPU0_RSVD_61 RSVD<61> @BASEBOARD_FAB2_LIB.BASEBOARD_FAB2(SCH_1):TP_CPU0_RSVD_61
CW62 TP_CPU0_RSVD_60 RSVD<60> @BASEBOARD_FAB2_LIB.BASEBOARD_FAB2(SCH_1):TP_CPU0_RSVD_60
CY23 TP_CPU0_RSVD_59 RSVD<59> @BASEBOARD_FAB2_LIB.BASEBOARD_FAB2(SCH_1):TP_CPU0_RSVD_59
CY25 PVCCMCP_CPU0 RSVD<58> @BASEBOARD_FAB2_LIB.BASEBOARD_FAB2(SCH_1):PVCCMCP_CPU0
CY39 TP_CPU0_RSVD_57 RSVD<57> @BASEBOARD_FAB2_LIB.BASEBOARD_FAB2(SCH_1):TP_CPU0_RSVD_57
CY53 TP_CPU0_RSVD_56 RSVD<56> @BASEBOARD_FAB2_LIB.BASEBOARD_FAB2(SCH_1):TP_CPU0_RSVD_56
CY57 TP_CPU0_RSVD_55 RSVD<55> @BASEBOARD_FAB2_LIB.BASEBOARD_FAB2(SCH_1):TP_CPU0_RSVD_55
CY63 TP_CPU0_RSVD_54 RSVD<54> @BASEBOARD_FAB2_LIB.BASEBOARD_FAB2(SCH_1):TP_CPU0_RSVD_54
CY73 TP_CPU0_RSVD_53 RSVD<53> @BASEBOARD_FAB2_LIB.BASEBOARD_FAB2(SCH_1):TP_CPU0_RSVD_53
DA24 PVCCMCP_CPU0 RSVD<52> @BASEBOARD_FAB2_LIB.BASEBOARD_FAB2(SCH_1):PVCCMCP_CPU0
DA40 TP_CPU0_RSVD_51 RSVD<51> @BASEBOARD_FAB2_LIB.BASEBOARD_FAB2(SCH_1):TP_CPU0_RSVD_51
DA52 TP_CPU0_RSVD_50 RSVD<50> @BASEBOARD_FAB2_LIB.BASEBOARD_FAB2(SCH_1):TP_CPU0_RSVD_50
DA54 TP_CPU0_RSVD_49 RSVD<49> @BASEBOARD_FAB2_LIB.BASEBOARD_FAB2(SCH_1):TP_CPU0_RSVD_49
DA56 TP_CPU0_RSVD_48 RSVD<48> @BASEBOARD_FAB2_LIB.BASEBOARD_FAB2(SCH_1):TP_CPU0_RSVD_48
DC46 TP_CPU0_RSVD_47 RSVD<47> @BASEBOARD_FAB2_LIB.BASEBOARD_FAB2(SCH_1):TP_CPU0_RSVD_47
DC52 TP_CPU0_RSVD_46 RSVD<46> @BASEBOARD_FAB2_LIB.BASEBOARD_FAB2(SCH_1):TP_CPU0_RSVD_46
DD51 TP_CPU0_RSVD_45 RSVD<45> @BASEBOARD_FAB2_LIB.BASEBOARD_FAB2(SCH_1):TP_CPU0_RSVD_45
DG36 TP_CPU0_RSVD_44 RSVD<44> @BASEBOARD_FAB2_LIB.BASEBOARD_FAB2(SCH_1):TP_CPU0_RSVD_44
DG64 TP_CPU0_RSVD_43 RSVD<43> @BASEBOARD_FAB2_LIB.BASEBOARD_FAB2(SCH_1):TP_CPU0_RSVD_43
DH65 TP_CPU0_RSVD_42 RSVD<42> @BASEBOARD_FAB2_LIB.BASEBOARD_FAB2(SCH_1):TP_CPU0_RSVD_42
DJ36 TP_CPU0_RSVD_41 RSVD<41> @BASEBOARD_FAB2_LIB.BASEBOARD_FAB2(SCH_1):TP_CPU0_RSVD_41
DJ66 TP_CPU0_RSVD_40 RSVD<40> @BASEBOARD_FAB2_LIB.BASEBOARD_FAB2(SCH_1):TP_CPU0_RSVD_40
DK15 TP_CPU0_RSVD_39 RSVD<39> @BASEBOARD_FAB2_LIB.BASEBOARD_FAB2(SCH_1):TP_CPU0_RSVD_39
DK37 TP_CPU0_RSVD_38 RSVD<38> @BASEBOARD_FAB2_LIB.BASEBOARD_FAB2(SCH_1):TP_CPU0_RSVD_38
DK65 TP_CPU0_RSVD_37 RSVD<37> @BASEBOARD_FAB2_LIB.BASEBOARD_FAB2(SCH_1):TP_CPU0_RSVD_37
DK67 TP_CPU0_RSVD_36 RSVD<36> @BASEBOARD_FAB2_LIB.BASEBOARD_FAB2(SCH_1):TP_CPU0_RSVD_36
DL38 TP_CPU0_RSVD_35 RSVD<35> @BASEBOARD_FAB2_LIB.BASEBOARD_FAB2(SCH_1):TP_CPU0_RSVD_35
DL66 TP_CPU0_RSVD_34 RSVD<34> @BASEBOARD_FAB2_LIB.BASEBOARD_FAB2(SCH_1):TP_CPU0_RSVD_34
DM67 TP_CPU0_RSVD_33 RSVD<33> @BASEBOARD_FAB2_LIB.BASEBOARD_FAB2(SCH_1):TP_CPU0_RSVD_33
DN62 TP_CPU0_RSVD_32 RSVD<32> @BASEBOARD_FAB2_LIB.BASEBOARD_FAB2(SCH_1):TP_CPU0_RSVD_32
DN66 TP_CPU0_RSVD_31 RSVD<31> @BASEBOARD_FAB2_LIB.BASEBOARD_FAB2(SCH_1):TP_CPU0_RSVD_31
DP17 TP_CPU0_RSVD_30 RSVD<30> @BASEBOARD_FAB2_LIB.BASEBOARD_FAB2(SCH_1):TP_CPU0_RSVD_30
DP65 TP_CPU0_RSVD_29 RSVD<29> @BASEBOARD_FAB2_LIB.BASEBOARD_FAB2(SCH_1):TP_CPU0_RSVD_29
DR44 TP_CPU0_RSVD_28 RSVD<28> @BASEBOARD_FAB2_LIB.BASEBOARD_FAB2(SCH_1):TP_CPU0_RSVD_28
DT71 TP_CPU0_RSVD_27 RSVD<27> @BASEBOARD_FAB2_LIB.BASEBOARD_FAB2(SCH_1):TP_CPU0_RSVD_27
DU44 TP_CPU0_RSVD_26 RSVD<26> @BASEBOARD_FAB2_LIB.BASEBOARD_FAB2(SCH_1):TP_CPU0_RSVD_26
DV61 TP_CPU0_RSVD_25 RSVD<25> @BASEBOARD_FAB2_LIB.BASEBOARD_FAB2(SCH_1):TP_CPU0_RSVD_25
DV71 TP_CPU0_RSVD_24 RSVD<24> @BASEBOARD_FAB2_LIB.BASEBOARD_FAB2(SCH_1):TP_CPU0_RSVD_24
DW44 TP_CPU0_RSVD_23 RSVD<23> @BASEBOARD_FAB2_LIB.BASEBOARD_FAB2(SCH_1):TP_CPU0_RSVD_23
DW46 TP_CPU0_RSVD_22 RSVD<22> @BASEBOARD_FAB2_LIB.BASEBOARD_FAB2(SCH_1):TP_CPU0_RSVD_22
 DY3 TP_CPU0_RSVD_21 RSVD<21> @BASEBOARD_FAB2_LIB.BASEBOARD_FAB2(SCH_1):TP_CPU0_RSVD_21
 EA4 TP_CPU0_RSVD_20 RSVD<20> @BASEBOARD_FAB2_LIB.BASEBOARD_FAB2(SCH_1):TP_CPU0_RSVD_20
EA44 TP_CPU0_RSVD_19 RSVD<19> @BASEBOARD_FAB2_LIB.BASEBOARD_FAB2(SCH_1):TP_CPU0_RSVD_19
 EB3 TP_CPU0_RSVD_18 RSVD<18> @BASEBOARD_FAB2_LIB.BASEBOARD_FAB2(SCH_1):TP_CPU0_RSVD_18
 EB5 TP_CPU0_RSVD_17 RSVD<17> @BASEBOARD_FAB2_LIB.BASEBOARD_FAB2(SCH_1):TP_CPU0_RSVD_17
EB85 TP_CPU0_RSVD_16 RSVD<16> @BASEBOARD_FAB2_LIB.BASEBOARD_FAB2(SCH_1):TP_CPU0_RSVD_16
EC16 TP_CPU0_RSVD_15 RSVD<15> @BASEBOARD_FAB2_LIB.BASEBOARD_FAB2(SCH_1):TP_CPU0_RSVD_15
 EC4 TP_CPU0_RSVD_14 RSVD<14> @BASEBOARD_FAB2_LIB.BASEBOARD_FAB2(SCH_1):TP_CPU0_RSVD_14
EC44 TP_CPU0_RSVD_13 RSVD<13> @BASEBOARD_FAB2_LIB.BASEBOARD_FAB2(SCH_1):TP_CPU0_RSVD_13
EC84 TP_CPU0_RSVD_12 RSVD<12> @BASEBOARD_FAB2_LIB.BASEBOARD_FAB2(SCH_1):TP_CPU0_RSVD_12
ED45 TP_CPU0_RSVD_11 RSVD<11> @BASEBOARD_FAB2_LIB.BASEBOARD_FAB2(SCH_1):TP_CPU0_RSVD_11
 ED5 TP_CPU0_RSVD_10 RSVD<10> @BASEBOARD_FAB2_LIB.BASEBOARD_FAB2(SCH_1):TP_CPU0_RSVD_10
ED83 TP_CPU0_RSVD_9 RSVD<9> @BASEBOARD_FAB2_LIB.BASEBOARD_FAB2(SCH_1):TP_CPU0_RSVD_9
EE16 TP_CPU0_RSVD_8 RSVD<8> @BASEBOARD_FAB2_LIB.BASEBOARD_FAB2(SCH_1):TP_CPU0_RSVD_8
EE46 TP_CPU0_RSVD_7 RSVD<7> @BASEBOARD_FAB2_LIB.BASEBOARD_FAB2(SCH_1):TP_CPU0_RSVD_7
 EE6 TP_CPU0_RSVD_6 RSVD<6> @BASEBOARD_FAB2_LIB.BASEBOARD_FAB2(SCH_1):TP_CPU0_RSVD_6
EE82 TP_CPU0_RSVD_5 RSVD<5> @BASEBOARD_FAB2_LIB.BASEBOARD_FAB2(SCH_1):TP_CPU0_RSVD_5
EE84 TP_CPU0_RSVD_4 RSVD<4> @BASEBOARD_FAB2_LIB.BASEBOARD_FAB2(SCH_1):TP_CPU0_RSVD_4
EF47 TP_CPU0_RSVD_3 RSVD<3> @BASEBOARD_FAB2_LIB.BASEBOARD_FAB2(SCH_1):TP_CPU0_RSVD_3
EF77 TP_CPU0_RSVD_2 RSVD<2> @BASEBOARD_FAB2_LIB.BASEBOARD_FAB2(SCH_1):TP_CPU0_RSVD_2
EF81 TP_CPU0_RSVD_1 RSVD<1> @BASEBOARD_FAB2_LIB.BASEBOARD_FAB2(SCH_1):TP_CPU0_RSVD_1
EF83 TP_CPU0_RSVD_0 RSVD<0> @BASEBOARD_FAB2_LIB.BASEBOARD_FAB2(SCH_1):TP_CPU0_RSVD_0
 CN6 PVCCIO_CPU0 VCCIO<19> @BASEBOARD_FAB2_LIB.BASEBOARD_FAB2(SCH_1):PVCCIO_CPU0
CU12 PVCCIO_CPU0 VCCIO<18> @BASEBOARD_FAB2_LIB.BASEBOARD_FAB2(SCH_1):PVCCIO_CPU0
CV21 PVCCIO_CPU0 VCCIO<17> @BASEBOARD_FAB2_LIB.BASEBOARD_FAB2(SCH_1):PVCCIO_CPU0
CU18 PVCCIO_CPU0 VCCIO<16> @BASEBOARD_FAB2_LIB.BASEBOARD_FAB2(SCH_1):PVCCIO_CPU0
CY17 PVCCIO_CPU0 VCCIO<15> @BASEBOARD_FAB2_LIB.BASEBOARD_FAB2(SCH_1):PVCCIO_CPU0
DC18 PVCCIO_CPU0 VCCIO<14> @BASEBOARD_FAB2_LIB.BASEBOARD_FAB2(SCH_1):PVCCIO_CPU0
DE14 PVCCIO_CPU0 VCCIO<13> @BASEBOARD_FAB2_LIB.BASEBOARD_FAB2(SCH_1):PVCCIO_CPU0
CP13 PVCCIO_CPU0 VCCIO<12> @BASEBOARD_FAB2_LIB.BASEBOARD_FAB2(SCH_1):PVCCIO_CPU0
CL20 PVCCIO_CPU0 VCCIO<11> @BASEBOARD_FAB2_LIB.BASEBOARD_FAB2(SCH_1):PVCCIO_CPU0
CG14 PVCCIO_CPU0 VCCIO<10> @BASEBOARD_FAB2_LIB.BASEBOARD_FAB2(SCH_1):PVCCIO_CPU0
 CF5 PVCCIO_CPU0 VCCIO<9> @BASEBOARD_FAB2_LIB.BASEBOARD_FAB2(SCH_1):PVCCIO_CPU0
DK21 PVCCIO_CPU0 VCCIO<8> @BASEBOARD_FAB2_LIB.BASEBOARD_FAB2(SCH_1):PVCCIO_CPU0
BE24 PVCCIO_CPU0 VCCIO<7> @BASEBOARD_FAB2_LIB.BASEBOARD_FAB2(SCH_1):PVCCIO_CPU0
 AT7 PVCCIO_CPU0 VCCIO<6> @BASEBOARD_FAB2_LIB.BASEBOARD_FAB2(SCH_1):PVCCIO_CPU0
 AT5 PVCCIO_CPU0 VCCIO<5> @BASEBOARD_FAB2_LIB.BASEBOARD_FAB2(SCH_1):PVCCIO_CPU0
 AM5 PVCCIO_CPU0 VCCIO<4> @BASEBOARD_FAB2_LIB.BASEBOARD_FAB2(SCH_1):PVCCIO_CPU0
DV11 PVCCIO_CPU0 VCCIO<3> @BASEBOARD_FAB2_LIB.BASEBOARD_FAB2(SCH_1):PVCCIO_CPU0
 AF5 PVCCIO_CPU0 VCCIO<2> @BASEBOARD_FAB2_LIB.BASEBOARD_FAB2(SCH_1):PVCCIO_CPU0
AE10 PVCCIO_CPU0 VCCIO<1> @BASEBOARD_FAB2_LIB.BASEBOARD_FAB2(SCH_1):PVCCIO_CPU0
EE10 PVCCIO_CPU0 VCCIO<0> @BASEBOARD_FAB2_LIB.BASEBOARD_FAB2(SCH_1):PVCCIO_CPU0
 BH5 VSENSE_PVCCIO_CPU0_SKT_VSEN VCCIO_SENSE @BASEBOARD_FAB2_LIB.BASEBOARD_FAB2(SCH_1):VSENSE_PVCCIO_CPU0_SKT_VSEN
CE76 VSENSE_PVSA_CPU0_SKT_VSEN VCCSA_SENSE @BASEBOARD_FAB2_LIB.BASEBOARD_FAB2(SCH_1):VSENSE_PVSA_CPU0_SKT_VSEN
 BF5 VSENSE_PVCCIO_CPU0_SKT_VRTN VSS_VCCIO_SENSE @BASEBOARD_FAB2_LIB.BASEBOARD_FAB2(SCH_1):VSENSE_PVCCIO_CPU0_SKT_VRTN
CG76 VSENSE_PVSA_CPU0_SKT_VRTN VSS_VCCSA_SENSE @BASEBOARD_FAB2_LIB.BASEBOARD_FAB2(SCH_1):VSENSE_PVSA_CPU0_SKT_VRTN


DRAWING: @BASEBOARD_FAB2_LIB.BASEBOARD_FAB2(SCH_1):PAGE40 

SKX_EXT_B_BGA1-IC,TBD  I20  U5D1
  B9    GND VSS<1253> @BASEBOARD_FAB2_LIB.BASEBOARD_FAB2(SCH_1):GND
 A42    GND VSS<1252> @BASEBOARD_FAB2_LIB.BASEBOARD_FAB2(SCH_1):GND
 B43    GND VSS<1251> @BASEBOARD_FAB2_LIB.BASEBOARD_FAB2(SCH_1):GND
  B5    GND VSS<1250> @BASEBOARD_FAB2_LIB.BASEBOARD_FAB2(SCH_1):GND
 B79    GND VSS<1249> @BASEBOARD_FAB2_LIB.BASEBOARD_FAB2(SCH_1):GND
  C4    GND VSS<1248> @BASEBOARD_FAB2_LIB.BASEBOARD_FAB2(SCH_1):GND
 C80    GND VSS<1247> @BASEBOARD_FAB2_LIB.BASEBOARD_FAB2(SCH_1):GND
  D3    GND VSS<1246> @BASEBOARD_FAB2_LIB.BASEBOARD_FAB2(SCH_1):GND
 D81    GND VSS<1245> @BASEBOARD_FAB2_LIB.BASEBOARD_FAB2(SCH_1):GND
 E82    GND VSS<1244> @BASEBOARD_FAB2_LIB.BASEBOARD_FAB2(SCH_1):GND
 J86    GND VSS<1243> @BASEBOARD_FAB2_LIB.BASEBOARD_FAB2(SCH_1):GND
DY85    GND VSS<1242> @BASEBOARD_FAB2_LIB.BASEBOARD_FAB2(SCH_1):GND
EA84    GND VSS<1241> @BASEBOARD_FAB2_LIB.BASEBOARD_FAB2(SCH_1):GND
EB83    GND VSS<1240> @BASEBOARD_FAB2_LIB.BASEBOARD_FAB2(SCH_1):GND
 DW2    GND VSS<1239> @BASEBOARD_FAB2_LIB.BASEBOARD_FAB2(SCH_1):GND
EC42    GND VSS<1238> @BASEBOARD_FAB2_LIB.BASEBOARD_FAB2(SCH_1):GND
 EC6    GND VSS<1237> @BASEBOARD_FAB2_LIB.BASEBOARD_FAB2(SCH_1):GND
EC82    GND VSS<1236> @BASEBOARD_FAB2_LIB.BASEBOARD_FAB2(SCH_1):GND
ED41    GND VSS<1235> @BASEBOARD_FAB2_LIB.BASEBOARD_FAB2(SCH_1):GND
 ED7    GND VSS<1234> @BASEBOARD_FAB2_LIB.BASEBOARD_FAB2(SCH_1):GND
ED81    GND VSS<1233> @BASEBOARD_FAB2_LIB.BASEBOARD_FAB2(SCH_1):GND
EE40    GND VSS<1232> @BASEBOARD_FAB2_LIB.BASEBOARD_FAB2(SCH_1):GND
 EE8    GND VSS<1231> @BASEBOARD_FAB2_LIB.BASEBOARD_FAB2(SCH_1):GND
EE80    GND VSS<1230> @BASEBOARD_FAB2_LIB.BASEBOARD_FAB2(SCH_1):GND
ED69    GND VSS<1229> @BASEBOARD_FAB2_LIB.BASEBOARD_FAB2(SCH_1):GND
 E66    GND VSS<1228> @BASEBOARD_FAB2_LIB.BASEBOARD_FAB2(SCH_1):GND
 V11    GND VSS<1227> @BASEBOARD_FAB2_LIB.BASEBOARD_FAB2(SCH_1):GND
  L8    GND VSS<1226> @BASEBOARD_FAB2_LIB.BASEBOARD_FAB2(SCH_1):GND
EA14    GND VSS<1225> @BASEBOARD_FAB2_LIB.BASEBOARD_FAB2(SCH_1):GND
DY63    GND VSS<1224> @BASEBOARD_FAB2_LIB.BASEBOARD_FAB2(SCH_1):GND
DY61    GND VSS<1223> @BASEBOARD_FAB2_LIB.BASEBOARD_FAB2(SCH_1):GND
DY59    GND VSS<1222> @BASEBOARD_FAB2_LIB.BASEBOARD_FAB2(SCH_1):GND
DY57    GND VSS<1221> @BASEBOARD_FAB2_LIB.BASEBOARD_FAB2(SCH_1):GND
DY55    GND VSS<1220> @BASEBOARD_FAB2_LIB.BASEBOARD_FAB2(SCH_1):GND
DY53    GND VSS<1219> @BASEBOARD_FAB2_LIB.BASEBOARD_FAB2(SCH_1):GND
DY51    GND VSS<1218> @BASEBOARD_FAB2_LIB.BASEBOARD_FAB2(SCH_1):GND
DY49    GND VSS<1217> @BASEBOARD_FAB2_LIB.BASEBOARD_FAB2(SCH_1):GND
DY47    GND VSS<1216> @BASEBOARD_FAB2_LIB.BASEBOARD_FAB2(SCH_1):GND
DY45    GND VSS<1215> @BASEBOARD_FAB2_LIB.BASEBOARD_FAB2(SCH_1):GND
DV19    GND VSS<1214> @BASEBOARD_FAB2_LIB.BASEBOARD_FAB2(SCH_1):GND
 DP9    GND VSS<1213> @BASEBOARD_FAB2_LIB.BASEBOARD_FAB2(SCH_1):GND
DP63    GND VSS<1212> @BASEBOARD_FAB2_LIB.BASEBOARD_FAB2(SCH_1):GND
DP61    GND VSS<1211> @BASEBOARD_FAB2_LIB.BASEBOARD_FAB2(SCH_1):GND
DP59    GND VSS<1210> @BASEBOARD_FAB2_LIB.BASEBOARD_FAB2(SCH_1):GND
DP57    GND VSS<1209> @BASEBOARD_FAB2_LIB.BASEBOARD_FAB2(SCH_1):GND
DP55    GND VSS<1208> @BASEBOARD_FAB2_LIB.BASEBOARD_FAB2(SCH_1):GND
DP53    GND VSS<1207> @BASEBOARD_FAB2_LIB.BASEBOARD_FAB2(SCH_1):GND
DP51    GND VSS<1206> @BASEBOARD_FAB2_LIB.BASEBOARD_FAB2(SCH_1):GND
DP49    GND VSS<1205> @BASEBOARD_FAB2_LIB.BASEBOARD_FAB2(SCH_1):GND
DP47    GND VSS<1204> @BASEBOARD_FAB2_LIB.BASEBOARD_FAB2(SCH_1):GND
DP45    GND VSS<1203> @BASEBOARD_FAB2_LIB.BASEBOARD_FAB2(SCH_1):GND
DN18    GND VSS<1202> @BASEBOARD_FAB2_LIB.BASEBOARD_FAB2(SCH_1):GND
 DL8    GND VSS<1201> @BASEBOARD_FAB2_LIB.BASEBOARD_FAB2(SCH_1):GND
DE62    GND VSS<1200> @BASEBOARD_FAB2_LIB.BASEBOARD_FAB2(SCH_1):GND
DE60    GND VSS<1199> @BASEBOARD_FAB2_LIB.BASEBOARD_FAB2(SCH_1):GND
DE58    GND VSS<1198> @BASEBOARD_FAB2_LIB.BASEBOARD_FAB2(SCH_1):GND
DE56    GND VSS<1197> @BASEBOARD_FAB2_LIB.BASEBOARD_FAB2(SCH_1):GND
DE54    GND VSS<1196> @BASEBOARD_FAB2_LIB.BASEBOARD_FAB2(SCH_1):GND
DE52    GND VSS<1195> @BASEBOARD_FAB2_LIB.BASEBOARD_FAB2(SCH_1):GND
DE50    GND VSS<1194> @BASEBOARD_FAB2_LIB.BASEBOARD_FAB2(SCH_1):GND
DE48    GND VSS<1193> @BASEBOARD_FAB2_LIB.BASEBOARD_FAB2(SCH_1):GND
 CW6    GND VSS<1192> @BASEBOARD_FAB2_LIB.BASEBOARD_FAB2(SCH_1):GND
 CG6    GND VSS<1191> @BASEBOARD_FAB2_LIB.BASEBOARD_FAB2(SCH_1):GND
 AR6    GND VSS<1190> @BASEBOARD_FAB2_LIB.BASEBOARD_FAB2(SCH_1):GND
 AJ4    GND VSS<1189> @BASEBOARD_FAB2_LIB.BASEBOARD_FAB2(SCH_1):GND
AC62    GND VSS<1188> @BASEBOARD_FAB2_LIB.BASEBOARD_FAB2(SCH_1):GND
AC60    GND VSS<1187> @BASEBOARD_FAB2_LIB.BASEBOARD_FAB2(SCH_1):GND
AC58    GND VSS<1186> @BASEBOARD_FAB2_LIB.BASEBOARD_FAB2(SCH_1):GND
 A26    GND VSS<1185> @BASEBOARD_FAB2_LIB.BASEBOARD_FAB2(SCH_1):GND
 A30    GND VSS<1184> @BASEBOARD_FAB2_LIB.BASEBOARD_FAB2(SCH_1):GND
 A32    GND VSS<1183> @BASEBOARD_FAB2_LIB.BASEBOARD_FAB2(SCH_1):GND
 A36    GND VSS<1182> @BASEBOARD_FAB2_LIB.BASEBOARD_FAB2(SCH_1):GND
 A38    GND VSS<1181> @BASEBOARD_FAB2_LIB.BASEBOARD_FAB2(SCH_1):GND
 B25    GND VSS<1180> @BASEBOARD_FAB2_LIB.BASEBOARD_FAB2(SCH_1):GND
 B31    GND VSS<1179> @BASEBOARD_FAB2_LIB.BASEBOARD_FAB2(SCH_1):GND
 B37    GND VSS<1178> @BASEBOARD_FAB2_LIB.BASEBOARD_FAB2(SCH_1):GND
 B71    GND VSS<1177> @BASEBOARD_FAB2_LIB.BASEBOARD_FAB2(SCH_1):GND
 B75    GND VSS<1176> @BASEBOARD_FAB2_LIB.BASEBOARD_FAB2(SCH_1):GND
  C8    GND VSS<1175> @BASEBOARD_FAB2_LIB.BASEBOARD_FAB2(SCH_1):GND
 C10    GND VSS<1174> @BASEBOARD_FAB2_LIB.BASEBOARD_FAB2(SCH_1):GND
 C12    GND VSS<1173> @BASEBOARD_FAB2_LIB.BASEBOARD_FAB2(SCH_1):GND
 C14    GND VSS<1172> @BASEBOARD_FAB2_LIB.BASEBOARD_FAB2(SCH_1):GND
 C16    GND VSS<1171> @BASEBOARD_FAB2_LIB.BASEBOARD_FAB2(SCH_1):GND
 C76    GND VSS<1170> @BASEBOARD_FAB2_LIB.BASEBOARD_FAB2(SCH_1):GND
 C78    GND VSS<1169> @BASEBOARD_FAB2_LIB.BASEBOARD_FAB2(SCH_1):GND
CM27    GND VSS<1168> @BASEBOARD_FAB2_LIB.BASEBOARD_FAB2(SCH_1):GND
 D11    GND VSS<1167> @BASEBOARD_FAB2_LIB.BASEBOARD_FAB2(SCH_1):GND
 D13    GND VSS<1166> @BASEBOARD_FAB2_LIB.BASEBOARD_FAB2(SCH_1):GND
 D25    GND VSS<1165> @BASEBOARD_FAB2_LIB.BASEBOARD_FAB2(SCH_1):GND
 D27    GND VSS<1164> @BASEBOARD_FAB2_LIB.BASEBOARD_FAB2(SCH_1):GND
 D29    GND VSS<1163> @BASEBOARD_FAB2_LIB.BASEBOARD_FAB2(SCH_1):GND
 D31    GND VSS<1162> @BASEBOARD_FAB2_LIB.BASEBOARD_FAB2(SCH_1):GND
 D33    GND VSS<1161> @BASEBOARD_FAB2_LIB.BASEBOARD_FAB2(SCH_1):GND
 D35    GND VSS<1160> @BASEBOARD_FAB2_LIB.BASEBOARD_FAB2(SCH_1):GND
 D37    GND VSS<1159> @BASEBOARD_FAB2_LIB.BASEBOARD_FAB2(SCH_1):GND
 D39    GND VSS<1158> @BASEBOARD_FAB2_LIB.BASEBOARD_FAB2(SCH_1):GND
 D41    GND VSS<1157> @BASEBOARD_FAB2_LIB.BASEBOARD_FAB2(SCH_1):GND
 D43    GND VSS<1156> @BASEBOARD_FAB2_LIB.BASEBOARD_FAB2(SCH_1):GND
 D77    GND VSS<1155> @BASEBOARD_FAB2_LIB.BASEBOARD_FAB2(SCH_1):GND
  E6    GND VSS<1154> @BASEBOARD_FAB2_LIB.BASEBOARD_FAB2(SCH_1):GND
  E8    GND VSS<1153> @BASEBOARD_FAB2_LIB.BASEBOARD_FAB2(SCH_1):GND
 E16    GND VSS<1152> @BASEBOARD_FAB2_LIB.BASEBOARD_FAB2(SCH_1):GND
 E18    GND VSS<1151> @BASEBOARD_FAB2_LIB.BASEBOARD_FAB2(SCH_1):GND
 E20    GND VSS<1150> @BASEBOARD_FAB2_LIB.BASEBOARD_FAB2(SCH_1):GND
 E22    GND VSS<1149> @BASEBOARD_FAB2_LIB.BASEBOARD_FAB2(SCH_1):GND
 E72    GND VSS<1148> @BASEBOARD_FAB2_LIB.BASEBOARD_FAB2(SCH_1):GND
 E74    GND VSS<1147> @BASEBOARD_FAB2_LIB.BASEBOARD_FAB2(SCH_1):GND
 E76    GND VSS<1146> @BASEBOARD_FAB2_LIB.BASEBOARD_FAB2(SCH_1):GND
  F5    GND VSS<1145> @BASEBOARD_FAB2_LIB.BASEBOARD_FAB2(SCH_1):GND
 F17    GND VSS<1144> @BASEBOARD_FAB2_LIB.BASEBOARD_FAB2(SCH_1):GND
 F19    GND VSS<1143> @BASEBOARD_FAB2_LIB.BASEBOARD_FAB2(SCH_1):GND
 F25    GND VSS<1142> @BASEBOARD_FAB2_LIB.BASEBOARD_FAB2(SCH_1):GND
 F31    GND VSS<1141> @BASEBOARD_FAB2_LIB.BASEBOARD_FAB2(SCH_1):GND
 F37    GND VSS<1140> @BASEBOARD_FAB2_LIB.BASEBOARD_FAB2(SCH_1):GND
 F43    GND VSS<1139> @BASEBOARD_FAB2_LIB.BASEBOARD_FAB2(SCH_1):GND
 F67    GND VSS<1138> @BASEBOARD_FAB2_LIB.BASEBOARD_FAB2(SCH_1):GND
 F69    GND VSS<1137> @BASEBOARD_FAB2_LIB.BASEBOARD_FAB2(SCH_1):GND
  G4    GND VSS<1136> @BASEBOARD_FAB2_LIB.BASEBOARD_FAB2(SCH_1):GND
  G8    GND VSS<1135> @BASEBOARD_FAB2_LIB.BASEBOARD_FAB2(SCH_1):GND
 G22    GND VSS<1134> @BASEBOARD_FAB2_LIB.BASEBOARD_FAB2(SCH_1):GND
 G24    GND VSS<1133> @BASEBOARD_FAB2_LIB.BASEBOARD_FAB2(SCH_1):GND
 G26    GND VSS<1132> @BASEBOARD_FAB2_LIB.BASEBOARD_FAB2(SCH_1):GND
 G30    GND VSS<1131> @BASEBOARD_FAB2_LIB.BASEBOARD_FAB2(SCH_1):GND
 G32    GND VSS<1130> @BASEBOARD_FAB2_LIB.BASEBOARD_FAB2(SCH_1):GND
 G36    GND VSS<1129> @BASEBOARD_FAB2_LIB.BASEBOARD_FAB2(SCH_1):GND
 G38    GND VSS<1128> @BASEBOARD_FAB2_LIB.BASEBOARD_FAB2(SCH_1):GND
 G42    GND VSS<1127> @BASEBOARD_FAB2_LIB.BASEBOARD_FAB2(SCH_1):GND
 G66    GND VSS<1126> @BASEBOARD_FAB2_LIB.BASEBOARD_FAB2(SCH_1):GND
 G70    GND VSS<1125> @BASEBOARD_FAB2_LIB.BASEBOARD_FAB2(SCH_1):GND
 G76    GND VSS<1124> @BASEBOARD_FAB2_LIB.BASEBOARD_FAB2(SCH_1):GND
 G78    GND VSS<1123> @BASEBOARD_FAB2_LIB.BASEBOARD_FAB2(SCH_1):GND
 G80    GND VSS<1122> @BASEBOARD_FAB2_LIB.BASEBOARD_FAB2(SCH_1):GND
 G82    GND VSS<1121> @BASEBOARD_FAB2_LIB.BASEBOARD_FAB2(SCH_1):GND
  H3    GND VSS<1120> @BASEBOARD_FAB2_LIB.BASEBOARD_FAB2(SCH_1):GND
 H11    GND VSS<1119> @BASEBOARD_FAB2_LIB.BASEBOARD_FAB2(SCH_1):GND
 H25    GND VSS<1118> @BASEBOARD_FAB2_LIB.BASEBOARD_FAB2(SCH_1):GND
 H27    GND VSS<1117> @BASEBOARD_FAB2_LIB.BASEBOARD_FAB2(SCH_1):GND
 H29    GND VSS<1116> @BASEBOARD_FAB2_LIB.BASEBOARD_FAB2(SCH_1):GND
 H31    GND VSS<1115> @BASEBOARD_FAB2_LIB.BASEBOARD_FAB2(SCH_1):GND
 H33    GND VSS<1114> @BASEBOARD_FAB2_LIB.BASEBOARD_FAB2(SCH_1):GND
 H35    GND VSS<1113> @BASEBOARD_FAB2_LIB.BASEBOARD_FAB2(SCH_1):GND
 H37    GND VSS<1112> @BASEBOARD_FAB2_LIB.BASEBOARD_FAB2(SCH_1):GND
 H39    GND VSS<1111> @BASEBOARD_FAB2_LIB.BASEBOARD_FAB2(SCH_1):GND
 H41    GND VSS<1110> @BASEBOARD_FAB2_LIB.BASEBOARD_FAB2(SCH_1):GND
 H65    GND VSS<1109> @BASEBOARD_FAB2_LIB.BASEBOARD_FAB2(SCH_1):GND
 H71    GND VSS<1108> @BASEBOARD_FAB2_LIB.BASEBOARD_FAB2(SCH_1):GND
 H75    GND VSS<1107> @BASEBOARD_FAB2_LIB.BASEBOARD_FAB2(SCH_1):GND
DN44    GND VSS<1106> @BASEBOARD_FAB2_LIB.BASEBOARD_FAB2(SCH_1):GND
  J4    GND VSS<1105> @BASEBOARD_FAB2_LIB.BASEBOARD_FAB2(SCH_1):GND
 J12    GND VSS<1104> @BASEBOARD_FAB2_LIB.BASEBOARD_FAB2(SCH_1):GND
 J14    GND VSS<1103> @BASEBOARD_FAB2_LIB.BASEBOARD_FAB2(SCH_1):GND
 J22    GND VSS<1102> @BASEBOARD_FAB2_LIB.BASEBOARD_FAB2(SCH_1):GND
 J26    GND VSS<1101> @BASEBOARD_FAB2_LIB.BASEBOARD_FAB2(SCH_1):GND
 J28    GND VSS<1100> @BASEBOARD_FAB2_LIB.BASEBOARD_FAB2(SCH_1):GND
 J32    GND VSS<1099> @BASEBOARD_FAB2_LIB.BASEBOARD_FAB2(SCH_1):GND
 J34    GND VSS<1098> @BASEBOARD_FAB2_LIB.BASEBOARD_FAB2(SCH_1):GND
 J38    GND VSS<1097> @BASEBOARD_FAB2_LIB.BASEBOARD_FAB2(SCH_1):GND
 J40    GND VSS<1096> @BASEBOARD_FAB2_LIB.BASEBOARD_FAB2(SCH_1):GND
 J72    GND VSS<1095> @BASEBOARD_FAB2_LIB.BASEBOARD_FAB2(SCH_1):GND
 J74    GND VSS<1094> @BASEBOARD_FAB2_LIB.BASEBOARD_FAB2(SCH_1):GND

SKX_EXT_B_BGA1-IC,TBD  I21  U5D1
 J76    GND VSS<1093> @BASEBOARD_FAB2_LIB.BASEBOARD_FAB2(SCH_1):GND
 J82    GND VSS<1092> @BASEBOARD_FAB2_LIB.BASEBOARD_FAB2(SCH_1):GND
 J84    GND VSS<1091> @BASEBOARD_FAB2_LIB.BASEBOARD_FAB2(SCH_1):GND
  K1    GND VSS<1090> @BASEBOARD_FAB2_LIB.BASEBOARD_FAB2(SCH_1):GND
 K11    GND VSS<1089> @BASEBOARD_FAB2_LIB.BASEBOARD_FAB2(SCH_1):GND
 K13    GND VSS<1088> @BASEBOARD_FAB2_LIB.BASEBOARD_FAB2(SCH_1):GND
 K17    GND VSS<1087> @BASEBOARD_FAB2_LIB.BASEBOARD_FAB2(SCH_1):GND
 DB7    GND VSS<1086> @BASEBOARD_FAB2_LIB.BASEBOARD_FAB2(SCH_1):GND
 K27    GND VSS<1085> @BASEBOARD_FAB2_LIB.BASEBOARD_FAB2(SCH_1):GND
 K33    GND VSS<1084> @BASEBOARD_FAB2_LIB.BASEBOARD_FAB2(SCH_1):GND
 K39    GND VSS<1083> @BASEBOARD_FAB2_LIB.BASEBOARD_FAB2(SCH_1):GND
 K65    GND VSS<1082> @BASEBOARD_FAB2_LIB.BASEBOARD_FAB2(SCH_1):GND
 K67    GND VSS<1081> @BASEBOARD_FAB2_LIB.BASEBOARD_FAB2(SCH_1):GND
 K69    GND VSS<1080> @BASEBOARD_FAB2_LIB.BASEBOARD_FAB2(SCH_1):GND
 K71    GND VSS<1079> @BASEBOARD_FAB2_LIB.BASEBOARD_FAB2(SCH_1):GND
 K73    GND VSS<1078> @BASEBOARD_FAB2_LIB.BASEBOARD_FAB2(SCH_1):GND
 K77    GND VSS<1077> @BASEBOARD_FAB2_LIB.BASEBOARD_FAB2(SCH_1):GND
 K81    GND VSS<1076> @BASEBOARD_FAB2_LIB.BASEBOARD_FAB2(SCH_1):GND
 K83    GND VSS<1075> @BASEBOARD_FAB2_LIB.BASEBOARD_FAB2(SCH_1):GND
 K85    GND VSS<1074> @BASEBOARD_FAB2_LIB.BASEBOARD_FAB2(SCH_1):GND
 L10    GND VSS<1073> @BASEBOARD_FAB2_LIB.BASEBOARD_FAB2(SCH_1):GND
  L2    GND VSS<1072> @BASEBOARD_FAB2_LIB.BASEBOARD_FAB2(SCH_1):GND
  L6    GND VSS<1071> @BASEBOARD_FAB2_LIB.BASEBOARD_FAB2(SCH_1):GND
 L20    GND VSS<1070> @BASEBOARD_FAB2_LIB.BASEBOARD_FAB2(SCH_1):GND
 L22    GND VSS<1069> @BASEBOARD_FAB2_LIB.BASEBOARD_FAB2(SCH_1):GND
 L72    GND VSS<1068> @BASEBOARD_FAB2_LIB.BASEBOARD_FAB2(SCH_1):GND
 L78    GND VSS<1067> @BASEBOARD_FAB2_LIB.BASEBOARD_FAB2(SCH_1):GND
 L80    GND VSS<1066> @BASEBOARD_FAB2_LIB.BASEBOARD_FAB2(SCH_1):GND
 L82    GND VSS<1065> @BASEBOARD_FAB2_LIB.BASEBOARD_FAB2(SCH_1):GND
 BT9    GND VSS<1064> @BASEBOARD_FAB2_LIB.BASEBOARD_FAB2(SCH_1):GND
 CT7    GND VSS<1063> @BASEBOARD_FAB2_LIB.BASEBOARD_FAB2(SCH_1):GND
 M15    GND VSS<1062> @BASEBOARD_FAB2_LIB.BASEBOARD_FAB2(SCH_1):GND
 M17    GND VSS<1061> @BASEBOARD_FAB2_LIB.BASEBOARD_FAB2(SCH_1):GND
 M19    GND VSS<1060> @BASEBOARD_FAB2_LIB.BASEBOARD_FAB2(SCH_1):GND
 M23    GND VSS<1059> @BASEBOARD_FAB2_LIB.BASEBOARD_FAB2(SCH_1):GND
 M25    GND VSS<1058> @BASEBOARD_FAB2_LIB.BASEBOARD_FAB2(SCH_1):GND
 M27    GND VSS<1057> @BASEBOARD_FAB2_LIB.BASEBOARD_FAB2(SCH_1):GND
 M29    GND VSS<1056> @BASEBOARD_FAB2_LIB.BASEBOARD_FAB2(SCH_1):GND
 M31    GND VSS<1055> @BASEBOARD_FAB2_LIB.BASEBOARD_FAB2(SCH_1):GND
 M33    GND VSS<1054> @BASEBOARD_FAB2_LIB.BASEBOARD_FAB2(SCH_1):GND
 M35    GND VSS<1053> @BASEBOARD_FAB2_LIB.BASEBOARD_FAB2(SCH_1):GND
 M37    GND VSS<1052> @BASEBOARD_FAB2_LIB.BASEBOARD_FAB2(SCH_1):GND
 M39    GND VSS<1051> @BASEBOARD_FAB2_LIB.BASEBOARD_FAB2(SCH_1):GND
 M41    GND VSS<1050> @BASEBOARD_FAB2_LIB.BASEBOARD_FAB2(SCH_1):GND
 M43    GND VSS<1049> @BASEBOARD_FAB2_LIB.BASEBOARD_FAB2(SCH_1):GND
 M65    GND VSS<1048> @BASEBOARD_FAB2_LIB.BASEBOARD_FAB2(SCH_1):GND
 M71    GND VSS<1047> @BASEBOARD_FAB2_LIB.BASEBOARD_FAB2(SCH_1):GND
 M79    GND VSS<1046> @BASEBOARD_FAB2_LIB.BASEBOARD_FAB2(SCH_1):GND
 M83    GND VSS<1045> @BASEBOARD_FAB2_LIB.BASEBOARD_FAB2(SCH_1):GND
 M85    GND VSS<1044> @BASEBOARD_FAB2_LIB.BASEBOARD_FAB2(SCH_1):GND
DM19    GND VSS<1043> @BASEBOARD_FAB2_LIB.BASEBOARD_FAB2(SCH_1):GND
 N20    GND VSS<1042> @BASEBOARD_FAB2_LIB.BASEBOARD_FAB2(SCH_1):GND
 N22    GND VSS<1041> @BASEBOARD_FAB2_LIB.BASEBOARD_FAB2(SCH_1):GND
  N6    GND VSS<1040> @BASEBOARD_FAB2_LIB.BASEBOARD_FAB2(SCH_1):GND
 N66    GND VSS<1039> @BASEBOARD_FAB2_LIB.BASEBOARD_FAB2(SCH_1):GND
 N70    GND VSS<1038> @BASEBOARD_FAB2_LIB.BASEBOARD_FAB2(SCH_1):GND
 N72    GND VSS<1037> @BASEBOARD_FAB2_LIB.BASEBOARD_FAB2(SCH_1):GND
 N74    GND VSS<1036> @BASEBOARD_FAB2_LIB.BASEBOARD_FAB2(SCH_1):GND
 N76    GND VSS<1035> @BASEBOARD_FAB2_LIB.BASEBOARD_FAB2(SCH_1):GND
 N78    GND VSS<1034> @BASEBOARD_FAB2_LIB.BASEBOARD_FAB2(SCH_1):GND
  N4    GND VSS<1033> @BASEBOARD_FAB2_LIB.BASEBOARD_FAB2(SCH_1):GND
  N8    GND VSS<1032> @BASEBOARD_FAB2_LIB.BASEBOARD_FAB2(SCH_1):GND
 P11    GND VSS<1031> @BASEBOARD_FAB2_LIB.BASEBOARD_FAB2(SCH_1):GND
 P15    GND VSS<1030> @BASEBOARD_FAB2_LIB.BASEBOARD_FAB2(SCH_1):GND
 P27    GND VSS<1029> @BASEBOARD_FAB2_LIB.BASEBOARD_FAB2(SCH_1):GND
 P33    GND VSS<1028> @BASEBOARD_FAB2_LIB.BASEBOARD_FAB2(SCH_1):GND
 P39    GND VSS<1027> @BASEBOARD_FAB2_LIB.BASEBOARD_FAB2(SCH_1):GND
 P67    GND VSS<1026> @BASEBOARD_FAB2_LIB.BASEBOARD_FAB2(SCH_1):GND
 P69    GND VSS<1025> @BASEBOARD_FAB2_LIB.BASEBOARD_FAB2(SCH_1):GND
 P71    GND VSS<1024> @BASEBOARD_FAB2_LIB.BASEBOARD_FAB2(SCH_1):GND
 P81    GND VSS<1023> @BASEBOARD_FAB2_LIB.BASEBOARD_FAB2(SCH_1):GND
 P83    GND VSS<1022> @BASEBOARD_FAB2_LIB.BASEBOARD_FAB2(SCH_1):GND
 R14    GND VSS<1021> @BASEBOARD_FAB2_LIB.BASEBOARD_FAB2(SCH_1):GND
 R18    GND VSS<1020> @BASEBOARD_FAB2_LIB.BASEBOARD_FAB2(SCH_1):GND
  R2    GND VSS<1019> @BASEBOARD_FAB2_LIB.BASEBOARD_FAB2(SCH_1):GND
  R4    GND VSS<1018> @BASEBOARD_FAB2_LIB.BASEBOARD_FAB2(SCH_1):GND
 R22    GND VSS<1017> @BASEBOARD_FAB2_LIB.BASEBOARD_FAB2(SCH_1):GND
 R26    GND VSS<1016> @BASEBOARD_FAB2_LIB.BASEBOARD_FAB2(SCH_1):GND
 R28    GND VSS<1015> @BASEBOARD_FAB2_LIB.BASEBOARD_FAB2(SCH_1):GND
 R32    GND VSS<1014> @BASEBOARD_FAB2_LIB.BASEBOARD_FAB2(SCH_1):GND
 R34    GND VSS<1013> @BASEBOARD_FAB2_LIB.BASEBOARD_FAB2(SCH_1):GND
 R38    GND VSS<1012> @BASEBOARD_FAB2_LIB.BASEBOARD_FAB2(SCH_1):GND
 R40    GND VSS<1011> @BASEBOARD_FAB2_LIB.BASEBOARD_FAB2(SCH_1):GND
 R68    GND VSS<1010> @BASEBOARD_FAB2_LIB.BASEBOARD_FAB2(SCH_1):GND
 R72    GND VSS<1009> @BASEBOARD_FAB2_LIB.BASEBOARD_FAB2(SCH_1):GND
 R78    GND VSS<1008> @BASEBOARD_FAB2_LIB.BASEBOARD_FAB2(SCH_1):GND
 R86    GND VSS<1007> @BASEBOARD_FAB2_LIB.BASEBOARD_FAB2(SCH_1):GND
 T13    GND VSS<1006> @BASEBOARD_FAB2_LIB.BASEBOARD_FAB2(SCH_1):GND
 T17    GND VSS<1005> @BASEBOARD_FAB2_LIB.BASEBOARD_FAB2(SCH_1):GND
 T25    GND VSS<1004> @BASEBOARD_FAB2_LIB.BASEBOARD_FAB2(SCH_1):GND
 T29    GND VSS<1003> @BASEBOARD_FAB2_LIB.BASEBOARD_FAB2(SCH_1):GND
 T31    GND VSS<1002> @BASEBOARD_FAB2_LIB.BASEBOARD_FAB2(SCH_1):GND
 T35    GND VSS<1001> @BASEBOARD_FAB2_LIB.BASEBOARD_FAB2(SCH_1):GND
 T37    GND VSS<1000> @BASEBOARD_FAB2_LIB.BASEBOARD_FAB2(SCH_1):GND
 T41    GND VSS<999> @BASEBOARD_FAB2_LIB.BASEBOARD_FAB2(SCH_1):GND
 T65    GND VSS<998> @BASEBOARD_FAB2_LIB.BASEBOARD_FAB2(SCH_1):GND
 T73    GND VSS<997> @BASEBOARD_FAB2_LIB.BASEBOARD_FAB2(SCH_1):GND
 T77    GND VSS<996> @BASEBOARD_FAB2_LIB.BASEBOARD_FAB2(SCH_1):GND
 T83    GND VSS<995> @BASEBOARD_FAB2_LIB.BASEBOARD_FAB2(SCH_1):GND
 T85    GND VSS<994> @BASEBOARD_FAB2_LIB.BASEBOARD_FAB2(SCH_1):GND
  U2    GND VSS<993> @BASEBOARD_FAB2_LIB.BASEBOARD_FAB2(SCH_1):GND
  U4    GND VSS<992> @BASEBOARD_FAB2_LIB.BASEBOARD_FAB2(SCH_1):GND
  U6    GND VSS<991> @BASEBOARD_FAB2_LIB.BASEBOARD_FAB2(SCH_1):GND
 U20    GND VSS<990> @BASEBOARD_FAB2_LIB.BASEBOARD_FAB2(SCH_1):GND
 U22    GND VSS<989> @BASEBOARD_FAB2_LIB.BASEBOARD_FAB2(SCH_1):GND
 U24    GND VSS<988> @BASEBOARD_FAB2_LIB.BASEBOARD_FAB2(SCH_1):GND
 U30    GND VSS<987> @BASEBOARD_FAB2_LIB.BASEBOARD_FAB2(SCH_1):GND
 U36    GND VSS<986> @BASEBOARD_FAB2_LIB.BASEBOARD_FAB2(SCH_1):GND
 U42    GND VSS<985> @BASEBOARD_FAB2_LIB.BASEBOARD_FAB2(SCH_1):GND
 U68    GND VSS<984> @BASEBOARD_FAB2_LIB.BASEBOARD_FAB2(SCH_1):GND
 U70    GND VSS<983> @BASEBOARD_FAB2_LIB.BASEBOARD_FAB2(SCH_1):GND
 U74    GND VSS<982> @BASEBOARD_FAB2_LIB.BASEBOARD_FAB2(SCH_1):GND
 U76    GND VSS<981> @BASEBOARD_FAB2_LIB.BASEBOARD_FAB2(SCH_1):GND
 U78    GND VSS<980> @BASEBOARD_FAB2_LIB.BASEBOARD_FAB2(SCH_1):GND
 U80    GND VSS<979> @BASEBOARD_FAB2_LIB.BASEBOARD_FAB2(SCH_1):GND
 U86    GND VSS<978> @BASEBOARD_FAB2_LIB.BASEBOARD_FAB2(SCH_1):GND
  V1    GND VSS<977> @BASEBOARD_FAB2_LIB.BASEBOARD_FAB2(SCH_1):GND
  V5    GND VSS<976> @BASEBOARD_FAB2_LIB.BASEBOARD_FAB2(SCH_1):GND
  V9    GND VSS<975> @BASEBOARD_FAB2_LIB.BASEBOARD_FAB2(SCH_1):GND
 V13    GND VSS<974> @BASEBOARD_FAB2_LIB.BASEBOARD_FAB2(SCH_1):GND
 V15    GND VSS<973> @BASEBOARD_FAB2_LIB.BASEBOARD_FAB2(SCH_1):GND
 V21    GND VSS<972> @BASEBOARD_FAB2_LIB.BASEBOARD_FAB2(SCH_1):GND
 V23    GND VSS<971> @BASEBOARD_FAB2_LIB.BASEBOARD_FAB2(SCH_1):GND
 V43    GND VSS<970> @BASEBOARD_FAB2_LIB.BASEBOARD_FAB2(SCH_1):GND
 V73    GND VSS<969> @BASEBOARD_FAB2_LIB.BASEBOARD_FAB2(SCH_1):GND
 V75    GND VSS<968> @BASEBOARD_FAB2_LIB.BASEBOARD_FAB2(SCH_1):GND
 V77    GND VSS<967> @BASEBOARD_FAB2_LIB.BASEBOARD_FAB2(SCH_1):GND
 V83    GND VSS<966> @BASEBOARD_FAB2_LIB.BASEBOARD_FAB2(SCH_1):GND
  W8    GND VSS<965> @BASEBOARD_FAB2_LIB.BASEBOARD_FAB2(SCH_1):GND
AC56    GND VSS<964> @BASEBOARD_FAB2_LIB.BASEBOARD_FAB2(SCH_1):GND
 W12    GND VSS<963> @BASEBOARD_FAB2_LIB.BASEBOARD_FAB2(SCH_1):GND
 W22    GND VSS<962> @BASEBOARD_FAB2_LIB.BASEBOARD_FAB2(SCH_1):GND
 W24    GND VSS<961> @BASEBOARD_FAB2_LIB.BASEBOARD_FAB2(SCH_1):GND
 W26    GND VSS<960> @BASEBOARD_FAB2_LIB.BASEBOARD_FAB2(SCH_1):GND
 W28    GND VSS<959> @BASEBOARD_FAB2_LIB.BASEBOARD_FAB2(SCH_1):GND
 W30    GND VSS<958> @BASEBOARD_FAB2_LIB.BASEBOARD_FAB2(SCH_1):GND
 W32    GND VSS<957> @BASEBOARD_FAB2_LIB.BASEBOARD_FAB2(SCH_1):GND
 W34    GND VSS<956> @BASEBOARD_FAB2_LIB.BASEBOARD_FAB2(SCH_1):GND
 W36    GND VSS<955> @BASEBOARD_FAB2_LIB.BASEBOARD_FAB2(SCH_1):GND
 W38    GND VSS<954> @BASEBOARD_FAB2_LIB.BASEBOARD_FAB2(SCH_1):GND
 W40    GND VSS<953> @BASEBOARD_FAB2_LIB.BASEBOARD_FAB2(SCH_1):GND
 W42    GND VSS<952> @BASEBOARD_FAB2_LIB.BASEBOARD_FAB2(SCH_1):GND
 W68    GND VSS<951> @BASEBOARD_FAB2_LIB.BASEBOARD_FAB2(SCH_1):GND
 W74    GND VSS<950> @BASEBOARD_FAB2_LIB.BASEBOARD_FAB2(SCH_1):GND
 W78    GND VSS<949> @BASEBOARD_FAB2_LIB.BASEBOARD_FAB2(SCH_1):GND
 W82    GND VSS<948> @BASEBOARD_FAB2_LIB.BASEBOARD_FAB2(SCH_1):GND
 Y15    GND VSS<947> @BASEBOARD_FAB2_LIB.BASEBOARD_FAB2(SCH_1):GND
 Y17    GND VSS<946> @BASEBOARD_FAB2_LIB.BASEBOARD_FAB2(SCH_1):GND
  Y5    GND VSS<945> @BASEBOARD_FAB2_LIB.BASEBOARD_FAB2(SCH_1):GND
 Y67    GND VSS<944> @BASEBOARD_FAB2_LIB.BASEBOARD_FAB2(SCH_1):GND
  Y7    GND VSS<943> @BASEBOARD_FAB2_LIB.BASEBOARD_FAB2(SCH_1):GND
  Y9    GND VSS<942> @BASEBOARD_FAB2_LIB.BASEBOARD_FAB2(SCH_1):GND
 Y71    GND VSS<941> @BASEBOARD_FAB2_LIB.BASEBOARD_FAB2(SCH_1):GND
 Y73    GND VSS<940> @BASEBOARD_FAB2_LIB.BASEBOARD_FAB2(SCH_1):GND
 Y79    GND VSS<939> @BASEBOARD_FAB2_LIB.BASEBOARD_FAB2(SCH_1):GND
 Y81    GND VSS<938> @BASEBOARD_FAB2_LIB.BASEBOARD_FAB2(SCH_1):GND
 Y83    GND VSS<937> @BASEBOARD_FAB2_LIB.BASEBOARD_FAB2(SCH_1):GND
 Y85    GND VSS<936> @BASEBOARD_FAB2_LIB.BASEBOARD_FAB2(SCH_1):GND
 AA4    GND VSS<935> @BASEBOARD_FAB2_LIB.BASEBOARD_FAB2(SCH_1):GND
AA16    GND VSS<934> @BASEBOARD_FAB2_LIB.BASEBOARD_FAB2(SCH_1):GND

SKX_EXT_B_BGA1-IC,TBD  I22  U5D1
AA18    GND VSS<933> @BASEBOARD_FAB2_LIB.BASEBOARD_FAB2(SCH_1):GND
AA22    GND VSS<932> @BASEBOARD_FAB2_LIB.BASEBOARD_FAB2(SCH_1):GND
AA24    GND VSS<931> @BASEBOARD_FAB2_LIB.BASEBOARD_FAB2(SCH_1):GND
AA30    GND VSS<930> @BASEBOARD_FAB2_LIB.BASEBOARD_FAB2(SCH_1):GND
AA36    GND VSS<929> @BASEBOARD_FAB2_LIB.BASEBOARD_FAB2(SCH_1):GND
AA42    GND VSS<928> @BASEBOARD_FAB2_LIB.BASEBOARD_FAB2(SCH_1):GND
AA64    GND VSS<927> @BASEBOARD_FAB2_LIB.BASEBOARD_FAB2(SCH_1):GND
AA66    GND VSS<926> @BASEBOARD_FAB2_LIB.BASEBOARD_FAB2(SCH_1):GND
AA68    GND VSS<925> @BASEBOARD_FAB2_LIB.BASEBOARD_FAB2(SCH_1):GND
AA76    GND VSS<924> @BASEBOARD_FAB2_LIB.BASEBOARD_FAB2(SCH_1):GND
AA78    GND VSS<923> @BASEBOARD_FAB2_LIB.BASEBOARD_FAB2(SCH_1):GND
AA80    GND VSS<922> @BASEBOARD_FAB2_LIB.BASEBOARD_FAB2(SCH_1):GND
AA82    GND VSS<921> @BASEBOARD_FAB2_LIB.BASEBOARD_FAB2(SCH_1):GND
 AB1    GND VSS<920> @BASEBOARD_FAB2_LIB.BASEBOARD_FAB2(SCH_1):GND
 AB5    GND VSS<919> @BASEBOARD_FAB2_LIB.BASEBOARD_FAB2(SCH_1):GND
AB11    GND VSS<918> @BASEBOARD_FAB2_LIB.BASEBOARD_FAB2(SCH_1):GND
AB21    GND VSS<917> @BASEBOARD_FAB2_LIB.BASEBOARD_FAB2(SCH_1):GND
AB23    GND VSS<916> @BASEBOARD_FAB2_LIB.BASEBOARD_FAB2(SCH_1):GND
AB25    GND VSS<915> @BASEBOARD_FAB2_LIB.BASEBOARD_FAB2(SCH_1):GND
AB29    GND VSS<914> @BASEBOARD_FAB2_LIB.BASEBOARD_FAB2(SCH_1):GND
AB31    GND VSS<913> @BASEBOARD_FAB2_LIB.BASEBOARD_FAB2(SCH_1):GND
AB35    GND VSS<912> @BASEBOARD_FAB2_LIB.BASEBOARD_FAB2(SCH_1):GND
AB37    GND VSS<911> @BASEBOARD_FAB2_LIB.BASEBOARD_FAB2(SCH_1):GND
AB41    GND VSS<910> @BASEBOARD_FAB2_LIB.BASEBOARD_FAB2(SCH_1):GND
AB65    GND VSS<909> @BASEBOARD_FAB2_LIB.BASEBOARD_FAB2(SCH_1):GND
AB69    GND VSS<908> @BASEBOARD_FAB2_LIB.BASEBOARD_FAB2(SCH_1):GND
AB73    GND VSS<907> @BASEBOARD_FAB2_LIB.BASEBOARD_FAB2(SCH_1):GND
AB79    GND VSS<906> @BASEBOARD_FAB2_LIB.BASEBOARD_FAB2(SCH_1):GND
AB83    GND VSS<905> @BASEBOARD_FAB2_LIB.BASEBOARD_FAB2(SCH_1):GND
AB85    GND VSS<904> @BASEBOARD_FAB2_LIB.BASEBOARD_FAB2(SCH_1):GND
AC18    GND VSS<903> @BASEBOARD_FAB2_LIB.BASEBOARD_FAB2(SCH_1):GND
AC22    GND VSS<902> @BASEBOARD_FAB2_LIB.BASEBOARD_FAB2(SCH_1):GND
AC26    GND VSS<901> @BASEBOARD_FAB2_LIB.BASEBOARD_FAB2(SCH_1):GND
AC28    GND VSS<900> @BASEBOARD_FAB2_LIB.BASEBOARD_FAB2(SCH_1):GND
AC32    GND VSS<899> @BASEBOARD_FAB2_LIB.BASEBOARD_FAB2(SCH_1):GND
AC34    GND VSS<898> @BASEBOARD_FAB2_LIB.BASEBOARD_FAB2(SCH_1):GND
AC38    GND VSS<897> @BASEBOARD_FAB2_LIB.BASEBOARD_FAB2(SCH_1):GND
AC40    GND VSS<896> @BASEBOARD_FAB2_LIB.BASEBOARD_FAB2(SCH_1):GND
AC64    GND VSS<895> @BASEBOARD_FAB2_LIB.BASEBOARD_FAB2(SCH_1):GND
AC70    GND VSS<894> @BASEBOARD_FAB2_LIB.BASEBOARD_FAB2(SCH_1):GND
AC72    GND VSS<893> @BASEBOARD_FAB2_LIB.BASEBOARD_FAB2(SCH_1):GND
AC78    GND VSS<892> @BASEBOARD_FAB2_LIB.BASEBOARD_FAB2(SCH_1):GND
AC84    GND VSS<891> @BASEBOARD_FAB2_LIB.BASEBOARD_FAB2(SCH_1):GND
AC86    GND VSS<890> @BASEBOARD_FAB2_LIB.BASEBOARD_FAB2(SCH_1):GND
 AD3    GND VSS<889> @BASEBOARD_FAB2_LIB.BASEBOARD_FAB2(SCH_1):GND
 AD7    GND VSS<888> @BASEBOARD_FAB2_LIB.BASEBOARD_FAB2(SCH_1):GND
 AD9    GND VSS<887> @BASEBOARD_FAB2_LIB.BASEBOARD_FAB2(SCH_1):GND
AD11    GND VSS<886> @BASEBOARD_FAB2_LIB.BASEBOARD_FAB2(SCH_1):GND
AD13    GND VSS<885> @BASEBOARD_FAB2_LIB.BASEBOARD_FAB2(SCH_1):GND
AD15    GND VSS<884> @BASEBOARD_FAB2_LIB.BASEBOARD_FAB2(SCH_1):GND
AD19    GND VSS<883> @BASEBOARD_FAB2_LIB.BASEBOARD_FAB2(SCH_1):GND
AD21    GND VSS<882> @BASEBOARD_FAB2_LIB.BASEBOARD_FAB2(SCH_1):GND
AD27    GND VSS<881> @BASEBOARD_FAB2_LIB.BASEBOARD_FAB2(SCH_1):GND
AD33    GND VSS<880> @BASEBOARD_FAB2_LIB.BASEBOARD_FAB2(SCH_1):GND
AD39    GND VSS<879> @BASEBOARD_FAB2_LIB.BASEBOARD_FAB2(SCH_1):GND
AD43    GND VSS<878> @BASEBOARD_FAB2_LIB.BASEBOARD_FAB2(SCH_1):GND
AD71    GND VSS<877> @BASEBOARD_FAB2_LIB.BASEBOARD_FAB2(SCH_1):GND
AD73    GND VSS<876> @BASEBOARD_FAB2_LIB.BASEBOARD_FAB2(SCH_1):GND
AD75    GND VSS<875> @BASEBOARD_FAB2_LIB.BASEBOARD_FAB2(SCH_1):GND
AD81    GND VSS<874> @BASEBOARD_FAB2_LIB.BASEBOARD_FAB2(SCH_1):GND
AD83    GND VSS<873> @BASEBOARD_FAB2_LIB.BASEBOARD_FAB2(SCH_1):GND
AD85    GND VSS<872> @BASEBOARD_FAB2_LIB.BASEBOARD_FAB2(SCH_1):GND
 AE4    GND VSS<871> @BASEBOARD_FAB2_LIB.BASEBOARD_FAB2(SCH_1):GND
 AE8    GND VSS<870> @BASEBOARD_FAB2_LIB.BASEBOARD_FAB2(SCH_1):GND
AC54    GND VSS<869> @BASEBOARD_FAB2_LIB.BASEBOARD_FAB2(SCH_1):GND
AE16    GND VSS<868> @BASEBOARD_FAB2_LIB.BASEBOARD_FAB2(SCH_1):GND
AE38    GND VSS<867> @BASEBOARD_FAB2_LIB.BASEBOARD_FAB2(SCH_1):GND
AE40    GND VSS<866> @BASEBOARD_FAB2_LIB.BASEBOARD_FAB2(SCH_1):GND
AE42    GND VSS<865> @BASEBOARD_FAB2_LIB.BASEBOARD_FAB2(SCH_1):GND
AE64    GND VSS<864> @BASEBOARD_FAB2_LIB.BASEBOARD_FAB2(SCH_1):GND
AE66    GND VSS<863> @BASEBOARD_FAB2_LIB.BASEBOARD_FAB2(SCH_1):GND
AE68    GND VSS<862> @BASEBOARD_FAB2_LIB.BASEBOARD_FAB2(SCH_1):GND
AE70    GND VSS<861> @BASEBOARD_FAB2_LIB.BASEBOARD_FAB2(SCH_1):GND
AE78    GND VSS<860> @BASEBOARD_FAB2_LIB.BASEBOARD_FAB2(SCH_1):GND
 AF1    GND VSS<859> @BASEBOARD_FAB2_LIB.BASEBOARD_FAB2(SCH_1):GND
AC52    GND VSS<858> @BASEBOARD_FAB2_LIB.BASEBOARD_FAB2(SCH_1):GND
 AF9    GND VSS<857> @BASEBOARD_FAB2_LIB.BASEBOARD_FAB2(SCH_1):GND
AF21    GND VSS<856> @BASEBOARD_FAB2_LIB.BASEBOARD_FAB2(SCH_1):GND
AF23    GND VSS<855> @BASEBOARD_FAB2_LIB.BASEBOARD_FAB2(SCH_1):GND
AF25    GND VSS<854> @BASEBOARD_FAB2_LIB.BASEBOARD_FAB2(SCH_1):GND
AF27    GND VSS<853> @BASEBOARD_FAB2_LIB.BASEBOARD_FAB2(SCH_1):GND
AF29    GND VSS<852> @BASEBOARD_FAB2_LIB.BASEBOARD_FAB2(SCH_1):GND
AF31    GND VSS<851> @BASEBOARD_FAB2_LIB.BASEBOARD_FAB2(SCH_1):GND
AF33    GND VSS<850> @BASEBOARD_FAB2_LIB.BASEBOARD_FAB2(SCH_1):GND
AF37    GND VSS<849> @BASEBOARD_FAB2_LIB.BASEBOARD_FAB2(SCH_1):GND
AF39    GND VSS<848> @BASEBOARD_FAB2_LIB.BASEBOARD_FAB2(SCH_1):GND
AF41    GND VSS<847> @BASEBOARD_FAB2_LIB.BASEBOARD_FAB2(SCH_1):GND
AF73    GND VSS<846> @BASEBOARD_FAB2_LIB.BASEBOARD_FAB2(SCH_1):GND
AF77    GND VSS<845> @BASEBOARD_FAB2_LIB.BASEBOARD_FAB2(SCH_1):GND
AF83    GND VSS<844> @BASEBOARD_FAB2_LIB.BASEBOARD_FAB2(SCH_1):GND
AF85    GND VSS<843> @BASEBOARD_FAB2_LIB.BASEBOARD_FAB2(SCH_1):GND
AG12    GND VSS<842> @BASEBOARD_FAB2_LIB.BASEBOARD_FAB2(SCH_1):GND
AG14    GND VSS<841> @BASEBOARD_FAB2_LIB.BASEBOARD_FAB2(SCH_1):GND
AG18    GND VSS<840> @BASEBOARD_FAB2_LIB.BASEBOARD_FAB2(SCH_1):GND
AG36    GND VSS<839> @BASEBOARD_FAB2_LIB.BASEBOARD_FAB2(SCH_1):GND
AG64    GND VSS<838> @BASEBOARD_FAB2_LIB.BASEBOARD_FAB2(SCH_1):GND
AG70    GND VSS<837> @BASEBOARD_FAB2_LIB.BASEBOARD_FAB2(SCH_1):GND
AG74    GND VSS<836> @BASEBOARD_FAB2_LIB.BASEBOARD_FAB2(SCH_1):GND
AG76    GND VSS<835> @BASEBOARD_FAB2_LIB.BASEBOARD_FAB2(SCH_1):GND
AG78    GND VSS<834> @BASEBOARD_FAB2_LIB.BASEBOARD_FAB2(SCH_1):GND
AG80    GND VSS<833> @BASEBOARD_FAB2_LIB.BASEBOARD_FAB2(SCH_1):GND
 AH1    GND VSS<832> @BASEBOARD_FAB2_LIB.BASEBOARD_FAB2(SCH_1):GND
 AH5    GND VSS<831> @BASEBOARD_FAB2_LIB.BASEBOARD_FAB2(SCH_1):GND
AH21    GND VSS<830> @BASEBOARD_FAB2_LIB.BASEBOARD_FAB2(SCH_1):GND
AH27    GND VSS<829> @BASEBOARD_FAB2_LIB.BASEBOARD_FAB2(SCH_1):GND
AH33    GND VSS<828> @BASEBOARD_FAB2_LIB.BASEBOARD_FAB2(SCH_1):GND
AH35    GND VSS<827> @BASEBOARD_FAB2_LIB.BASEBOARD_FAB2(SCH_1):GND
AH45    GND VSS<826> @BASEBOARD_FAB2_LIB.BASEBOARD_FAB2(SCH_1):GND
AH47    GND VSS<825> @BASEBOARD_FAB2_LIB.BASEBOARD_FAB2(SCH_1):GND
AH49    GND VSS<824> @BASEBOARD_FAB2_LIB.BASEBOARD_FAB2(SCH_1):GND
AH51    GND VSS<823> @BASEBOARD_FAB2_LIB.BASEBOARD_FAB2(SCH_1):GND
AH53    GND VSS<822> @BASEBOARD_FAB2_LIB.BASEBOARD_FAB2(SCH_1):GND
AH59    GND VSS<821> @BASEBOARD_FAB2_LIB.BASEBOARD_FAB2(SCH_1):GND
AH61    GND VSS<820> @BASEBOARD_FAB2_LIB.BASEBOARD_FAB2(SCH_1):GND
AH65    GND VSS<819> @BASEBOARD_FAB2_LIB.BASEBOARD_FAB2(SCH_1):GND
AH69    GND VSS<818> @BASEBOARD_FAB2_LIB.BASEBOARD_FAB2(SCH_1):GND
AH75    GND VSS<817> @BASEBOARD_FAB2_LIB.BASEBOARD_FAB2(SCH_1):GND
AH77    GND VSS<816> @BASEBOARD_FAB2_LIB.BASEBOARD_FAB2(SCH_1):GND
AH83    GND VSS<815> @BASEBOARD_FAB2_LIB.BASEBOARD_FAB2(SCH_1):GND
 AJ8    GND VSS<814> @BASEBOARD_FAB2_LIB.BASEBOARD_FAB2(SCH_1):GND
AJ22    GND VSS<813> @BASEBOARD_FAB2_LIB.BASEBOARD_FAB2(SCH_1):GND
AJ26    GND VSS<812> @BASEBOARD_FAB2_LIB.BASEBOARD_FAB2(SCH_1):GND
AJ28    GND VSS<811> @BASEBOARD_FAB2_LIB.BASEBOARD_FAB2(SCH_1):GND
AJ32    GND VSS<810> @BASEBOARD_FAB2_LIB.BASEBOARD_FAB2(SCH_1):GND
AJ34    GND VSS<809> @BASEBOARD_FAB2_LIB.BASEBOARD_FAB2(SCH_1):GND
AJ46    GND VSS<808> @BASEBOARD_FAB2_LIB.BASEBOARD_FAB2(SCH_1):GND
AJ48    GND VSS<807> @BASEBOARD_FAB2_LIB.BASEBOARD_FAB2(SCH_1):GND
AJ50    GND VSS<806> @BASEBOARD_FAB2_LIB.BASEBOARD_FAB2(SCH_1):GND
AJ52    GND VSS<805> @BASEBOARD_FAB2_LIB.BASEBOARD_FAB2(SCH_1):GND
AJ54    GND VSS<804> @BASEBOARD_FAB2_LIB.BASEBOARD_FAB2(SCH_1):GND
AJ66    GND VSS<803> @BASEBOARD_FAB2_LIB.BASEBOARD_FAB2(SCH_1):GND
AJ68    GND VSS<802> @BASEBOARD_FAB2_LIB.BASEBOARD_FAB2(SCH_1):GND
AJ74    GND VSS<801> @BASEBOARD_FAB2_LIB.BASEBOARD_FAB2(SCH_1):GND
AJ78    GND VSS<800> @BASEBOARD_FAB2_LIB.BASEBOARD_FAB2(SCH_1):GND
AJ82    GND VSS<799> @BASEBOARD_FAB2_LIB.BASEBOARD_FAB2(SCH_1):GND
AJ86    GND VSS<798> @BASEBOARD_FAB2_LIB.BASEBOARD_FAB2(SCH_1):GND
 AK9    GND VSS<797> @BASEBOARD_FAB2_LIB.BASEBOARD_FAB2(SCH_1):GND
AK13    GND VSS<796> @BASEBOARD_FAB2_LIB.BASEBOARD_FAB2(SCH_1):GND
AK19    GND VSS<795> @BASEBOARD_FAB2_LIB.BASEBOARD_FAB2(SCH_1):GND
AK23    GND VSS<794> @BASEBOARD_FAB2_LIB.BASEBOARD_FAB2(SCH_1):GND
AK25    GND VSS<793> @BASEBOARD_FAB2_LIB.BASEBOARD_FAB2(SCH_1):GND
AK29    GND VSS<792> @BASEBOARD_FAB2_LIB.BASEBOARD_FAB2(SCH_1):GND
AK31    GND VSS<791> @BASEBOARD_FAB2_LIB.BASEBOARD_FAB2(SCH_1):GND
AK33    GND VSS<790> @BASEBOARD_FAB2_LIB.BASEBOARD_FAB2(SCH_1):GND
AK55    GND VSS<789> @BASEBOARD_FAB2_LIB.BASEBOARD_FAB2(SCH_1):GND
AK65    GND VSS<788> @BASEBOARD_FAB2_LIB.BASEBOARD_FAB2(SCH_1):GND
AK67    GND VSS<787> @BASEBOARD_FAB2_LIB.BASEBOARD_FAB2(SCH_1):GND
AK73    GND VSS<786> @BASEBOARD_FAB2_LIB.BASEBOARD_FAB2(SCH_1):GND
AK79    GND VSS<785> @BASEBOARD_FAB2_LIB.BASEBOARD_FAB2(SCH_1):GND
AK81    GND VSS<784> @BASEBOARD_FAB2_LIB.BASEBOARD_FAB2(SCH_1):GND
AK83    GND VSS<783> @BASEBOARD_FAB2_LIB.BASEBOARD_FAB2(SCH_1):GND
AK85    GND VSS<782> @BASEBOARD_FAB2_LIB.BASEBOARD_FAB2(SCH_1):GND
 AL4    GND VSS<781> @BASEBOARD_FAB2_LIB.BASEBOARD_FAB2(SCH_1):GND
AL10    GND VSS<780> @BASEBOARD_FAB2_LIB.BASEBOARD_FAB2(SCH_1):GND
AL24    GND VSS<779> @BASEBOARD_FAB2_LIB.BASEBOARD_FAB2(SCH_1):GND
AL30    GND VSS<778> @BASEBOARD_FAB2_LIB.BASEBOARD_FAB2(SCH_1):GND
AL32    GND VSS<777> @BASEBOARD_FAB2_LIB.BASEBOARD_FAB2(SCH_1):GND
AL56    GND VSS<776> @BASEBOARD_FAB2_LIB.BASEBOARD_FAB2(SCH_1):GND
AL64    GND VSS<775> @BASEBOARD_FAB2_LIB.BASEBOARD_FAB2(SCH_1):GND
AL68    GND VSS<774> @BASEBOARD_FAB2_LIB.BASEBOARD_FAB2(SCH_1):GND

SKX_EXT_B_BGA1-IC,TBD  I23  U5D1
AL76    GND VSS<773> @BASEBOARD_FAB2_LIB.BASEBOARD_FAB2(SCH_1):GND
AL78    GND VSS<772> @BASEBOARD_FAB2_LIB.BASEBOARD_FAB2(SCH_1):GND
AL80    GND VSS<771> @BASEBOARD_FAB2_LIB.BASEBOARD_FAB2(SCH_1):GND
AL82    GND VSS<770> @BASEBOARD_FAB2_LIB.BASEBOARD_FAB2(SCH_1):GND
AL86    GND VSS<769> @BASEBOARD_FAB2_LIB.BASEBOARD_FAB2(SCH_1):GND
 AM1    GND VSS<768> @BASEBOARD_FAB2_LIB.BASEBOARD_FAB2(SCH_1):GND
AC50    GND VSS<767> @BASEBOARD_FAB2_LIB.BASEBOARD_FAB2(SCH_1):GND
AM31    GND VSS<766> @BASEBOARD_FAB2_LIB.BASEBOARD_FAB2(SCH_1):GND
AM57    GND VSS<765> @BASEBOARD_FAB2_LIB.BASEBOARD_FAB2(SCH_1):GND
AM63    GND VSS<764> @BASEBOARD_FAB2_LIB.BASEBOARD_FAB2(SCH_1):GND
AM69    GND VSS<763> @BASEBOARD_FAB2_LIB.BASEBOARD_FAB2(SCH_1):GND
AM73    GND VSS<762> @BASEBOARD_FAB2_LIB.BASEBOARD_FAB2(SCH_1):GND
AM79    GND VSS<761> @BASEBOARD_FAB2_LIB.BASEBOARD_FAB2(SCH_1):GND
AM83    GND VSS<760> @BASEBOARD_FAB2_LIB.BASEBOARD_FAB2(SCH_1):GND
 AN2    GND VSS<759> @BASEBOARD_FAB2_LIB.BASEBOARD_FAB2(SCH_1):GND
 AN6    GND VSS<758> @BASEBOARD_FAB2_LIB.BASEBOARD_FAB2(SCH_1):GND
AN28    GND VSS<757> @BASEBOARD_FAB2_LIB.BASEBOARD_FAB2(SCH_1):GND
AN58    GND VSS<756> @BASEBOARD_FAB2_LIB.BASEBOARD_FAB2(SCH_1):GND
AN78    GND VSS<755> @BASEBOARD_FAB2_LIB.BASEBOARD_FAB2(SCH_1):GND
 AP5    GND VSS<754> @BASEBOARD_FAB2_LIB.BASEBOARD_FAB2(SCH_1):GND
 AP9    GND VSS<753> @BASEBOARD_FAB2_LIB.BASEBOARD_FAB2(SCH_1):GND
AP13    GND VSS<752> @BASEBOARD_FAB2_LIB.BASEBOARD_FAB2(SCH_1):GND
AP19    GND VSS<751> @BASEBOARD_FAB2_LIB.BASEBOARD_FAB2(SCH_1):GND
AP31    GND VSS<750> @BASEBOARD_FAB2_LIB.BASEBOARD_FAB2(SCH_1):GND
AP59    GND VSS<749> @BASEBOARD_FAB2_LIB.BASEBOARD_FAB2(SCH_1):GND
AP63    GND VSS<748> @BASEBOARD_FAB2_LIB.BASEBOARD_FAB2(SCH_1):GND
AP65    GND VSS<747> @BASEBOARD_FAB2_LIB.BASEBOARD_FAB2(SCH_1):GND
AP67    GND VSS<746> @BASEBOARD_FAB2_LIB.BASEBOARD_FAB2(SCH_1):GND
AP69    GND VSS<745> @BASEBOARD_FAB2_LIB.BASEBOARD_FAB2(SCH_1):GND
AP73    GND VSS<744> @BASEBOARD_FAB2_LIB.BASEBOARD_FAB2(SCH_1):GND
AP75    GND VSS<743> @BASEBOARD_FAB2_LIB.BASEBOARD_FAB2(SCH_1):GND
AP81    GND VSS<742> @BASEBOARD_FAB2_LIB.BASEBOARD_FAB2(SCH_1):GND
AP83    GND VSS<741> @BASEBOARD_FAB2_LIB.BASEBOARD_FAB2(SCH_1):GND
AP85    GND VSS<740> @BASEBOARD_FAB2_LIB.BASEBOARD_FAB2(SCH_1):GND
AR10    GND VSS<739> @BASEBOARD_FAB2_LIB.BASEBOARD_FAB2(SCH_1):GND
AR24    GND VSS<738> @BASEBOARD_FAB2_LIB.BASEBOARD_FAB2(SCH_1):GND
AR30    GND VSS<737> @BASEBOARD_FAB2_LIB.BASEBOARD_FAB2(SCH_1):GND
AR60    GND VSS<736> @BASEBOARD_FAB2_LIB.BASEBOARD_FAB2(SCH_1):GND
AR72    GND VSS<735> @BASEBOARD_FAB2_LIB.BASEBOARD_FAB2(SCH_1):GND
AR78    GND VSS<734> @BASEBOARD_FAB2_LIB.BASEBOARD_FAB2(SCH_1):GND
AC48    GND VSS<733> @BASEBOARD_FAB2_LIB.BASEBOARD_FAB2(SCH_1):GND
 P63    GND VSS<732> @BASEBOARD_FAB2_LIB.BASEBOARD_FAB2(SCH_1):GND
AT15    GND VSS<731> @BASEBOARD_FAB2_LIB.BASEBOARD_FAB2(SCH_1):GND
AT17    GND VSS<730> @BASEBOARD_FAB2_LIB.BASEBOARD_FAB2(SCH_1):GND
AT21    GND VSS<729> @BASEBOARD_FAB2_LIB.BASEBOARD_FAB2(SCH_1):GND
AT27    GND VSS<728> @BASEBOARD_FAB2_LIB.BASEBOARD_FAB2(SCH_1):GND
AT61    GND VSS<727> @BASEBOARD_FAB2_LIB.BASEBOARD_FAB2(SCH_1):GND
AT63    GND VSS<726> @BASEBOARD_FAB2_LIB.BASEBOARD_FAB2(SCH_1):GND
AT69    GND VSS<725> @BASEBOARD_FAB2_LIB.BASEBOARD_FAB2(SCH_1):GND
AT73    GND VSS<724> @BASEBOARD_FAB2_LIB.BASEBOARD_FAB2(SCH_1):GND
AT77    GND VSS<723> @BASEBOARD_FAB2_LIB.BASEBOARD_FAB2(SCH_1):GND
AT83    GND VSS<722> @BASEBOARD_FAB2_LIB.BASEBOARD_FAB2(SCH_1):GND
AT85    GND VSS<721> @BASEBOARD_FAB2_LIB.BASEBOARD_FAB2(SCH_1):GND
 AU2    GND VSS<720> @BASEBOARD_FAB2_LIB.BASEBOARD_FAB2(SCH_1):GND
 AU6    GND VSS<719> @BASEBOARD_FAB2_LIB.BASEBOARD_FAB2(SCH_1):GND
AU26    GND VSS<718> @BASEBOARD_FAB2_LIB.BASEBOARD_FAB2(SCH_1):GND
AU28    GND VSS<717> @BASEBOARD_FAB2_LIB.BASEBOARD_FAB2(SCH_1):GND
AU62    GND VSS<716> @BASEBOARD_FAB2_LIB.BASEBOARD_FAB2(SCH_1):GND
AU64    GND VSS<715> @BASEBOARD_FAB2_LIB.BASEBOARD_FAB2(SCH_1):GND
AU68    GND VSS<714> @BASEBOARD_FAB2_LIB.BASEBOARD_FAB2(SCH_1):GND
AU74    GND VSS<713> @BASEBOARD_FAB2_LIB.BASEBOARD_FAB2(SCH_1):GND
AU76    GND VSS<712> @BASEBOARD_FAB2_LIB.BASEBOARD_FAB2(SCH_1):GND
AU78    GND VSS<711> @BASEBOARD_FAB2_LIB.BASEBOARD_FAB2(SCH_1):GND
AU80    GND VSS<710> @BASEBOARD_FAB2_LIB.BASEBOARD_FAB2(SCH_1):GND
AU84    GND VSS<709> @BASEBOARD_FAB2_LIB.BASEBOARD_FAB2(SCH_1):GND
AU86    GND VSS<708> @BASEBOARD_FAB2_LIB.BASEBOARD_FAB2(SCH_1):GND
 AV1    GND VSS<707> @BASEBOARD_FAB2_LIB.BASEBOARD_FAB2(SCH_1):GND
 AV3    GND VSS<706> @BASEBOARD_FAB2_LIB.BASEBOARD_FAB2(SCH_1):GND
 AV7    GND VSS<705> @BASEBOARD_FAB2_LIB.BASEBOARD_FAB2(SCH_1):GND
AV11    GND VSS<704> @BASEBOARD_FAB2_LIB.BASEBOARD_FAB2(SCH_1):GND
AV13    GND VSS<703> @BASEBOARD_FAB2_LIB.BASEBOARD_FAB2(SCH_1):GND
AV19    GND VSS<702> @BASEBOARD_FAB2_LIB.BASEBOARD_FAB2(SCH_1):GND
AV23    GND VSS<701> @BASEBOARD_FAB2_LIB.BASEBOARD_FAB2(SCH_1):GND
AV25    GND VSS<700> @BASEBOARD_FAB2_LIB.BASEBOARD_FAB2(SCH_1):GND
AV63    GND VSS<699> @BASEBOARD_FAB2_LIB.BASEBOARD_FAB2(SCH_1):GND
AV65    GND VSS<698> @BASEBOARD_FAB2_LIB.BASEBOARD_FAB2(SCH_1):GND
AV67    GND VSS<697> @BASEBOARD_FAB2_LIB.BASEBOARD_FAB2(SCH_1):GND
AV75    GND VSS<696> @BASEBOARD_FAB2_LIB.BASEBOARD_FAB2(SCH_1):GND
AV83    GND VSS<695> @BASEBOARD_FAB2_LIB.BASEBOARD_FAB2(SCH_1):GND
 AW2    GND VSS<694> @BASEBOARD_FAB2_LIB.BASEBOARD_FAB2(SCH_1):GND
AW10    GND VSS<693> @BASEBOARD_FAB2_LIB.BASEBOARD_FAB2(SCH_1):GND
AW62    GND VSS<692> @BASEBOARD_FAB2_LIB.BASEBOARD_FAB2(SCH_1):GND
AW66    GND VSS<691> @BASEBOARD_FAB2_LIB.BASEBOARD_FAB2(SCH_1):GND
AW68    GND VSS<690> @BASEBOARD_FAB2_LIB.BASEBOARD_FAB2(SCH_1):GND
AW70    GND VSS<689> @BASEBOARD_FAB2_LIB.BASEBOARD_FAB2(SCH_1):GND
AW72    GND VSS<688> @BASEBOARD_FAB2_LIB.BASEBOARD_FAB2(SCH_1):GND
AW74    GND VSS<687> @BASEBOARD_FAB2_LIB.BASEBOARD_FAB2(SCH_1):GND
AW78    GND VSS<686> @BASEBOARD_FAB2_LIB.BASEBOARD_FAB2(SCH_1):GND
AW82    GND VSS<685> @BASEBOARD_FAB2_LIB.BASEBOARD_FAB2(SCH_1):GND
AW84    GND VSS<684> @BASEBOARD_FAB2_LIB.BASEBOARD_FAB2(SCH_1):GND
 AY5    GND VSS<683> @BASEBOARD_FAB2_LIB.BASEBOARD_FAB2(SCH_1):GND
AY15    GND VSS<682> @BASEBOARD_FAB2_LIB.BASEBOARD_FAB2(SCH_1):GND
AY17    GND VSS<681> @BASEBOARD_FAB2_LIB.BASEBOARD_FAB2(SCH_1):GND
AY21    GND VSS<680> @BASEBOARD_FAB2_LIB.BASEBOARD_FAB2(SCH_1):GND
AY23    GND VSS<679> @BASEBOARD_FAB2_LIB.BASEBOARD_FAB2(SCH_1):GND
AY25    GND VSS<678> @BASEBOARD_FAB2_LIB.BASEBOARD_FAB2(SCH_1):GND
AY63    GND VSS<677> @BASEBOARD_FAB2_LIB.BASEBOARD_FAB2(SCH_1):GND
AY79    GND VSS<676> @BASEBOARD_FAB2_LIB.BASEBOARD_FAB2(SCH_1):GND
AY81    GND VSS<675> @BASEBOARD_FAB2_LIB.BASEBOARD_FAB2(SCH_1):GND
 BA2    GND VSS<674> @BASEBOARD_FAB2_LIB.BASEBOARD_FAB2(SCH_1):GND
 BA6    GND VSS<673> @BASEBOARD_FAB2_LIB.BASEBOARD_FAB2(SCH_1):GND
BA12    GND VSS<672> @BASEBOARD_FAB2_LIB.BASEBOARD_FAB2(SCH_1):GND
BA62    GND VSS<671> @BASEBOARD_FAB2_LIB.BASEBOARD_FAB2(SCH_1):GND
BA68    GND VSS<670> @BASEBOARD_FAB2_LIB.BASEBOARD_FAB2(SCH_1):GND
BA74    GND VSS<669> @BASEBOARD_FAB2_LIB.BASEBOARD_FAB2(SCH_1):GND
BA80    GND VSS<668> @BASEBOARD_FAB2_LIB.BASEBOARD_FAB2(SCH_1):GND
BA84    GND VSS<667> @BASEBOARD_FAB2_LIB.BASEBOARD_FAB2(SCH_1):GND
BB19    GND VSS<666> @BASEBOARD_FAB2_LIB.BASEBOARD_FAB2(SCH_1):GND
BB23    GND VSS<665> @BASEBOARD_FAB2_LIB.BASEBOARD_FAB2(SCH_1):GND
BB63    GND VSS<664> @BASEBOARD_FAB2_LIB.BASEBOARD_FAB2(SCH_1):GND
BB69    GND VSS<663> @BASEBOARD_FAB2_LIB.BASEBOARD_FAB2(SCH_1):GND
BB73    GND VSS<662> @BASEBOARD_FAB2_LIB.BASEBOARD_FAB2(SCH_1):GND
BB75    GND VSS<661> @BASEBOARD_FAB2_LIB.BASEBOARD_FAB2(SCH_1):GND
BB77    GND VSS<660> @BASEBOARD_FAB2_LIB.BASEBOARD_FAB2(SCH_1):GND
BB79    GND VSS<659> @BASEBOARD_FAB2_LIB.BASEBOARD_FAB2(SCH_1):GND
BB81    GND VSS<658> @BASEBOARD_FAB2_LIB.BASEBOARD_FAB2(SCH_1):GND
BB83    GND VSS<657> @BASEBOARD_FAB2_LIB.BASEBOARD_FAB2(SCH_1):GND
 BC4    GND VSS<656> @BASEBOARD_FAB2_LIB.BASEBOARD_FAB2(SCH_1):GND
 BC8    GND VSS<655> @BASEBOARD_FAB2_LIB.BASEBOARD_FAB2(SCH_1):GND
BC12    GND VSS<654> @BASEBOARD_FAB2_LIB.BASEBOARD_FAB2(SCH_1):GND
BC16    GND VSS<653> @BASEBOARD_FAB2_LIB.BASEBOARD_FAB2(SCH_1):GND
BC70    GND VSS<652> @BASEBOARD_FAB2_LIB.BASEBOARD_FAB2(SCH_1):GND
BC72    GND VSS<651> @BASEBOARD_FAB2_LIB.BASEBOARD_FAB2(SCH_1):GND
BC74    GND VSS<650> @BASEBOARD_FAB2_LIB.BASEBOARD_FAB2(SCH_1):GND
BC76    GND VSS<649> @BASEBOARD_FAB2_LIB.BASEBOARD_FAB2(SCH_1):GND
BC78    GND VSS<648> @BASEBOARD_FAB2_LIB.BASEBOARD_FAB2(SCH_1):GND
BC80    GND VSS<647> @BASEBOARD_FAB2_LIB.BASEBOARD_FAB2(SCH_1):GND
BC82    GND VSS<646> @BASEBOARD_FAB2_LIB.BASEBOARD_FAB2(SCH_1):GND
 BD5    GND VSS<645> @BASEBOARD_FAB2_LIB.BASEBOARD_FAB2(SCH_1):GND
BD11    GND VSS<644> @BASEBOARD_FAB2_LIB.BASEBOARD_FAB2(SCH_1):GND
BD15    GND VSS<643> @BASEBOARD_FAB2_LIB.BASEBOARD_FAB2(SCH_1):GND
BD21    GND VSS<642> @BASEBOARD_FAB2_LIB.BASEBOARD_FAB2(SCH_1):GND
BD27    GND VSS<641> @BASEBOARD_FAB2_LIB.BASEBOARD_FAB2(SCH_1):GND
BD63    GND VSS<640> @BASEBOARD_FAB2_LIB.BASEBOARD_FAB2(SCH_1):GND
BD71    GND VSS<639> @BASEBOARD_FAB2_LIB.BASEBOARD_FAB2(SCH_1):GND
 BE4    GND VSS<638> @BASEBOARD_FAB2_LIB.BASEBOARD_FAB2(SCH_1):GND
 BE6    GND VSS<637> @BASEBOARD_FAB2_LIB.BASEBOARD_FAB2(SCH_1):GND
 BE8    GND VSS<636> @BASEBOARD_FAB2_LIB.BASEBOARD_FAB2(SCH_1):GND
BE10    GND VSS<635> @BASEBOARD_FAB2_LIB.BASEBOARD_FAB2(SCH_1):GND
BE26    GND VSS<634> @BASEBOARD_FAB2_LIB.BASEBOARD_FAB2(SCH_1):GND
BE64    GND VSS<633> @BASEBOARD_FAB2_LIB.BASEBOARD_FAB2(SCH_1):GND
BE66    GND VSS<632> @BASEBOARD_FAB2_LIB.BASEBOARD_FAB2(SCH_1):GND
BE68    GND VSS<631> @BASEBOARD_FAB2_LIB.BASEBOARD_FAB2(SCH_1):GND
BE70    GND VSS<630> @BASEBOARD_FAB2_LIB.BASEBOARD_FAB2(SCH_1):GND
 BF9    GND VSS<629> @BASEBOARD_FAB2_LIB.BASEBOARD_FAB2(SCH_1):GND
BF15    GND VSS<628> @BASEBOARD_FAB2_LIB.BASEBOARD_FAB2(SCH_1):GND
BF17    GND VSS<627> @BASEBOARD_FAB2_LIB.BASEBOARD_FAB2(SCH_1):GND
BF19    GND VSS<626> @BASEBOARD_FAB2_LIB.BASEBOARD_FAB2(SCH_1):GND
BF25    GND VSS<625> @BASEBOARD_FAB2_LIB.BASEBOARD_FAB2(SCH_1):GND
BF63    GND VSS<624> @BASEBOARD_FAB2_LIB.BASEBOARD_FAB2(SCH_1):GND
BF65    GND VSS<623> @BASEBOARD_FAB2_LIB.BASEBOARD_FAB2(SCH_1):GND
BF67    GND VSS<622> @BASEBOARD_FAB2_LIB.BASEBOARD_FAB2(SCH_1):GND
BF69    GND VSS<621> @BASEBOARD_FAB2_LIB.BASEBOARD_FAB2(SCH_1):GND
BF71    GND VSS<620> @BASEBOARD_FAB2_LIB.BASEBOARD_FAB2(SCH_1):GND
 BG6    GND VSS<619> @BASEBOARD_FAB2_LIB.BASEBOARD_FAB2(SCH_1):GND
 BG8    GND VSS<618> @BASEBOARD_FAB2_LIB.BASEBOARD_FAB2(SCH_1):GND
BG10    GND VSS<617> @BASEBOARD_FAB2_LIB.BASEBOARD_FAB2(SCH_1):GND
BG22    GND VSS<616> @BASEBOARD_FAB2_LIB.BASEBOARD_FAB2(SCH_1):GND
BG24    GND VSS<615> @BASEBOARD_FAB2_LIB.BASEBOARD_FAB2(SCH_1):GND
BG72    GND VSS<614> @BASEBOARD_FAB2_LIB.BASEBOARD_FAB2(SCH_1):GND


DRAWING: @BASEBOARD_FAB2_LIB.BASEBOARD_FAB2(SCH_1):PAGE41 

SKX_EXT_B_BGA1-IC,TBD  I283  U5D1
BG74    GND VSS<613> @BASEBOARD_FAB2_LIB.BASEBOARD_FAB2(SCH_1):GND
BG76    GND VSS<612> @BASEBOARD_FAB2_LIB.BASEBOARD_FAB2(SCH_1):GND
BG78    GND VSS<611> @BASEBOARD_FAB2_LIB.BASEBOARD_FAB2(SCH_1):GND
BG80    GND VSS<610> @BASEBOARD_FAB2_LIB.BASEBOARD_FAB2(SCH_1):GND
BG82    GND VSS<609> @BASEBOARD_FAB2_LIB.BASEBOARD_FAB2(SCH_1):GND
 BH7    GND VSS<608> @BASEBOARD_FAB2_LIB.BASEBOARD_FAB2(SCH_1):GND
 BH9    GND VSS<607> @BASEBOARD_FAB2_LIB.BASEBOARD_FAB2(SCH_1):GND
BH11    GND VSS<606> @BASEBOARD_FAB2_LIB.BASEBOARD_FAB2(SCH_1):GND
BH15    GND VSS<605> @BASEBOARD_FAB2_LIB.BASEBOARD_FAB2(SCH_1):GND
BH21    GND VSS<604> @BASEBOARD_FAB2_LIB.BASEBOARD_FAB2(SCH_1):GND
 BJ4    GND VSS<603> @BASEBOARD_FAB2_LIB.BASEBOARD_FAB2(SCH_1):GND
 BJ6    GND VSS<602> @BASEBOARD_FAB2_LIB.BASEBOARD_FAB2(SCH_1):GND
 BK3    GND VSS<601> @BASEBOARD_FAB2_LIB.BASEBOARD_FAB2(SCH_1):GND
 BK7    GND VSS<600> @BASEBOARD_FAB2_LIB.BASEBOARD_FAB2(SCH_1):GND
BK11    GND VSS<599> @BASEBOARD_FAB2_LIB.BASEBOARD_FAB2(SCH_1):GND
BK19    GND VSS<598> @BASEBOARD_FAB2_LIB.BASEBOARD_FAB2(SCH_1):GND
 BL6    GND VSS<597> @BASEBOARD_FAB2_LIB.BASEBOARD_FAB2(SCH_1):GND
BL10    GND VSS<596> @BASEBOARD_FAB2_LIB.BASEBOARD_FAB2(SCH_1):GND
BL12    GND VSS<595> @BASEBOARD_FAB2_LIB.BASEBOARD_FAB2(SCH_1):GND
 P61    GND VSS<594> @BASEBOARD_FAB2_LIB.BASEBOARD_FAB2(SCH_1):GND
BL22    GND VSS<593> @BASEBOARD_FAB2_LIB.BASEBOARD_FAB2(SCH_1):GND
BL24    GND VSS<592> @BASEBOARD_FAB2_LIB.BASEBOARD_FAB2(SCH_1):GND
BL64    GND VSS<591> @BASEBOARD_FAB2_LIB.BASEBOARD_FAB2(SCH_1):GND
BL66    GND VSS<590> @BASEBOARD_FAB2_LIB.BASEBOARD_FAB2(SCH_1):GND
BL68    GND VSS<589> @BASEBOARD_FAB2_LIB.BASEBOARD_FAB2(SCH_1):GND
BL70    GND VSS<588> @BASEBOARD_FAB2_LIB.BASEBOARD_FAB2(SCH_1):GND
BL72    GND VSS<587> @BASEBOARD_FAB2_LIB.BASEBOARD_FAB2(SCH_1):GND
BL74    GND VSS<586> @BASEBOARD_FAB2_LIB.BASEBOARD_FAB2(SCH_1):GND
BL76    GND VSS<585> @BASEBOARD_FAB2_LIB.BASEBOARD_FAB2(SCH_1):GND
BL78    GND VSS<584> @BASEBOARD_FAB2_LIB.BASEBOARD_FAB2(SCH_1):GND
BL80    GND VSS<583> @BASEBOARD_FAB2_LIB.BASEBOARD_FAB2(SCH_1):GND
BL82    GND VSS<582> @BASEBOARD_FAB2_LIB.BASEBOARD_FAB2(SCH_1):GND
 BM9    GND VSS<581> @BASEBOARD_FAB2_LIB.BASEBOARD_FAB2(SCH_1):GND
BM13    GND VSS<580> @BASEBOARD_FAB2_LIB.BASEBOARD_FAB2(SCH_1):GND
BM15    GND VSS<579> @BASEBOARD_FAB2_LIB.BASEBOARD_FAB2(SCH_1):GND
 P59    GND VSS<578> @BASEBOARD_FAB2_LIB.BASEBOARD_FAB2(SCH_1):GND
BM25    GND VSS<577> @BASEBOARD_FAB2_LIB.BASEBOARD_FAB2(SCH_1):GND
 BN6    GND VSS<576> @BASEBOARD_FAB2_LIB.BASEBOARD_FAB2(SCH_1):GND
BN10    GND VSS<575> @BASEBOARD_FAB2_LIB.BASEBOARD_FAB2(SCH_1):GND
BN20    GND VSS<574> @BASEBOARD_FAB2_LIB.BASEBOARD_FAB2(SCH_1):GND
BN26    GND VSS<573> @BASEBOARD_FAB2_LIB.BASEBOARD_FAB2(SCH_1):GND
 BP3    GND VSS<572> @BASEBOARD_FAB2_LIB.BASEBOARD_FAB2(SCH_1):GND
BP27    GND VSS<571> @BASEBOARD_FAB2_LIB.BASEBOARD_FAB2(SCH_1):GND
 BR6    GND VSS<570> @BASEBOARD_FAB2_LIB.BASEBOARD_FAB2(SCH_1):GND
BR10    GND VSS<569> @BASEBOARD_FAB2_LIB.BASEBOARD_FAB2(SCH_1):GND
BR16    GND VSS<568> @BASEBOARD_FAB2_LIB.BASEBOARD_FAB2(SCH_1):GND
 P57    GND VSS<567> @BASEBOARD_FAB2_LIB.BASEBOARD_FAB2(SCH_1):GND
BR64    GND VSS<566> @BASEBOARD_FAB2_LIB.BASEBOARD_FAB2(SCH_1):GND
BR66    GND VSS<565> @BASEBOARD_FAB2_LIB.BASEBOARD_FAB2(SCH_1):GND
BR68    GND VSS<564> @BASEBOARD_FAB2_LIB.BASEBOARD_FAB2(SCH_1):GND
BR70    GND VSS<563> @BASEBOARD_FAB2_LIB.BASEBOARD_FAB2(SCH_1):GND
BR72    GND VSS<562> @BASEBOARD_FAB2_LIB.BASEBOARD_FAB2(SCH_1):GND
BR74    GND VSS<561> @BASEBOARD_FAB2_LIB.BASEBOARD_FAB2(SCH_1):GND
BR76    GND VSS<560> @BASEBOARD_FAB2_LIB.BASEBOARD_FAB2(SCH_1):GND
BR78    GND VSS<559> @BASEBOARD_FAB2_LIB.BASEBOARD_FAB2(SCH_1):GND
BR80    GND VSS<558> @BASEBOARD_FAB2_LIB.BASEBOARD_FAB2(SCH_1):GND
BR82    GND VSS<557> @BASEBOARD_FAB2_LIB.BASEBOARD_FAB2(SCH_1):GND
 BT3    GND VSS<556> @BASEBOARD_FAB2_LIB.BASEBOARD_FAB2(SCH_1):GND
 BT5    GND VSS<555> @BASEBOARD_FAB2_LIB.BASEBOARD_FAB2(SCH_1):GND
BT21    GND VSS<554> @BASEBOARD_FAB2_LIB.BASEBOARD_FAB2(SCH_1):GND
BT23    GND VSS<553> @BASEBOARD_FAB2_LIB.BASEBOARD_FAB2(SCH_1):GND
BT25    GND VSS<552> @BASEBOARD_FAB2_LIB.BASEBOARD_FAB2(SCH_1):GND
 BU8    GND VSS<551> @BASEBOARD_FAB2_LIB.BASEBOARD_FAB2(SCH_1):GND
 BV5    GND VSS<550> @BASEBOARD_FAB2_LIB.BASEBOARD_FAB2(SCH_1):GND
BU10    GND VSS<549> @BASEBOARD_FAB2_LIB.BASEBOARD_FAB2(SCH_1):GND
BV17    GND VSS<548> @BASEBOARD_FAB2_LIB.BASEBOARD_FAB2(SCH_1):GND
BV25    GND VSS<547> @BASEBOARD_FAB2_LIB.BASEBOARD_FAB2(SCH_1):GND
 BW6    GND VSS<546> @BASEBOARD_FAB2_LIB.BASEBOARD_FAB2(SCH_1):GND
 P55    GND VSS<545> @BASEBOARD_FAB2_LIB.BASEBOARD_FAB2(SCH_1):GND
BW12    GND VSS<544> @BASEBOARD_FAB2_LIB.BASEBOARD_FAB2(SCH_1):GND
BW14    GND VSS<543> @BASEBOARD_FAB2_LIB.BASEBOARD_FAB2(SCH_1):GND
BW16    GND VSS<542> @BASEBOARD_FAB2_LIB.BASEBOARD_FAB2(SCH_1):GND
BW18    GND VSS<541> @BASEBOARD_FAB2_LIB.BASEBOARD_FAB2(SCH_1):GND
BW26    GND VSS<540> @BASEBOARD_FAB2_LIB.BASEBOARD_FAB2(SCH_1):GND
BW72    GND VSS<539> @BASEBOARD_FAB2_LIB.BASEBOARD_FAB2(SCH_1):GND
BW74    GND VSS<538> @BASEBOARD_FAB2_LIB.BASEBOARD_FAB2(SCH_1):GND
BW76    GND VSS<537> @BASEBOARD_FAB2_LIB.BASEBOARD_FAB2(SCH_1):GND
BW78    GND VSS<536> @BASEBOARD_FAB2_LIB.BASEBOARD_FAB2(SCH_1):GND
BW80    GND VSS<535> @BASEBOARD_FAB2_LIB.BASEBOARD_FAB2(SCH_1):GND
BW82    GND VSS<534> @BASEBOARD_FAB2_LIB.BASEBOARD_FAB2(SCH_1):GND
BY11    GND VSS<533> @BASEBOARD_FAB2_LIB.BASEBOARD_FAB2(SCH_1):GND
BY13    GND VSS<532> @BASEBOARD_FAB2_LIB.BASEBOARD_FAB2(SCH_1):GND
BY23    GND VSS<531> @BASEBOARD_FAB2_LIB.BASEBOARD_FAB2(SCH_1):GND
BY63    GND VSS<530> @BASEBOARD_FAB2_LIB.BASEBOARD_FAB2(SCH_1):GND
BY65    GND VSS<529> @BASEBOARD_FAB2_LIB.BASEBOARD_FAB2(SCH_1):GND
BY67    GND VSS<528> @BASEBOARD_FAB2_LIB.BASEBOARD_FAB2(SCH_1):GND
BY69    GND VSS<527> @BASEBOARD_FAB2_LIB.BASEBOARD_FAB2(SCH_1):GND
BY71    GND VSS<526> @BASEBOARD_FAB2_LIB.BASEBOARD_FAB2(SCH_1):GND
 CA2    GND VSS<525> @BASEBOARD_FAB2_LIB.BASEBOARD_FAB2(SCH_1):GND
 CA6    GND VSS<524> @BASEBOARD_FAB2_LIB.BASEBOARD_FAB2(SCH_1):GND
 CA8    GND VSS<523> @BASEBOARD_FAB2_LIB.BASEBOARD_FAB2(SCH_1):GND
CA10    GND VSS<522> @BASEBOARD_FAB2_LIB.BASEBOARD_FAB2(SCH_1):GND
CA14    GND VSS<521> @BASEBOARD_FAB2_LIB.BASEBOARD_FAB2(SCH_1):GND
CA18    GND VSS<520> @BASEBOARD_FAB2_LIB.BASEBOARD_FAB2(SCH_1):GND
CA26    GND VSS<519> @BASEBOARD_FAB2_LIB.BASEBOARD_FAB2(SCH_1):GND
CA64    GND VSS<518> @BASEBOARD_FAB2_LIB.BASEBOARD_FAB2(SCH_1):GND
CA66    GND VSS<517> @BASEBOARD_FAB2_LIB.BASEBOARD_FAB2(SCH_1):GND
CA68    GND VSS<516> @BASEBOARD_FAB2_LIB.BASEBOARD_FAB2(SCH_1):GND
CA70    GND VSS<515> @BASEBOARD_FAB2_LIB.BASEBOARD_FAB2(SCH_1):GND
 CB7    GND VSS<514> @BASEBOARD_FAB2_LIB.BASEBOARD_FAB2(SCH_1):GND
 CB9    GND VSS<513> @BASEBOARD_FAB2_LIB.BASEBOARD_FAB2(SCH_1):GND
CB27    GND VSS<512> @BASEBOARD_FAB2_LIB.BASEBOARD_FAB2(SCH_1):GND
CB63    GND VSS<511> @BASEBOARD_FAB2_LIB.BASEBOARD_FAB2(SCH_1):GND
CB71    GND VSS<510> @BASEBOARD_FAB2_LIB.BASEBOARD_FAB2(SCH_1):GND
 CC4    GND VSS<509> @BASEBOARD_FAB2_LIB.BASEBOARD_FAB2(SCH_1):GND
CC16    GND VSS<508> @BASEBOARD_FAB2_LIB.BASEBOARD_FAB2(SCH_1):GND
CC18    GND VSS<507> @BASEBOARD_FAB2_LIB.BASEBOARD_FAB2(SCH_1):GND
CC24    GND VSS<506> @BASEBOARD_FAB2_LIB.BASEBOARD_FAB2(SCH_1):GND
CC64    GND VSS<505> @BASEBOARD_FAB2_LIB.BASEBOARD_FAB2(SCH_1):GND
CC72    GND VSS<504> @BASEBOARD_FAB2_LIB.BASEBOARD_FAB2(SCH_1):GND
CC74    GND VSS<503> @BASEBOARD_FAB2_LIB.BASEBOARD_FAB2(SCH_1):GND
CC76    GND VSS<502> @BASEBOARD_FAB2_LIB.BASEBOARD_FAB2(SCH_1):GND
CC78    GND VSS<501> @BASEBOARD_FAB2_LIB.BASEBOARD_FAB2(SCH_1):GND
CC80    GND VSS<500> @BASEBOARD_FAB2_LIB.BASEBOARD_FAB2(SCH_1):GND
CC82    GND VSS<499> @BASEBOARD_FAB2_LIB.BASEBOARD_FAB2(SCH_1):GND
 CD5    GND VSS<498> @BASEBOARD_FAB2_LIB.BASEBOARD_FAB2(SCH_1):GND
CD13    GND VSS<497> @BASEBOARD_FAB2_LIB.BASEBOARD_FAB2(SCH_1):GND
CD63    GND VSS<496> @BASEBOARD_FAB2_LIB.BASEBOARD_FAB2(SCH_1):GND
CD73    GND VSS<495> @BASEBOARD_FAB2_LIB.BASEBOARD_FAB2(SCH_1):GND
CD75    GND VSS<494> @BASEBOARD_FAB2_LIB.BASEBOARD_FAB2(SCH_1):GND
CD77    GND VSS<493> @BASEBOARD_FAB2_LIB.BASEBOARD_FAB2(SCH_1):GND
CD79    GND VSS<492> @BASEBOARD_FAB2_LIB.BASEBOARD_FAB2(SCH_1):GND
CD81    GND VSS<491> @BASEBOARD_FAB2_LIB.BASEBOARD_FAB2(SCH_1):GND
CE10    GND VSS<490> @BASEBOARD_FAB2_LIB.BASEBOARD_FAB2(SCH_1):GND
CE14    GND VSS<489> @BASEBOARD_FAB2_LIB.BASEBOARD_FAB2(SCH_1):GND
CE20    GND VSS<488> @BASEBOARD_FAB2_LIB.BASEBOARD_FAB2(SCH_1):GND
CE26    GND VSS<487> @BASEBOARD_FAB2_LIB.BASEBOARD_FAB2(SCH_1):GND
CE62    GND VSS<486> @BASEBOARD_FAB2_LIB.BASEBOARD_FAB2(SCH_1):GND
CE70    GND VSS<485> @BASEBOARD_FAB2_LIB.BASEBOARD_FAB2(SCH_1):GND
CE82    GND VSS<484> @BASEBOARD_FAB2_LIB.BASEBOARD_FAB2(SCH_1):GND
 P53    GND VSS<483> @BASEBOARD_FAB2_LIB.BASEBOARD_FAB2(SCH_1):GND
 CF9    GND VSS<482> @BASEBOARD_FAB2_LIB.BASEBOARD_FAB2(SCH_1):GND
CF63    GND VSS<481> @BASEBOARD_FAB2_LIB.BASEBOARD_FAB2(SCH_1):GND
CF69    GND VSS<480> @BASEBOARD_FAB2_LIB.BASEBOARD_FAB2(SCH_1):GND
CF71    GND VSS<479> @BASEBOARD_FAB2_LIB.BASEBOARD_FAB2(SCH_1):GND
CF77    GND VSS<478> @BASEBOARD_FAB2_LIB.BASEBOARD_FAB2(SCH_1):GND
CF83    GND VSS<477> @BASEBOARD_FAB2_LIB.BASEBOARD_FAB2(SCH_1):GND
 P51    GND VSS<476> @BASEBOARD_FAB2_LIB.BASEBOARD_FAB2(SCH_1):GND
CG18    GND VSS<475> @BASEBOARD_FAB2_LIB.BASEBOARD_FAB2(SCH_1):GND
CG22    GND VSS<474> @BASEBOARD_FAB2_LIB.BASEBOARD_FAB2(SCH_1):GND
CG62    GND VSS<473> @BASEBOARD_FAB2_LIB.BASEBOARD_FAB2(SCH_1):GND
CG68    GND VSS<472> @BASEBOARD_FAB2_LIB.BASEBOARD_FAB2(SCH_1):GND
CG72    GND VSS<471> @BASEBOARD_FAB2_LIB.BASEBOARD_FAB2(SCH_1):GND
CG80    GND VSS<470> @BASEBOARD_FAB2_LIB.BASEBOARD_FAB2(SCH_1):GND
 CH1    GND VSS<469> @BASEBOARD_FAB2_LIB.BASEBOARD_FAB2(SCH_1):GND
 CH3    GND VSS<468> @BASEBOARD_FAB2_LIB.BASEBOARD_FAB2(SCH_1):GND
CH15    GND VSS<467> @BASEBOARD_FAB2_LIB.BASEBOARD_FAB2(SCH_1):GND
CH19    GND VSS<466> @BASEBOARD_FAB2_LIB.BASEBOARD_FAB2(SCH_1):GND
CH63    GND VSS<465> @BASEBOARD_FAB2_LIB.BASEBOARD_FAB2(SCH_1):GND
CH67    GND VSS<464> @BASEBOARD_FAB2_LIB.BASEBOARD_FAB2(SCH_1):GND
CH73    GND VSS<463> @BASEBOARD_FAB2_LIB.BASEBOARD_FAB2(SCH_1):GND
CH79    GND VSS<462> @BASEBOARD_FAB2_LIB.BASEBOARD_FAB2(SCH_1):GND
CH81    GND VSS<461> @BASEBOARD_FAB2_LIB.BASEBOARD_FAB2(SCH_1):GND
CH83    GND VSS<460> @BASEBOARD_FAB2_LIB.BASEBOARD_FAB2(SCH_1):GND
 CJ2    GND VSS<459> @BASEBOARD_FAB2_LIB.BASEBOARD_FAB2(SCH_1):GND
 CJ6    GND VSS<458> @BASEBOARD_FAB2_LIB.BASEBOARD_FAB2(SCH_1):GND
 CJ8    GND VSS<457> @BASEBOARD_FAB2_LIB.BASEBOARD_FAB2(SCH_1):GND
CJ10    GND VSS<456> @BASEBOARD_FAB2_LIB.BASEBOARD_FAB2(SCH_1):GND
CJ12    GND VSS<455> @BASEBOARD_FAB2_LIB.BASEBOARD_FAB2(SCH_1):GND
 P49    GND VSS<454> @BASEBOARD_FAB2_LIB.BASEBOARD_FAB2(SCH_1):GND

SKX_EXT_B_BGA1-IC,TBD  I284  U5D1
 P47    GND VSS<453> @BASEBOARD_FAB2_LIB.BASEBOARD_FAB2(SCH_1):GND
CJ62    GND VSS<452> @BASEBOARD_FAB2_LIB.BASEBOARD_FAB2(SCH_1):GND
CJ74    GND VSS<451> @BASEBOARD_FAB2_LIB.BASEBOARD_FAB2(SCH_1):GND
CJ76    GND VSS<450> @BASEBOARD_FAB2_LIB.BASEBOARD_FAB2(SCH_1):GND
CJ78    GND VSS<449> @BASEBOARD_FAB2_LIB.BASEBOARD_FAB2(SCH_1):GND
CJ82    GND VSS<448> @BASEBOARD_FAB2_LIB.BASEBOARD_FAB2(SCH_1):GND
CJ84    GND VSS<447> @BASEBOARD_FAB2_LIB.BASEBOARD_FAB2(SCH_1):GND
CJ86    GND VSS<446> @BASEBOARD_FAB2_LIB.BASEBOARD_FAB2(SCH_1):GND
CK11    GND VSS<445> @BASEBOARD_FAB2_LIB.BASEBOARD_FAB2(SCH_1):GND
CK15    GND VSS<444> @BASEBOARD_FAB2_LIB.BASEBOARD_FAB2(SCH_1):GND
CK21    GND VSS<443> @BASEBOARD_FAB2_LIB.BASEBOARD_FAB2(SCH_1):GND
CK27    GND VSS<442> @BASEBOARD_FAB2_LIB.BASEBOARD_FAB2(SCH_1):GND
CK63    GND VSS<441> @BASEBOARD_FAB2_LIB.BASEBOARD_FAB2(SCH_1):GND
CK65    GND VSS<440> @BASEBOARD_FAB2_LIB.BASEBOARD_FAB2(SCH_1):GND
CK67    GND VSS<439> @BASEBOARD_FAB2_LIB.BASEBOARD_FAB2(SCH_1):GND
CK69    GND VSS<438> @BASEBOARD_FAB2_LIB.BASEBOARD_FAB2(SCH_1):GND
CK71    GND VSS<437> @BASEBOARD_FAB2_LIB.BASEBOARD_FAB2(SCH_1):GND
CK73    GND VSS<436> @BASEBOARD_FAB2_LIB.BASEBOARD_FAB2(SCH_1):GND
CK75    GND VSS<435> @BASEBOARD_FAB2_LIB.BASEBOARD_FAB2(SCH_1):GND
CK83    GND VSS<434> @BASEBOARD_FAB2_LIB.BASEBOARD_FAB2(SCH_1):GND
CK85    GND VSS<433> @BASEBOARD_FAB2_LIB.BASEBOARD_FAB2(SCH_1):GND
 CL8    GND VSS<432> @BASEBOARD_FAB2_LIB.BASEBOARD_FAB2(SCH_1):GND
CL14    GND VSS<431> @BASEBOARD_FAB2_LIB.BASEBOARD_FAB2(SCH_1):GND
CL18    GND VSS<430> @BASEBOARD_FAB2_LIB.BASEBOARD_FAB2(SCH_1):GND
 P45    GND VSS<429> @BASEBOARD_FAB2_LIB.BASEBOARD_FAB2(SCH_1):GND
 H63    GND VSS<428> @BASEBOARD_FAB2_LIB.BASEBOARD_FAB2(SCH_1):GND
CL62    GND VSS<427> @BASEBOARD_FAB2_LIB.BASEBOARD_FAB2(SCH_1):GND
CL64    GND VSS<426> @BASEBOARD_FAB2_LIB.BASEBOARD_FAB2(SCH_1):GND
CL66    GND VSS<425> @BASEBOARD_FAB2_LIB.BASEBOARD_FAB2(SCH_1):GND
CL74    GND VSS<424> @BASEBOARD_FAB2_LIB.BASEBOARD_FAB2(SCH_1):GND
CL76    GND VSS<423> @BASEBOARD_FAB2_LIB.BASEBOARD_FAB2(SCH_1):GND
CL78    GND VSS<422> @BASEBOARD_FAB2_LIB.BASEBOARD_FAB2(SCH_1):GND
CL80    GND VSS<421> @BASEBOARD_FAB2_LIB.BASEBOARD_FAB2(SCH_1):GND
CM19    GND VSS<420> @BASEBOARD_FAB2_LIB.BASEBOARD_FAB2(SCH_1):GND
CM29    GND VSS<419> @BASEBOARD_FAB2_LIB.BASEBOARD_FAB2(SCH_1):GND
 CM5    GND VSS<418> @BASEBOARD_FAB2_LIB.BASEBOARD_FAB2(SCH_1):GND
CM31    GND VSS<417> @BASEBOARD_FAB2_LIB.BASEBOARD_FAB2(SCH_1):GND
CM61    GND VSS<416> @BASEBOARD_FAB2_LIB.BASEBOARD_FAB2(SCH_1):GND
CM63    GND VSS<415> @BASEBOARD_FAB2_LIB.BASEBOARD_FAB2(SCH_1):GND
CM67    GND VSS<414> @BASEBOARD_FAB2_LIB.BASEBOARD_FAB2(SCH_1):GND
CM73    GND VSS<413> @BASEBOARD_FAB2_LIB.BASEBOARD_FAB2(SCH_1):GND
CM77    GND VSS<412> @BASEBOARD_FAB2_LIB.BASEBOARD_FAB2(SCH_1):GND
CM83    GND VSS<411> @BASEBOARD_FAB2_LIB.BASEBOARD_FAB2(SCH_1):GND
CM85    GND VSS<410> @BASEBOARD_FAB2_LIB.BASEBOARD_FAB2(SCH_1):GND
 CN2    GND VSS<409> @BASEBOARD_FAB2_LIB.BASEBOARD_FAB2(SCH_1):GND
CN12    GND VSS<408> @BASEBOARD_FAB2_LIB.BASEBOARD_FAB2(SCH_1):GND
 H61    GND VSS<407> @BASEBOARD_FAB2_LIB.BASEBOARD_FAB2(SCH_1):GND
CN26    GND VSS<406> @BASEBOARD_FAB2_LIB.BASEBOARD_FAB2(SCH_1):GND
CN32    GND VSS<405> @BASEBOARD_FAB2_LIB.BASEBOARD_FAB2(SCH_1):GND
CN60    GND VSS<404> @BASEBOARD_FAB2_LIB.BASEBOARD_FAB2(SCH_1):GND
CN62    GND VSS<403> @BASEBOARD_FAB2_LIB.BASEBOARD_FAB2(SCH_1):GND
CN68    GND VSS<402> @BASEBOARD_FAB2_LIB.BASEBOARD_FAB2(SCH_1):GND
CN78    GND VSS<401> @BASEBOARD_FAB2_LIB.BASEBOARD_FAB2(SCH_1):GND
 CP1    GND VSS<400> @BASEBOARD_FAB2_LIB.BASEBOARD_FAB2(SCH_1):GND
 H59    GND VSS<399> @BASEBOARD_FAB2_LIB.BASEBOARD_FAB2(SCH_1):GND
CP25    GND VSS<398> @BASEBOARD_FAB2_LIB.BASEBOARD_FAB2(SCH_1):GND
CP59    GND VSS<397> @BASEBOARD_FAB2_LIB.BASEBOARD_FAB2(SCH_1):GND
CP69    GND VSS<396> @BASEBOARD_FAB2_LIB.BASEBOARD_FAB2(SCH_1):GND
CP73    GND VSS<395> @BASEBOARD_FAB2_LIB.BASEBOARD_FAB2(SCH_1):GND
CP75    GND VSS<394> @BASEBOARD_FAB2_LIB.BASEBOARD_FAB2(SCH_1):GND
CP81    GND VSS<393> @BASEBOARD_FAB2_LIB.BASEBOARD_FAB2(SCH_1):GND
CP83    GND VSS<392> @BASEBOARD_FAB2_LIB.BASEBOARD_FAB2(SCH_1):GND
 CR6    GND VSS<391> @BASEBOARD_FAB2_LIB.BASEBOARD_FAB2(SCH_1):GND
CR10    GND VSS<390> @BASEBOARD_FAB2_LIB.BASEBOARD_FAB2(SCH_1):GND
CR22    GND VSS<389> @BASEBOARD_FAB2_LIB.BASEBOARD_FAB2(SCH_1):GND
CR24    GND VSS<388> @BASEBOARD_FAB2_LIB.BASEBOARD_FAB2(SCH_1):GND
CR32    GND VSS<387> @BASEBOARD_FAB2_LIB.BASEBOARD_FAB2(SCH_1):GND
CR58    GND VSS<386> @BASEBOARD_FAB2_LIB.BASEBOARD_FAB2(SCH_1):GND
CR62    GND VSS<385> @BASEBOARD_FAB2_LIB.BASEBOARD_FAB2(SCH_1):GND
CR64    GND VSS<384> @BASEBOARD_FAB2_LIB.BASEBOARD_FAB2(SCH_1):GND
CR66    GND VSS<383> @BASEBOARD_FAB2_LIB.BASEBOARD_FAB2(SCH_1):GND
CR68    GND VSS<382> @BASEBOARD_FAB2_LIB.BASEBOARD_FAB2(SCH_1):GND
CR78    GND VSS<381> @BASEBOARD_FAB2_LIB.BASEBOARD_FAB2(SCH_1):GND
CR86    GND VSS<380> @BASEBOARD_FAB2_LIB.BASEBOARD_FAB2(SCH_1):GND
 H57    GND VSS<379> @BASEBOARD_FAB2_LIB.BASEBOARD_FAB2(SCH_1):GND
CT13    GND VSS<378> @BASEBOARD_FAB2_LIB.BASEBOARD_FAB2(SCH_1):GND
CT19    GND VSS<377> @BASEBOARD_FAB2_LIB.BASEBOARD_FAB2(SCH_1):GND
CT27    GND VSS<376> @BASEBOARD_FAB2_LIB.BASEBOARD_FAB2(SCH_1):GND
CT29    GND VSS<375> @BASEBOARD_FAB2_LIB.BASEBOARD_FAB2(SCH_1):GND
CT33    GND VSS<374> @BASEBOARD_FAB2_LIB.BASEBOARD_FAB2(SCH_1):GND
CT35    GND VSS<373> @BASEBOARD_FAB2_LIB.BASEBOARD_FAB2(SCH_1):GND
CT57    GND VSS<372> @BASEBOARD_FAB2_LIB.BASEBOARD_FAB2(SCH_1):GND
CT73    GND VSS<371> @BASEBOARD_FAB2_LIB.BASEBOARD_FAB2(SCH_1):GND
CT79    GND VSS<370> @BASEBOARD_FAB2_LIB.BASEBOARD_FAB2(SCH_1):GND
CT83    GND VSS<369> @BASEBOARD_FAB2_LIB.BASEBOARD_FAB2(SCH_1):GND
CT85    GND VSS<368> @BASEBOARD_FAB2_LIB.BASEBOARD_FAB2(SCH_1):GND
 CU4    GND VSS<367> @BASEBOARD_FAB2_LIB.BASEBOARD_FAB2(SCH_1):GND
CU22    GND VSS<366> @BASEBOARD_FAB2_LIB.BASEBOARD_FAB2(SCH_1):GND
CU28    GND VSS<365> @BASEBOARD_FAB2_LIB.BASEBOARD_FAB2(SCH_1):GND
CU30    GND VSS<364> @BASEBOARD_FAB2_LIB.BASEBOARD_FAB2(SCH_1):GND
CU34    GND VSS<363> @BASEBOARD_FAB2_LIB.BASEBOARD_FAB2(SCH_1):GND
CU36    GND VSS<362> @BASEBOARD_FAB2_LIB.BASEBOARD_FAB2(SCH_1):GND
CU56    GND VSS<361> @BASEBOARD_FAB2_LIB.BASEBOARD_FAB2(SCH_1):GND
CU62    GND VSS<360> @BASEBOARD_FAB2_LIB.BASEBOARD_FAB2(SCH_1):GND
CU68    GND VSS<359> @BASEBOARD_FAB2_LIB.BASEBOARD_FAB2(SCH_1):GND
CU76    GND VSS<358> @BASEBOARD_FAB2_LIB.BASEBOARD_FAB2(SCH_1):GND
CU78    GND VSS<357> @BASEBOARD_FAB2_LIB.BASEBOARD_FAB2(SCH_1):GND
CU80    GND VSS<356> @BASEBOARD_FAB2_LIB.BASEBOARD_FAB2(SCH_1):GND
CU82    GND VSS<355> @BASEBOARD_FAB2_LIB.BASEBOARD_FAB2(SCH_1):GND
CU86    GND VSS<354> @BASEBOARD_FAB2_LIB.BASEBOARD_FAB2(SCH_1):GND
 CV1    GND VSS<353> @BASEBOARD_FAB2_LIB.BASEBOARD_FAB2(SCH_1):GND
 H55    GND VSS<352> @BASEBOARD_FAB2_LIB.BASEBOARD_FAB2(SCH_1):GND
CV17    GND VSS<351> @BASEBOARD_FAB2_LIB.BASEBOARD_FAB2(SCH_1):GND
CV25    GND VSS<350> @BASEBOARD_FAB2_LIB.BASEBOARD_FAB2(SCH_1):GND
CV27    GND VSS<349> @BASEBOARD_FAB2_LIB.BASEBOARD_FAB2(SCH_1):GND
CV31    GND VSS<348> @BASEBOARD_FAB2_LIB.BASEBOARD_FAB2(SCH_1):GND
CV33    GND VSS<347> @BASEBOARD_FAB2_LIB.BASEBOARD_FAB2(SCH_1):GND
CV37    GND VSS<346> @BASEBOARD_FAB2_LIB.BASEBOARD_FAB2(SCH_1):GND
CV39    GND VSS<345> @BASEBOARD_FAB2_LIB.BASEBOARD_FAB2(SCH_1):GND
CV41    GND VSS<344> @BASEBOARD_FAB2_LIB.BASEBOARD_FAB2(SCH_1):GND
CV53    GND VSS<343> @BASEBOARD_FAB2_LIB.BASEBOARD_FAB2(SCH_1):GND
CV55    GND VSS<342> @BASEBOARD_FAB2_LIB.BASEBOARD_FAB2(SCH_1):GND
CV63    GND VSS<341> @BASEBOARD_FAB2_LIB.BASEBOARD_FAB2(SCH_1):GND
CV67    GND VSS<340> @BASEBOARD_FAB2_LIB.BASEBOARD_FAB2(SCH_1):GND
CV73    GND VSS<339> @BASEBOARD_FAB2_LIB.BASEBOARD_FAB2(SCH_1):GND
CV79    GND VSS<338> @BASEBOARD_FAB2_LIB.BASEBOARD_FAB2(SCH_1):GND
CV81    GND VSS<337> @BASEBOARD_FAB2_LIB.BASEBOARD_FAB2(SCH_1):GND
CV83    GND VSS<336> @BASEBOARD_FAB2_LIB.BASEBOARD_FAB2(SCH_1):GND
CW12    GND VSS<335> @BASEBOARD_FAB2_LIB.BASEBOARD_FAB2(SCH_1):GND
CW26    GND VSS<334> @BASEBOARD_FAB2_LIB.BASEBOARD_FAB2(SCH_1):GND
CW32    GND VSS<333> @BASEBOARD_FAB2_LIB.BASEBOARD_FAB2(SCH_1):GND
CW38    GND VSS<332> @BASEBOARD_FAB2_LIB.BASEBOARD_FAB2(SCH_1):GND
CW40    GND VSS<331> @BASEBOARD_FAB2_LIB.BASEBOARD_FAB2(SCH_1):GND
CW42    GND VSS<330> @BASEBOARD_FAB2_LIB.BASEBOARD_FAB2(SCH_1):GND
CW52    GND VSS<329> @BASEBOARD_FAB2_LIB.BASEBOARD_FAB2(SCH_1):GND
CW54    GND VSS<328> @BASEBOARD_FAB2_LIB.BASEBOARD_FAB2(SCH_1):GND
CW64    GND VSS<327> @BASEBOARD_FAB2_LIB.BASEBOARD_FAB2(SCH_1):GND
CW66    GND VSS<326> @BASEBOARD_FAB2_LIB.BASEBOARD_FAB2(SCH_1):GND
CW68    GND VSS<325> @BASEBOARD_FAB2_LIB.BASEBOARD_FAB2(SCH_1):GND
CW74    GND VSS<324> @BASEBOARD_FAB2_LIB.BASEBOARD_FAB2(SCH_1):GND
CW78    GND VSS<323> @BASEBOARD_FAB2_LIB.BASEBOARD_FAB2(SCH_1):GND
CW82    GND VSS<322> @BASEBOARD_FAB2_LIB.BASEBOARD_FAB2(SCH_1):GND
 CY1    GND VSS<321> @BASEBOARD_FAB2_LIB.BASEBOARD_FAB2(SCH_1):GND
 CY9    GND VSS<320> @BASEBOARD_FAB2_LIB.BASEBOARD_FAB2(SCH_1):GND
CY13    GND VSS<319> @BASEBOARD_FAB2_LIB.BASEBOARD_FAB2(SCH_1):GND
CY15    GND VSS<318> @BASEBOARD_FAB2_LIB.BASEBOARD_FAB2(SCH_1):GND
CY21    GND VSS<317> @BASEBOARD_FAB2_LIB.BASEBOARD_FAB2(SCH_1):GND
CY41    GND VSS<316> @BASEBOARD_FAB2_LIB.BASEBOARD_FAB2(SCH_1):GND
CY45    GND VSS<315> @BASEBOARD_FAB2_LIB.BASEBOARD_FAB2(SCH_1):GND
CY51    GND VSS<314> @BASEBOARD_FAB2_LIB.BASEBOARD_FAB2(SCH_1):GND
CY59    GND VSS<313> @BASEBOARD_FAB2_LIB.BASEBOARD_FAB2(SCH_1):GND
CY61    GND VSS<312> @BASEBOARD_FAB2_LIB.BASEBOARD_FAB2(SCH_1):GND
CY65    GND VSS<311> @BASEBOARD_FAB2_LIB.BASEBOARD_FAB2(SCH_1):GND
CY69    GND VSS<310> @BASEBOARD_FAB2_LIB.BASEBOARD_FAB2(SCH_1):GND
CY75    GND VSS<309> @BASEBOARD_FAB2_LIB.BASEBOARD_FAB2(SCH_1):GND
CY77    GND VSS<308> @BASEBOARD_FAB2_LIB.BASEBOARD_FAB2(SCH_1):GND
CY83    GND VSS<307> @BASEBOARD_FAB2_LIB.BASEBOARD_FAB2(SCH_1):GND
CY85    GND VSS<306> @BASEBOARD_FAB2_LIB.BASEBOARD_FAB2(SCH_1):GND
 DA6    GND VSS<305> @BASEBOARD_FAB2_LIB.BASEBOARD_FAB2(SCH_1):GND
 H53    GND VSS<304> @BASEBOARD_FAB2_LIB.BASEBOARD_FAB2(SCH_1):GND
DA18    GND VSS<303> @BASEBOARD_FAB2_LIB.BASEBOARD_FAB2(SCH_1):GND
DA26    GND VSS<302> @BASEBOARD_FAB2_LIB.BASEBOARD_FAB2(SCH_1):GND
DA28    GND VSS<301> @BASEBOARD_FAB2_LIB.BASEBOARD_FAB2(SCH_1):GND
DA30    GND VSS<300> @BASEBOARD_FAB2_LIB.BASEBOARD_FAB2(SCH_1):GND
DA32    GND VSS<299> @BASEBOARD_FAB2_LIB.BASEBOARD_FAB2(SCH_1):GND
DA34    GND VSS<298> @BASEBOARD_FAB2_LIB.BASEBOARD_FAB2(SCH_1):GND
DA36    GND VSS<297> @BASEBOARD_FAB2_LIB.BASEBOARD_FAB2(SCH_1):GND
DA38    GND VSS<296> @BASEBOARD_FAB2_LIB.BASEBOARD_FAB2(SCH_1):GND
DA44    GND VSS<295> @BASEBOARD_FAB2_LIB.BASEBOARD_FAB2(SCH_1):GND
DA46    GND VSS<294> @BASEBOARD_FAB2_LIB.BASEBOARD_FAB2(SCH_1):GND

SKX_EXT_B_BGA1-IC,TBD  I285  U5D1
DA48    GND VSS<293> @BASEBOARD_FAB2_LIB.BASEBOARD_FAB2(SCH_1):GND
DA50    GND VSS<292> @BASEBOARD_FAB2_LIB.BASEBOARD_FAB2(SCH_1):GND
DA64    GND VSS<291> @BASEBOARD_FAB2_LIB.BASEBOARD_FAB2(SCH_1):GND
DA70    GND VSS<290> @BASEBOARD_FAB2_LIB.BASEBOARD_FAB2(SCH_1):GND
DA74    GND VSS<289> @BASEBOARD_FAB2_LIB.BASEBOARD_FAB2(SCH_1):GND
DA76    GND VSS<288> @BASEBOARD_FAB2_LIB.BASEBOARD_FAB2(SCH_1):GND
DA78    GND VSS<287> @BASEBOARD_FAB2_LIB.BASEBOARD_FAB2(SCH_1):GND
DA80    GND VSS<286> @BASEBOARD_FAB2_LIB.BASEBOARD_FAB2(SCH_1):GND
 DB3    GND VSS<285> @BASEBOARD_FAB2_LIB.BASEBOARD_FAB2(SCH_1):GND
DB13    GND VSS<284> @BASEBOARD_FAB2_LIB.BASEBOARD_FAB2(SCH_1):GND
DB17    GND VSS<283> @BASEBOARD_FAB2_LIB.BASEBOARD_FAB2(SCH_1):GND
DB23    GND VSS<282> @BASEBOARD_FAB2_LIB.BASEBOARD_FAB2(SCH_1):GND
DB25    GND VSS<281> @BASEBOARD_FAB2_LIB.BASEBOARD_FAB2(SCH_1):GND
DB39    GND VSS<280> @BASEBOARD_FAB2_LIB.BASEBOARD_FAB2(SCH_1):GND
DB41    GND VSS<279> @BASEBOARD_FAB2_LIB.BASEBOARD_FAB2(SCH_1):GND
DB47    GND VSS<278> @BASEBOARD_FAB2_LIB.BASEBOARD_FAB2(SCH_1):GND
DB49    GND VSS<277> @BASEBOARD_FAB2_LIB.BASEBOARD_FAB2(SCH_1):GND
DB73    GND VSS<276> @BASEBOARD_FAB2_LIB.BASEBOARD_FAB2(SCH_1):GND
DB77    GND VSS<275> @BASEBOARD_FAB2_LIB.BASEBOARD_FAB2(SCH_1):GND
DB83    GND VSS<274> @BASEBOARD_FAB2_LIB.BASEBOARD_FAB2(SCH_1):GND
DB85    GND VSS<273> @BASEBOARD_FAB2_LIB.BASEBOARD_FAB2(SCH_1):GND
DC14    GND VSS<272> @BASEBOARD_FAB2_LIB.BASEBOARD_FAB2(SCH_1):GND
DC24    GND VSS<271> @BASEBOARD_FAB2_LIB.BASEBOARD_FAB2(SCH_1):GND
DC26    GND VSS<270> @BASEBOARD_FAB2_LIB.BASEBOARD_FAB2(SCH_1):GND
DC32    GND VSS<269> @BASEBOARD_FAB2_LIB.BASEBOARD_FAB2(SCH_1):GND
DC38    GND VSS<268> @BASEBOARD_FAB2_LIB.BASEBOARD_FAB2(SCH_1):GND
DC42    GND VSS<267> @BASEBOARD_FAB2_LIB.BASEBOARD_FAB2(SCH_1):GND
DC64    GND VSS<266> @BASEBOARD_FAB2_LIB.BASEBOARD_FAB2(SCH_1):GND
DC66    GND VSS<265> @BASEBOARD_FAB2_LIB.BASEBOARD_FAB2(SCH_1):GND
DC68    GND VSS<264> @BASEBOARD_FAB2_LIB.BASEBOARD_FAB2(SCH_1):GND
DC70    GND VSS<263> @BASEBOARD_FAB2_LIB.BASEBOARD_FAB2(SCH_1):GND
DC78    GND VSS<262> @BASEBOARD_FAB2_LIB.BASEBOARD_FAB2(SCH_1):GND
DC84    GND VSS<261> @BASEBOARD_FAB2_LIB.BASEBOARD_FAB2(SCH_1):GND
DC86    GND VSS<260> @BASEBOARD_FAB2_LIB.BASEBOARD_FAB2(SCH_1):GND
DD11    GND VSS<259> @BASEBOARD_FAB2_LIB.BASEBOARD_FAB2(SCH_1):GND
DD23    GND VSS<258> @BASEBOARD_FAB2_LIB.BASEBOARD_FAB2(SCH_1):GND
DD27    GND VSS<257> @BASEBOARD_FAB2_LIB.BASEBOARD_FAB2(SCH_1):GND
DD31    GND VSS<256> @BASEBOARD_FAB2_LIB.BASEBOARD_FAB2(SCH_1):GND
DD33    GND VSS<255> @BASEBOARD_FAB2_LIB.BASEBOARD_FAB2(SCH_1):GND
DD37    GND VSS<254> @BASEBOARD_FAB2_LIB.BASEBOARD_FAB2(SCH_1):GND
DD71    GND VSS<253> @BASEBOARD_FAB2_LIB.BASEBOARD_FAB2(SCH_1):GND
DD73    GND VSS<252> @BASEBOARD_FAB2_LIB.BASEBOARD_FAB2(SCH_1):GND
DD75    GND VSS<251> @BASEBOARD_FAB2_LIB.BASEBOARD_FAB2(SCH_1):GND
DD81    GND VSS<250> @BASEBOARD_FAB2_LIB.BASEBOARD_FAB2(SCH_1):GND
DD83    GND VSS<249> @BASEBOARD_FAB2_LIB.BASEBOARD_FAB2(SCH_1):GND
 DE6    GND VSS<248> @BASEBOARD_FAB2_LIB.BASEBOARD_FAB2(SCH_1):GND
 DE8    GND VSS<247> @BASEBOARD_FAB2_LIB.BASEBOARD_FAB2(SCH_1):GND
DE18    GND VSS<246> @BASEBOARD_FAB2_LIB.BASEBOARD_FAB2(SCH_1):GND
DE20    GND VSS<245> @BASEBOARD_FAB2_LIB.BASEBOARD_FAB2(SCH_1):GND
DE24    GND VSS<244> @BASEBOARD_FAB2_LIB.BASEBOARD_FAB2(SCH_1):GND
DE28    GND VSS<243> @BASEBOARD_FAB2_LIB.BASEBOARD_FAB2(SCH_1):GND
DE30    GND VSS<242> @BASEBOARD_FAB2_LIB.BASEBOARD_FAB2(SCH_1):GND
DE34    GND VSS<241> @BASEBOARD_FAB2_LIB.BASEBOARD_FAB2(SCH_1):GND
DE36    GND VSS<240> @BASEBOARD_FAB2_LIB.BASEBOARD_FAB2(SCH_1):GND
DE64    GND VSS<239> @BASEBOARD_FAB2_LIB.BASEBOARD_FAB2(SCH_1):GND
DE70    GND VSS<238> @BASEBOARD_FAB2_LIB.BASEBOARD_FAB2(SCH_1):GND
DE72    GND VSS<237> @BASEBOARD_FAB2_LIB.BASEBOARD_FAB2(SCH_1):GND
DE78    GND VSS<236> @BASEBOARD_FAB2_LIB.BASEBOARD_FAB2(SCH_1):GND
 DF5    GND VSS<235> @BASEBOARD_FAB2_LIB.BASEBOARD_FAB2(SCH_1):GND
 DF7    GND VSS<234> @BASEBOARD_FAB2_LIB.BASEBOARD_FAB2(SCH_1):GND
 H51    GND VSS<233> @BASEBOARD_FAB2_LIB.BASEBOARD_FAB2(SCH_1):GND
DF19    GND VSS<232> @BASEBOARD_FAB2_LIB.BASEBOARD_FAB2(SCH_1):GND
DF29    GND VSS<231> @BASEBOARD_FAB2_LIB.BASEBOARD_FAB2(SCH_1):GND
DF35    GND VSS<230> @BASEBOARD_FAB2_LIB.BASEBOARD_FAB2(SCH_1):GND
DF37    GND VSS<229> @BASEBOARD_FAB2_LIB.BASEBOARD_FAB2(SCH_1):GND
DF39    GND VSS<228> @BASEBOARD_FAB2_LIB.BASEBOARD_FAB2(SCH_1):GND
DF41    GND VSS<227> @BASEBOARD_FAB2_LIB.BASEBOARD_FAB2(SCH_1):GND
DF65    GND VSS<226> @BASEBOARD_FAB2_LIB.BASEBOARD_FAB2(SCH_1):GND
DF69    GND VSS<225> @BASEBOARD_FAB2_LIB.BASEBOARD_FAB2(SCH_1):GND
DF73    GND VSS<224> @BASEBOARD_FAB2_LIB.BASEBOARD_FAB2(SCH_1):GND
DF79    GND VSS<223> @BASEBOARD_FAB2_LIB.BASEBOARD_FAB2(SCH_1):GND
DF83    GND VSS<222> @BASEBOARD_FAB2_LIB.BASEBOARD_FAB2(SCH_1):GND
DF85    GND VSS<221> @BASEBOARD_FAB2_LIB.BASEBOARD_FAB2(SCH_1):GND
 DG2    GND VSS<220> @BASEBOARD_FAB2_LIB.BASEBOARD_FAB2(SCH_1):GND
 H49    GND VSS<219> @BASEBOARD_FAB2_LIB.BASEBOARD_FAB2(SCH_1):GND
DG14    GND VSS<218> @BASEBOARD_FAB2_LIB.BASEBOARD_FAB2(SCH_1):GND
DG16    GND VSS<217> @BASEBOARD_FAB2_LIB.BASEBOARD_FAB2(SCH_1):GND
DG24    GND VSS<216> @BASEBOARD_FAB2_LIB.BASEBOARD_FAB2(SCH_1):GND
DG66    GND VSS<215> @BASEBOARD_FAB2_LIB.BASEBOARD_FAB2(SCH_1):GND
DG68    GND VSS<214> @BASEBOARD_FAB2_LIB.BASEBOARD_FAB2(SCH_1):GND
DG76    GND VSS<213> @BASEBOARD_FAB2_LIB.BASEBOARD_FAB2(SCH_1):GND
DG78    GND VSS<212> @BASEBOARD_FAB2_LIB.BASEBOARD_FAB2(SCH_1):GND
DG80    GND VSS<211> @BASEBOARD_FAB2_LIB.BASEBOARD_FAB2(SCH_1):GND
DG82    GND VSS<210> @BASEBOARD_FAB2_LIB.BASEBOARD_FAB2(SCH_1):GND
DH13    GND VSS<209> @BASEBOARD_FAB2_LIB.BASEBOARD_FAB2(SCH_1):GND
DH15    GND VSS<208> @BASEBOARD_FAB2_LIB.BASEBOARD_FAB2(SCH_1):GND
DH23    GND VSS<207> @BASEBOARD_FAB2_LIB.BASEBOARD_FAB2(SCH_1):GND
DH25    GND VSS<206> @BASEBOARD_FAB2_LIB.BASEBOARD_FAB2(SCH_1):GND
DH27    GND VSS<205> @BASEBOARD_FAB2_LIB.BASEBOARD_FAB2(SCH_1):GND
DH29    GND VSS<204> @BASEBOARD_FAB2_LIB.BASEBOARD_FAB2(SCH_1):GND
DH31    GND VSS<203> @BASEBOARD_FAB2_LIB.BASEBOARD_FAB2(SCH_1):GND
DH33    GND VSS<202> @BASEBOARD_FAB2_LIB.BASEBOARD_FAB2(SCH_1):GND
DH35    GND VSS<201> @BASEBOARD_FAB2_LIB.BASEBOARD_FAB2(SCH_1):GND
DH37    GND VSS<200> @BASEBOARD_FAB2_LIB.BASEBOARD_FAB2(SCH_1):GND
DH41    GND VSS<199> @BASEBOARD_FAB2_LIB.BASEBOARD_FAB2(SCH_1):GND
DH67    GND VSS<198> @BASEBOARD_FAB2_LIB.BASEBOARD_FAB2(SCH_1):GND
DH71    GND VSS<197> @BASEBOARD_FAB2_LIB.BASEBOARD_FAB2(SCH_1):GND
DH73    GND VSS<196> @BASEBOARD_FAB2_LIB.BASEBOARD_FAB2(SCH_1):GND
DH79    GND VSS<195> @BASEBOARD_FAB2_LIB.BASEBOARD_FAB2(SCH_1):GND
DH81    GND VSS<194> @BASEBOARD_FAB2_LIB.BASEBOARD_FAB2(SCH_1):GND
DH83    GND VSS<193> @BASEBOARD_FAB2_LIB.BASEBOARD_FAB2(SCH_1):GND
 DJ2    GND VSS<192> @BASEBOARD_FAB2_LIB.BASEBOARD_FAB2(SCH_1):GND
DJ10    GND VSS<191> @BASEBOARD_FAB2_LIB.BASEBOARD_FAB2(SCH_1):GND
 H47    GND VSS<190> @BASEBOARD_FAB2_LIB.BASEBOARD_FAB2(SCH_1):GND
DJ22    GND VSS<189> @BASEBOARD_FAB2_LIB.BASEBOARD_FAB2(SCH_1):GND
DJ38    GND VSS<188> @BASEBOARD_FAB2_LIB.BASEBOARD_FAB2(SCH_1):GND
DJ42    GND VSS<187> @BASEBOARD_FAB2_LIB.BASEBOARD_FAB2(SCH_1):GND
DJ68    GND VSS<186> @BASEBOARD_FAB2_LIB.BASEBOARD_FAB2(SCH_1):GND
DJ74    GND VSS<185> @BASEBOARD_FAB2_LIB.BASEBOARD_FAB2(SCH_1):GND
DJ78    GND VSS<184> @BASEBOARD_FAB2_LIB.BASEBOARD_FAB2(SCH_1):GND
DJ82    GND VSS<183> @BASEBOARD_FAB2_LIB.BASEBOARD_FAB2(SCH_1):GND
DJ84    GND VSS<182> @BASEBOARD_FAB2_LIB.BASEBOARD_FAB2(SCH_1):GND
 DK7    GND VSS<181> @BASEBOARD_FAB2_LIB.BASEBOARD_FAB2(SCH_1):GND
DK23    GND VSS<180> @BASEBOARD_FAB2_LIB.BASEBOARD_FAB2(SCH_1):GND
DK29    GND VSS<179> @BASEBOARD_FAB2_LIB.BASEBOARD_FAB2(SCH_1):GND
DK35    GND VSS<178> @BASEBOARD_FAB2_LIB.BASEBOARD_FAB2(SCH_1):GND
DK39    GND VSS<177> @BASEBOARD_FAB2_LIB.BASEBOARD_FAB2(SCH_1):GND
DK41    GND VSS<176> @BASEBOARD_FAB2_LIB.BASEBOARD_FAB2(SCH_1):GND
DK73    GND VSS<175> @BASEBOARD_FAB2_LIB.BASEBOARD_FAB2(SCH_1):GND
DK75    GND VSS<174> @BASEBOARD_FAB2_LIB.BASEBOARD_FAB2(SCH_1):GND
DK77    GND VSS<173> @BASEBOARD_FAB2_LIB.BASEBOARD_FAB2(SCH_1):GND
DK83    GND VSS<172> @BASEBOARD_FAB2_LIB.BASEBOARD_FAB2(SCH_1):GND
DK85    GND VSS<171> @BASEBOARD_FAB2_LIB.BASEBOARD_FAB2(SCH_1):GND
DL16    GND VSS<170> @BASEBOARD_FAB2_LIB.BASEBOARD_FAB2(SCH_1):GND
DL18    GND VSS<169> @BASEBOARD_FAB2_LIB.BASEBOARD_FAB2(SCH_1):GND
 DL4    GND VSS<168> @BASEBOARD_FAB2_LIB.BASEBOARD_FAB2(SCH_1):GND
DL22    GND VSS<167> @BASEBOARD_FAB2_LIB.BASEBOARD_FAB2(SCH_1):GND
DL24    GND VSS<166> @BASEBOARD_FAB2_LIB.BASEBOARD_FAB2(SCH_1):GND
DL28    GND VSS<165> @BASEBOARD_FAB2_LIB.BASEBOARD_FAB2(SCH_1):GND
DL30    GND VSS<164> @BASEBOARD_FAB2_LIB.BASEBOARD_FAB2(SCH_1):GND
DL34    GND VSS<163> @BASEBOARD_FAB2_LIB.BASEBOARD_FAB2(SCH_1):GND
DL36    GND VSS<162> @BASEBOARD_FAB2_LIB.BASEBOARD_FAB2(SCH_1):GND
DL40    GND VSS<161> @BASEBOARD_FAB2_LIB.BASEBOARD_FAB2(SCH_1):GND
DL68    GND VSS<160> @BASEBOARD_FAB2_LIB.BASEBOARD_FAB2(SCH_1):GND
DL70    GND VSS<159> @BASEBOARD_FAB2_LIB.BASEBOARD_FAB2(SCH_1):GND
DL74    GND VSS<158> @BASEBOARD_FAB2_LIB.BASEBOARD_FAB2(SCH_1):GND
DL76    GND VSS<157> @BASEBOARD_FAB2_LIB.BASEBOARD_FAB2(SCH_1):GND
DL78    GND VSS<156> @BASEBOARD_FAB2_LIB.BASEBOARD_FAB2(SCH_1):GND
DL80    GND VSS<155> @BASEBOARD_FAB2_LIB.BASEBOARD_FAB2(SCH_1):GND
DM15    GND VSS<154> @BASEBOARD_FAB2_LIB.BASEBOARD_FAB2(SCH_1):GND
 H45    GND VSS<153> @BASEBOARD_FAB2_LIB.BASEBOARD_FAB2(SCH_1):GND
DM25    GND VSS<152> @BASEBOARD_FAB2_LIB.BASEBOARD_FAB2(SCH_1):GND
DM27    GND VSS<151> @BASEBOARD_FAB2_LIB.BASEBOARD_FAB2(SCH_1):GND
DM31    GND VSS<150> @BASEBOARD_FAB2_LIB.BASEBOARD_FAB2(SCH_1):GND
DM33    GND VSS<149> @BASEBOARD_FAB2_LIB.BASEBOARD_FAB2(SCH_1):GND
DM37    GND VSS<148> @BASEBOARD_FAB2_LIB.BASEBOARD_FAB2(SCH_1):GND
DM39    GND VSS<147> @BASEBOARD_FAB2_LIB.BASEBOARD_FAB2(SCH_1):GND
DM65    GND VSS<146> @BASEBOARD_FAB2_LIB.BASEBOARD_FAB2(SCH_1):GND
DM73    GND VSS<145> @BASEBOARD_FAB2_LIB.BASEBOARD_FAB2(SCH_1):GND
DM77    GND VSS<144> @BASEBOARD_FAB2_LIB.BASEBOARD_FAB2(SCH_1):GND
DM83    GND VSS<143> @BASEBOARD_FAB2_LIB.BASEBOARD_FAB2(SCH_1):GND
 DN2    GND VSS<142> @BASEBOARD_FAB2_LIB.BASEBOARD_FAB2(SCH_1):GND
BH17    GND VSS<141> @BASEBOARD_FAB2_LIB.BASEBOARD_FAB2(SCH_1):GND
DN12    GND VSS<140> @BASEBOARD_FAB2_LIB.BASEBOARD_FAB2(SCH_1):GND
DN22    GND VSS<139> @BASEBOARD_FAB2_LIB.BASEBOARD_FAB2(SCH_1):GND
DN26    GND VSS<138> @BASEBOARD_FAB2_LIB.BASEBOARD_FAB2(SCH_1):GND
DN32    GND VSS<137> @BASEBOARD_FAB2_LIB.BASEBOARD_FAB2(SCH_1):GND
DN38    GND VSS<136> @BASEBOARD_FAB2_LIB.BASEBOARD_FAB2(SCH_1):GND
DN68    GND VSS<135> @BASEBOARD_FAB2_LIB.BASEBOARD_FAB2(SCH_1):GND
DN72    GND VSS<134> @BASEBOARD_FAB2_LIB.BASEBOARD_FAB2(SCH_1):GND

SKX_EXT_B_BGA1-IC,TBD  I286  U5D1
DN78    GND VSS<133> @BASEBOARD_FAB2_LIB.BASEBOARD_FAB2(SCH_1):GND
DP67    GND VSS<132> @BASEBOARD_FAB2_LIB.BASEBOARD_FAB2(SCH_1):GND
DP69    GND VSS<131> @BASEBOARD_FAB2_LIB.BASEBOARD_FAB2(SCH_1):GND
DP71    GND VSS<130> @BASEBOARD_FAB2_LIB.BASEBOARD_FAB2(SCH_1):GND
DP81    GND VSS<129> @BASEBOARD_FAB2_LIB.BASEBOARD_FAB2(SCH_1):GND
DP83    GND VSS<128> @BASEBOARD_FAB2_LIB.BASEBOARD_FAB2(SCH_1):GND
BR26    GND VSS<127> @BASEBOARD_FAB2_LIB.BASEBOARD_FAB2(SCH_1):GND
 DR6    GND VSS<126> @BASEBOARD_FAB2_LIB.BASEBOARD_FAB2(SCH_1):GND
CA20    GND VSS<125> @BASEBOARD_FAB2_LIB.BASEBOARD_FAB2(SCH_1):GND
CL22    GND VSS<124> @BASEBOARD_FAB2_LIB.BASEBOARD_FAB2(SCH_1):GND
DR20    GND VSS<123> @BASEBOARD_FAB2_LIB.BASEBOARD_FAB2(SCH_1):GND
DR22    GND VSS<122> @BASEBOARD_FAB2_LIB.BASEBOARD_FAB2(SCH_1):GND
DR24    GND VSS<121> @BASEBOARD_FAB2_LIB.BASEBOARD_FAB2(SCH_1):GND
DR26    GND VSS<120> @BASEBOARD_FAB2_LIB.BASEBOARD_FAB2(SCH_1):GND
DR28    GND VSS<119> @BASEBOARD_FAB2_LIB.BASEBOARD_FAB2(SCH_1):GND
DR30    GND VSS<118> @BASEBOARD_FAB2_LIB.BASEBOARD_FAB2(SCH_1):GND
DR32    GND VSS<117> @BASEBOARD_FAB2_LIB.BASEBOARD_FAB2(SCH_1):GND
DR34    GND VSS<116> @BASEBOARD_FAB2_LIB.BASEBOARD_FAB2(SCH_1):GND
DR36    GND VSS<115> @BASEBOARD_FAB2_LIB.BASEBOARD_FAB2(SCH_1):GND
DR38    GND VSS<114> @BASEBOARD_FAB2_LIB.BASEBOARD_FAB2(SCH_1):GND
DR40    GND VSS<113> @BASEBOARD_FAB2_LIB.BASEBOARD_FAB2(SCH_1):GND
DR42    GND VSS<112> @BASEBOARD_FAB2_LIB.BASEBOARD_FAB2(SCH_1):GND
DR66    GND VSS<111> @BASEBOARD_FAB2_LIB.BASEBOARD_FAB2(SCH_1):GND
DR68    GND VSS<110> @BASEBOARD_FAB2_LIB.BASEBOARD_FAB2(SCH_1):GND
DR70    GND VSS<109> @BASEBOARD_FAB2_LIB.BASEBOARD_FAB2(SCH_1):GND
DR72    GND VSS<108> @BASEBOARD_FAB2_LIB.BASEBOARD_FAB2(SCH_1):GND
DR74    GND VSS<107> @BASEBOARD_FAB2_LIB.BASEBOARD_FAB2(SCH_1):GND
DR76    GND VSS<106> @BASEBOARD_FAB2_LIB.BASEBOARD_FAB2(SCH_1):GND
DR78    GND VSS<105> @BASEBOARD_FAB2_LIB.BASEBOARD_FAB2(SCH_1):GND
 DT3    GND VSS<104> @BASEBOARD_FAB2_LIB.BASEBOARD_FAB2(SCH_1):GND
DT17    GND VSS<103> @BASEBOARD_FAB2_LIB.BASEBOARD_FAB2(SCH_1):GND
DH21    GND VSS<102> @BASEBOARD_FAB2_LIB.BASEBOARD_FAB2(SCH_1):GND
DT65    GND VSS<101> @BASEBOARD_FAB2_LIB.BASEBOARD_FAB2(SCH_1):GND
DT69    GND VSS<100> @BASEBOARD_FAB2_LIB.BASEBOARD_FAB2(SCH_1):GND
DT79    GND VSS<99> @BASEBOARD_FAB2_LIB.BASEBOARD_FAB2(SCH_1):GND
DT83    GND VSS<98> @BASEBOARD_FAB2_LIB.BASEBOARD_FAB2(SCH_1):GND
DT85    GND VSS<97> @BASEBOARD_FAB2_LIB.BASEBOARD_FAB2(SCH_1):GND
DU10    GND VSS<96> @BASEBOARD_FAB2_LIB.BASEBOARD_FAB2(SCH_1):GND
DU14    GND VSS<95> @BASEBOARD_FAB2_LIB.BASEBOARD_FAB2(SCH_1):GND
CN14    GND VSS<94> @BASEBOARD_FAB2_LIB.BASEBOARD_FAB2(SCH_1):GND
DU22    GND VSS<93> @BASEBOARD_FAB2_LIB.BASEBOARD_FAB2(SCH_1):GND
DU26    GND VSS<92> @BASEBOARD_FAB2_LIB.BASEBOARD_FAB2(SCH_1):GND
DU32    GND VSS<91> @BASEBOARD_FAB2_LIB.BASEBOARD_FAB2(SCH_1):GND
DU38    GND VSS<90> @BASEBOARD_FAB2_LIB.BASEBOARD_FAB2(SCH_1):GND
DU70    GND VSS<89> @BASEBOARD_FAB2_LIB.BASEBOARD_FAB2(SCH_1):GND
DU72    GND VSS<88> @BASEBOARD_FAB2_LIB.BASEBOARD_FAB2(SCH_1):GND
DU78    GND VSS<87> @BASEBOARD_FAB2_LIB.BASEBOARD_FAB2(SCH_1):GND
DU80    GND VSS<86> @BASEBOARD_FAB2_LIB.BASEBOARD_FAB2(SCH_1):GND
DU82    GND VSS<85> @BASEBOARD_FAB2_LIB.BASEBOARD_FAB2(SCH_1):GND
DU84    GND VSS<84> @BASEBOARD_FAB2_LIB.BASEBOARD_FAB2(SCH_1):GND
DV21    GND VSS<83> @BASEBOARD_FAB2_LIB.BASEBOARD_FAB2(SCH_1):GND
DV25    GND VSS<82> @BASEBOARD_FAB2_LIB.BASEBOARD_FAB2(SCH_1):GND
DV27    GND VSS<81> @BASEBOARD_FAB2_LIB.BASEBOARD_FAB2(SCH_1):GND
DV31    GND VSS<80> @BASEBOARD_FAB2_LIB.BASEBOARD_FAB2(SCH_1):GND
DV33    GND VSS<79> @BASEBOARD_FAB2_LIB.BASEBOARD_FAB2(SCH_1):GND
DV37    GND VSS<78> @BASEBOARD_FAB2_LIB.BASEBOARD_FAB2(SCH_1):GND
DV39    GND VSS<77> @BASEBOARD_FAB2_LIB.BASEBOARD_FAB2(SCH_1):GND
DV73    GND VSS<76> @BASEBOARD_FAB2_LIB.BASEBOARD_FAB2(SCH_1):GND
DV77    GND VSS<75> @BASEBOARD_FAB2_LIB.BASEBOARD_FAB2(SCH_1):GND
DV81    GND VSS<74> @BASEBOARD_FAB2_LIB.BASEBOARD_FAB2(SCH_1):GND
DW12    GND VSS<73> @BASEBOARD_FAB2_LIB.BASEBOARD_FAB2(SCH_1):GND
DW20    GND VSS<72> @BASEBOARD_FAB2_LIB.BASEBOARD_FAB2(SCH_1):GND
DW24    GND VSS<71> @BASEBOARD_FAB2_LIB.BASEBOARD_FAB2(SCH_1):GND
DW28    GND VSS<70> @BASEBOARD_FAB2_LIB.BASEBOARD_FAB2(SCH_1):GND
DW30    GND VSS<69> @BASEBOARD_FAB2_LIB.BASEBOARD_FAB2(SCH_1):GND
DW34    GND VSS<68> @BASEBOARD_FAB2_LIB.BASEBOARD_FAB2(SCH_1):GND
DW36    GND VSS<67> @BASEBOARD_FAB2_LIB.BASEBOARD_FAB2(SCH_1):GND
DW40    GND VSS<66> @BASEBOARD_FAB2_LIB.BASEBOARD_FAB2(SCH_1):GND
DW64    GND VSS<65> @BASEBOARD_FAB2_LIB.BASEBOARD_FAB2(SCH_1):GND
DW66    GND VSS<64> @BASEBOARD_FAB2_LIB.BASEBOARD_FAB2(SCH_1):GND
DW68    GND VSS<63> @BASEBOARD_FAB2_LIB.BASEBOARD_FAB2(SCH_1):GND
DW70    GND VSS<62> @BASEBOARD_FAB2_LIB.BASEBOARD_FAB2(SCH_1):GND
DW72    GND VSS<61> @BASEBOARD_FAB2_LIB.BASEBOARD_FAB2(SCH_1):GND
DW74    GND VSS<60> @BASEBOARD_FAB2_LIB.BASEBOARD_FAB2(SCH_1):GND
DW76    GND VSS<59> @BASEBOARD_FAB2_LIB.BASEBOARD_FAB2(SCH_1):GND
 DW8    GND VSS<58> @BASEBOARD_FAB2_LIB.BASEBOARD_FAB2(SCH_1):GND
DW82    GND VSS<57> @BASEBOARD_FAB2_LIB.BASEBOARD_FAB2(SCH_1):GND
DW84    GND VSS<56> @BASEBOARD_FAB2_LIB.BASEBOARD_FAB2(SCH_1):GND
 DY5    GND VSS<55> @BASEBOARD_FAB2_LIB.BASEBOARD_FAB2(SCH_1):GND
DY19    GND VSS<54> @BASEBOARD_FAB2_LIB.BASEBOARD_FAB2(SCH_1):GND
DY23    GND VSS<53> @BASEBOARD_FAB2_LIB.BASEBOARD_FAB2(SCH_1):GND
DY29    GND VSS<52> @BASEBOARD_FAB2_LIB.BASEBOARD_FAB2(SCH_1):GND
DY35    GND VSS<51> @BASEBOARD_FAB2_LIB.BASEBOARD_FAB2(SCH_1):GND
DY41    GND VSS<50> @BASEBOARD_FAB2_LIB.BASEBOARD_FAB2(SCH_1):GND
DY71    GND VSS<49> @BASEBOARD_FAB2_LIB.BASEBOARD_FAB2(SCH_1):GND
DY75    GND VSS<48> @BASEBOARD_FAB2_LIB.BASEBOARD_FAB2(SCH_1):GND
 EA6    GND VSS<47> @BASEBOARD_FAB2_LIB.BASEBOARD_FAB2(SCH_1):GND
 J16    GND VSS<46> @BASEBOARD_FAB2_LIB.BASEBOARD_FAB2(SCH_1):GND
EA16    GND VSS<45> @BASEBOARD_FAB2_LIB.BASEBOARD_FAB2(SCH_1):GND
EA20    GND VSS<44> @BASEBOARD_FAB2_LIB.BASEBOARD_FAB2(SCH_1):GND
EA22    GND VSS<43> @BASEBOARD_FAB2_LIB.BASEBOARD_FAB2(SCH_1):GND
EA42    GND VSS<42> @BASEBOARD_FAB2_LIB.BASEBOARD_FAB2(SCH_1):GND
EA64    GND VSS<41> @BASEBOARD_FAB2_LIB.BASEBOARD_FAB2(SCH_1):GND
EA70    GND VSS<40> @BASEBOARD_FAB2_LIB.BASEBOARD_FAB2(SCH_1):GND
EA76    GND VSS<39> @BASEBOARD_FAB2_LIB.BASEBOARD_FAB2(SCH_1):GND
EA78    GND VSS<38> @BASEBOARD_FAB2_LIB.BASEBOARD_FAB2(SCH_1):GND
EA80    GND VSS<37> @BASEBOARD_FAB2_LIB.BASEBOARD_FAB2(SCH_1):GND
EA82    GND VSS<36> @BASEBOARD_FAB2_LIB.BASEBOARD_FAB2(SCH_1):GND
EB13    GND VSS<35> @BASEBOARD_FAB2_LIB.BASEBOARD_FAB2(SCH_1):GND
BR18    GND VSS<34> @BASEBOARD_FAB2_LIB.BASEBOARD_FAB2(SCH_1):GND
EB23    GND VSS<33> @BASEBOARD_FAB2_LIB.BASEBOARD_FAB2(SCH_1):GND
EB25    GND VSS<32> @BASEBOARD_FAB2_LIB.BASEBOARD_FAB2(SCH_1):GND
EB27    GND VSS<31> @BASEBOARD_FAB2_LIB.BASEBOARD_FAB2(SCH_1):GND
EB29    GND VSS<30> @BASEBOARD_FAB2_LIB.BASEBOARD_FAB2(SCH_1):GND
EB31    GND VSS<29> @BASEBOARD_FAB2_LIB.BASEBOARD_FAB2(SCH_1):GND
EB33    GND VSS<28> @BASEBOARD_FAB2_LIB.BASEBOARD_FAB2(SCH_1):GND
EB35    GND VSS<27> @BASEBOARD_FAB2_LIB.BASEBOARD_FAB2(SCH_1):GND
EB37    GND VSS<26> @BASEBOARD_FAB2_LIB.BASEBOARD_FAB2(SCH_1):GND
EB39    GND VSS<25> @BASEBOARD_FAB2_LIB.BASEBOARD_FAB2(SCH_1):GND
EB41    GND VSS<24> @BASEBOARD_FAB2_LIB.BASEBOARD_FAB2(SCH_1):GND
EB65    GND VSS<23> @BASEBOARD_FAB2_LIB.BASEBOARD_FAB2(SCH_1):GND
EB69    GND VSS<22> @BASEBOARD_FAB2_LIB.BASEBOARD_FAB2(SCH_1):GND
EC10    GND VSS<21> @BASEBOARD_FAB2_LIB.BASEBOARD_FAB2(SCH_1):GND
EC70    GND VSS<20> @BASEBOARD_FAB2_LIB.BASEBOARD_FAB2(SCH_1):GND
EC72    GND VSS<19> @BASEBOARD_FAB2_LIB.BASEBOARD_FAB2(SCH_1):GND
EC74    GND VSS<18> @BASEBOARD_FAB2_LIB.BASEBOARD_FAB2(SCH_1):GND
EC76    GND VSS<17> @BASEBOARD_FAB2_LIB.BASEBOARD_FAB2(SCH_1):GND
ED11    GND VSS<16> @BASEBOARD_FAB2_LIB.BASEBOARD_FAB2(SCH_1):GND
ED15    GND VSS<15> @BASEBOARD_FAB2_LIB.BASEBOARD_FAB2(SCH_1):GND
ED23    GND VSS<14> @BASEBOARD_FAB2_LIB.BASEBOARD_FAB2(SCH_1):GND
ED29    GND VSS<13> @BASEBOARD_FAB2_LIB.BASEBOARD_FAB2(SCH_1):GND
ED35    GND VSS<12> @BASEBOARD_FAB2_LIB.BASEBOARD_FAB2(SCH_1):GND
ED77    GND VSS<11> @BASEBOARD_FAB2_LIB.BASEBOARD_FAB2(SCH_1):GND
EE24    GND VSS<10> @BASEBOARD_FAB2_LIB.BASEBOARD_FAB2(SCH_1):GND
EE28    GND VSS<9> @BASEBOARD_FAB2_LIB.BASEBOARD_FAB2(SCH_1):GND
EE30    GND VSS<8> @BASEBOARD_FAB2_LIB.BASEBOARD_FAB2(SCH_1):GND
EE34    GND VSS<7> @BASEBOARD_FAB2_LIB.BASEBOARD_FAB2(SCH_1):GND
EE36    GND VSS<6> @BASEBOARD_FAB2_LIB.BASEBOARD_FAB2(SCH_1):GND
EE70    GND VSS<5> @BASEBOARD_FAB2_LIB.BASEBOARD_FAB2(SCH_1):GND
EE76    GND VSS<4> @BASEBOARD_FAB2_LIB.BASEBOARD_FAB2(SCH_1):GND
EE78    GND VSS<3> @BASEBOARD_FAB2_LIB.BASEBOARD_FAB2(SCH_1):GND
EF71    GND VSS<2> @BASEBOARD_FAB2_LIB.BASEBOARD_FAB2(SCH_1):GND
EF75    GND VSS<1> @BASEBOARD_FAB2_LIB.BASEBOARD_FAB2(SCH_1):GND
EF79    GND VSS<0> @BASEBOARD_FAB2_LIB.BASEBOARD_FAB2(SCH_1):GND


DRAWING: @BASEBOARD_FAB2_LIB.BASEBOARD_FAB2(SCH_1):PAGE42 

CAP_0805-47UF,4V,20%,X6S,C9533A  I10  C4P1
   1 PVCCIO_CPU0      A @BASEBOARD_FAB2_LIB.BASEBOARD_FAB2(SCH_1):PVCCIO_CPU0
   2    GND      B @BASEBOARD_FAB2_LIB.BASEBOARD_FAB2(SCH_1):GND

CAP_0805-47UF,4V,20%,X6S,C9533A  I12  C4P9
   1 PVCCIO_CPU0      A @BASEBOARD_FAB2_LIB.BASEBOARD_FAB2(SCH_1):PVCCIO_CPU0
   2    GND      B @BASEBOARD_FAB2_LIB.BASEBOARD_FAB2(SCH_1):GND

CAP_0805-47UF,4V,20%,X6S,C9533A  I17  C4P10
   1 PVCCIO_CPU0      A @BASEBOARD_FAB2_LIB.BASEBOARD_FAB2(SCH_1):PVCCIO_CPU0
   2    GND      B @BASEBOARD_FAB2_LIB.BASEBOARD_FAB2(SCH_1):GND

CAP_0805LF-22UF,4V,20%,X6S,C95A  I25  C5P7
   1 PVSA_CPU0      A @BASEBOARD_FAB2_LIB.BASEBOARD_FAB2(SCH_1):PVSA_CPU0
   2    GND      B @BASEBOARD_FAB2_LIB.BASEBOARD_FAB2(SCH_1):GND

CAP_0805-47UF,4V,20%,X6S,C9533A  I28  C5P23
   1 PVCCIN_CPU0      A @BASEBOARD_FAB2_LIB.BASEBOARD_FAB2(SCH_1):PVCCIN_CPU0
   2    GND      B @BASEBOARD_FAB2_LIB.BASEBOARD_FAB2(SCH_1):GND

CAP_0805-47UF,4V,20%,X6S,C9533A  I33  C5P24
   1 PVCCIN_CPU0      A @BASEBOARD_FAB2_LIB.BASEBOARD_FAB2(SCH_1):PVCCIN_CPU0
   2    GND      B @BASEBOARD_FAB2_LIB.BASEBOARD_FAB2(SCH_1):GND

CAP_0805-47UF,4V,20%,X6S,C9533A  I37  C5P25
   1 PVCCIN_CPU0      A @BASEBOARD_FAB2_LIB.BASEBOARD_FAB2(SCH_1):PVCCIN_CPU0
   2    GND      B @BASEBOARD_FAB2_LIB.BASEBOARD_FAB2(SCH_1):GND

CAP_0805-47UF,4V,20%,X6S,C9533A  I41  C5P14
   1 PVCCIN_CPU0      A @BASEBOARD_FAB2_LIB.BASEBOARD_FAB2(SCH_1):PVCCIN_CPU0
   2    GND      B @BASEBOARD_FAB2_LIB.BASEBOARD_FAB2(SCH_1):GND

CAP_0805-47UF,4V,20%,X6S,C9533A  I44  C5P27
   1 PVCCIN_CPU0      A @BASEBOARD_FAB2_LIB.BASEBOARD_FAB2(SCH_1):PVCCIN_CPU0
   2    GND      B @BASEBOARD_FAB2_LIB.BASEBOARD_FAB2(SCH_1):GND

CAP_0805-47UF,4V,20%,X6S,C9533A  I50  C5P33
   1 PVCCIN_CPU0      A @BASEBOARD_FAB2_LIB.BASEBOARD_FAB2(SCH_1):PVCCIN_CPU0
   2    GND      B @BASEBOARD_FAB2_LIB.BASEBOARD_FAB2(SCH_1):GND

CAP_0805-47UF,4V,20%,X6S,C9533A  I51  C5P35
   1 PVCCIN_CPU0      A @BASEBOARD_FAB2_LIB.BASEBOARD_FAB2(SCH_1):PVCCIN_CPU0
   2    GND      B @BASEBOARD_FAB2_LIB.BASEBOARD_FAB2(SCH_1):GND

CAP_0805-47UF,4V,20%,X6S,C9533A  I53  C5P32
   1 PVCCIN_CPU0      A @BASEBOARD_FAB2_LIB.BASEBOARD_FAB2(SCH_1):PVCCIN_CPU0
   2    GND      B @BASEBOARD_FAB2_LIB.BASEBOARD_FAB2(SCH_1):GND

CAP_0805-47UF,4V,20%,X6S,C9533A  I54  C5P34
   1 PVCCIN_CPU0      A @BASEBOARD_FAB2_LIB.BASEBOARD_FAB2(SCH_1):PVCCIN_CPU0
   2    GND      B @BASEBOARD_FAB2_LIB.BASEBOARD_FAB2(SCH_1):GND

CAP_0805-47UF,4V,20%,X6S,C9533A  I55  C5P22
   1 PVCCIN_CPU0      A @BASEBOARD_FAB2_LIB.BASEBOARD_FAB2(SCH_1):PVCCIN_CPU0
   2    GND      B @BASEBOARD_FAB2_LIB.BASEBOARD_FAB2(SCH_1):GND

CAP_0805-47UF,4V,20%,X6S,C9533A  I56  C5P26
   1 PVCCIN_CPU0      A @BASEBOARD_FAB2_LIB.BASEBOARD_FAB2(SCH_1):PVCCIN_CPU0
   2    GND      B @BASEBOARD_FAB2_LIB.BASEBOARD_FAB2(SCH_1):GND

CAP_0805-47UF,4V,20%,X6S,C9533A  I57  C5P40
   1 PVCCIN_CPU0      A @BASEBOARD_FAB2_LIB.BASEBOARD_FAB2(SCH_1):PVCCIN_CPU0
   2    GND      B @BASEBOARD_FAB2_LIB.BASEBOARD_FAB2(SCH_1):GND

CAP_0805-47UF,4V,20%,X6S,C9533A  I63  C5P37
   1 PVCCIN_CPU0      A @BASEBOARD_FAB2_LIB.BASEBOARD_FAB2(SCH_1):PVCCIN_CPU0
   2    GND      B @BASEBOARD_FAB2_LIB.BASEBOARD_FAB2(SCH_1):GND

CAP_0805-47UF,4V,20%,X6S,C9533A  I65  C5P36
   1 PVCCIN_CPU0      A @BASEBOARD_FAB2_LIB.BASEBOARD_FAB2(SCH_1):PVCCIN_CPU0
   2    GND      B @BASEBOARD_FAB2_LIB.BASEBOARD_FAB2(SCH_1):GND

CAP_A_0603V-22.0UF,4V,20%,X6S,A  I68  C6D8
   1 PVCCMCP_CPU0      A @BASEBOARD_FAB2_LIB.BASEBOARD_FAB2(SCH_1):PVCCMCP_CPU0
   2    GND      B @BASEBOARD_FAB2_LIB.BASEBOARD_FAB2(SCH_1):GND

CAP_A_0603V-22.0UF,4V,20%,X6S,A  I69  C5D38
   1 PVCCMCP_CPU0      A @BASEBOARD_FAB2_LIB.BASEBOARD_FAB2(SCH_1):PVCCMCP_CPU0
   2    GND      B @BASEBOARD_FAB2_LIB.BASEBOARD_FAB2(SCH_1):GND

CAP_A_0603V-22.0UF,4V,20%,X6S,A  I70  C5D37
   1 PVCCMCP_CPU0      A @BASEBOARD_FAB2_LIB.BASEBOARD_FAB2(SCH_1):PVCCMCP_CPU0
   2    GND      B @BASEBOARD_FAB2_LIB.BASEBOARD_FAB2(SCH_1):GND

CAP_A_0603V-22.0UF,4V,20%,X6S,A  I72  C6D7
   1 PVCCIO_CPU0      A @BASEBOARD_FAB2_LIB.BASEBOARD_FAB2(SCH_1):PVCCIO_CPU0
   2    GND      B @BASEBOARD_FAB2_LIB.BASEBOARD_FAB2(SCH_1):GND

CAP_A_0603V-22.0UF,4V,20%,X6S,A  I74  C6D4
   1 PVCCIO_CPU0      A @BASEBOARD_FAB2_LIB.BASEBOARD_FAB2(SCH_1):PVCCIO_CPU0
   2    GND      B @BASEBOARD_FAB2_LIB.BASEBOARD_FAB2(SCH_1):GND

CAP_A_0603V-22.0UF,4V,20%,X6S,A  I75  C6D5
   1 PVCCMCP_CPU0      A @BASEBOARD_FAB2_LIB.BASEBOARD_FAB2(SCH_1):PVCCMCP_CPU0
   2    GND      B @BASEBOARD_FAB2_LIB.BASEBOARD_FAB2(SCH_1):GND

CAP_A_0603V-22.0UF,4V,20%,X6S,A  I77  C6D2
   1 PVCCMCP_CPU0      A @BASEBOARD_FAB2_LIB.BASEBOARD_FAB2(SCH_1):PVCCMCP_CPU0
   2    GND      B @BASEBOARD_FAB2_LIB.BASEBOARD_FAB2(SCH_1):GND

CAP_A_0603V-22.0UF,4V,20%,X6S,A  I80  C6D3
   1 PVCCIO_CPU0      A @BASEBOARD_FAB2_LIB.BASEBOARD_FAB2(SCH_1):PVCCIO_CPU0
   2    GND      B @BASEBOARD_FAB2_LIB.BASEBOARD_FAB2(SCH_1):GND

CAP_A_0603V-22.0UF,4V,20%,X6S,A  I81  C6D6
   1 PVCCIO_CPU0      A @BASEBOARD_FAB2_LIB.BASEBOARD_FAB2(SCH_1):PVCCIO_CPU0
   2    GND      B @BASEBOARD_FAB2_LIB.BASEBOARD_FAB2(SCH_1):GND

CAP_A_0603V-22.0UF,4V,20%,X6S,A  I83  C5D51
   1 PVCCMCP_CPU0      A @BASEBOARD_FAB2_LIB.BASEBOARD_FAB2(SCH_1):PVCCMCP_CPU0
   2    GND      B @BASEBOARD_FAB2_LIB.BASEBOARD_FAB2(SCH_1):GND

CAP_A_0603V-22.0UF,4V,20%,X6S,A  I88  C5D21
   1 PVCCMCP_CPU0      A @BASEBOARD_FAB2_LIB.BASEBOARD_FAB2(SCH_1):PVCCMCP_CPU0
   2    GND      B @BASEBOARD_FAB2_LIB.BASEBOARD_FAB2(SCH_1):GND

CAP_A_0603V-22.0UF,4V,20%,X6S,A  I89  C5D50
   1 PVCCMCP_CPU0      A @BASEBOARD_FAB2_LIB.BASEBOARD_FAB2(SCH_1):PVCCMCP_CPU0
   2    GND      B @BASEBOARD_FAB2_LIB.BASEBOARD_FAB2(SCH_1):GND

CAP_A_0603V-22.0UF,4V,20%,X6S,A  I90  C5D48
   1 PVCCMCP_CPU0      A @BASEBOARD_FAB2_LIB.BASEBOARD_FAB2(SCH_1):PVCCMCP_CPU0
   2    GND      B @BASEBOARD_FAB2_LIB.BASEBOARD_FAB2(SCH_1):GND

CAP_0603LF-10UF,4V,20%,X6S,E15A  I91  C5D13
   1 PVSA_CPU0      A @BASEBOARD_FAB2_LIB.BASEBOARD_FAB2(SCH_1):PVSA_CPU0
   2    GND      B @BASEBOARD_FAB2_LIB.BASEBOARD_FAB2(SCH_1):GND

CAP_0603LF-10UF,4V,20%,X6S,E15A  I93  C5D11
   1 PVSA_CPU0      A @BASEBOARD_FAB2_LIB.BASEBOARD_FAB2(SCH_1):PVSA_CPU0
   2    GND      B @BASEBOARD_FAB2_LIB.BASEBOARD_FAB2(SCH_1):GND

CAP_0603LF-10UF,4V,20%,X6S,E15A  I94  C5D12
   1 PVSA_CPU0      A @BASEBOARD_FAB2_LIB.BASEBOARD_FAB2(SCH_1):PVSA_CPU0
   2    GND      B @BASEBOARD_FAB2_LIB.BASEBOARD_FAB2(SCH_1):GND

CAP_A_0603V-22.0UF,4V,20%,X6S,A  I98  C5D23
   1 PVCCMCP_CPU0      A @BASEBOARD_FAB2_LIB.BASEBOARD_FAB2(SCH_1):PVCCMCP_CPU0
   2    GND      B @BASEBOARD_FAB2_LIB.BASEBOARD_FAB2(SCH_1):GND

CAP_A_0603V-22.0UF,4V,20%,X6S,A  I100  C5D28
   1 PVCCIN_CPU0      A @BASEBOARD_FAB2_LIB.BASEBOARD_FAB2(SCH_1):PVCCIN_CPU0
   2    GND      B @BASEBOARD_FAB2_LIB.BASEBOARD_FAB2(SCH_1):GND

CAP_A_0603V-22.0UF,4V,20%,X6S,A  I102  C5D29
   1 PVCCIN_CPU0      A @BASEBOARD_FAB2_LIB.BASEBOARD_FAB2(SCH_1):PVCCIN_CPU0
   2    GND      B @BASEBOARD_FAB2_LIB.BASEBOARD_FAB2(SCH_1):GND

CAP_A_0603V-22.0UF,4V,20%,X6S,A  I103  C5D32
   1 PVCCIN_CPU0      A @BASEBOARD_FAB2_LIB.BASEBOARD_FAB2(SCH_1):PVCCIN_CPU0
   2    GND      B @BASEBOARD_FAB2_LIB.BASEBOARD_FAB2(SCH_1):GND

CAP_A_0603V-22.0UF,4V,20%,X6S,A  I104  C5D47
   1 PVCCIN_CPU0      A @BASEBOARD_FAB2_LIB.BASEBOARD_FAB2(SCH_1):PVCCIN_CPU0
   2    GND      B @BASEBOARD_FAB2_LIB.BASEBOARD_FAB2(SCH_1):GND

CAP_A_0603V-22.0UF,4V,20%,X6S,A  I106  C5D31
   1 PVCCIN_CPU0      A @BASEBOARD_FAB2_LIB.BASEBOARD_FAB2(SCH_1):PVCCIN_CPU0
   2    GND      B @BASEBOARD_FAB2_LIB.BASEBOARD_FAB2(SCH_1):GND

CAP_A_0603V-22.0UF,4V,20%,X6S,A  I107  C5D46
   1 PVCCIN_CPU0      A @BASEBOARD_FAB2_LIB.BASEBOARD_FAB2(SCH_1):PVCCIN_CPU0
   2    GND      B @BASEBOARD_FAB2_LIB.BASEBOARD_FAB2(SCH_1):GND

CAP_0603LF-10UF,4V,20%,X6S,E15A  I108  C5D10
   1 PVSA_CPU0      A @BASEBOARD_FAB2_LIB.BASEBOARD_FAB2(SCH_1):PVSA_CPU0
   2    GND      B @BASEBOARD_FAB2_LIB.BASEBOARD_FAB2(SCH_1):GND

CAP_A_0603V-22.0UF,4V,20%,X6S,A  I109  C5D27
   1 PVCCIN_CPU0      A @BASEBOARD_FAB2_LIB.BASEBOARD_FAB2(SCH_1):PVCCIN_CPU0
   2    GND      B @BASEBOARD_FAB2_LIB.BASEBOARD_FAB2(SCH_1):GND

CAP_A_0603V-22.0UF,4V,20%,X6S,A  I111  C5D30
   1 PVCCIN_CPU0      A @BASEBOARD_FAB2_LIB.BASEBOARD_FAB2(SCH_1):PVCCIN_CPU0
   2    GND      B @BASEBOARD_FAB2_LIB.BASEBOARD_FAB2(SCH_1):GND

CAP_A_0603V-22.0UF,4V,20%,X6S,A  I114  C5D41
   1 PVCCIN_CPU0      A @BASEBOARD_FAB2_LIB.BASEBOARD_FAB2(SCH_1):PVCCIN_CPU0
   2    GND      B @BASEBOARD_FAB2_LIB.BASEBOARD_FAB2(SCH_1):GND

CAP_A_0603V-22.0UF,4V,20%,X6S,A  I115  C5D40
   1 PVCCIN_CPU0      A @BASEBOARD_FAB2_LIB.BASEBOARD_FAB2(SCH_1):PVCCIN_CPU0
   2    GND      B @BASEBOARD_FAB2_LIB.BASEBOARD_FAB2(SCH_1):GND

CAP_A_0603V-22.0UF,4V,20%,X6S,A  I117  C5D14
   1 PVCCIN_CPU0      A @BASEBOARD_FAB2_LIB.BASEBOARD_FAB2(SCH_1):PVCCIN_CPU0
   2    GND      B @BASEBOARD_FAB2_LIB.BASEBOARD_FAB2(SCH_1):GND

CAP_A_0603V-22.0UF,4V,20%,X6S,A  I118  C5D17
   1 PVCCIN_CPU0      A @BASEBOARD_FAB2_LIB.BASEBOARD_FAB2(SCH_1):PVCCIN_CPU0
   2    GND      B @BASEBOARD_FAB2_LIB.BASEBOARD_FAB2(SCH_1):GND

CAP_A_0603V-22.0UF,4V,20%,X6S,A  I123  C5D16
   1 PVCCIN_CPU0      A @BASEBOARD_FAB2_LIB.BASEBOARD_FAB2(SCH_1):PVCCIN_CPU0
   2    GND      B @BASEBOARD_FAB2_LIB.BASEBOARD_FAB2(SCH_1):GND

CAP_A_0603V-22.0UF,4V,20%,X6S,A  I125  C5D5
   1 PVCCIN_CPU0      A @BASEBOARD_FAB2_LIB.BASEBOARD_FAB2(SCH_1):PVCCIN_CPU0
   2    GND      B @BASEBOARD_FAB2_LIB.BASEBOARD_FAB2(SCH_1):GND

CAP_A_0603V-22.0UF,4V,20%,X6S,A  I128  C5D19
   1 PVCCIN_CPU0      A @BASEBOARD_FAB2_LIB.BASEBOARD_FAB2(SCH_1):PVCCIN_CPU0
   2    GND      B @BASEBOARD_FAB2_LIB.BASEBOARD_FAB2(SCH_1):GND

CAP_A_0603V-22.0UF,4V,20%,X6S,A  I131  C5D43
   1 PVCCIN_CPU0      A @BASEBOARD_FAB2_LIB.BASEBOARD_FAB2(SCH_1):PVCCIN_CPU0
   2    GND      B @BASEBOARD_FAB2_LIB.BASEBOARD_FAB2(SCH_1):GND

CAP_A_0603V-22.0UF,4V,20%,X6S,A  I132  C5D15
   1 PVCCIN_CPU0      A @BASEBOARD_FAB2_LIB.BASEBOARD_FAB2(SCH_1):PVCCIN_CPU0
   2    GND      B @BASEBOARD_FAB2_LIB.BASEBOARD_FAB2(SCH_1):GND

CAP_A_0603V-22.0UF,4V,20%,X6S,A  I134  C5D18
   1 PVCCIN_CPU0      A @BASEBOARD_FAB2_LIB.BASEBOARD_FAB2(SCH_1):PVCCIN_CPU0
   2    GND      B @BASEBOARD_FAB2_LIB.BASEBOARD_FAB2(SCH_1):GND

CAP_A_0603V-22.0UF,4V,20%,X6S,A  I135  C5D42
   1 PVCCIN_CPU0      A @BASEBOARD_FAB2_LIB.BASEBOARD_FAB2(SCH_1):PVCCIN_CPU0
   2    GND      B @BASEBOARD_FAB2_LIB.BASEBOARD_FAB2(SCH_1):GND

CAP_A_0603V-22.0UF,4V,20%,X6S,A  I138  C5D24
   1 PVCCIN_CPU0      A @BASEBOARD_FAB2_LIB.BASEBOARD_FAB2(SCH_1):PVCCIN_CPU0
   2    GND      B @BASEBOARD_FAB2_LIB.BASEBOARD_FAB2(SCH_1):GND

CAP_A_0603V-22.0UF,4V,20%,X6S,A  I140  C5D39
   1 PVCCIN_CPU0      A @BASEBOARD_FAB2_LIB.BASEBOARD_FAB2(SCH_1):PVCCIN_CPU0
   2    GND      B @BASEBOARD_FAB2_LIB.BASEBOARD_FAB2(SCH_1):GND

CAP_A_0603V-22.0UF,4V,20%,X6S,A  I142  C5D44
   1 PVCCIN_CPU0      A @BASEBOARD_FAB2_LIB.BASEBOARD_FAB2(SCH_1):PVCCIN_CPU0
   2    GND      B @BASEBOARD_FAB2_LIB.BASEBOARD_FAB2(SCH_1):GND

CAP_A_0603V-22.0UF,4V,20%,X6S,A  I145  C6D9
   1 PVCCIO_CPU0      A @BASEBOARD_FAB2_LIB.BASEBOARD_FAB2(SCH_1):PVCCIO_CPU0
   2    GND      B @BASEBOARD_FAB2_LIB.BASEBOARD_FAB2(SCH_1):GND

CAP_A_0603V-22.0UF,4V,20%,X6S,A  I147  C6D10
   1 PVCCIO_CPU0      A @BASEBOARD_FAB2_LIB.BASEBOARD_FAB2(SCH_1):PVCCIO_CPU0
   2    GND      B @BASEBOARD_FAB2_LIB.BASEBOARD_FAB2(SCH_1):GND

CAP_A_0603V-22.0UF,4V,20%,X6S,A  I151  C5D36
   1 PVCCMCP_CPU0      A @BASEBOARD_FAB2_LIB.BASEBOARD_FAB2(SCH_1):PVCCMCP_CPU0
   2    GND      B @BASEBOARD_FAB2_LIB.BASEBOARD_FAB2(SCH_1):GND

CAP_A_0603V-22.0UF,4V,20%,X6S,A  I152  C5D49
   1 PVCCMCP_CPU0      A @BASEBOARD_FAB2_LIB.BASEBOARD_FAB2(SCH_1):PVCCMCP_CPU0
   2    GND      B @BASEBOARD_FAB2_LIB.BASEBOARD_FAB2(SCH_1):GND

CAP_A_0603V-22.0UF,4V,20%,X6S,A  I153  C5D22
   1 PVCCMCP_CPU0      A @BASEBOARD_FAB2_LIB.BASEBOARD_FAB2(SCH_1):PVCCMCP_CPU0
   2    GND      B @BASEBOARD_FAB2_LIB.BASEBOARD_FAB2(SCH_1):GND

CAP_A_0603V-22.0UF,4V,20%,X6S,A  I154  C5D26
   1 PVCCIN_CPU0      A @BASEBOARD_FAB2_LIB.BASEBOARD_FAB2(SCH_1):PVCCIN_CPU0
   2    GND      B @BASEBOARD_FAB2_LIB.BASEBOARD_FAB2(SCH_1):GND

CAP_A_0603V-22.0UF,4V,20%,X6S,A  I155  C5D25
   1 PVCCIN_CPU0      A @BASEBOARD_FAB2_LIB.BASEBOARD_FAB2(SCH_1):PVCCIN_CPU0
   2    GND      B @BASEBOARD_FAB2_LIB.BASEBOARD_FAB2(SCH_1):GND

CAP_A_0603V-22.0UF,4V,20%,X6S,A  I156  C5D45
   1 PVCCIN_CPU0      A @BASEBOARD_FAB2_LIB.BASEBOARD_FAB2(SCH_1):PVCCIN_CPU0
   2    GND      B @BASEBOARD_FAB2_LIB.BASEBOARD_FAB2(SCH_1):GND

CAP_A_0603V-22.0UF,4V,20%,X6S,A  I164  C4P6
   1 PVCCIO_CPU0      A @BASEBOARD_FAB2_LIB.BASEBOARD_FAB2(SCH_1):PVCCIO_CPU0
   2    GND      B @BASEBOARD_FAB2_LIB.BASEBOARD_FAB2(SCH_1):GND

CAP_A_0603V-22.0UF,4V,20%,X6S,A  I173  C5D20
   1 PVCCMCP_CPU0      A @BASEBOARD_FAB2_LIB.BASEBOARD_FAB2(SCH_1):PVCCMCP_CPU0
   2    GND      B @BASEBOARD_FAB2_LIB.BASEBOARD_FAB2(SCH_1):GND

CAP_A_0603V-22.0UF,4V,20%,X6S,A  I174  C5D33
   1 PVCCMCP_CPU0      A @BASEBOARD_FAB2_LIB.BASEBOARD_FAB2(SCH_1):PVCCMCP_CPU0
   2    GND      B @BASEBOARD_FAB2_LIB.BASEBOARD_FAB2(SCH_1):GND

CAP_A_0603V-22.0UF,4V,20%,X6S,A  I175  C5D34
   1 PVCCMCP_CPU0      A @BASEBOARD_FAB2_LIB.BASEBOARD_FAB2(SCH_1):PVCCMCP_CPU0
   2    GND      B @BASEBOARD_FAB2_LIB.BASEBOARD_FAB2(SCH_1):GND

CAP_A_0603V-22.0UF,4V,20%,X6S,A  I176  C5D35
   1 PVCCMCP_CPU0      A @BASEBOARD_FAB2_LIB.BASEBOARD_FAB2(SCH_1):PVCCMCP_CPU0
   2    GND      B @BASEBOARD_FAB2_LIB.BASEBOARD_FAB2(SCH_1):GND

CAP_A_0603V-22.0UF,4V,20%,X6S,A  I178  C4P8
   1 PVCCIO_CPU0      A @BASEBOARD_FAB2_LIB.BASEBOARD_FAB2(SCH_1):PVCCIO_CPU0
   2    GND      B @BASEBOARD_FAB2_LIB.BASEBOARD_FAB2(SCH_1):GND

CAP_A_0603V-22.0UF,4V,20%,X6S,A  I179  C5D53
   1 PVCCMCP_CPU0      A @BASEBOARD_FAB2_LIB.BASEBOARD_FAB2(SCH_1):PVCCMCP_CPU0
   2    GND      B @BASEBOARD_FAB2_LIB.BASEBOARD_FAB2(SCH_1):GND

CAP_A_0603V-22.0UF,4V,20%,X6S,A  I180  C5D52
   1 PVCCMCP_CPU0      A @BASEBOARD_FAB2_LIB.BASEBOARD_FAB2(SCH_1):PVCCMCP_CPU0
   2    GND      B @BASEBOARD_FAB2_LIB.BASEBOARD_FAB2(SCH_1):GND

CAP_0805-47UF,4V,20%,X6S,C9533A  I187  C5P15
   1 PVCCIN_CPU0      A @BASEBOARD_FAB2_LIB.BASEBOARD_FAB2(SCH_1):PVCCIN_CPU0
   2    GND      B @BASEBOARD_FAB2_LIB.BASEBOARD_FAB2(SCH_1):GND

CAP_0805-47UF,4V,20%,X6S,C9533A  I188  C5P16
   1 PVCCIN_CPU0      A @BASEBOARD_FAB2_LIB.BASEBOARD_FAB2(SCH_1):PVCCIN_CPU0
   2    GND      B @BASEBOARD_FAB2_LIB.BASEBOARD_FAB2(SCH_1):GND

CAP_0805-47UF,4V,20%,X6S,C9533A  I190  C5P17
   1 PVCCIN_CPU0      A @BASEBOARD_FAB2_LIB.BASEBOARD_FAB2(SCH_1):PVCCIN_CPU0
   2    GND      B @BASEBOARD_FAB2_LIB.BASEBOARD_FAB2(SCH_1):GND

CAP_0805-100UF,4V,20%,X5R,6024A  I211  C8W3
   1 PVCCIN_CPU0      A @BASEBOARD_FAB2_LIB.BASEBOARD_FAB2(SCH_1):PVCCIN_CPU0
   2    GND      B @BASEBOARD_FAB2_LIB.BASEBOARD_FAB2(SCH_1):GND

CAP_0805LF-22UF,4V,20%,X6S,C95A  I214  C5P8
   1 PVSA_CPU0      A @BASEBOARD_FAB2_LIB.BASEBOARD_FAB2(SCH_1):PVSA_CPU0
   2    GND      B @BASEBOARD_FAB2_LIB.BASEBOARD_FAB2(SCH_1):GND

CAP_0805LF-22UF,4V,20%,X6S,C95A  I215  C5P9
   1 PVSA_CPU0      A @BASEBOARD_FAB2_LIB.BASEBOARD_FAB2(SCH_1):PVSA_CPU0
   2    GND      B @BASEBOARD_FAB2_LIB.BASEBOARD_FAB2(SCH_1):GND

CAP_A_0603V-22.0UF,4V,20%,X6S,A  I217  C5W1
   1 PVCCMCP_CPU0      A @BASEBOARD_FAB2_LIB.BASEBOARD_FAB2(SCH_1):PVCCMCP_CPU0
   2    GND      B @BASEBOARD_FAB2_LIB.BASEBOARD_FAB2(SCH_1):GND

CAP_A_0603V-22.0UF,4V,20%,X6S,A  I218  C5W2
   1 PVCCMCP_CPU0      A @BASEBOARD_FAB2_LIB.BASEBOARD_FAB2(SCH_1):PVCCMCP_CPU0
   2    GND      B @BASEBOARD_FAB2_LIB.BASEBOARD_FAB2(SCH_1):GND

CAP_0805-100UF,4V,20%,X5R,6024A  I220  C5P29
   1 PVCCMCP_CPU0      A @BASEBOARD_FAB2_LIB.BASEBOARD_FAB2(SCH_1):PVCCMCP_CPU0
   2    GND      B @BASEBOARD_FAB2_LIB.BASEBOARD_FAB2(SCH_1):GND

CAP_0805-100UF,4V,20%,X5R,6024A  I221  C5P30
   1 PVCCMCP_CPU0      A @BASEBOARD_FAB2_LIB.BASEBOARD_FAB2(SCH_1):PVCCMCP_CPU0
   2    GND      B @BASEBOARD_FAB2_LIB.BASEBOARD_FAB2(SCH_1):GND

CAP_0805-100UF,4V,20%,X5R,6024A  I222  C5P19
   1 PVCCMCP_CPU0      A @BASEBOARD_FAB2_LIB.BASEBOARD_FAB2(SCH_1):PVCCMCP_CPU0
   2    GND      B @BASEBOARD_FAB2_LIB.BASEBOARD_FAB2(SCH_1):GND

CAP_0805-100UF,4V,20%,X5R,6024A  I223  C4P4
   1 PVCCMCP_CPU0      A @BASEBOARD_FAB2_LIB.BASEBOARD_FAB2(SCH_1):PVCCMCP_CPU0
   2    GND      B @BASEBOARD_FAB2_LIB.BASEBOARD_FAB2(SCH_1):GND

CAP_0805-100UF,4V,20%,X5R,6024A  I224  C4P7
   1 PVCCMCP_CPU0      A @BASEBOARD_FAB2_LIB.BASEBOARD_FAB2(SCH_1):PVCCMCP_CPU0
   2    GND      B @BASEBOARD_FAB2_LIB.BASEBOARD_FAB2(SCH_1):GND

CAP_0805-100UF,4V,20%,X5R,6024A  I225  C4P3
   1 PVCCMCP_CPU0      A @BASEBOARD_FAB2_LIB.BASEBOARD_FAB2(SCH_1):PVCCMCP_CPU0
   2    GND      B @BASEBOARD_FAB2_LIB.BASEBOARD_FAB2(SCH_1):GND

CAP_0805-100UF,4V,20%,X5R,6024A  I226  C5P10
   1 PVCCMCP_CPU0      A @BASEBOARD_FAB2_LIB.BASEBOARD_FAB2(SCH_1):PVCCMCP_CPU0
   2    GND      B @BASEBOARD_FAB2_LIB.BASEBOARD_FAB2(SCH_1):GND

CAP_0805-100UF,4V,20%,X5R,6024A  I227  C5P11
   1 PVCCMCP_CPU0      A @BASEBOARD_FAB2_LIB.BASEBOARD_FAB2(SCH_1):PVCCMCP_CPU0
   2    GND      B @BASEBOARD_FAB2_LIB.BASEBOARD_FAB2(SCH_1):GND

CAP_0805-100UF,4V,20%,X5R,6024A  I228  C5P18
   1 PVCCMCP_CPU0      A @BASEBOARD_FAB2_LIB.BASEBOARD_FAB2(SCH_1):PVCCMCP_CPU0
   2    GND      B @BASEBOARD_FAB2_LIB.BASEBOARD_FAB2(SCH_1):GND

CAP_0805-100UF,4V,20%,X5R,6024A  I229  C5P28
   1 PVCCMCP_CPU0      A @BASEBOARD_FAB2_LIB.BASEBOARD_FAB2(SCH_1):PVCCMCP_CPU0
   2    GND      B @BASEBOARD_FAB2_LIB.BASEBOARD_FAB2(SCH_1):GND

CAP_0805-100UF,4V,20%,X5R,6024A  I230  C4P2
   1 PVCCMCP_CPU0      A @BASEBOARD_FAB2_LIB.BASEBOARD_FAB2(SCH_1):PVCCMCP_CPU0
   2    GND      B @BASEBOARD_FAB2_LIB.BASEBOARD_FAB2(SCH_1):GND

CAP_0805-100UF,4V,20%,X5R,6024A  I231  C5P31
   1 PVCCMCP_CPU0      A @BASEBOARD_FAB2_LIB.BASEBOARD_FAB2(SCH_1):PVCCMCP_CPU0
   2    GND      B @BASEBOARD_FAB2_LIB.BASEBOARD_FAB2(SCH_1):GND

CAP_0805-100UF,4V,20%,X5R,6024A  I232  C5P13
   1 PVCCMCP_CPU0      A @BASEBOARD_FAB2_LIB.BASEBOARD_FAB2(SCH_1):PVCCMCP_CPU0
   2    GND      B @BASEBOARD_FAB2_LIB.BASEBOARD_FAB2(SCH_1):GND

CAP_0805-100UF,4V,20%,X5R,6024A  I233  C4P5
   1 PVCCMCP_CPU0      A @BASEBOARD_FAB2_LIB.BASEBOARD_FAB2(SCH_1):PVCCMCP_CPU0
   2    GND      B @BASEBOARD_FAB2_LIB.BASEBOARD_FAB2(SCH_1):GND

CAP_0805-100UF,4V,20%,X5R,6024A  I234  C5P20
   1 PVCCMCP_CPU0      A @BASEBOARD_FAB2_LIB.BASEBOARD_FAB2(SCH_1):PVCCMCP_CPU0
   2    GND      B @BASEBOARD_FAB2_LIB.BASEBOARD_FAB2(SCH_1):GND

CAP_0805-100UF,4V,20%,X5R,6024A  I235  C5P21
   1 PVCCMCP_CPU0      A @BASEBOARD_FAB2_LIB.BASEBOARD_FAB2(SCH_1):PVCCMCP_CPU0
   2    GND      B @BASEBOARD_FAB2_LIB.BASEBOARD_FAB2(SCH_1):GND

CAP_0805-100UF,4V,20%,X5R,6024A  I236  C5P12
   1 PVCCMCP_CPU0      A @BASEBOARD_FAB2_LIB.BASEBOARD_FAB2(SCH_1):PVCCMCP_CPU0
   2    GND      B @BASEBOARD_FAB2_LIB.BASEBOARD_FAB2(SCH_1):GND


DRAWING: @BASEBOARD_FAB2_LIB.BASEBOARD_FAB2(SCH_1):PAGE43 

SCONN288_H44441004_PIP-SCONN,HA  I1  J4G1
  79 M_A_MA<0>     A0 @BASEBOARD_FAB2_LIB.BASEBOARD_FAB2(SCH_1):M_A_MA(0)
  72 M_A_MA<1>     A1 @BASEBOARD_FAB2_LIB.BASEBOARD_FAB2(SCH_1):M_A_MA(1)
 225 M_A_MA<10>    A10 @BASEBOARD_FAB2_LIB.BASEBOARD_FAB2(SCH_1):M_A_MA(10)
 210 M_A_MA<11>    A11 @BASEBOARD_FAB2_LIB.BASEBOARD_FAB2(SCH_1):M_A_MA(11)
  65 M_A_MA<12>    A12 @BASEBOARD_FAB2_LIB.BASEBOARD_FAB2(SCH_1):M_A_MA(12)
 232 M_A_MA<13>    A13 @BASEBOARD_FAB2_LIB.BASEBOARD_FAB2(SCH_1):M_A_MA(13)
 228 M_A_MA<14> A14_WE_N @BASEBOARD_FAB2_LIB.BASEBOARD_FAB2(SCH_1):M_A_MA(14)
  86 M_A_MA<15> A15_CAS_N @BASEBOARD_FAB2_LIB.BASEBOARD_FAB2(SCH_1):M_A_MA(15)
  82 M_A_MA<16> A16_RAS_N @BASEBOARD_FAB2_LIB.BASEBOARD_FAB2(SCH_1):M_A_MA(16)
 234 M_A_MA<17>    A17 @BASEBOARD_FAB2_LIB.BASEBOARD_FAB2(SCH_1):M_A_MA(17)
 216 M_A_MA<2>     A2 @BASEBOARD_FAB2_LIB.BASEBOARD_FAB2(SCH_1):M_A_MA(2)
  71 M_A_MA<3>     A3 @BASEBOARD_FAB2_LIB.BASEBOARD_FAB2(SCH_1):M_A_MA(3)
 214 M_A_MA<4>     A4 @BASEBOARD_FAB2_LIB.BASEBOARD_FAB2(SCH_1):M_A_MA(4)
 213 M_A_MA<5>     A5 @BASEBOARD_FAB2_LIB.BASEBOARD_FAB2(SCH_1):M_A_MA(5)
  69 M_A_MA<6>     A6 @BASEBOARD_FAB2_LIB.BASEBOARD_FAB2(SCH_1):M_A_MA(6)
 211 M_A_MA<7>     A7 @BASEBOARD_FAB2_LIB.BASEBOARD_FAB2(SCH_1):M_A_MA(7)
  68 M_A_MA<8>     A8 @BASEBOARD_FAB2_LIB.BASEBOARD_FAB2(SCH_1):M_A_MA(8)
  66 M_A_MA<9>     A9 @BASEBOARD_FAB2_LIB.BASEBOARD_FAB2(SCH_1):M_A_MA(9)
  62 M_A_ACT_N  ACT_N @BASEBOARD_FAB2_LIB.BASEBOARD_FAB2(SCH_1):M_A_ACT_N
 208 M_A_ALERT_N ALERT_N @BASEBOARD_FAB2_LIB.BASEBOARD_FAB2(SCH_1):M_A_ALERT_N
 224 M_A_BA<1>  BA<1> @BASEBOARD_FAB2_LIB.BASEBOARD_FAB2(SCH_1):M_A_BA(1)
  81 M_A_BA<0>  BA<0> @BASEBOARD_FAB2_LIB.BASEBOARD_FAB2(SCH_1):M_A_BA(0)
 207 M_A_BG<1>  BG<1> @BASEBOARD_FAB2_LIB.BASEBOARD_FAB2(SCH_1):M_A_BG(1)
  63 M_A_BG<0>  BG<0> @BASEBOARD_FAB2_LIB.BASEBOARD_FAB2(SCH_1):M_A_BG(0)
 235 M_A_C<2>   C<2> @BASEBOARD_FAB2_LIB.BASEBOARD_FAB2(SCH_1):M_A_C(2)
 199 M_A_ECC<6>  CB<7> @BASEBOARD_FAB2_LIB.BASEBOARD_FAB2(SCH_1):M_A_ECC(6)
  54 M_A_ECC<7>  CB<6> @BASEBOARD_FAB2_LIB.BASEBOARD_FAB2(SCH_1):M_A_ECC(7)
 192 M_A_ECC<4>  CB<5> @BASEBOARD_FAB2_LIB.BASEBOARD_FAB2(SCH_1):M_A_ECC(4)
  47 M_A_ECC<5>  CB<4> @BASEBOARD_FAB2_LIB.BASEBOARD_FAB2(SCH_1):M_A_ECC(5)
 201 M_A_ECC<2>  CB<3> @BASEBOARD_FAB2_LIB.BASEBOARD_FAB2(SCH_1):M_A_ECC(2)
  56 M_A_ECC<3>  CB<2> @BASEBOARD_FAB2_LIB.BASEBOARD_FAB2(SCH_1):M_A_ECC(3)
 194 M_A_ECC<0>  CB<1> @BASEBOARD_FAB2_LIB.BASEBOARD_FAB2(SCH_1):M_A_ECC(0)
  49 M_A_ECC<1>  CB<0> @BASEBOARD_FAB2_LIB.BASEBOARD_FAB2(SCH_1):M_A_ECC(1)
  75 M_A_CLK_DN<0>   CK0N @BASEBOARD_FAB2_LIB.BASEBOARD_FAB2(SCH_1):M_A_CLK_DN(0)
  74 M_A_CLK_DP<0>   CK0P @BASEBOARD_FAB2_LIB.BASEBOARD_FAB2(SCH_1):M_A_CLK_DP(0)
 219 M_A_CLK_DN<1>   CK1N @BASEBOARD_FAB2_LIB.BASEBOARD_FAB2(SCH_1):M_A_CLK_DN(1)
 218 M_A_CLK_DP<1>   CK1P @BASEBOARD_FAB2_LIB.BASEBOARD_FAB2(SCH_1):M_A_CLK_DP(1)
 203 M_A_CKE<1> CKE<1> @BASEBOARD_FAB2_LIB.BASEBOARD_FAB2(SCH_1):M_A_CKE(1)
  60 M_A_CKE<0> CKE<0> @BASEBOARD_FAB2_LIB.BASEBOARD_FAB2(SCH_1):M_A_CKE(0)
 280 M_A_DQ<62> DQ<63> @BASEBOARD_FAB2_LIB.BASEBOARD_FAB2(SCH_1):M_A_DQ(62)
 135 M_A_DQ<63> DQ<62> @BASEBOARD_FAB2_LIB.BASEBOARD_FAB2(SCH_1):M_A_DQ(63)
 273 M_A_DQ<60> DQ<61> @BASEBOARD_FAB2_LIB.BASEBOARD_FAB2(SCH_1):M_A_DQ(60)
 128 M_A_DQ<61> DQ<60> @BASEBOARD_FAB2_LIB.BASEBOARD_FAB2(SCH_1):M_A_DQ(61)
 282 M_A_DQ<58> DQ<59> @BASEBOARD_FAB2_LIB.BASEBOARD_FAB2(SCH_1):M_A_DQ(58)
 137 M_A_DQ<59> DQ<58> @BASEBOARD_FAB2_LIB.BASEBOARD_FAB2(SCH_1):M_A_DQ(59)
 275 M_A_DQ<56> DQ<57> @BASEBOARD_FAB2_LIB.BASEBOARD_FAB2(SCH_1):M_A_DQ(56)
 130 M_A_DQ<57> DQ<56> @BASEBOARD_FAB2_LIB.BASEBOARD_FAB2(SCH_1):M_A_DQ(57)
 269 M_A_DQ<54> DQ<55> @BASEBOARD_FAB2_LIB.BASEBOARD_FAB2(SCH_1):M_A_DQ(54)
 124 M_A_DQ<55> DQ<54> @BASEBOARD_FAB2_LIB.BASEBOARD_FAB2(SCH_1):M_A_DQ(55)
 262 M_A_DQ<52> DQ<53> @BASEBOARD_FAB2_LIB.BASEBOARD_FAB2(SCH_1):M_A_DQ(52)
 117 M_A_DQ<53> DQ<52> @BASEBOARD_FAB2_LIB.BASEBOARD_FAB2(SCH_1):M_A_DQ(53)
 271 M_A_DQ<50> DQ<51> @BASEBOARD_FAB2_LIB.BASEBOARD_FAB2(SCH_1):M_A_DQ(50)
 126 M_A_DQ<51> DQ<50> @BASEBOARD_FAB2_LIB.BASEBOARD_FAB2(SCH_1):M_A_DQ(51)
 264 M_A_DQ<48> DQ<49> @BASEBOARD_FAB2_LIB.BASEBOARD_FAB2(SCH_1):M_A_DQ(48)
 119 M_A_DQ<49> DQ<48> @BASEBOARD_FAB2_LIB.BASEBOARD_FAB2(SCH_1):M_A_DQ(49)
 258 M_A_DQ<46> DQ<47> @BASEBOARD_FAB2_LIB.BASEBOARD_FAB2(SCH_1):M_A_DQ(46)
 113 M_A_DQ<47> DQ<46> @BASEBOARD_FAB2_LIB.BASEBOARD_FAB2(SCH_1):M_A_DQ(47)
 251 M_A_DQ<44> DQ<45> @BASEBOARD_FAB2_LIB.BASEBOARD_FAB2(SCH_1):M_A_DQ(44)
 106 M_A_DQ<45> DQ<44> @BASEBOARD_FAB2_LIB.BASEBOARD_FAB2(SCH_1):M_A_DQ(45)
 260 M_A_DQ<42> DQ<43> @BASEBOARD_FAB2_LIB.BASEBOARD_FAB2(SCH_1):M_A_DQ(42)
 115 M_A_DQ<43> DQ<42> @BASEBOARD_FAB2_LIB.BASEBOARD_FAB2(SCH_1):M_A_DQ(43)
 253 M_A_DQ<40> DQ<41> @BASEBOARD_FAB2_LIB.BASEBOARD_FAB2(SCH_1):M_A_DQ(40)
 108 M_A_DQ<41> DQ<40> @BASEBOARD_FAB2_LIB.BASEBOARD_FAB2(SCH_1):M_A_DQ(41)
 247 M_A_DQ<38> DQ<39> @BASEBOARD_FAB2_LIB.BASEBOARD_FAB2(SCH_1):M_A_DQ(38)
 102 M_A_DQ<39> DQ<38> @BASEBOARD_FAB2_LIB.BASEBOARD_FAB2(SCH_1):M_A_DQ(39)
 240 M_A_DQ<36> DQ<37> @BASEBOARD_FAB2_LIB.BASEBOARD_FAB2(SCH_1):M_A_DQ(36)
  95 M_A_DQ<37> DQ<36> @BASEBOARD_FAB2_LIB.BASEBOARD_FAB2(SCH_1):M_A_DQ(37)
 249 M_A_DQ<34> DQ<35> @BASEBOARD_FAB2_LIB.BASEBOARD_FAB2(SCH_1):M_A_DQ(34)
 104 M_A_DQ<35> DQ<34> @BASEBOARD_FAB2_LIB.BASEBOARD_FAB2(SCH_1):M_A_DQ(35)
 242 M_A_DQ<32> DQ<33> @BASEBOARD_FAB2_LIB.BASEBOARD_FAB2(SCH_1):M_A_DQ(32)
  97 M_A_DQ<33> DQ<32> @BASEBOARD_FAB2_LIB.BASEBOARD_FAB2(SCH_1):M_A_DQ(33)
 188 M_A_DQ<30> DQ<31> @BASEBOARD_FAB2_LIB.BASEBOARD_FAB2(SCH_1):M_A_DQ(30)
  43 M_A_DQ<31> DQ<30> @BASEBOARD_FAB2_LIB.BASEBOARD_FAB2(SCH_1):M_A_DQ(31)
 181 M_A_DQ<28> DQ<29> @BASEBOARD_FAB2_LIB.BASEBOARD_FAB2(SCH_1):M_A_DQ(28)
  36 M_A_DQ<29> DQ<28> @BASEBOARD_FAB2_LIB.BASEBOARD_FAB2(SCH_1):M_A_DQ(29)
 190 M_A_DQ<26> DQ<27> @BASEBOARD_FAB2_LIB.BASEBOARD_FAB2(SCH_1):M_A_DQ(26)
  45 M_A_DQ<27> DQ<26> @BASEBOARD_FAB2_LIB.BASEBOARD_FAB2(SCH_1):M_A_DQ(27)
 183 M_A_DQ<24> DQ<25> @BASEBOARD_FAB2_LIB.BASEBOARD_FAB2(SCH_1):M_A_DQ(24)
  38 M_A_DQ<25> DQ<24> @BASEBOARD_FAB2_LIB.BASEBOARD_FAB2(SCH_1):M_A_DQ(25)
 177 M_A_DQ<22> DQ<23> @BASEBOARD_FAB2_LIB.BASEBOARD_FAB2(SCH_1):M_A_DQ(22)
  32 M_A_DQ<23> DQ<22> @BASEBOARD_FAB2_LIB.BASEBOARD_FAB2(SCH_1):M_A_DQ(23)
 170 M_A_DQ<20> DQ<21> @BASEBOARD_FAB2_LIB.BASEBOARD_FAB2(SCH_1):M_A_DQ(20)
  25 M_A_DQ<21> DQ<20> @BASEBOARD_FAB2_LIB.BASEBOARD_FAB2(SCH_1):M_A_DQ(21)
 179 M_A_DQ<18> DQ<19> @BASEBOARD_FAB2_LIB.BASEBOARD_FAB2(SCH_1):M_A_DQ(18)
  34 M_A_DQ<19> DQ<18> @BASEBOARD_FAB2_LIB.BASEBOARD_FAB2(SCH_1):M_A_DQ(19)
 172 M_A_DQ<16> DQ<17> @BASEBOARD_FAB2_LIB.BASEBOARD_FAB2(SCH_1):M_A_DQ(16)
  27 M_A_DQ<17> DQ<16> @BASEBOARD_FAB2_LIB.BASEBOARD_FAB2(SCH_1):M_A_DQ(17)
 166 M_A_DQ<14> DQ<15> @BASEBOARD_FAB2_LIB.BASEBOARD_FAB2(SCH_1):M_A_DQ(14)
  21 M_A_DQ<15> DQ<14> @BASEBOARD_FAB2_LIB.BASEBOARD_FAB2(SCH_1):M_A_DQ(15)
 159 M_A_DQ<12> DQ<13> @BASEBOARD_FAB2_LIB.BASEBOARD_FAB2(SCH_1):M_A_DQ(12)
  14 M_A_DQ<13> DQ<12> @BASEBOARD_FAB2_LIB.BASEBOARD_FAB2(SCH_1):M_A_DQ(13)
 168 M_A_DQ<10> DQ<11> @BASEBOARD_FAB2_LIB.BASEBOARD_FAB2(SCH_1):M_A_DQ(10)
  23 M_A_DQ<11> DQ<10> @BASEBOARD_FAB2_LIB.BASEBOARD_FAB2(SCH_1):M_A_DQ(11)
 161 M_A_DQ<8>  DQ<9> @BASEBOARD_FAB2_LIB.BASEBOARD_FAB2(SCH_1):M_A_DQ(8)
  16 M_A_DQ<9>  DQ<8> @BASEBOARD_FAB2_LIB.BASEBOARD_FAB2(SCH_1):M_A_DQ(9)
 155 M_A_DQ<6>  DQ<7> @BASEBOARD_FAB2_LIB.BASEBOARD_FAB2(SCH_1):M_A_DQ(6)
  10 M_A_DQ<7>  DQ<6> @BASEBOARD_FAB2_LIB.BASEBOARD_FAB2(SCH_1):M_A_DQ(7)
 148 M_A_DQ<4>  DQ<5> @BASEBOARD_FAB2_LIB.BASEBOARD_FAB2(SCH_1):M_A_DQ(4)
   3 M_A_DQ<5>  DQ<4> @BASEBOARD_FAB2_LIB.BASEBOARD_FAB2(SCH_1):M_A_DQ(5)
 157 M_A_DQ<2>  DQ<3> @BASEBOARD_FAB2_LIB.BASEBOARD_FAB2(SCH_1):M_A_DQ(2)
  12 M_A_DQ<3>  DQ<2> @BASEBOARD_FAB2_LIB.BASEBOARD_FAB2(SCH_1):M_A_DQ(3)
 150 M_A_DQ<0>  DQ<1> @BASEBOARD_FAB2_LIB.BASEBOARD_FAB2(SCH_1):M_A_DQ(0)
   5 M_A_DQ<1>  DQ<0> @BASEBOARD_FAB2_LIB.BASEBOARD_FAB2(SCH_1):M_A_DQ(1)
  78 FM_DIMM_EVENT_COD_N EVENT_N @BASEBOARD_FAB2_LIB.BASEBOARD_FAB2(SCH_1):FM_DIMM_EVENT_COD_N
  91 M_A_ODT<1> ODT<1> @BASEBOARD_FAB2_LIB.BASEBOARD_FAB2(SCH_1):M_A_ODT(1)
  87 M_A_ODT<0> ODT<0> @BASEBOARD_FAB2_LIB.BASEBOARD_FAB2(SCH_1):M_A_ODT(0)
 222 M_A_PAR    PAR @BASEBOARD_FAB2_LIB.BASEBOARD_FAB2(SCH_1):M_A_PAR
  58 M_ABC_RST_N RESET_N @BASEBOARD_FAB2_LIB.BASEBOARD_FAB2(SCH_1):M_ABC_RST_N
 144 TP_CH_A_DIMM_A0_RFU_2 RFU<2> @BASEBOARD_FAB2_LIB.BASEBOARD_FAB2(SCH_1):TP_CH_A_DIMM_A0_RFU_2
 227 TP_CH_A_DIMM_A0_RFU_1 RFU<1> @BASEBOARD_FAB2_LIB.BASEBOARD_FAB2(SCH_1):TP_CH_A_DIMM_A0_RFU_1
 205 TP_CH_A_DIMM_A0_RFU_0 RFU<0> @BASEBOARD_FAB2_LIB.BASEBOARD_FAB2(SCH_1):TP_CH_A_DIMM_A0_RFU_0
  84 M_A_CS_N<0>   S0_N @BASEBOARD_FAB2_LIB.BASEBOARD_FAB2(SCH_1):M_A_CS_N(0)
  89 M_A_CS_N<1>   S1_N @BASEBOARD_FAB2_LIB.BASEBOARD_FAB2(SCH_1):M_A_CS_N(1)
  93 M_A_CS_N<2> S2_N_C<0> @BASEBOARD_FAB2_LIB.BASEBOARD_FAB2(SCH_1):M_A_CS_N(2)
 237 M_A_CS_N<3> S3_N_C<1> @BASEBOARD_FAB2_LIB.BASEBOARD_FAB2(SCH_1):M_A_CS_N(3)
 238    GND  SA<2> @BASEBOARD_FAB2_LIB.BASEBOARD_FAB2(SCH_1):GND
 140    GND  SA<1> @BASEBOARD_FAB2_LIB.BASEBOARD_FAB2(SCH_1):GND
 139    GND  SA<0> @BASEBOARD_FAB2_LIB.BASEBOARD_FAB2(SCH_1):GND
 230 FM_ADR_COMPLETE_ABC_N SAVE_N_NC @BASEBOARD_FAB2_LIB.BASEBOARD_FAB2(SCH_1):FM_ADR_COMPLETE_ABC_N
 141 SMB_DDR_ABC_VPP_SCL    SCL @BASEBOARD_FAB2_LIB.BASEBOARD_FAB2(SCH_1):SMB_DDR_ABC_VPP_SCL
 285 SMB_DDR_ABC_VPP_SDA    SDA @BASEBOARD_FAB2_LIB.BASEBOARD_FAB2(SCH_1):SMB_DDR_ABC_VPP_SDA
 284 PVPP_ABC VDDSPD @BASEBOARD_FAB2_LIB.BASEBOARD_FAB2(SCH_1):PVPP_ABC
 146 M_A_VREF VREFCA @BASEBOARD_FAB2_LIB.BASEBOARD_FAB2(SCH_1):M_A_VREF

SCONN288_H44441004_PIP-SCONN,HA  I2  J4G1
 152 M_A_DQS_DN<0>  DQS0N @BASEBOARD_FAB2_LIB.BASEBOARD_FAB2(SCH_1):M_A_DQS_DN(0)
 153 M_A_DQS_DP<0>  DQS0P @BASEBOARD_FAB2_LIB.BASEBOARD_FAB2(SCH_1):M_A_DQS_DP(0)
  19 M_A_DQS_DN<10> DQS10N @BASEBOARD_FAB2_LIB.BASEBOARD_FAB2(SCH_1):M_A_DQS_DN(10)
  18 M_A_DQS_DP<10> DQS10P @BASEBOARD_FAB2_LIB.BASEBOARD_FAB2(SCH_1):M_A_DQS_DP(10)
  30 M_A_DQS_DN<11> DQS11N @BASEBOARD_FAB2_LIB.BASEBOARD_FAB2(SCH_1):M_A_DQS_DN(11)
  29 M_A_DQS_DP<11> DQS11P @BASEBOARD_FAB2_LIB.BASEBOARD_FAB2(SCH_1):M_A_DQS_DP(11)
  41 M_A_DQS_DN<12> DQS12N @BASEBOARD_FAB2_LIB.BASEBOARD_FAB2(SCH_1):M_A_DQS_DN(12)
  40 M_A_DQS_DP<12> DQS12P @BASEBOARD_FAB2_LIB.BASEBOARD_FAB2(SCH_1):M_A_DQS_DP(12)
 100 M_A_DQS_DN<13> DQS13N @BASEBOARD_FAB2_LIB.BASEBOARD_FAB2(SCH_1):M_A_DQS_DN(13)
  99 M_A_DQS_DP<13> DQS13P @BASEBOARD_FAB2_LIB.BASEBOARD_FAB2(SCH_1):M_A_DQS_DP(13)
 111 M_A_DQS_DN<14> DQS14N @BASEBOARD_FAB2_LIB.BASEBOARD_FAB2(SCH_1):M_A_DQS_DN(14)
 110 M_A_DQS_DP<14> DQS14P @BASEBOARD_FAB2_LIB.BASEBOARD_FAB2(SCH_1):M_A_DQS_DP(14)
 122 M_A_DQS_DN<15> DQS15N @BASEBOARD_FAB2_LIB.BASEBOARD_FAB2(SCH_1):M_A_DQS_DN(15)
 121 M_A_DQS_DP<15> DQS15P @BASEBOARD_FAB2_LIB.BASEBOARD_FAB2(SCH_1):M_A_DQS_DP(15)
 133 M_A_DQS_DN<16> DQS16N @BASEBOARD_FAB2_LIB.BASEBOARD_FAB2(SCH_1):M_A_DQS_DN(16)
 132 M_A_DQS_DP<16> DQS16P @BASEBOARD_FAB2_LIB.BASEBOARD_FAB2(SCH_1):M_A_DQS_DP(16)
  52 M_A_DQS_DN<17> DQS17N @BASEBOARD_FAB2_LIB.BASEBOARD_FAB2(SCH_1):M_A_DQS_DN(17)
  51 M_A_DQS_DP<17> DQS17P @BASEBOARD_FAB2_LIB.BASEBOARD_FAB2(SCH_1):M_A_DQS_DP(17)
 163 M_A_DQS_DN<1>  DQS1N @BASEBOARD_FAB2_LIB.BASEBOARD_FAB2(SCH_1):M_A_DQS_DN(1)
 164 M_A_DQS_DP<1>  DQS1P @BASEBOARD_FAB2_LIB.BASEBOARD_FAB2(SCH_1):M_A_DQS_DP(1)
 174 M_A_DQS_DN<2>  DQS2N @BASEBOARD_FAB2_LIB.BASEBOARD_FAB2(SCH_1):M_A_DQS_DN(2)
 175 M_A_DQS_DP<2>  DQS2P @BASEBOARD_FAB2_LIB.BASEBOARD_FAB2(SCH_1):M_A_DQS_DP(2)
 185 M_A_DQS_DN<3>  DQS3N @BASEBOARD_FAB2_LIB.BASEBOARD_FAB2(SCH_1):M_A_DQS_DN(3)
 186 M_A_DQS_DP<3>  DQS3P @BASEBOARD_FAB2_LIB.BASEBOARD_FAB2(SCH_1):M_A_DQS_DP(3)
 244 M_A_DQS_DN<4>  DQS4N @BASEBOARD_FAB2_LIB.BASEBOARD_FAB2(SCH_1):M_A_DQS_DN(4)
 245 M_A_DQS_DP<4>  DQS4P @BASEBOARD_FAB2_LIB.BASEBOARD_FAB2(SCH_1):M_A_DQS_DP(4)
 255 M_A_DQS_DN<5>  DQS5N @BASEBOARD_FAB2_LIB.BASEBOARD_FAB2(SCH_1):M_A_DQS_DN(5)
 256 M_A_DQS_DP<5>  DQS5P @BASEBOARD_FAB2_LIB.BASEBOARD_FAB2(SCH_1):M_A_DQS_DP(5)
 266 M_A_DQS_DN<6>  DQS6N @BASEBOARD_FAB2_LIB.BASEBOARD_FAB2(SCH_1):M_A_DQS_DN(6)
 267 M_A_DQS_DP<6>  DQS6P @BASEBOARD_FAB2_LIB.BASEBOARD_FAB2(SCH_1):M_A_DQS_DP(6)
 277 M_A_DQS_DN<7>  DQS7N @BASEBOARD_FAB2_LIB.BASEBOARD_FAB2(SCH_1):M_A_DQS_DN(7)
 278 M_A_DQS_DP<7>  DQS7P @BASEBOARD_FAB2_LIB.BASEBOARD_FAB2(SCH_1):M_A_DQS_DP(7)
 196 M_A_DQS_DN<8>  DQS8N @BASEBOARD_FAB2_LIB.BASEBOARD_FAB2(SCH_1):M_A_DQS_DN(8)
 197 M_A_DQS_DP<8>  DQS8P @BASEBOARD_FAB2_LIB.BASEBOARD_FAB2(SCH_1):M_A_DQS_DP(8)
   8 M_A_DQS_DN<9>  DQS9N @BASEBOARD_FAB2_LIB.BASEBOARD_FAB2(SCH_1):M_A_DQS_DN(9)
   7 M_A_DQS_DP<9>  DQS9P @BASEBOARD_FAB2_LIB.BASEBOARD_FAB2(SCH_1):M_A_DQS_DP(9)

SCONN288_H44441004_PIP-SCONN,HA  I259  J4G1
   2    GND VSS<93> @BASEBOARD_FAB2_LIB.BASEBOARD_FAB2(SCH_1):GND
   4    GND VSS<92> @BASEBOARD_FAB2_LIB.BASEBOARD_FAB2(SCH_1):GND
   6    GND VSS<91> @BASEBOARD_FAB2_LIB.BASEBOARD_FAB2(SCH_1):GND
   9    GND VSS<90> @BASEBOARD_FAB2_LIB.BASEBOARD_FAB2(SCH_1):GND
  11    GND VSS<89> @BASEBOARD_FAB2_LIB.BASEBOARD_FAB2(SCH_1):GND
  13    GND VSS<88> @BASEBOARD_FAB2_LIB.BASEBOARD_FAB2(SCH_1):GND
  15    GND VSS<87> @BASEBOARD_FAB2_LIB.BASEBOARD_FAB2(SCH_1):GND
  17    GND VSS<86> @BASEBOARD_FAB2_LIB.BASEBOARD_FAB2(SCH_1):GND
  20    GND VSS<85> @BASEBOARD_FAB2_LIB.BASEBOARD_FAB2(SCH_1):GND
  22    GND VSS<84> @BASEBOARD_FAB2_LIB.BASEBOARD_FAB2(SCH_1):GND
  24    GND VSS<83> @BASEBOARD_FAB2_LIB.BASEBOARD_FAB2(SCH_1):GND
  26    GND VSS<82> @BASEBOARD_FAB2_LIB.BASEBOARD_FAB2(SCH_1):GND
  28    GND VSS<81> @BASEBOARD_FAB2_LIB.BASEBOARD_FAB2(SCH_1):GND
  31    GND VSS<80> @BASEBOARD_FAB2_LIB.BASEBOARD_FAB2(SCH_1):GND
  33    GND VSS<79> @BASEBOARD_FAB2_LIB.BASEBOARD_FAB2(SCH_1):GND
  35    GND VSS<78> @BASEBOARD_FAB2_LIB.BASEBOARD_FAB2(SCH_1):GND
  37    GND VSS<77> @BASEBOARD_FAB2_LIB.BASEBOARD_FAB2(SCH_1):GND
  39    GND VSS<76> @BASEBOARD_FAB2_LIB.BASEBOARD_FAB2(SCH_1):GND
  42    GND VSS<75> @BASEBOARD_FAB2_LIB.BASEBOARD_FAB2(SCH_1):GND
  44    GND VSS<74> @BASEBOARD_FAB2_LIB.BASEBOARD_FAB2(SCH_1):GND
  46    GND VSS<73> @BASEBOARD_FAB2_LIB.BASEBOARD_FAB2(SCH_1):GND
  48    GND VSS<72> @BASEBOARD_FAB2_LIB.BASEBOARD_FAB2(SCH_1):GND
  50    GND VSS<71> @BASEBOARD_FAB2_LIB.BASEBOARD_FAB2(SCH_1):GND
  53    GND VSS<70> @BASEBOARD_FAB2_LIB.BASEBOARD_FAB2(SCH_1):GND
  55    GND VSS<69> @BASEBOARD_FAB2_LIB.BASEBOARD_FAB2(SCH_1):GND
  57    GND VSS<68> @BASEBOARD_FAB2_LIB.BASEBOARD_FAB2(SCH_1):GND
  94    GND VSS<67> @BASEBOARD_FAB2_LIB.BASEBOARD_FAB2(SCH_1):GND
  96    GND VSS<66> @BASEBOARD_FAB2_LIB.BASEBOARD_FAB2(SCH_1):GND
  98    GND VSS<65> @BASEBOARD_FAB2_LIB.BASEBOARD_FAB2(SCH_1):GND
 101    GND VSS<64> @BASEBOARD_FAB2_LIB.BASEBOARD_FAB2(SCH_1):GND
 103    GND VSS<63> @BASEBOARD_FAB2_LIB.BASEBOARD_FAB2(SCH_1):GND
 105    GND VSS<62> @BASEBOARD_FAB2_LIB.BASEBOARD_FAB2(SCH_1):GND
 107    GND VSS<61> @BASEBOARD_FAB2_LIB.BASEBOARD_FAB2(SCH_1):GND
 109    GND VSS<60> @BASEBOARD_FAB2_LIB.BASEBOARD_FAB2(SCH_1):GND
 112    GND VSS<59> @BASEBOARD_FAB2_LIB.BASEBOARD_FAB2(SCH_1):GND
 114    GND VSS<58> @BASEBOARD_FAB2_LIB.BASEBOARD_FAB2(SCH_1):GND
 116    GND VSS<57> @BASEBOARD_FAB2_LIB.BASEBOARD_FAB2(SCH_1):GND
 118    GND VSS<56> @BASEBOARD_FAB2_LIB.BASEBOARD_FAB2(SCH_1):GND
 120    GND VSS<55> @BASEBOARD_FAB2_LIB.BASEBOARD_FAB2(SCH_1):GND
 123    GND VSS<54> @BASEBOARD_FAB2_LIB.BASEBOARD_FAB2(SCH_1):GND
 125    GND VSS<53> @BASEBOARD_FAB2_LIB.BASEBOARD_FAB2(SCH_1):GND
 127    GND VSS<52> @BASEBOARD_FAB2_LIB.BASEBOARD_FAB2(SCH_1):GND
 129    GND VSS<51> @BASEBOARD_FAB2_LIB.BASEBOARD_FAB2(SCH_1):GND
 131    GND VSS<50> @BASEBOARD_FAB2_LIB.BASEBOARD_FAB2(SCH_1):GND
 134    GND VSS<49> @BASEBOARD_FAB2_LIB.BASEBOARD_FAB2(SCH_1):GND
 136    GND VSS<48> @BASEBOARD_FAB2_LIB.BASEBOARD_FAB2(SCH_1):GND
 138    GND VSS<47> @BASEBOARD_FAB2_LIB.BASEBOARD_FAB2(SCH_1):GND
 147    GND VSS<46> @BASEBOARD_FAB2_LIB.BASEBOARD_FAB2(SCH_1):GND
 149    GND VSS<45> @BASEBOARD_FAB2_LIB.BASEBOARD_FAB2(SCH_1):GND
 151    GND VSS<44> @BASEBOARD_FAB2_LIB.BASEBOARD_FAB2(SCH_1):GND
 154    GND VSS<43> @BASEBOARD_FAB2_LIB.BASEBOARD_FAB2(SCH_1):GND
 156    GND VSS<42> @BASEBOARD_FAB2_LIB.BASEBOARD_FAB2(SCH_1):GND
 158    GND VSS<41> @BASEBOARD_FAB2_LIB.BASEBOARD_FAB2(SCH_1):GND
 160    GND VSS<40> @BASEBOARD_FAB2_LIB.BASEBOARD_FAB2(SCH_1):GND
 162    GND VSS<39> @BASEBOARD_FAB2_LIB.BASEBOARD_FAB2(SCH_1):GND
 165    GND VSS<38> @BASEBOARD_FAB2_LIB.BASEBOARD_FAB2(SCH_1):GND
 167    GND VSS<37> @BASEBOARD_FAB2_LIB.BASEBOARD_FAB2(SCH_1):GND
 169    GND VSS<36> @BASEBOARD_FAB2_LIB.BASEBOARD_FAB2(SCH_1):GND
 171    GND VSS<35> @BASEBOARD_FAB2_LIB.BASEBOARD_FAB2(SCH_1):GND
 173    GND VSS<34> @BASEBOARD_FAB2_LIB.BASEBOARD_FAB2(SCH_1):GND
 176    GND VSS<33> @BASEBOARD_FAB2_LIB.BASEBOARD_FAB2(SCH_1):GND
 178    GND VSS<32> @BASEBOARD_FAB2_LIB.BASEBOARD_FAB2(SCH_1):GND
 180    GND VSS<31> @BASEBOARD_FAB2_LIB.BASEBOARD_FAB2(SCH_1):GND
 182    GND VSS<30> @BASEBOARD_FAB2_LIB.BASEBOARD_FAB2(SCH_1):GND
 184    GND VSS<29> @BASEBOARD_FAB2_LIB.BASEBOARD_FAB2(SCH_1):GND
 187    GND VSS<28> @BASEBOARD_FAB2_LIB.BASEBOARD_FAB2(SCH_1):GND
 189    GND VSS<27> @BASEBOARD_FAB2_LIB.BASEBOARD_FAB2(SCH_1):GND
 191    GND VSS<26> @BASEBOARD_FAB2_LIB.BASEBOARD_FAB2(SCH_1):GND
 193    GND VSS<25> @BASEBOARD_FAB2_LIB.BASEBOARD_FAB2(SCH_1):GND
 195    GND VSS<24> @BASEBOARD_FAB2_LIB.BASEBOARD_FAB2(SCH_1):GND
 198    GND VSS<23> @BASEBOARD_FAB2_LIB.BASEBOARD_FAB2(SCH_1):GND
 200    GND VSS<22> @BASEBOARD_FAB2_LIB.BASEBOARD_FAB2(SCH_1):GND
 202    GND VSS<21> @BASEBOARD_FAB2_LIB.BASEBOARD_FAB2(SCH_1):GND
 239    GND VSS<20> @BASEBOARD_FAB2_LIB.BASEBOARD_FAB2(SCH_1):GND
 241    GND VSS<19> @BASEBOARD_FAB2_LIB.BASEBOARD_FAB2(SCH_1):GND
 243    GND VSS<18> @BASEBOARD_FAB2_LIB.BASEBOARD_FAB2(SCH_1):GND
 246    GND VSS<17> @BASEBOARD_FAB2_LIB.BASEBOARD_FAB2(SCH_1):GND
 248    GND VSS<16> @BASEBOARD_FAB2_LIB.BASEBOARD_FAB2(SCH_1):GND
 250    GND VSS<15> @BASEBOARD_FAB2_LIB.BASEBOARD_FAB2(SCH_1):GND
 252    GND VSS<14> @BASEBOARD_FAB2_LIB.BASEBOARD_FAB2(SCH_1):GND
 254    GND VSS<13> @BASEBOARD_FAB2_LIB.BASEBOARD_FAB2(SCH_1):GND
 257    GND VSS<12> @BASEBOARD_FAB2_LIB.BASEBOARD_FAB2(SCH_1):GND
 259    GND VSS<11> @BASEBOARD_FAB2_LIB.BASEBOARD_FAB2(SCH_1):GND
 261    GND VSS<10> @BASEBOARD_FAB2_LIB.BASEBOARD_FAB2(SCH_1):GND
 263    GND VSS<9> @BASEBOARD_FAB2_LIB.BASEBOARD_FAB2(SCH_1):GND
 265    GND VSS<8> @BASEBOARD_FAB2_LIB.BASEBOARD_FAB2(SCH_1):GND
 268    GND VSS<7> @BASEBOARD_FAB2_LIB.BASEBOARD_FAB2(SCH_1):GND
 270    GND VSS<6> @BASEBOARD_FAB2_LIB.BASEBOARD_FAB2(SCH_1):GND
 272    GND VSS<5> @BASEBOARD_FAB2_LIB.BASEBOARD_FAB2(SCH_1):GND
 274    GND VSS<4> @BASEBOARD_FAB2_LIB.BASEBOARD_FAB2(SCH_1):GND
 276    GND VSS<3> @BASEBOARD_FAB2_LIB.BASEBOARD_FAB2(SCH_1):GND
 279    GND VSS<2> @BASEBOARD_FAB2_LIB.BASEBOARD_FAB2(SCH_1):GND
 281    GND VSS<1> @BASEBOARD_FAB2_LIB.BASEBOARD_FAB2(SCH_1):GND
 283    GND VSS<0> @BASEBOARD_FAB2_LIB.BASEBOARD_FAB2(SCH_1):GND

SCONN288_H44441004_PIP-SCONN,HA  I260  J4G1
   1 P12V_NVDIMM_ABC 12V<1> @BASEBOARD_FAB2_LIB.BASEBOARD_FAB2(SCH_1):P12V_NVDIMM_ABC
 145 P12V_NVDIMM_ABC 12V<0> @BASEBOARD_FAB2_LIB.BASEBOARD_FAB2(SCH_1):P12V_NVDIMM_ABC
  59 PVDDQ_ABC VDD<25> @BASEBOARD_FAB2_LIB.BASEBOARD_FAB2(SCH_1):PVDDQ_ABC
  61 PVDDQ_ABC VDD<24> @BASEBOARD_FAB2_LIB.BASEBOARD_FAB2(SCH_1):PVDDQ_ABC
  64 PVDDQ_ABC VDD<23> @BASEBOARD_FAB2_LIB.BASEBOARD_FAB2(SCH_1):PVDDQ_ABC
  67 PVDDQ_ABC VDD<22> @BASEBOARD_FAB2_LIB.BASEBOARD_FAB2(SCH_1):PVDDQ_ABC
  70 PVDDQ_ABC VDD<21> @BASEBOARD_FAB2_LIB.BASEBOARD_FAB2(SCH_1):PVDDQ_ABC
  73 PVDDQ_ABC VDD<20> @BASEBOARD_FAB2_LIB.BASEBOARD_FAB2(SCH_1):PVDDQ_ABC
  76 PVDDQ_ABC VDD<19> @BASEBOARD_FAB2_LIB.BASEBOARD_FAB2(SCH_1):PVDDQ_ABC
  80 PVDDQ_ABC VDD<18> @BASEBOARD_FAB2_LIB.BASEBOARD_FAB2(SCH_1):PVDDQ_ABC
  83 PVDDQ_ABC VDD<17> @BASEBOARD_FAB2_LIB.BASEBOARD_FAB2(SCH_1):PVDDQ_ABC
  85 PVDDQ_ABC VDD<16> @BASEBOARD_FAB2_LIB.BASEBOARD_FAB2(SCH_1):PVDDQ_ABC
  88 PVDDQ_ABC VDD<15> @BASEBOARD_FAB2_LIB.BASEBOARD_FAB2(SCH_1):PVDDQ_ABC
  90 PVDDQ_ABC VDD<14> @BASEBOARD_FAB2_LIB.BASEBOARD_FAB2(SCH_1):PVDDQ_ABC
  92 PVDDQ_ABC VDD<13> @BASEBOARD_FAB2_LIB.BASEBOARD_FAB2(SCH_1):PVDDQ_ABC
 204 PVDDQ_ABC VDD<12> @BASEBOARD_FAB2_LIB.BASEBOARD_FAB2(SCH_1):PVDDQ_ABC
 206 PVDDQ_ABC VDD<11> @BASEBOARD_FAB2_LIB.BASEBOARD_FAB2(SCH_1):PVDDQ_ABC
 209 PVDDQ_ABC VDD<10> @BASEBOARD_FAB2_LIB.BASEBOARD_FAB2(SCH_1):PVDDQ_ABC
 212 PVDDQ_ABC VDD<9> @BASEBOARD_FAB2_LIB.BASEBOARD_FAB2(SCH_1):PVDDQ_ABC
 215 PVDDQ_ABC VDD<8> @BASEBOARD_FAB2_LIB.BASEBOARD_FAB2(SCH_1):PVDDQ_ABC
 217 PVDDQ_ABC VDD<7> @BASEBOARD_FAB2_LIB.BASEBOARD_FAB2(SCH_1):PVDDQ_ABC
 220 PVDDQ_ABC VDD<6> @BASEBOARD_FAB2_LIB.BASEBOARD_FAB2(SCH_1):PVDDQ_ABC
 223 PVDDQ_ABC VDD<5> @BASEBOARD_FAB2_LIB.BASEBOARD_FAB2(SCH_1):PVDDQ_ABC
 226 PVDDQ_ABC VDD<4> @BASEBOARD_FAB2_LIB.BASEBOARD_FAB2(SCH_1):PVDDQ_ABC
 229 PVDDQ_ABC VDD<3> @BASEBOARD_FAB2_LIB.BASEBOARD_FAB2(SCH_1):PVDDQ_ABC
 231 PVDDQ_ABC VDD<2> @BASEBOARD_FAB2_LIB.BASEBOARD_FAB2(SCH_1):PVDDQ_ABC
 233 PVDDQ_ABC VDD<1> @BASEBOARD_FAB2_LIB.BASEBOARD_FAB2(SCH_1):PVDDQ_ABC
 236 PVDDQ_ABC VDD<0> @BASEBOARD_FAB2_LIB.BASEBOARD_FAB2(SCH_1):PVDDQ_ABC
 142 PVPP_ABC VPP<4> @BASEBOARD_FAB2_LIB.BASEBOARD_FAB2(SCH_1):PVPP_ABC
 143 PVPP_ABC VPP<3> @BASEBOARD_FAB2_LIB.BASEBOARD_FAB2(SCH_1):PVPP_ABC
 288 PVPP_ABC VPP<2> @BASEBOARD_FAB2_LIB.BASEBOARD_FAB2(SCH_1):PVPP_ABC
 286 PVPP_ABC VPP<1> @BASEBOARD_FAB2_LIB.BASEBOARD_FAB2(SCH_1):PVPP_ABC
 287 PVPP_ABC VPP<0> @BASEBOARD_FAB2_LIB.BASEBOARD_FAB2(SCH_1):PVPP_ABC
  77 PVTT_ABC VTT<1> @BASEBOARD_FAB2_LIB.BASEBOARD_FAB2(SCH_1):PVTT_ABC
 221 PVTT_ABC VTT<0> @BASEBOARD_FAB2_LIB.BASEBOARD_FAB2(SCH_1):PVTT_ABC

CAP_A_0402V-0.01UF,25V,10%,X7RA  I272  C4F10
   1 M_A_VREF      A @BASEBOARD_FAB2_LIB.BASEBOARD_FAB2(SCH_1):M_A_VREF
   2    GND      B @BASEBOARD_FAB2_LIB.BASEBOARD_FAB2(SCH_1):GND


DRAWING: @BASEBOARD_FAB2_LIB.BASEBOARD_FAB2(SCH_1):PAGE44 

CAP_A_0402V-0.01UF,25V,10%,X7RA  I2  C6T1
   1 M_A_VREF      A @BASEBOARD_FAB2_LIB.BASEBOARD_FAB2(SCH_1):M_A_VREF
   2    GND      B @BASEBOARD_FAB2_LIB.BASEBOARD_FAB2(SCH_1):GND

SCONN288_H44441003_PIP-SCONN,HA  I13  J6T1
  79 M_A_MA<0>     A0 @BASEBOARD_FAB2_LIB.BASEBOARD_FAB2(SCH_1):M_A_MA(0)
  72 M_A_MA<1>     A1 @BASEBOARD_FAB2_LIB.BASEBOARD_FAB2(SCH_1):M_A_MA(1)
 225 M_A_MA<10>    A10 @BASEBOARD_FAB2_LIB.BASEBOARD_FAB2(SCH_1):M_A_MA(10)
 210 M_A_MA<11>    A11 @BASEBOARD_FAB2_LIB.BASEBOARD_FAB2(SCH_1):M_A_MA(11)
  65 M_A_MA<12>    A12 @BASEBOARD_FAB2_LIB.BASEBOARD_FAB2(SCH_1):M_A_MA(12)
 232 M_A_MA<13>    A13 @BASEBOARD_FAB2_LIB.BASEBOARD_FAB2(SCH_1):M_A_MA(13)
 228 M_A_MA<14> A14_WE_N @BASEBOARD_FAB2_LIB.BASEBOARD_FAB2(SCH_1):M_A_MA(14)
  86 M_A_MA<15> A15_CAS_N @BASEBOARD_FAB2_LIB.BASEBOARD_FAB2(SCH_1):M_A_MA(15)
  82 M_A_MA<16> A16_RAS_N @BASEBOARD_FAB2_LIB.BASEBOARD_FAB2(SCH_1):M_A_MA(16)
 234 M_A_MA<17>    A17 @BASEBOARD_FAB2_LIB.BASEBOARD_FAB2(SCH_1):M_A_MA(17)
 216 M_A_MA<2>     A2 @BASEBOARD_FAB2_LIB.BASEBOARD_FAB2(SCH_1):M_A_MA(2)
  71 M_A_MA<3>     A3 @BASEBOARD_FAB2_LIB.BASEBOARD_FAB2(SCH_1):M_A_MA(3)
 214 M_A_MA<4>     A4 @BASEBOARD_FAB2_LIB.BASEBOARD_FAB2(SCH_1):M_A_MA(4)
 213 M_A_MA<5>     A5 @BASEBOARD_FAB2_LIB.BASEBOARD_FAB2(SCH_1):M_A_MA(5)
  69 M_A_MA<6>     A6 @BASEBOARD_FAB2_LIB.BASEBOARD_FAB2(SCH_1):M_A_MA(6)
 211 M_A_MA<7>     A7 @BASEBOARD_FAB2_LIB.BASEBOARD_FAB2(SCH_1):M_A_MA(7)
  68 M_A_MA<8>     A8 @BASEBOARD_FAB2_LIB.BASEBOARD_FAB2(SCH_1):M_A_MA(8)
  66 M_A_MA<9>     A9 @BASEBOARD_FAB2_LIB.BASEBOARD_FAB2(SCH_1):M_A_MA(9)
  62 M_A_ACT_N  ACT_N @BASEBOARD_FAB2_LIB.BASEBOARD_FAB2(SCH_1):M_A_ACT_N
 208 M_A_ALERT_N ALERT_N @BASEBOARD_FAB2_LIB.BASEBOARD_FAB2(SCH_1):M_A_ALERT_N
 224 M_A_BA<1>  BA<1> @BASEBOARD_FAB2_LIB.BASEBOARD_FAB2(SCH_1):M_A_BA(1)
  81 M_A_BA<0>  BA<0> @BASEBOARD_FAB2_LIB.BASEBOARD_FAB2(SCH_1):M_A_BA(0)
 207 M_A_BG<1>  BG<1> @BASEBOARD_FAB2_LIB.BASEBOARD_FAB2(SCH_1):M_A_BG(1)
  63 M_A_BG<0>  BG<0> @BASEBOARD_FAB2_LIB.BASEBOARD_FAB2(SCH_1):M_A_BG(0)
 235 M_A_C<2>   C<2> @BASEBOARD_FAB2_LIB.BASEBOARD_FAB2(SCH_1):M_A_C(2)
 199 M_A_ECC<7>  CB<7> @BASEBOARD_FAB2_LIB.BASEBOARD_FAB2(SCH_1):M_A_ECC(7)
  54 M_A_ECC<6>  CB<6> @BASEBOARD_FAB2_LIB.BASEBOARD_FAB2(SCH_1):M_A_ECC(6)
 192 M_A_ECC<5>  CB<5> @BASEBOARD_FAB2_LIB.BASEBOARD_FAB2(SCH_1):M_A_ECC(5)
  47 M_A_ECC<4>  CB<4> @BASEBOARD_FAB2_LIB.BASEBOARD_FAB2(SCH_1):M_A_ECC(4)
 201 M_A_ECC<3>  CB<3> @BASEBOARD_FAB2_LIB.BASEBOARD_FAB2(SCH_1):M_A_ECC(3)
  56 M_A_ECC<2>  CB<2> @BASEBOARD_FAB2_LIB.BASEBOARD_FAB2(SCH_1):M_A_ECC(2)
 194 M_A_ECC<1>  CB<1> @BASEBOARD_FAB2_LIB.BASEBOARD_FAB2(SCH_1):M_A_ECC(1)
  49 M_A_ECC<0>  CB<0> @BASEBOARD_FAB2_LIB.BASEBOARD_FAB2(SCH_1):M_A_ECC(0)
  75 M_A_CLK_DN<2>   CK0N @BASEBOARD_FAB2_LIB.BASEBOARD_FAB2(SCH_1):M_A_CLK_DN(2)
  74 M_A_CLK_DP<2>   CK0P @BASEBOARD_FAB2_LIB.BASEBOARD_FAB2(SCH_1):M_A_CLK_DP(2)
 219 M_A_CLK_DN<3>   CK1N @BASEBOARD_FAB2_LIB.BASEBOARD_FAB2(SCH_1):M_A_CLK_DN(3)
 218 M_A_CLK_DP<3>   CK1P @BASEBOARD_FAB2_LIB.BASEBOARD_FAB2(SCH_1):M_A_CLK_DP(3)
 203 M_A_CKE<3> CKE<1> @BASEBOARD_FAB2_LIB.BASEBOARD_FAB2(SCH_1):M_A_CKE(3)
  60 M_A_CKE<2> CKE<0> @BASEBOARD_FAB2_LIB.BASEBOARD_FAB2(SCH_1):M_A_CKE(2)
 280 M_A_DQ<63> DQ<63> @BASEBOARD_FAB2_LIB.BASEBOARD_FAB2(SCH_1):M_A_DQ(63)
 135 M_A_DQ<62> DQ<62> @BASEBOARD_FAB2_LIB.BASEBOARD_FAB2(SCH_1):M_A_DQ(62)
 273 M_A_DQ<61> DQ<61> @BASEBOARD_FAB2_LIB.BASEBOARD_FAB2(SCH_1):M_A_DQ(61)
 128 M_A_DQ<60> DQ<60> @BASEBOARD_FAB2_LIB.BASEBOARD_FAB2(SCH_1):M_A_DQ(60)
 282 M_A_DQ<59> DQ<59> @BASEBOARD_FAB2_LIB.BASEBOARD_FAB2(SCH_1):M_A_DQ(59)
 137 M_A_DQ<58> DQ<58> @BASEBOARD_FAB2_LIB.BASEBOARD_FAB2(SCH_1):M_A_DQ(58)
 275 M_A_DQ<57> DQ<57> @BASEBOARD_FAB2_LIB.BASEBOARD_FAB2(SCH_1):M_A_DQ(57)
 130 M_A_DQ<56> DQ<56> @BASEBOARD_FAB2_LIB.BASEBOARD_FAB2(SCH_1):M_A_DQ(56)
 269 M_A_DQ<55> DQ<55> @BASEBOARD_FAB2_LIB.BASEBOARD_FAB2(SCH_1):M_A_DQ(55)
 124 M_A_DQ<54> DQ<54> @BASEBOARD_FAB2_LIB.BASEBOARD_FAB2(SCH_1):M_A_DQ(54)
 262 M_A_DQ<53> DQ<53> @BASEBOARD_FAB2_LIB.BASEBOARD_FAB2(SCH_1):M_A_DQ(53)
 117 M_A_DQ<52> DQ<52> @BASEBOARD_FAB2_LIB.BASEBOARD_FAB2(SCH_1):M_A_DQ(52)
 271 M_A_DQ<51> DQ<51> @BASEBOARD_FAB2_LIB.BASEBOARD_FAB2(SCH_1):M_A_DQ(51)
 126 M_A_DQ<50> DQ<50> @BASEBOARD_FAB2_LIB.BASEBOARD_FAB2(SCH_1):M_A_DQ(50)
 264 M_A_DQ<49> DQ<49> @BASEBOARD_FAB2_LIB.BASEBOARD_FAB2(SCH_1):M_A_DQ(49)
 119 M_A_DQ<48> DQ<48> @BASEBOARD_FAB2_LIB.BASEBOARD_FAB2(SCH_1):M_A_DQ(48)
 258 M_A_DQ<47> DQ<47> @BASEBOARD_FAB2_LIB.BASEBOARD_FAB2(SCH_1):M_A_DQ(47)
 113 M_A_DQ<46> DQ<46> @BASEBOARD_FAB2_LIB.BASEBOARD_FAB2(SCH_1):M_A_DQ(46)
 251 M_A_DQ<45> DQ<45> @BASEBOARD_FAB2_LIB.BASEBOARD_FAB2(SCH_1):M_A_DQ(45)
 106 M_A_DQ<44> DQ<44> @BASEBOARD_FAB2_LIB.BASEBOARD_FAB2(SCH_1):M_A_DQ(44)
 260 M_A_DQ<43> DQ<43> @BASEBOARD_FAB2_LIB.BASEBOARD_FAB2(SCH_1):M_A_DQ(43)
 115 M_A_DQ<42> DQ<42> @BASEBOARD_FAB2_LIB.BASEBOARD_FAB2(SCH_1):M_A_DQ(42)
 253 M_A_DQ<41> DQ<41> @BASEBOARD_FAB2_LIB.BASEBOARD_FAB2(SCH_1):M_A_DQ(41)
 108 M_A_DQ<40> DQ<40> @BASEBOARD_FAB2_LIB.BASEBOARD_FAB2(SCH_1):M_A_DQ(40)
 247 M_A_DQ<39> DQ<39> @BASEBOARD_FAB2_LIB.BASEBOARD_FAB2(SCH_1):M_A_DQ(39)
 102 M_A_DQ<38> DQ<38> @BASEBOARD_FAB2_LIB.BASEBOARD_FAB2(SCH_1):M_A_DQ(38)
 240 M_A_DQ<37> DQ<37> @BASEBOARD_FAB2_LIB.BASEBOARD_FAB2(SCH_1):M_A_DQ(37)
  95 M_A_DQ<36> DQ<36> @BASEBOARD_FAB2_LIB.BASEBOARD_FAB2(SCH_1):M_A_DQ(36)
 249 M_A_DQ<35> DQ<35> @BASEBOARD_FAB2_LIB.BASEBOARD_FAB2(SCH_1):M_A_DQ(35)
 104 M_A_DQ<34> DQ<34> @BASEBOARD_FAB2_LIB.BASEBOARD_FAB2(SCH_1):M_A_DQ(34)
 242 M_A_DQ<33> DQ<33> @BASEBOARD_FAB2_LIB.BASEBOARD_FAB2(SCH_1):M_A_DQ(33)
  97 M_A_DQ<32> DQ<32> @BASEBOARD_FAB2_LIB.BASEBOARD_FAB2(SCH_1):M_A_DQ(32)
 188 M_A_DQ<31> DQ<31> @BASEBOARD_FAB2_LIB.BASEBOARD_FAB2(SCH_1):M_A_DQ(31)
  43 M_A_DQ<30> DQ<30> @BASEBOARD_FAB2_LIB.BASEBOARD_FAB2(SCH_1):M_A_DQ(30)
 181 M_A_DQ<29> DQ<29> @BASEBOARD_FAB2_LIB.BASEBOARD_FAB2(SCH_1):M_A_DQ(29)
  36 M_A_DQ<28> DQ<28> @BASEBOARD_FAB2_LIB.BASEBOARD_FAB2(SCH_1):M_A_DQ(28)
 190 M_A_DQ<27> DQ<27> @BASEBOARD_FAB2_LIB.BASEBOARD_FAB2(SCH_1):M_A_DQ(27)
  45 M_A_DQ<26> DQ<26> @BASEBOARD_FAB2_LIB.BASEBOARD_FAB2(SCH_1):M_A_DQ(26)
 183 M_A_DQ<25> DQ<25> @BASEBOARD_FAB2_LIB.BASEBOARD_FAB2(SCH_1):M_A_DQ(25)
  38 M_A_DQ<24> DQ<24> @BASEBOARD_FAB2_LIB.BASEBOARD_FAB2(SCH_1):M_A_DQ(24)
 177 M_A_DQ<23> DQ<23> @BASEBOARD_FAB2_LIB.BASEBOARD_FAB2(SCH_1):M_A_DQ(23)
  32 M_A_DQ<22> DQ<22> @BASEBOARD_FAB2_LIB.BASEBOARD_FAB2(SCH_1):M_A_DQ(22)
 170 M_A_DQ<21> DQ<21> @BASEBOARD_FAB2_LIB.BASEBOARD_FAB2(SCH_1):M_A_DQ(21)
  25 M_A_DQ<20> DQ<20> @BASEBOARD_FAB2_LIB.BASEBOARD_FAB2(SCH_1):M_A_DQ(20)
 179 M_A_DQ<19> DQ<19> @BASEBOARD_FAB2_LIB.BASEBOARD_FAB2(SCH_1):M_A_DQ(19)
  34 M_A_DQ<18> DQ<18> @BASEBOARD_FAB2_LIB.BASEBOARD_FAB2(SCH_1):M_A_DQ(18)
 172 M_A_DQ<17> DQ<17> @BASEBOARD_FAB2_LIB.BASEBOARD_FAB2(SCH_1):M_A_DQ(17)
  27 M_A_DQ<16> DQ<16> @BASEBOARD_FAB2_LIB.BASEBOARD_FAB2(SCH_1):M_A_DQ(16)
 166 M_A_DQ<15> DQ<15> @BASEBOARD_FAB2_LIB.BASEBOARD_FAB2(SCH_1):M_A_DQ(15)
  21 M_A_DQ<14> DQ<14> @BASEBOARD_FAB2_LIB.BASEBOARD_FAB2(SCH_1):M_A_DQ(14)
 159 M_A_DQ<13> DQ<13> @BASEBOARD_FAB2_LIB.BASEBOARD_FAB2(SCH_1):M_A_DQ(13)
  14 M_A_DQ<12> DQ<12> @BASEBOARD_FAB2_LIB.BASEBOARD_FAB2(SCH_1):M_A_DQ(12)
 168 M_A_DQ<11> DQ<11> @BASEBOARD_FAB2_LIB.BASEBOARD_FAB2(SCH_1):M_A_DQ(11)
  23 M_A_DQ<10> DQ<10> @BASEBOARD_FAB2_LIB.BASEBOARD_FAB2(SCH_1):M_A_DQ(10)
 161 M_A_DQ<9>  DQ<9> @BASEBOARD_FAB2_LIB.BASEBOARD_FAB2(SCH_1):M_A_DQ(9)
  16 M_A_DQ<8>  DQ<8> @BASEBOARD_FAB2_LIB.BASEBOARD_FAB2(SCH_1):M_A_DQ(8)
 155 M_A_DQ<7>  DQ<7> @BASEBOARD_FAB2_LIB.BASEBOARD_FAB2(SCH_1):M_A_DQ(7)
  10 M_A_DQ<6>  DQ<6> @BASEBOARD_FAB2_LIB.BASEBOARD_FAB2(SCH_1):M_A_DQ(6)
 148 M_A_DQ<5>  DQ<5> @BASEBOARD_FAB2_LIB.BASEBOARD_FAB2(SCH_1):M_A_DQ(5)
   3 M_A_DQ<4>  DQ<4> @BASEBOARD_FAB2_LIB.BASEBOARD_FAB2(SCH_1):M_A_DQ(4)
 157 M_A_DQ<3>  DQ<3> @BASEBOARD_FAB2_LIB.BASEBOARD_FAB2(SCH_1):M_A_DQ(3)
  12 M_A_DQ<2>  DQ<2> @BASEBOARD_FAB2_LIB.BASEBOARD_FAB2(SCH_1):M_A_DQ(2)
 150 M_A_DQ<1>  DQ<1> @BASEBOARD_FAB2_LIB.BASEBOARD_FAB2(SCH_1):M_A_DQ(1)
   5 M_A_DQ<0>  DQ<0> @BASEBOARD_FAB2_LIB.BASEBOARD_FAB2(SCH_1):M_A_DQ(0)
  78 FM_DIMM_EVENT_COD_N EVENT_N @BASEBOARD_FAB2_LIB.BASEBOARD_FAB2(SCH_1):FM_DIMM_EVENT_COD_N
  91 M_A_ODT<3> ODT<1> @BASEBOARD_FAB2_LIB.BASEBOARD_FAB2(SCH_1):M_A_ODT(3)
  87 M_A_ODT<2> ODT<0> @BASEBOARD_FAB2_LIB.BASEBOARD_FAB2(SCH_1):M_A_ODT(2)
 222 M_A_PAR    PAR @BASEBOARD_FAB2_LIB.BASEBOARD_FAB2(SCH_1):M_A_PAR
  58 M_ABC_RST_N RESET_N @BASEBOARD_FAB2_LIB.BASEBOARD_FAB2(SCH_1):M_ABC_RST_N
 144 TP_CH_A_DIMM_A1_RFU_2 RFU<2> @BASEBOARD_FAB2_LIB.BASEBOARD_FAB2(SCH_1):TP_CH_A_DIMM_A1_RFU_2
 227 TP_CH_A_DIMM_A1_RFU_1 RFU<1> @BASEBOARD_FAB2_LIB.BASEBOARD_FAB2(SCH_1):TP_CH_A_DIMM_A1_RFU_1
 205 TP_CH_A_DIMM_A1_RFU_0 RFU<0> @BASEBOARD_FAB2_LIB.BASEBOARD_FAB2(SCH_1):TP_CH_A_DIMM_A1_RFU_0
  84 M_A_CS_N<4>   S0_N @BASEBOARD_FAB2_LIB.BASEBOARD_FAB2(SCH_1):M_A_CS_N(4)
  89 M_A_CS_N<5>   S1_N @BASEBOARD_FAB2_LIB.BASEBOARD_FAB2(SCH_1):M_A_CS_N(5)
  93 M_A_CS_N<6> S2_N_C<0> @BASEBOARD_FAB2_LIB.BASEBOARD_FAB2(SCH_1):M_A_CS_N(6)
 237 M_A_CS_N<7> S3_N_C<1> @BASEBOARD_FAB2_LIB.BASEBOARD_FAB2(SCH_1):M_A_CS_N(7)
 238    GND  SA<2> @BASEBOARD_FAB2_LIB.BASEBOARD_FAB2(SCH_1):GND
 140    GND  SA<1> @BASEBOARD_FAB2_LIB.BASEBOARD_FAB2(SCH_1):GND
 139 PVPP_ABC  SA<0> @BASEBOARD_FAB2_LIB.BASEBOARD_FAB2(SCH_1):PVPP_ABC
 230 FM_ADR_COMPLETE_ABC_N SAVE_N_NC @BASEBOARD_FAB2_LIB.BASEBOARD_FAB2(SCH_1):FM_ADR_COMPLETE_ABC_N
 141 SMB_DDR_ABC_VPP_SCL    SCL @BASEBOARD_FAB2_LIB.BASEBOARD_FAB2(SCH_1):SMB_DDR_ABC_VPP_SCL
 285 SMB_DDR_ABC_VPP_SDA    SDA @BASEBOARD_FAB2_LIB.BASEBOARD_FAB2(SCH_1):SMB_DDR_ABC_VPP_SDA
 284 PVPP_ABC VDDSPD @BASEBOARD_FAB2_LIB.BASEBOARD_FAB2(SCH_1):PVPP_ABC
 146 M_A_VREF VREFCA @BASEBOARD_FAB2_LIB.BASEBOARD_FAB2(SCH_1):M_A_VREF

SCONN288_H44441003_PIP-SCONN,HA  I75  J6T1
   1 P12V_NVDIMM_ABC 12V<1> @BASEBOARD_FAB2_LIB.BASEBOARD_FAB2(SCH_1):P12V_NVDIMM_ABC
 145 P12V_NVDIMM_ABC 12V<0> @BASEBOARD_FAB2_LIB.BASEBOARD_FAB2(SCH_1):P12V_NVDIMM_ABC
  59 PVDDQ_ABC VDD<25> @BASEBOARD_FAB2_LIB.BASEBOARD_FAB2(SCH_1):PVDDQ_ABC
  61 PVDDQ_ABC VDD<24> @BASEBOARD_FAB2_LIB.BASEBOARD_FAB2(SCH_1):PVDDQ_ABC
  64 PVDDQ_ABC VDD<23> @BASEBOARD_FAB2_LIB.BASEBOARD_FAB2(SCH_1):PVDDQ_ABC
  67 PVDDQ_ABC VDD<22> @BASEBOARD_FAB2_LIB.BASEBOARD_FAB2(SCH_1):PVDDQ_ABC
  70 PVDDQ_ABC VDD<21> @BASEBOARD_FAB2_LIB.BASEBOARD_FAB2(SCH_1):PVDDQ_ABC
  73 PVDDQ_ABC VDD<20> @BASEBOARD_FAB2_LIB.BASEBOARD_FAB2(SCH_1):PVDDQ_ABC
  76 PVDDQ_ABC VDD<19> @BASEBOARD_FAB2_LIB.BASEBOARD_FAB2(SCH_1):PVDDQ_ABC
  80 PVDDQ_ABC VDD<18> @BASEBOARD_FAB2_LIB.BASEBOARD_FAB2(SCH_1):PVDDQ_ABC
  83 PVDDQ_ABC VDD<17> @BASEBOARD_FAB2_LIB.BASEBOARD_FAB2(SCH_1):PVDDQ_ABC
  85 PVDDQ_ABC VDD<16> @BASEBOARD_FAB2_LIB.BASEBOARD_FAB2(SCH_1):PVDDQ_ABC
  88 PVDDQ_ABC VDD<15> @BASEBOARD_FAB2_LIB.BASEBOARD_FAB2(SCH_1):PVDDQ_ABC
  90 PVDDQ_ABC VDD<14> @BASEBOARD_FAB2_LIB.BASEBOARD_FAB2(SCH_1):PVDDQ_ABC
  92 PVDDQ_ABC VDD<13> @BASEBOARD_FAB2_LIB.BASEBOARD_FAB2(SCH_1):PVDDQ_ABC
 204 PVDDQ_ABC VDD<12> @BASEBOARD_FAB2_LIB.BASEBOARD_FAB2(SCH_1):PVDDQ_ABC
 206 PVDDQ_ABC VDD<11> @BASEBOARD_FAB2_LIB.BASEBOARD_FAB2(SCH_1):PVDDQ_ABC
 209 PVDDQ_ABC VDD<10> @BASEBOARD_FAB2_LIB.BASEBOARD_FAB2(SCH_1):PVDDQ_ABC
 212 PVDDQ_ABC VDD<9> @BASEBOARD_FAB2_LIB.BASEBOARD_FAB2(SCH_1):PVDDQ_ABC
 215 PVDDQ_ABC VDD<8> @BASEBOARD_FAB2_LIB.BASEBOARD_FAB2(SCH_1):PVDDQ_ABC
 217 PVDDQ_ABC VDD<7> @BASEBOARD_FAB2_LIB.BASEBOARD_FAB2(SCH_1):PVDDQ_ABC
 220 PVDDQ_ABC VDD<6> @BASEBOARD_FAB2_LIB.BASEBOARD_FAB2(SCH_1):PVDDQ_ABC
 223 PVDDQ_ABC VDD<5> @BASEBOARD_FAB2_LIB.BASEBOARD_FAB2(SCH_1):PVDDQ_ABC
 226 PVDDQ_ABC VDD<4> @BASEBOARD_FAB2_LIB.BASEBOARD_FAB2(SCH_1):PVDDQ_ABC
 229 PVDDQ_ABC VDD<3> @BASEBOARD_FAB2_LIB.BASEBOARD_FAB2(SCH_1):PVDDQ_ABC
 231 PVDDQ_ABC VDD<2> @BASEBOARD_FAB2_LIB.BASEBOARD_FAB2(SCH_1):PVDDQ_ABC
 233 PVDDQ_ABC VDD<1> @BASEBOARD_FAB2_LIB.BASEBOARD_FAB2(SCH_1):PVDDQ_ABC
 236 PVDDQ_ABC VDD<0> @BASEBOARD_FAB2_LIB.BASEBOARD_FAB2(SCH_1):PVDDQ_ABC
 142 PVPP_ABC VPP<4> @BASEBOARD_FAB2_LIB.BASEBOARD_FAB2(SCH_1):PVPP_ABC
 143 PVPP_ABC VPP<3> @BASEBOARD_FAB2_LIB.BASEBOARD_FAB2(SCH_1):PVPP_ABC
 288 PVPP_ABC VPP<2> @BASEBOARD_FAB2_LIB.BASEBOARD_FAB2(SCH_1):PVPP_ABC
 286 PVPP_ABC VPP<1> @BASEBOARD_FAB2_LIB.BASEBOARD_FAB2(SCH_1):PVPP_ABC
 287 PVPP_ABC VPP<0> @BASEBOARD_FAB2_LIB.BASEBOARD_FAB2(SCH_1):PVPP_ABC
  77 PVTT_ABC VTT<1> @BASEBOARD_FAB2_LIB.BASEBOARD_FAB2(SCH_1):PVTT_ABC
 221 PVTT_ABC VTT<0> @BASEBOARD_FAB2_LIB.BASEBOARD_FAB2(SCH_1):PVTT_ABC

SCONN288_H44441003_PIP-SCONN,HA  I120  J6T1
 152 M_A_DQS_DN<0>  DQS0N @BASEBOARD_FAB2_LIB.BASEBOARD_FAB2(SCH_1):M_A_DQS_DN(0)
 153 M_A_DQS_DP<0>  DQS0P @BASEBOARD_FAB2_LIB.BASEBOARD_FAB2(SCH_1):M_A_DQS_DP(0)
  19 M_A_DQS_DN<10> DQS10N @BASEBOARD_FAB2_LIB.BASEBOARD_FAB2(SCH_1):M_A_DQS_DN(10)
  18 M_A_DQS_DP<10> DQS10P @BASEBOARD_FAB2_LIB.BASEBOARD_FAB2(SCH_1):M_A_DQS_DP(10)
  30 M_A_DQS_DN<11> DQS11N @BASEBOARD_FAB2_LIB.BASEBOARD_FAB2(SCH_1):M_A_DQS_DN(11)
  29 M_A_DQS_DP<11> DQS11P @BASEBOARD_FAB2_LIB.BASEBOARD_FAB2(SCH_1):M_A_DQS_DP(11)
  41 M_A_DQS_DN<12> DQS12N @BASEBOARD_FAB2_LIB.BASEBOARD_FAB2(SCH_1):M_A_DQS_DN(12)
  40 M_A_DQS_DP<12> DQS12P @BASEBOARD_FAB2_LIB.BASEBOARD_FAB2(SCH_1):M_A_DQS_DP(12)
 100 M_A_DQS_DN<13> DQS13N @BASEBOARD_FAB2_LIB.BASEBOARD_FAB2(SCH_1):M_A_DQS_DN(13)
  99 M_A_DQS_DP<13> DQS13P @BASEBOARD_FAB2_LIB.BASEBOARD_FAB2(SCH_1):M_A_DQS_DP(13)
 111 M_A_DQS_DN<14> DQS14N @BASEBOARD_FAB2_LIB.BASEBOARD_FAB2(SCH_1):M_A_DQS_DN(14)
 110 M_A_DQS_DP<14> DQS14P @BASEBOARD_FAB2_LIB.BASEBOARD_FAB2(SCH_1):M_A_DQS_DP(14)
 122 M_A_DQS_DN<15> DQS15N @BASEBOARD_FAB2_LIB.BASEBOARD_FAB2(SCH_1):M_A_DQS_DN(15)
 121 M_A_DQS_DP<15> DQS15P @BASEBOARD_FAB2_LIB.BASEBOARD_FAB2(SCH_1):M_A_DQS_DP(15)
 133 M_A_DQS_DN<16> DQS16N @BASEBOARD_FAB2_LIB.BASEBOARD_FAB2(SCH_1):M_A_DQS_DN(16)
 132 M_A_DQS_DP<16> DQS16P @BASEBOARD_FAB2_LIB.BASEBOARD_FAB2(SCH_1):M_A_DQS_DP(16)
  52 M_A_DQS_DN<17> DQS17N @BASEBOARD_FAB2_LIB.BASEBOARD_FAB2(SCH_1):M_A_DQS_DN(17)
  51 M_A_DQS_DP<17> DQS17P @BASEBOARD_FAB2_LIB.BASEBOARD_FAB2(SCH_1):M_A_DQS_DP(17)
 163 M_A_DQS_DN<1>  DQS1N @BASEBOARD_FAB2_LIB.BASEBOARD_FAB2(SCH_1):M_A_DQS_DN(1)
 164 M_A_DQS_DP<1>  DQS1P @BASEBOARD_FAB2_LIB.BASEBOARD_FAB2(SCH_1):M_A_DQS_DP(1)
 174 M_A_DQS_DN<2>  DQS2N @BASEBOARD_FAB2_LIB.BASEBOARD_FAB2(SCH_1):M_A_DQS_DN(2)
 175 M_A_DQS_DP<2>  DQS2P @BASEBOARD_FAB2_LIB.BASEBOARD_FAB2(SCH_1):M_A_DQS_DP(2)
 185 M_A_DQS_DN<3>  DQS3N @BASEBOARD_FAB2_LIB.BASEBOARD_FAB2(SCH_1):M_A_DQS_DN(3)
 186 M_A_DQS_DP<3>  DQS3P @BASEBOARD_FAB2_LIB.BASEBOARD_FAB2(SCH_1):M_A_DQS_DP(3)
 244 M_A_DQS_DN<4>  DQS4N @BASEBOARD_FAB2_LIB.BASEBOARD_FAB2(SCH_1):M_A_DQS_DN(4)
 245 M_A_DQS_DP<4>  DQS4P @BASEBOARD_FAB2_LIB.BASEBOARD_FAB2(SCH_1):M_A_DQS_DP(4)
 255 M_A_DQS_DN<5>  DQS5N @BASEBOARD_FAB2_LIB.BASEBOARD_FAB2(SCH_1):M_A_DQS_DN(5)
 256 M_A_DQS_DP<5>  DQS5P @BASEBOARD_FAB2_LIB.BASEBOARD_FAB2(SCH_1):M_A_DQS_DP(5)
 266 M_A_DQS_DN<6>  DQS6N @BASEBOARD_FAB2_LIB.BASEBOARD_FAB2(SCH_1):M_A_DQS_DN(6)
 267 M_A_DQS_DP<6>  DQS6P @BASEBOARD_FAB2_LIB.BASEBOARD_FAB2(SCH_1):M_A_DQS_DP(6)
 277 M_A_DQS_DN<7>  DQS7N @BASEBOARD_FAB2_LIB.BASEBOARD_FAB2(SCH_1):M_A_DQS_DN(7)
 278 M_A_DQS_DP<7>  DQS7P @BASEBOARD_FAB2_LIB.BASEBOARD_FAB2(SCH_1):M_A_DQS_DP(7)
 196 M_A_DQS_DN<8>  DQS8N @BASEBOARD_FAB2_LIB.BASEBOARD_FAB2(SCH_1):M_A_DQS_DN(8)
 197 M_A_DQS_DP<8>  DQS8P @BASEBOARD_FAB2_LIB.BASEBOARD_FAB2(SCH_1):M_A_DQS_DP(8)
   8 M_A_DQS_DN<9>  DQS9N @BASEBOARD_FAB2_LIB.BASEBOARD_FAB2(SCH_1):M_A_DQS_DN(9)
   7 M_A_DQS_DP<9>  DQS9P @BASEBOARD_FAB2_LIB.BASEBOARD_FAB2(SCH_1):M_A_DQS_DP(9)

SCONN288_H44441003_PIP-SCONN,HA  I139  J6T1
   2    GND VSS<93> @BASEBOARD_FAB2_LIB.BASEBOARD_FAB2(SCH_1):GND
   4    GND VSS<92> @BASEBOARD_FAB2_LIB.BASEBOARD_FAB2(SCH_1):GND
   6    GND VSS<91> @BASEBOARD_FAB2_LIB.BASEBOARD_FAB2(SCH_1):GND
   9    GND VSS<90> @BASEBOARD_FAB2_LIB.BASEBOARD_FAB2(SCH_1):GND
  11    GND VSS<89> @BASEBOARD_FAB2_LIB.BASEBOARD_FAB2(SCH_1):GND
  13    GND VSS<88> @BASEBOARD_FAB2_LIB.BASEBOARD_FAB2(SCH_1):GND
  15    GND VSS<87> @BASEBOARD_FAB2_LIB.BASEBOARD_FAB2(SCH_1):GND
  17    GND VSS<86> @BASEBOARD_FAB2_LIB.BASEBOARD_FAB2(SCH_1):GND
  20    GND VSS<85> @BASEBOARD_FAB2_LIB.BASEBOARD_FAB2(SCH_1):GND
  22    GND VSS<84> @BASEBOARD_FAB2_LIB.BASEBOARD_FAB2(SCH_1):GND
  24    GND VSS<83> @BASEBOARD_FAB2_LIB.BASEBOARD_FAB2(SCH_1):GND
  26    GND VSS<82> @BASEBOARD_FAB2_LIB.BASEBOARD_FAB2(SCH_1):GND
  28    GND VSS<81> @BASEBOARD_FAB2_LIB.BASEBOARD_FAB2(SCH_1):GND
  31    GND VSS<80> @BASEBOARD_FAB2_LIB.BASEBOARD_FAB2(SCH_1):GND
  33    GND VSS<79> @BASEBOARD_FAB2_LIB.BASEBOARD_FAB2(SCH_1):GND
  35    GND VSS<78> @BASEBOARD_FAB2_LIB.BASEBOARD_FAB2(SCH_1):GND
  37    GND VSS<77> @BASEBOARD_FAB2_LIB.BASEBOARD_FAB2(SCH_1):GND
  39    GND VSS<76> @BASEBOARD_FAB2_LIB.BASEBOARD_FAB2(SCH_1):GND
  42    GND VSS<75> @BASEBOARD_FAB2_LIB.BASEBOARD_FAB2(SCH_1):GND
  44    GND VSS<74> @BASEBOARD_FAB2_LIB.BASEBOARD_FAB2(SCH_1):GND
  46    GND VSS<73> @BASEBOARD_FAB2_LIB.BASEBOARD_FAB2(SCH_1):GND
  48    GND VSS<72> @BASEBOARD_FAB2_LIB.BASEBOARD_FAB2(SCH_1):GND
  50    GND VSS<71> @BASEBOARD_FAB2_LIB.BASEBOARD_FAB2(SCH_1):GND
  53    GND VSS<70> @BASEBOARD_FAB2_LIB.BASEBOARD_FAB2(SCH_1):GND
  55    GND VSS<69> @BASEBOARD_FAB2_LIB.BASEBOARD_FAB2(SCH_1):GND
  57    GND VSS<68> @BASEBOARD_FAB2_LIB.BASEBOARD_FAB2(SCH_1):GND
  94    GND VSS<67> @BASEBOARD_FAB2_LIB.BASEBOARD_FAB2(SCH_1):GND
  96    GND VSS<66> @BASEBOARD_FAB2_LIB.BASEBOARD_FAB2(SCH_1):GND
  98    GND VSS<65> @BASEBOARD_FAB2_LIB.BASEBOARD_FAB2(SCH_1):GND
 101    GND VSS<64> @BASEBOARD_FAB2_LIB.BASEBOARD_FAB2(SCH_1):GND
 103    GND VSS<63> @BASEBOARD_FAB2_LIB.BASEBOARD_FAB2(SCH_1):GND
 105    GND VSS<62> @BASEBOARD_FAB2_LIB.BASEBOARD_FAB2(SCH_1):GND
 107    GND VSS<61> @BASEBOARD_FAB2_LIB.BASEBOARD_FAB2(SCH_1):GND
 109    GND VSS<60> @BASEBOARD_FAB2_LIB.BASEBOARD_FAB2(SCH_1):GND
 112    GND VSS<59> @BASEBOARD_FAB2_LIB.BASEBOARD_FAB2(SCH_1):GND
 114    GND VSS<58> @BASEBOARD_FAB2_LIB.BASEBOARD_FAB2(SCH_1):GND
 116    GND VSS<57> @BASEBOARD_FAB2_LIB.BASEBOARD_FAB2(SCH_1):GND
 118    GND VSS<56> @BASEBOARD_FAB2_LIB.BASEBOARD_FAB2(SCH_1):GND
 120    GND VSS<55> @BASEBOARD_FAB2_LIB.BASEBOARD_FAB2(SCH_1):GND
 123    GND VSS<54> @BASEBOARD_FAB2_LIB.BASEBOARD_FAB2(SCH_1):GND
 125    GND VSS<53> @BASEBOARD_FAB2_LIB.BASEBOARD_FAB2(SCH_1):GND
 127    GND VSS<52> @BASEBOARD_FAB2_LIB.BASEBOARD_FAB2(SCH_1):GND
 129    GND VSS<51> @BASEBOARD_FAB2_LIB.BASEBOARD_FAB2(SCH_1):GND
 131    GND VSS<50> @BASEBOARD_FAB2_LIB.BASEBOARD_FAB2(SCH_1):GND
 134    GND VSS<49> @BASEBOARD_FAB2_LIB.BASEBOARD_FAB2(SCH_1):GND
 136    GND VSS<48> @BASEBOARD_FAB2_LIB.BASEBOARD_FAB2(SCH_1):GND
 138    GND VSS<47> @BASEBOARD_FAB2_LIB.BASEBOARD_FAB2(SCH_1):GND
 147    GND VSS<46> @BASEBOARD_FAB2_LIB.BASEBOARD_FAB2(SCH_1):GND
 149    GND VSS<45> @BASEBOARD_FAB2_LIB.BASEBOARD_FAB2(SCH_1):GND
 151    GND VSS<44> @BASEBOARD_FAB2_LIB.BASEBOARD_FAB2(SCH_1):GND
 154    GND VSS<43> @BASEBOARD_FAB2_LIB.BASEBOARD_FAB2(SCH_1):GND
 156    GND VSS<42> @BASEBOARD_FAB2_LIB.BASEBOARD_FAB2(SCH_1):GND
 158    GND VSS<41> @BASEBOARD_FAB2_LIB.BASEBOARD_FAB2(SCH_1):GND
 160    GND VSS<40> @BASEBOARD_FAB2_LIB.BASEBOARD_FAB2(SCH_1):GND
 162    GND VSS<39> @BASEBOARD_FAB2_LIB.BASEBOARD_FAB2(SCH_1):GND
 165    GND VSS<38> @BASEBOARD_FAB2_LIB.BASEBOARD_FAB2(SCH_1):GND
 167    GND VSS<37> @BASEBOARD_FAB2_LIB.BASEBOARD_FAB2(SCH_1):GND
 169    GND VSS<36> @BASEBOARD_FAB2_LIB.BASEBOARD_FAB2(SCH_1):GND
 171    GND VSS<35> @BASEBOARD_FAB2_LIB.BASEBOARD_FAB2(SCH_1):GND
 173    GND VSS<34> @BASEBOARD_FAB2_LIB.BASEBOARD_FAB2(SCH_1):GND
 176    GND VSS<33> @BASEBOARD_FAB2_LIB.BASEBOARD_FAB2(SCH_1):GND
 178    GND VSS<32> @BASEBOARD_FAB2_LIB.BASEBOARD_FAB2(SCH_1):GND
 180    GND VSS<31> @BASEBOARD_FAB2_LIB.BASEBOARD_FAB2(SCH_1):GND
 182    GND VSS<30> @BASEBOARD_FAB2_LIB.BASEBOARD_FAB2(SCH_1):GND
 184    GND VSS<29> @BASEBOARD_FAB2_LIB.BASEBOARD_FAB2(SCH_1):GND
 187    GND VSS<28> @BASEBOARD_FAB2_LIB.BASEBOARD_FAB2(SCH_1):GND
 189    GND VSS<27> @BASEBOARD_FAB2_LIB.BASEBOARD_FAB2(SCH_1):GND
 191    GND VSS<26> @BASEBOARD_FAB2_LIB.BASEBOARD_FAB2(SCH_1):GND
 193    GND VSS<25> @BASEBOARD_FAB2_LIB.BASEBOARD_FAB2(SCH_1):GND
 195    GND VSS<24> @BASEBOARD_FAB2_LIB.BASEBOARD_FAB2(SCH_1):GND
 198    GND VSS<23> @BASEBOARD_FAB2_LIB.BASEBOARD_FAB2(SCH_1):GND
 200    GND VSS<22> @BASEBOARD_FAB2_LIB.BASEBOARD_FAB2(SCH_1):GND
 202    GND VSS<21> @BASEBOARD_FAB2_LIB.BASEBOARD_FAB2(SCH_1):GND
 239    GND VSS<20> @BASEBOARD_FAB2_LIB.BASEBOARD_FAB2(SCH_1):GND
 241    GND VSS<19> @BASEBOARD_FAB2_LIB.BASEBOARD_FAB2(SCH_1):GND
 243    GND VSS<18> @BASEBOARD_FAB2_LIB.BASEBOARD_FAB2(SCH_1):GND
 246    GND VSS<17> @BASEBOARD_FAB2_LIB.BASEBOARD_FAB2(SCH_1):GND
 248    GND VSS<16> @BASEBOARD_FAB2_LIB.BASEBOARD_FAB2(SCH_1):GND
 250    GND VSS<15> @BASEBOARD_FAB2_LIB.BASEBOARD_FAB2(SCH_1):GND
 252    GND VSS<14> @BASEBOARD_FAB2_LIB.BASEBOARD_FAB2(SCH_1):GND
 254    GND VSS<13> @BASEBOARD_FAB2_LIB.BASEBOARD_FAB2(SCH_1):GND
 257    GND VSS<12> @BASEBOARD_FAB2_LIB.BASEBOARD_FAB2(SCH_1):GND
 259    GND VSS<11> @BASEBOARD_FAB2_LIB.BASEBOARD_FAB2(SCH_1):GND
 261    GND VSS<10> @BASEBOARD_FAB2_LIB.BASEBOARD_FAB2(SCH_1):GND
 263    GND VSS<9> @BASEBOARD_FAB2_LIB.BASEBOARD_FAB2(SCH_1):GND
 265    GND VSS<8> @BASEBOARD_FAB2_LIB.BASEBOARD_FAB2(SCH_1):GND
 268    GND VSS<7> @BASEBOARD_FAB2_LIB.BASEBOARD_FAB2(SCH_1):GND
 270    GND VSS<6> @BASEBOARD_FAB2_LIB.BASEBOARD_FAB2(SCH_1):GND
 272    GND VSS<5> @BASEBOARD_FAB2_LIB.BASEBOARD_FAB2(SCH_1):GND
 274    GND VSS<4> @BASEBOARD_FAB2_LIB.BASEBOARD_FAB2(SCH_1):GND
 276    GND VSS<3> @BASEBOARD_FAB2_LIB.BASEBOARD_FAB2(SCH_1):GND
 279    GND VSS<2> @BASEBOARD_FAB2_LIB.BASEBOARD_FAB2(SCH_1):GND
 281    GND VSS<1> @BASEBOARD_FAB2_LIB.BASEBOARD_FAB2(SCH_1):GND
 283    GND VSS<0> @BASEBOARD_FAB2_LIB.BASEBOARD_FAB2(SCH_1):GND


DRAWING: @BASEBOARD_FAB2_LIB.BASEBOARD_FAB2(SCH_1):PAGE45 

SCONN288_H44441004_PIP-SCONN,HA  I43  J4G2
   2    GND VSS<93> @BASEBOARD_FAB2_LIB.BASEBOARD_FAB2(SCH_1):GND
   4    GND VSS<92> @BASEBOARD_FAB2_LIB.BASEBOARD_FAB2(SCH_1):GND
   6    GND VSS<91> @BASEBOARD_FAB2_LIB.BASEBOARD_FAB2(SCH_1):GND
   9    GND VSS<90> @BASEBOARD_FAB2_LIB.BASEBOARD_FAB2(SCH_1):GND
  11    GND VSS<89> @BASEBOARD_FAB2_LIB.BASEBOARD_FAB2(SCH_1):GND
  13    GND VSS<88> @BASEBOARD_FAB2_LIB.BASEBOARD_FAB2(SCH_1):GND
  15    GND VSS<87> @BASEBOARD_FAB2_LIB.BASEBOARD_FAB2(SCH_1):GND
  17    GND VSS<86> @BASEBOARD_FAB2_LIB.BASEBOARD_FAB2(SCH_1):GND
  20    GND VSS<85> @BASEBOARD_FAB2_LIB.BASEBOARD_FAB2(SCH_1):GND
  22    GND VSS<84> @BASEBOARD_FAB2_LIB.BASEBOARD_FAB2(SCH_1):GND
  24    GND VSS<83> @BASEBOARD_FAB2_LIB.BASEBOARD_FAB2(SCH_1):GND
  26    GND VSS<82> @BASEBOARD_FAB2_LIB.BASEBOARD_FAB2(SCH_1):GND
  28    GND VSS<81> @BASEBOARD_FAB2_LIB.BASEBOARD_FAB2(SCH_1):GND
  31    GND VSS<80> @BASEBOARD_FAB2_LIB.BASEBOARD_FAB2(SCH_1):GND
  33    GND VSS<79> @BASEBOARD_FAB2_LIB.BASEBOARD_FAB2(SCH_1):GND
  35    GND VSS<78> @BASEBOARD_FAB2_LIB.BASEBOARD_FAB2(SCH_1):GND
  37    GND VSS<77> @BASEBOARD_FAB2_LIB.BASEBOARD_FAB2(SCH_1):GND
  39    GND VSS<76> @BASEBOARD_FAB2_LIB.BASEBOARD_FAB2(SCH_1):GND
  42    GND VSS<75> @BASEBOARD_FAB2_LIB.BASEBOARD_FAB2(SCH_1):GND
  44    GND VSS<74> @BASEBOARD_FAB2_LIB.BASEBOARD_FAB2(SCH_1):GND
  46    GND VSS<73> @BASEBOARD_FAB2_LIB.BASEBOARD_FAB2(SCH_1):GND
  48    GND VSS<72> @BASEBOARD_FAB2_LIB.BASEBOARD_FAB2(SCH_1):GND
  50    GND VSS<71> @BASEBOARD_FAB2_LIB.BASEBOARD_FAB2(SCH_1):GND
  53    GND VSS<70> @BASEBOARD_FAB2_LIB.BASEBOARD_FAB2(SCH_1):GND
  55    GND VSS<69> @BASEBOARD_FAB2_LIB.BASEBOARD_FAB2(SCH_1):GND
  57    GND VSS<68> @BASEBOARD_FAB2_LIB.BASEBOARD_FAB2(SCH_1):GND
  94    GND VSS<67> @BASEBOARD_FAB2_LIB.BASEBOARD_FAB2(SCH_1):GND
  96    GND VSS<66> @BASEBOARD_FAB2_LIB.BASEBOARD_FAB2(SCH_1):GND
  98    GND VSS<65> @BASEBOARD_FAB2_LIB.BASEBOARD_FAB2(SCH_1):GND
 101    GND VSS<64> @BASEBOARD_FAB2_LIB.BASEBOARD_FAB2(SCH_1):GND
 103    GND VSS<63> @BASEBOARD_FAB2_LIB.BASEBOARD_FAB2(SCH_1):GND
 105    GND VSS<62> @BASEBOARD_FAB2_LIB.BASEBOARD_FAB2(SCH_1):GND
 107    GND VSS<61> @BASEBOARD_FAB2_LIB.BASEBOARD_FAB2(SCH_1):GND
 109    GND VSS<60> @BASEBOARD_FAB2_LIB.BASEBOARD_FAB2(SCH_1):GND
 112    GND VSS<59> @BASEBOARD_FAB2_LIB.BASEBOARD_FAB2(SCH_1):GND
 114    GND VSS<58> @BASEBOARD_FAB2_LIB.BASEBOARD_FAB2(SCH_1):GND
 116    GND VSS<57> @BASEBOARD_FAB2_LIB.BASEBOARD_FAB2(SCH_1):GND
 118    GND VSS<56> @BASEBOARD_FAB2_LIB.BASEBOARD_FAB2(SCH_1):GND
 120    GND VSS<55> @BASEBOARD_FAB2_LIB.BASEBOARD_FAB2(SCH_1):GND
 123    GND VSS<54> @BASEBOARD_FAB2_LIB.BASEBOARD_FAB2(SCH_1):GND
 125    GND VSS<53> @BASEBOARD_FAB2_LIB.BASEBOARD_FAB2(SCH_1):GND
 127    GND VSS<52> @BASEBOARD_FAB2_LIB.BASEBOARD_FAB2(SCH_1):GND
 129    GND VSS<51> @BASEBOARD_FAB2_LIB.BASEBOARD_FAB2(SCH_1):GND
 131    GND VSS<50> @BASEBOARD_FAB2_LIB.BASEBOARD_FAB2(SCH_1):GND
 134    GND VSS<49> @BASEBOARD_FAB2_LIB.BASEBOARD_FAB2(SCH_1):GND
 136    GND VSS<48> @BASEBOARD_FAB2_LIB.BASEBOARD_FAB2(SCH_1):GND
 138    GND VSS<47> @BASEBOARD_FAB2_LIB.BASEBOARD_FAB2(SCH_1):GND
 147    GND VSS<46> @BASEBOARD_FAB2_LIB.BASEBOARD_FAB2(SCH_1):GND
 149    GND VSS<45> @BASEBOARD_FAB2_LIB.BASEBOARD_FAB2(SCH_1):GND
 151    GND VSS<44> @BASEBOARD_FAB2_LIB.BASEBOARD_FAB2(SCH_1):GND
 154    GND VSS<43> @BASEBOARD_FAB2_LIB.BASEBOARD_FAB2(SCH_1):GND
 156    GND VSS<42> @BASEBOARD_FAB2_LIB.BASEBOARD_FAB2(SCH_1):GND
 158    GND VSS<41> @BASEBOARD_FAB2_LIB.BASEBOARD_FAB2(SCH_1):GND
 160    GND VSS<40> @BASEBOARD_FAB2_LIB.BASEBOARD_FAB2(SCH_1):GND
 162    GND VSS<39> @BASEBOARD_FAB2_LIB.BASEBOARD_FAB2(SCH_1):GND
 165    GND VSS<38> @BASEBOARD_FAB2_LIB.BASEBOARD_FAB2(SCH_1):GND
 167    GND VSS<37> @BASEBOARD_FAB2_LIB.BASEBOARD_FAB2(SCH_1):GND
 169    GND VSS<36> @BASEBOARD_FAB2_LIB.BASEBOARD_FAB2(SCH_1):GND
 171    GND VSS<35> @BASEBOARD_FAB2_LIB.BASEBOARD_FAB2(SCH_1):GND
 173    GND VSS<34> @BASEBOARD_FAB2_LIB.BASEBOARD_FAB2(SCH_1):GND
 176    GND VSS<33> @BASEBOARD_FAB2_LIB.BASEBOARD_FAB2(SCH_1):GND
 178    GND VSS<32> @BASEBOARD_FAB2_LIB.BASEBOARD_FAB2(SCH_1):GND
 180    GND VSS<31> @BASEBOARD_FAB2_LIB.BASEBOARD_FAB2(SCH_1):GND
 182    GND VSS<30> @BASEBOARD_FAB2_LIB.BASEBOARD_FAB2(SCH_1):GND
 184    GND VSS<29> @BASEBOARD_FAB2_LIB.BASEBOARD_FAB2(SCH_1):GND
 187    GND VSS<28> @BASEBOARD_FAB2_LIB.BASEBOARD_FAB2(SCH_1):GND
 189    GND VSS<27> @BASEBOARD_FAB2_LIB.BASEBOARD_FAB2(SCH_1):GND
 191    GND VSS<26> @BASEBOARD_FAB2_LIB.BASEBOARD_FAB2(SCH_1):GND
 193    GND VSS<25> @BASEBOARD_FAB2_LIB.BASEBOARD_FAB2(SCH_1):GND
 195    GND VSS<24> @BASEBOARD_FAB2_LIB.BASEBOARD_FAB2(SCH_1):GND
 198    GND VSS<23> @BASEBOARD_FAB2_LIB.BASEBOARD_FAB2(SCH_1):GND
 200    GND VSS<22> @BASEBOARD_FAB2_LIB.BASEBOARD_FAB2(SCH_1):GND
 202    GND VSS<21> @BASEBOARD_FAB2_LIB.BASEBOARD_FAB2(SCH_1):GND
 239    GND VSS<20> @BASEBOARD_FAB2_LIB.BASEBOARD_FAB2(SCH_1):GND
 241    GND VSS<19> @BASEBOARD_FAB2_LIB.BASEBOARD_FAB2(SCH_1):GND
 243    GND VSS<18> @BASEBOARD_FAB2_LIB.BASEBOARD_FAB2(SCH_1):GND
 246    GND VSS<17> @BASEBOARD_FAB2_LIB.BASEBOARD_FAB2(SCH_1):GND
 248    GND VSS<16> @BASEBOARD_FAB2_LIB.BASEBOARD_FAB2(SCH_1):GND
 250    GND VSS<15> @BASEBOARD_FAB2_LIB.BASEBOARD_FAB2(SCH_1):GND
 252    GND VSS<14> @BASEBOARD_FAB2_LIB.BASEBOARD_FAB2(SCH_1):GND
 254    GND VSS<13> @BASEBOARD_FAB2_LIB.BASEBOARD_FAB2(SCH_1):GND
 257    GND VSS<12> @BASEBOARD_FAB2_LIB.BASEBOARD_FAB2(SCH_1):GND
 259    GND VSS<11> @BASEBOARD_FAB2_LIB.BASEBOARD_FAB2(SCH_1):GND
 261    GND VSS<10> @BASEBOARD_FAB2_LIB.BASEBOARD_FAB2(SCH_1):GND
 263    GND VSS<9> @BASEBOARD_FAB2_LIB.BASEBOARD_FAB2(SCH_1):GND
 265    GND VSS<8> @BASEBOARD_FAB2_LIB.BASEBOARD_FAB2(SCH_1):GND
 268    GND VSS<7> @BASEBOARD_FAB2_LIB.BASEBOARD_FAB2(SCH_1):GND
 270    GND VSS<6> @BASEBOARD_FAB2_LIB.BASEBOARD_FAB2(SCH_1):GND
 272    GND VSS<5> @BASEBOARD_FAB2_LIB.BASEBOARD_FAB2(SCH_1):GND
 274    GND VSS<4> @BASEBOARD_FAB2_LIB.BASEBOARD_FAB2(SCH_1):GND
 276    GND VSS<3> @BASEBOARD_FAB2_LIB.BASEBOARD_FAB2(SCH_1):GND
 279    GND VSS<2> @BASEBOARD_FAB2_LIB.BASEBOARD_FAB2(SCH_1):GND
 281    GND VSS<1> @BASEBOARD_FAB2_LIB.BASEBOARD_FAB2(SCH_1):GND
 283    GND VSS<0> @BASEBOARD_FAB2_LIB.BASEBOARD_FAB2(SCH_1):GND

SCONN288_H44441004_PIP-SCONN,HA  I61  J4G2
 152 M_B_DQS_DN<0>  DQS0N @BASEBOARD_FAB2_LIB.BASEBOARD_FAB2(SCH_1):M_B_DQS_DN(0)
 153 M_B_DQS_DP<0>  DQS0P @BASEBOARD_FAB2_LIB.BASEBOARD_FAB2(SCH_1):M_B_DQS_DP(0)
  19 M_B_DQS_DN<10> DQS10N @BASEBOARD_FAB2_LIB.BASEBOARD_FAB2(SCH_1):M_B_DQS_DN(10)
  18 M_B_DQS_DP<10> DQS10P @BASEBOARD_FAB2_LIB.BASEBOARD_FAB2(SCH_1):M_B_DQS_DP(10)
  30 M_B_DQS_DN<11> DQS11N @BASEBOARD_FAB2_LIB.BASEBOARD_FAB2(SCH_1):M_B_DQS_DN(11)
  29 M_B_DQS_DP<11> DQS11P @BASEBOARD_FAB2_LIB.BASEBOARD_FAB2(SCH_1):M_B_DQS_DP(11)
  41 M_B_DQS_DN<12> DQS12N @BASEBOARD_FAB2_LIB.BASEBOARD_FAB2(SCH_1):M_B_DQS_DN(12)
  40 M_B_DQS_DP<12> DQS12P @BASEBOARD_FAB2_LIB.BASEBOARD_FAB2(SCH_1):M_B_DQS_DP(12)
 100 M_B_DQS_DN<13> DQS13N @BASEBOARD_FAB2_LIB.BASEBOARD_FAB2(SCH_1):M_B_DQS_DN(13)
  99 M_B_DQS_DP<13> DQS13P @BASEBOARD_FAB2_LIB.BASEBOARD_FAB2(SCH_1):M_B_DQS_DP(13)
 111 M_B_DQS_DN<14> DQS14N @BASEBOARD_FAB2_LIB.BASEBOARD_FAB2(SCH_1):M_B_DQS_DN(14)
 110 M_B_DQS_DP<14> DQS14P @BASEBOARD_FAB2_LIB.BASEBOARD_FAB2(SCH_1):M_B_DQS_DP(14)
 122 M_B_DQS_DN<15> DQS15N @BASEBOARD_FAB2_LIB.BASEBOARD_FAB2(SCH_1):M_B_DQS_DN(15)
 121 M_B_DQS_DP<15> DQS15P @BASEBOARD_FAB2_LIB.BASEBOARD_FAB2(SCH_1):M_B_DQS_DP(15)
 133 M_B_DQS_DN<16> DQS16N @BASEBOARD_FAB2_LIB.BASEBOARD_FAB2(SCH_1):M_B_DQS_DN(16)
 132 M_B_DQS_DP<16> DQS16P @BASEBOARD_FAB2_LIB.BASEBOARD_FAB2(SCH_1):M_B_DQS_DP(16)
  52 M_B_DQS_DN<17> DQS17N @BASEBOARD_FAB2_LIB.BASEBOARD_FAB2(SCH_1):M_B_DQS_DN(17)
  51 M_B_DQS_DP<17> DQS17P @BASEBOARD_FAB2_LIB.BASEBOARD_FAB2(SCH_1):M_B_DQS_DP(17)
 163 M_B_DQS_DN<1>  DQS1N @BASEBOARD_FAB2_LIB.BASEBOARD_FAB2(SCH_1):M_B_DQS_DN(1)
 164 M_B_DQS_DP<1>  DQS1P @BASEBOARD_FAB2_LIB.BASEBOARD_FAB2(SCH_1):M_B_DQS_DP(1)
 174 M_B_DQS_DN<2>  DQS2N @BASEBOARD_FAB2_LIB.BASEBOARD_FAB2(SCH_1):M_B_DQS_DN(2)
 175 M_B_DQS_DP<2>  DQS2P @BASEBOARD_FAB2_LIB.BASEBOARD_FAB2(SCH_1):M_B_DQS_DP(2)
 185 M_B_DQS_DN<3>  DQS3N @BASEBOARD_FAB2_LIB.BASEBOARD_FAB2(SCH_1):M_B_DQS_DN(3)
 186 M_B_DQS_DP<3>  DQS3P @BASEBOARD_FAB2_LIB.BASEBOARD_FAB2(SCH_1):M_B_DQS_DP(3)
 244 M_B_DQS_DN<4>  DQS4N @BASEBOARD_FAB2_LIB.BASEBOARD_FAB2(SCH_1):M_B_DQS_DN(4)
 245 M_B_DQS_DP<4>  DQS4P @BASEBOARD_FAB2_LIB.BASEBOARD_FAB2(SCH_1):M_B_DQS_DP(4)
 255 M_B_DQS_DN<5>  DQS5N @BASEBOARD_FAB2_LIB.BASEBOARD_FAB2(SCH_1):M_B_DQS_DN(5)
 256 M_B_DQS_DP<5>  DQS5P @BASEBOARD_FAB2_LIB.BASEBOARD_FAB2(SCH_1):M_B_DQS_DP(5)
 266 M_B_DQS_DN<6>  DQS6N @BASEBOARD_FAB2_LIB.BASEBOARD_FAB2(SCH_1):M_B_DQS_DN(6)
 267 M_B_DQS_DP<6>  DQS6P @BASEBOARD_FAB2_LIB.BASEBOARD_FAB2(SCH_1):M_B_DQS_DP(6)
 277 M_B_DQS_DN<7>  DQS7N @BASEBOARD_FAB2_LIB.BASEBOARD_FAB2(SCH_1):M_B_DQS_DN(7)
 278 M_B_DQS_DP<7>  DQS7P @BASEBOARD_FAB2_LIB.BASEBOARD_FAB2(SCH_1):M_B_DQS_DP(7)
 196 M_B_DQS_DN<8>  DQS8N @BASEBOARD_FAB2_LIB.BASEBOARD_FAB2(SCH_1):M_B_DQS_DN(8)
 197 M_B_DQS_DP<8>  DQS8P @BASEBOARD_FAB2_LIB.BASEBOARD_FAB2(SCH_1):M_B_DQS_DP(8)
   8 M_B_DQS_DN<9>  DQS9N @BASEBOARD_FAB2_LIB.BASEBOARD_FAB2(SCH_1):M_B_DQS_DN(9)
   7 M_B_DQS_DP<9>  DQS9P @BASEBOARD_FAB2_LIB.BASEBOARD_FAB2(SCH_1):M_B_DQS_DP(9)

SCONN288_H44441004_PIP-SCONN,HA  I111  J4G2
  79 M_B_MA<0>     A0 @BASEBOARD_FAB2_LIB.BASEBOARD_FAB2(SCH_1):M_B_MA(0)
  72 M_B_MA<1>     A1 @BASEBOARD_FAB2_LIB.BASEBOARD_FAB2(SCH_1):M_B_MA(1)
 225 M_B_MA<10>    A10 @BASEBOARD_FAB2_LIB.BASEBOARD_FAB2(SCH_1):M_B_MA(10)
 210 M_B_MA<11>    A11 @BASEBOARD_FAB2_LIB.BASEBOARD_FAB2(SCH_1):M_B_MA(11)
  65 M_B_MA<12>    A12 @BASEBOARD_FAB2_LIB.BASEBOARD_FAB2(SCH_1):M_B_MA(12)
 232 M_B_MA<13>    A13 @BASEBOARD_FAB2_LIB.BASEBOARD_FAB2(SCH_1):M_B_MA(13)
 228 M_B_MA<14> A14_WE_N @BASEBOARD_FAB2_LIB.BASEBOARD_FAB2(SCH_1):M_B_MA(14)
  86 M_B_MA<15> A15_CAS_N @BASEBOARD_FAB2_LIB.BASEBOARD_FAB2(SCH_1):M_B_MA(15)
  82 M_B_MA<16> A16_RAS_N @BASEBOARD_FAB2_LIB.BASEBOARD_FAB2(SCH_1):M_B_MA(16)
 234 M_B_MA<17>    A17 @BASEBOARD_FAB2_LIB.BASEBOARD_FAB2(SCH_1):M_B_MA(17)
 216 M_B_MA<2>     A2 @BASEBOARD_FAB2_LIB.BASEBOARD_FAB2(SCH_1):M_B_MA(2)
  71 M_B_MA<3>     A3 @BASEBOARD_FAB2_LIB.BASEBOARD_FAB2(SCH_1):M_B_MA(3)
 214 M_B_MA<4>     A4 @BASEBOARD_FAB2_LIB.BASEBOARD_FAB2(SCH_1):M_B_MA(4)
 213 M_B_MA<5>     A5 @BASEBOARD_FAB2_LIB.BASEBOARD_FAB2(SCH_1):M_B_MA(5)
  69 M_B_MA<6>     A6 @BASEBOARD_FAB2_LIB.BASEBOARD_FAB2(SCH_1):M_B_MA(6)
 211 M_B_MA<7>     A7 @BASEBOARD_FAB2_LIB.BASEBOARD_FAB2(SCH_1):M_B_MA(7)
  68 M_B_MA<8>     A8 @BASEBOARD_FAB2_LIB.BASEBOARD_FAB2(SCH_1):M_B_MA(8)
  66 M_B_MA<9>     A9 @BASEBOARD_FAB2_LIB.BASEBOARD_FAB2(SCH_1):M_B_MA(9)
  62 M_B_ACT_N  ACT_N @BASEBOARD_FAB2_LIB.BASEBOARD_FAB2(SCH_1):M_B_ACT_N
 208 M_B_ALERT_N ALERT_N @BASEBOARD_FAB2_LIB.BASEBOARD_FAB2(SCH_1):M_B_ALERT_N
 224 M_B_BA<1>  BA<1> @BASEBOARD_FAB2_LIB.BASEBOARD_FAB2(SCH_1):M_B_BA(1)
  81 M_B_BA<0>  BA<0> @BASEBOARD_FAB2_LIB.BASEBOARD_FAB2(SCH_1):M_B_BA(0)
 207 M_B_BG<1>  BG<1> @BASEBOARD_FAB2_LIB.BASEBOARD_FAB2(SCH_1):M_B_BG(1)
  63 M_B_BG<0>  BG<0> @BASEBOARD_FAB2_LIB.BASEBOARD_FAB2(SCH_1):M_B_BG(0)
 235 M_B_C<2>   C<2> @BASEBOARD_FAB2_LIB.BASEBOARD_FAB2(SCH_1):M_B_C(2)
 199 M_B_ECC<6>  CB<7> @BASEBOARD_FAB2_LIB.BASEBOARD_FAB2(SCH_1):M_B_ECC(6)
  54 M_B_ECC<7>  CB<6> @BASEBOARD_FAB2_LIB.BASEBOARD_FAB2(SCH_1):M_B_ECC(7)
 192 M_B_ECC<4>  CB<5> @BASEBOARD_FAB2_LIB.BASEBOARD_FAB2(SCH_1):M_B_ECC(4)
  47 M_B_ECC<5>  CB<4> @BASEBOARD_FAB2_LIB.BASEBOARD_FAB2(SCH_1):M_B_ECC(5)
 201 M_B_ECC<2>  CB<3> @BASEBOARD_FAB2_LIB.BASEBOARD_FAB2(SCH_1):M_B_ECC(2)
  56 M_B_ECC<3>  CB<2> @BASEBOARD_FAB2_LIB.BASEBOARD_FAB2(SCH_1):M_B_ECC(3)
 194 M_B_ECC<0>  CB<1> @BASEBOARD_FAB2_LIB.BASEBOARD_FAB2(SCH_1):M_B_ECC(0)
  49 M_B_ECC<1>  CB<0> @BASEBOARD_FAB2_LIB.BASEBOARD_FAB2(SCH_1):M_B_ECC(1)
  75 M_B_CLK_DN<0>   CK0N @BASEBOARD_FAB2_LIB.BASEBOARD_FAB2(SCH_1):M_B_CLK_DN(0)
  74 M_B_CLK_DP<0>   CK0P @BASEBOARD_FAB2_LIB.BASEBOARD_FAB2(SCH_1):M_B_CLK_DP(0)
 219 M_B_CLK_DN<1>   CK1N @BASEBOARD_FAB2_LIB.BASEBOARD_FAB2(SCH_1):M_B_CLK_DN(1)
 218 M_B_CLK_DP<1>   CK1P @BASEBOARD_FAB2_LIB.BASEBOARD_FAB2(SCH_1):M_B_CLK_DP(1)
 203 M_B_CKE<1> CKE<1> @BASEBOARD_FAB2_LIB.BASEBOARD_FAB2(SCH_1):M_B_CKE(1)
  60 M_B_CKE<0> CKE<0> @BASEBOARD_FAB2_LIB.BASEBOARD_FAB2(SCH_1):M_B_CKE(0)
 280 M_B_DQ<62> DQ<63> @BASEBOARD_FAB2_LIB.BASEBOARD_FAB2(SCH_1):M_B_DQ(62)
 135 M_B_DQ<63> DQ<62> @BASEBOARD_FAB2_LIB.BASEBOARD_FAB2(SCH_1):M_B_DQ(63)
 273 M_B_DQ<60> DQ<61> @BASEBOARD_FAB2_LIB.BASEBOARD_FAB2(SCH_1):M_B_DQ(60)
 128 M_B_DQ<61> DQ<60> @BASEBOARD_FAB2_LIB.BASEBOARD_FAB2(SCH_1):M_B_DQ(61)
 282 M_B_DQ<58> DQ<59> @BASEBOARD_FAB2_LIB.BASEBOARD_FAB2(SCH_1):M_B_DQ(58)
 137 M_B_DQ<59> DQ<58> @BASEBOARD_FAB2_LIB.BASEBOARD_FAB2(SCH_1):M_B_DQ(59)
 275 M_B_DQ<56> DQ<57> @BASEBOARD_FAB2_LIB.BASEBOARD_FAB2(SCH_1):M_B_DQ(56)
 130 M_B_DQ<57> DQ<56> @BASEBOARD_FAB2_LIB.BASEBOARD_FAB2(SCH_1):M_B_DQ(57)
 269 M_B_DQ<54> DQ<55> @BASEBOARD_FAB2_LIB.BASEBOARD_FAB2(SCH_1):M_B_DQ(54)
 124 M_B_DQ<55> DQ<54> @BASEBOARD_FAB2_LIB.BASEBOARD_FAB2(SCH_1):M_B_DQ(55)
 262 M_B_DQ<52> DQ<53> @BASEBOARD_FAB2_LIB.BASEBOARD_FAB2(SCH_1):M_B_DQ(52)
 117 M_B_DQ<53> DQ<52> @BASEBOARD_FAB2_LIB.BASEBOARD_FAB2(SCH_1):M_B_DQ(53)
 271 M_B_DQ<50> DQ<51> @BASEBOARD_FAB2_LIB.BASEBOARD_FAB2(SCH_1):M_B_DQ(50)
 126 M_B_DQ<51> DQ<50> @BASEBOARD_FAB2_LIB.BASEBOARD_FAB2(SCH_1):M_B_DQ(51)
 264 M_B_DQ<48> DQ<49> @BASEBOARD_FAB2_LIB.BASEBOARD_FAB2(SCH_1):M_B_DQ(48)
 119 M_B_DQ<49> DQ<48> @BASEBOARD_FAB2_LIB.BASEBOARD_FAB2(SCH_1):M_B_DQ(49)
 258 M_B_DQ<46> DQ<47> @BASEBOARD_FAB2_LIB.BASEBOARD_FAB2(SCH_1):M_B_DQ(46)
 113 M_B_DQ<47> DQ<46> @BASEBOARD_FAB2_LIB.BASEBOARD_FAB2(SCH_1):M_B_DQ(47)
 251 M_B_DQ<44> DQ<45> @BASEBOARD_FAB2_LIB.BASEBOARD_FAB2(SCH_1):M_B_DQ(44)
 106 M_B_DQ<45> DQ<44> @BASEBOARD_FAB2_LIB.BASEBOARD_FAB2(SCH_1):M_B_DQ(45)
 260 M_B_DQ<42> DQ<43> @BASEBOARD_FAB2_LIB.BASEBOARD_FAB2(SCH_1):M_B_DQ(42)
 115 M_B_DQ<43> DQ<42> @BASEBOARD_FAB2_LIB.BASEBOARD_FAB2(SCH_1):M_B_DQ(43)
 253 M_B_DQ<40> DQ<41> @BASEBOARD_FAB2_LIB.BASEBOARD_FAB2(SCH_1):M_B_DQ(40)
 108 M_B_DQ<41> DQ<40> @BASEBOARD_FAB2_LIB.BASEBOARD_FAB2(SCH_1):M_B_DQ(41)
 247 M_B_DQ<38> DQ<39> @BASEBOARD_FAB2_LIB.BASEBOARD_FAB2(SCH_1):M_B_DQ(38)
 102 M_B_DQ<39> DQ<38> @BASEBOARD_FAB2_LIB.BASEBOARD_FAB2(SCH_1):M_B_DQ(39)
 240 M_B_DQ<36> DQ<37> @BASEBOARD_FAB2_LIB.BASEBOARD_FAB2(SCH_1):M_B_DQ(36)
  95 M_B_DQ<37> DQ<36> @BASEBOARD_FAB2_LIB.BASEBOARD_FAB2(SCH_1):M_B_DQ(37)
 249 M_B_DQ<34> DQ<35> @BASEBOARD_FAB2_LIB.BASEBOARD_FAB2(SCH_1):M_B_DQ(34)
 104 M_B_DQ<35> DQ<34> @BASEBOARD_FAB2_LIB.BASEBOARD_FAB2(SCH_1):M_B_DQ(35)
 242 M_B_DQ<32> DQ<33> @BASEBOARD_FAB2_LIB.BASEBOARD_FAB2(SCH_1):M_B_DQ(32)
  97 M_B_DQ<33> DQ<32> @BASEBOARD_FAB2_LIB.BASEBOARD_FAB2(SCH_1):M_B_DQ(33)
 188 M_B_DQ<30> DQ<31> @BASEBOARD_FAB2_LIB.BASEBOARD_FAB2(SCH_1):M_B_DQ(30)
  43 M_B_DQ<31> DQ<30> @BASEBOARD_FAB2_LIB.BASEBOARD_FAB2(SCH_1):M_B_DQ(31)
 181 M_B_DQ<28> DQ<29> @BASEBOARD_FAB2_LIB.BASEBOARD_FAB2(SCH_1):M_B_DQ(28)
  36 M_B_DQ<29> DQ<28> @BASEBOARD_FAB2_LIB.BASEBOARD_FAB2(SCH_1):M_B_DQ(29)
 190 M_B_DQ<26> DQ<27> @BASEBOARD_FAB2_LIB.BASEBOARD_FAB2(SCH_1):M_B_DQ(26)
  45 M_B_DQ<27> DQ<26> @BASEBOARD_FAB2_LIB.BASEBOARD_FAB2(SCH_1):M_B_DQ(27)
 183 M_B_DQ<24> DQ<25> @BASEBOARD_FAB2_LIB.BASEBOARD_FAB2(SCH_1):M_B_DQ(24)
  38 M_B_DQ<25> DQ<24> @BASEBOARD_FAB2_LIB.BASEBOARD_FAB2(SCH_1):M_B_DQ(25)
 177 M_B_DQ<22> DQ<23> @BASEBOARD_FAB2_LIB.BASEBOARD_FAB2(SCH_1):M_B_DQ(22)
  32 M_B_DQ<23> DQ<22> @BASEBOARD_FAB2_LIB.BASEBOARD_FAB2(SCH_1):M_B_DQ(23)
 170 M_B_DQ<20> DQ<21> @BASEBOARD_FAB2_LIB.BASEBOARD_FAB2(SCH_1):M_B_DQ(20)
  25 M_B_DQ<21> DQ<20> @BASEBOARD_FAB2_LIB.BASEBOARD_FAB2(SCH_1):M_B_DQ(21)
 179 M_B_DQ<18> DQ<19> @BASEBOARD_FAB2_LIB.BASEBOARD_FAB2(SCH_1):M_B_DQ(18)
  34 M_B_DQ<19> DQ<18> @BASEBOARD_FAB2_LIB.BASEBOARD_FAB2(SCH_1):M_B_DQ(19)
 172 M_B_DQ<16> DQ<17> @BASEBOARD_FAB2_LIB.BASEBOARD_FAB2(SCH_1):M_B_DQ(16)
  27 M_B_DQ<17> DQ<16> @BASEBOARD_FAB2_LIB.BASEBOARD_FAB2(SCH_1):M_B_DQ(17)
 166 M_B_DQ<14> DQ<15> @BASEBOARD_FAB2_LIB.BASEBOARD_FAB2(SCH_1):M_B_DQ(14)
  21 M_B_DQ<15> DQ<14> @BASEBOARD_FAB2_LIB.BASEBOARD_FAB2(SCH_1):M_B_DQ(15)
 159 M_B_DQ<12> DQ<13> @BASEBOARD_FAB2_LIB.BASEBOARD_FAB2(SCH_1):M_B_DQ(12)
  14 M_B_DQ<13> DQ<12> @BASEBOARD_FAB2_LIB.BASEBOARD_FAB2(SCH_1):M_B_DQ(13)
 168 M_B_DQ<10> DQ<11> @BASEBOARD_FAB2_LIB.BASEBOARD_FAB2(SCH_1):M_B_DQ(10)
  23 M_B_DQ<11> DQ<10> @BASEBOARD_FAB2_LIB.BASEBOARD_FAB2(SCH_1):M_B_DQ(11)
 161 M_B_DQ<8>  DQ<9> @BASEBOARD_FAB2_LIB.BASEBOARD_FAB2(SCH_1):M_B_DQ(8)
  16 M_B_DQ<9>  DQ<8> @BASEBOARD_FAB2_LIB.BASEBOARD_FAB2(SCH_1):M_B_DQ(9)
 155 M_B_DQ<6>  DQ<7> @BASEBOARD_FAB2_LIB.BASEBOARD_FAB2(SCH_1):M_B_DQ(6)
  10 M_B_DQ<7>  DQ<6> @BASEBOARD_FAB2_LIB.BASEBOARD_FAB2(SCH_1):M_B_DQ(7)
 148 M_B_DQ<4>  DQ<5> @BASEBOARD_FAB2_LIB.BASEBOARD_FAB2(SCH_1):M_B_DQ(4)
   3 M_B_DQ<5>  DQ<4> @BASEBOARD_FAB2_LIB.BASEBOARD_FAB2(SCH_1):M_B_DQ(5)
 157 M_B_DQ<2>  DQ<3> @BASEBOARD_FAB2_LIB.BASEBOARD_FAB2(SCH_1):M_B_DQ(2)
  12 M_B_DQ<3>  DQ<2> @BASEBOARD_FAB2_LIB.BASEBOARD_FAB2(SCH_1):M_B_DQ(3)
 150 M_B_DQ<0>  DQ<1> @BASEBOARD_FAB2_LIB.BASEBOARD_FAB2(SCH_1):M_B_DQ(0)
   5 M_B_DQ<1>  DQ<0> @BASEBOARD_FAB2_LIB.BASEBOARD_FAB2(SCH_1):M_B_DQ(1)
  78 FM_DIMM_EVENT_COD_N EVENT_N @BASEBOARD_FAB2_LIB.BASEBOARD_FAB2(SCH_1):FM_DIMM_EVENT_COD_N
  91 M_B_ODT<1> ODT<1> @BASEBOARD_FAB2_LIB.BASEBOARD_FAB2(SCH_1):M_B_ODT(1)
  87 M_B_ODT<0> ODT<0> @BASEBOARD_FAB2_LIB.BASEBOARD_FAB2(SCH_1):M_B_ODT(0)
 222 M_B_PAR    PAR @BASEBOARD_FAB2_LIB.BASEBOARD_FAB2(SCH_1):M_B_PAR
  58 M_ABC_RST_N RESET_N @BASEBOARD_FAB2_LIB.BASEBOARD_FAB2(SCH_1):M_ABC_RST_N
 144 TP_CH_B_DIMM_B0_RFU_2 RFU<2> @BASEBOARD_FAB2_LIB.BASEBOARD_FAB2(SCH_1):TP_CH_B_DIMM_B0_RFU_2
 227 TP_CH_B_DIMM_B0_RFU_1 RFU<1> @BASEBOARD_FAB2_LIB.BASEBOARD_FAB2(SCH_1):TP_CH_B_DIMM_B0_RFU_1
 205 TP_CH_B_DIMM_B0_RFU_0 RFU<0> @BASEBOARD_FAB2_LIB.BASEBOARD_FAB2(SCH_1):TP_CH_B_DIMM_B0_RFU_0
  84 M_B_CS_N<0>   S0_N @BASEBOARD_FAB2_LIB.BASEBOARD_FAB2(SCH_1):M_B_CS_N(0)
  89 M_B_CS_N<1>   S1_N @BASEBOARD_FAB2_LIB.BASEBOARD_FAB2(SCH_1):M_B_CS_N(1)
  93 M_B_CS_N<2> S2_N_C<0> @BASEBOARD_FAB2_LIB.BASEBOARD_FAB2(SCH_1):M_B_CS_N(2)
 237 M_B_CS_N<3> S3_N_C<1> @BASEBOARD_FAB2_LIB.BASEBOARD_FAB2(SCH_1):M_B_CS_N(3)
 238    GND  SA<2> @BASEBOARD_FAB2_LIB.BASEBOARD_FAB2(SCH_1):GND
 140 PVPP_ABC  SA<1> @BASEBOARD_FAB2_LIB.BASEBOARD_FAB2(SCH_1):PVPP_ABC
 139    GND  SA<0> @BASEBOARD_FAB2_LIB.BASEBOARD_FAB2(SCH_1):GND
 230 FM_ADR_COMPLETE_ABC_N SAVE_N_NC @BASEBOARD_FAB2_LIB.BASEBOARD_FAB2(SCH_1):FM_ADR_COMPLETE_ABC_N
 141 SMB_DDR_ABC_VPP_SCL    SCL @BASEBOARD_FAB2_LIB.BASEBOARD_FAB2(SCH_1):SMB_DDR_ABC_VPP_SCL
 285 SMB_DDR_ABC_VPP_SDA    SDA @BASEBOARD_FAB2_LIB.BASEBOARD_FAB2(SCH_1):SMB_DDR_ABC_VPP_SDA
 284 PVPP_ABC VDDSPD @BASEBOARD_FAB2_LIB.BASEBOARD_FAB2(SCH_1):PVPP_ABC
 146 M_B_VREF VREFCA @BASEBOARD_FAB2_LIB.BASEBOARD_FAB2(SCH_1):M_B_VREF

SCONN288_H44441004_PIP-SCONN,HA  I169  J4G2
   1 P12V_NVDIMM_ABC 12V<1> @BASEBOARD_FAB2_LIB.BASEBOARD_FAB2(SCH_1):P12V_NVDIMM_ABC
 145 P12V_NVDIMM_ABC 12V<0> @BASEBOARD_FAB2_LIB.BASEBOARD_FAB2(SCH_1):P12V_NVDIMM_ABC
  59 PVDDQ_ABC VDD<25> @BASEBOARD_FAB2_LIB.BASEBOARD_FAB2(SCH_1):PVDDQ_ABC
  61 PVDDQ_ABC VDD<24> @BASEBOARD_FAB2_LIB.BASEBOARD_FAB2(SCH_1):PVDDQ_ABC
  64 PVDDQ_ABC VDD<23> @BASEBOARD_FAB2_LIB.BASEBOARD_FAB2(SCH_1):PVDDQ_ABC
  67 PVDDQ_ABC VDD<22> @BASEBOARD_FAB2_LIB.BASEBOARD_FAB2(SCH_1):PVDDQ_ABC
  70 PVDDQ_ABC VDD<21> @BASEBOARD_FAB2_LIB.BASEBOARD_FAB2(SCH_1):PVDDQ_ABC
  73 PVDDQ_ABC VDD<20> @BASEBOARD_FAB2_LIB.BASEBOARD_FAB2(SCH_1):PVDDQ_ABC
  76 PVDDQ_ABC VDD<19> @BASEBOARD_FAB2_LIB.BASEBOARD_FAB2(SCH_1):PVDDQ_ABC
  80 PVDDQ_ABC VDD<18> @BASEBOARD_FAB2_LIB.BASEBOARD_FAB2(SCH_1):PVDDQ_ABC
  83 PVDDQ_ABC VDD<17> @BASEBOARD_FAB2_LIB.BASEBOARD_FAB2(SCH_1):PVDDQ_ABC
  85 PVDDQ_ABC VDD<16> @BASEBOARD_FAB2_LIB.BASEBOARD_FAB2(SCH_1):PVDDQ_ABC
  88 PVDDQ_ABC VDD<15> @BASEBOARD_FAB2_LIB.BASEBOARD_FAB2(SCH_1):PVDDQ_ABC
  90 PVDDQ_ABC VDD<14> @BASEBOARD_FAB2_LIB.BASEBOARD_FAB2(SCH_1):PVDDQ_ABC
  92 PVDDQ_ABC VDD<13> @BASEBOARD_FAB2_LIB.BASEBOARD_FAB2(SCH_1):PVDDQ_ABC
 204 PVDDQ_ABC VDD<12> @BASEBOARD_FAB2_LIB.BASEBOARD_FAB2(SCH_1):PVDDQ_ABC
 206 PVDDQ_ABC VDD<11> @BASEBOARD_FAB2_LIB.BASEBOARD_FAB2(SCH_1):PVDDQ_ABC
 209 PVDDQ_ABC VDD<10> @BASEBOARD_FAB2_LIB.BASEBOARD_FAB2(SCH_1):PVDDQ_ABC
 212 PVDDQ_ABC VDD<9> @BASEBOARD_FAB2_LIB.BASEBOARD_FAB2(SCH_1):PVDDQ_ABC
 215 PVDDQ_ABC VDD<8> @BASEBOARD_FAB2_LIB.BASEBOARD_FAB2(SCH_1):PVDDQ_ABC
 217 PVDDQ_ABC VDD<7> @BASEBOARD_FAB2_LIB.BASEBOARD_FAB2(SCH_1):PVDDQ_ABC
 220 PVDDQ_ABC VDD<6> @BASEBOARD_FAB2_LIB.BASEBOARD_FAB2(SCH_1):PVDDQ_ABC
 223 PVDDQ_ABC VDD<5> @BASEBOARD_FAB2_LIB.BASEBOARD_FAB2(SCH_1):PVDDQ_ABC
 226 PVDDQ_ABC VDD<4> @BASEBOARD_FAB2_LIB.BASEBOARD_FAB2(SCH_1):PVDDQ_ABC
 229 PVDDQ_ABC VDD<3> @BASEBOARD_FAB2_LIB.BASEBOARD_FAB2(SCH_1):PVDDQ_ABC
 231 PVDDQ_ABC VDD<2> @BASEBOARD_FAB2_LIB.BASEBOARD_FAB2(SCH_1):PVDDQ_ABC
 233 PVDDQ_ABC VDD<1> @BASEBOARD_FAB2_LIB.BASEBOARD_FAB2(SCH_1):PVDDQ_ABC
 236 PVDDQ_ABC VDD<0> @BASEBOARD_FAB2_LIB.BASEBOARD_FAB2(SCH_1):PVDDQ_ABC
 142 PVPP_ABC VPP<4> @BASEBOARD_FAB2_LIB.BASEBOARD_FAB2(SCH_1):PVPP_ABC
 143 PVPP_ABC VPP<3> @BASEBOARD_FAB2_LIB.BASEBOARD_FAB2(SCH_1):PVPP_ABC
 288 PVPP_ABC VPP<2> @BASEBOARD_FAB2_LIB.BASEBOARD_FAB2(SCH_1):PVPP_ABC
 286 PVPP_ABC VPP<1> @BASEBOARD_FAB2_LIB.BASEBOARD_FAB2(SCH_1):PVPP_ABC
 287 PVPP_ABC VPP<0> @BASEBOARD_FAB2_LIB.BASEBOARD_FAB2(SCH_1):PVPP_ABC
  77 PVTT_ABC VTT<1> @BASEBOARD_FAB2_LIB.BASEBOARD_FAB2(SCH_1):PVTT_ABC
 221 PVTT_ABC VTT<0> @BASEBOARD_FAB2_LIB.BASEBOARD_FAB2(SCH_1):PVTT_ABC

CAP_A_0402V-0.01UF,25V,10%,X7RA  I179  C4G3
   1 M_B_VREF      A @BASEBOARD_FAB2_LIB.BASEBOARD_FAB2(SCH_1):M_B_VREF
   2    GND      B @BASEBOARD_FAB2_LIB.BASEBOARD_FAB2(SCH_1):GND


DRAWING: @BASEBOARD_FAB2_LIB.BASEBOARD_FAB2(SCH_1):PAGE46 

CAP_A_0402V-0.01UF,25V,10%,X7RA  I5  C6U9
   1 M_B_VREF      A @BASEBOARD_FAB2_LIB.BASEBOARD_FAB2(SCH_1):M_B_VREF
   2    GND      B @BASEBOARD_FAB2_LIB.BASEBOARD_FAB2(SCH_1):GND

SCONN288_H44441003_PIP-SCONN,HA  I14  J6U1
  79 M_B_MA<0>     A0 @BASEBOARD_FAB2_LIB.BASEBOARD_FAB2(SCH_1):M_B_MA(0)
  72 M_B_MA<1>     A1 @BASEBOARD_FAB2_LIB.BASEBOARD_FAB2(SCH_1):M_B_MA(1)
 225 M_B_MA<10>    A10 @BASEBOARD_FAB2_LIB.BASEBOARD_FAB2(SCH_1):M_B_MA(10)
 210 M_B_MA<11>    A11 @BASEBOARD_FAB2_LIB.BASEBOARD_FAB2(SCH_1):M_B_MA(11)
  65 M_B_MA<12>    A12 @BASEBOARD_FAB2_LIB.BASEBOARD_FAB2(SCH_1):M_B_MA(12)
 232 M_B_MA<13>    A13 @BASEBOARD_FAB2_LIB.BASEBOARD_FAB2(SCH_1):M_B_MA(13)
 228 M_B_MA<14> A14_WE_N @BASEBOARD_FAB2_LIB.BASEBOARD_FAB2(SCH_1):M_B_MA(14)
  86 M_B_MA<15> A15_CAS_N @BASEBOARD_FAB2_LIB.BASEBOARD_FAB2(SCH_1):M_B_MA(15)
  82 M_B_MA<16> A16_RAS_N @BASEBOARD_FAB2_LIB.BASEBOARD_FAB2(SCH_1):M_B_MA(16)
 234 M_B_MA<17>    A17 @BASEBOARD_FAB2_LIB.BASEBOARD_FAB2(SCH_1):M_B_MA(17)
 216 M_B_MA<2>     A2 @BASEBOARD_FAB2_LIB.BASEBOARD_FAB2(SCH_1):M_B_MA(2)
  71 M_B_MA<3>     A3 @BASEBOARD_FAB2_LIB.BASEBOARD_FAB2(SCH_1):M_B_MA(3)
 214 M_B_MA<4>     A4 @BASEBOARD_FAB2_LIB.BASEBOARD_FAB2(SCH_1):M_B_MA(4)
 213 M_B_MA<5>     A5 @BASEBOARD_FAB2_LIB.BASEBOARD_FAB2(SCH_1):M_B_MA(5)
  69 M_B_MA<6>     A6 @BASEBOARD_FAB2_LIB.BASEBOARD_FAB2(SCH_1):M_B_MA(6)
 211 M_B_MA<7>     A7 @BASEBOARD_FAB2_LIB.BASEBOARD_FAB2(SCH_1):M_B_MA(7)
  68 M_B_MA<8>     A8 @BASEBOARD_FAB2_LIB.BASEBOARD_FAB2(SCH_1):M_B_MA(8)
  66 M_B_MA<9>     A9 @BASEBOARD_FAB2_LIB.BASEBOARD_FAB2(SCH_1):M_B_MA(9)
  62 M_B_ACT_N  ACT_N @BASEBOARD_FAB2_LIB.BASEBOARD_FAB2(SCH_1):M_B_ACT_N
 208 M_B_ALERT_N ALERT_N @BASEBOARD_FAB2_LIB.BASEBOARD_FAB2(SCH_1):M_B_ALERT_N
 224 M_B_BA<1>  BA<1> @BASEBOARD_FAB2_LIB.BASEBOARD_FAB2(SCH_1):M_B_BA(1)
  81 M_B_BA<0>  BA<0> @BASEBOARD_FAB2_LIB.BASEBOARD_FAB2(SCH_1):M_B_BA(0)
 207 M_B_BG<1>  BG<1> @BASEBOARD_FAB2_LIB.BASEBOARD_FAB2(SCH_1):M_B_BG(1)
  63 M_B_BG<0>  BG<0> @BASEBOARD_FAB2_LIB.BASEBOARD_FAB2(SCH_1):M_B_BG(0)
 235 M_B_C<2>   C<2> @BASEBOARD_FAB2_LIB.BASEBOARD_FAB2(SCH_1):M_B_C(2)
 199 M_B_ECC<7>  CB<7> @BASEBOARD_FAB2_LIB.BASEBOARD_FAB2(SCH_1):M_B_ECC(7)
  54 M_B_ECC<6>  CB<6> @BASEBOARD_FAB2_LIB.BASEBOARD_FAB2(SCH_1):M_B_ECC(6)
 192 M_B_ECC<5>  CB<5> @BASEBOARD_FAB2_LIB.BASEBOARD_FAB2(SCH_1):M_B_ECC(5)
  47 M_B_ECC<4>  CB<4> @BASEBOARD_FAB2_LIB.BASEBOARD_FAB2(SCH_1):M_B_ECC(4)
 201 M_B_ECC<3>  CB<3> @BASEBOARD_FAB2_LIB.BASEBOARD_FAB2(SCH_1):M_B_ECC(3)
  56 M_B_ECC<2>  CB<2> @BASEBOARD_FAB2_LIB.BASEBOARD_FAB2(SCH_1):M_B_ECC(2)
 194 M_B_ECC<1>  CB<1> @BASEBOARD_FAB2_LIB.BASEBOARD_FAB2(SCH_1):M_B_ECC(1)
  49 M_B_ECC<0>  CB<0> @BASEBOARD_FAB2_LIB.BASEBOARD_FAB2(SCH_1):M_B_ECC(0)
  75 M_B_CLK_DN<2>   CK0N @BASEBOARD_FAB2_LIB.BASEBOARD_FAB2(SCH_1):M_B_CLK_DN(2)
  74 M_B_CLK_DP<2>   CK0P @BASEBOARD_FAB2_LIB.BASEBOARD_FAB2(SCH_1):M_B_CLK_DP(2)
 219 M_B_CLK_DN<3>   CK1N @BASEBOARD_FAB2_LIB.BASEBOARD_FAB2(SCH_1):M_B_CLK_DN(3)
 218 M_B_CLK_DP<3>   CK1P @BASEBOARD_FAB2_LIB.BASEBOARD_FAB2(SCH_1):M_B_CLK_DP(3)
 203 M_B_CKE<3> CKE<1> @BASEBOARD_FAB2_LIB.BASEBOARD_FAB2(SCH_1):M_B_CKE(3)
  60 M_B_CKE<2> CKE<0> @BASEBOARD_FAB2_LIB.BASEBOARD_FAB2(SCH_1):M_B_CKE(2)
 280 M_B_DQ<63> DQ<63> @BASEBOARD_FAB2_LIB.BASEBOARD_FAB2(SCH_1):M_B_DQ(63)
 135 M_B_DQ<62> DQ<62> @BASEBOARD_FAB2_LIB.BASEBOARD_FAB2(SCH_1):M_B_DQ(62)
 273 M_B_DQ<61> DQ<61> @BASEBOARD_FAB2_LIB.BASEBOARD_FAB2(SCH_1):M_B_DQ(61)
 128 M_B_DQ<60> DQ<60> @BASEBOARD_FAB2_LIB.BASEBOARD_FAB2(SCH_1):M_B_DQ(60)
 282 M_B_DQ<59> DQ<59> @BASEBOARD_FAB2_LIB.BASEBOARD_FAB2(SCH_1):M_B_DQ(59)
 137 M_B_DQ<58> DQ<58> @BASEBOARD_FAB2_LIB.BASEBOARD_FAB2(SCH_1):M_B_DQ(58)
 275 M_B_DQ<57> DQ<57> @BASEBOARD_FAB2_LIB.BASEBOARD_FAB2(SCH_1):M_B_DQ(57)
 130 M_B_DQ<56> DQ<56> @BASEBOARD_FAB2_LIB.BASEBOARD_FAB2(SCH_1):M_B_DQ(56)
 269 M_B_DQ<55> DQ<55> @BASEBOARD_FAB2_LIB.BASEBOARD_FAB2(SCH_1):M_B_DQ(55)
 124 M_B_DQ<54> DQ<54> @BASEBOARD_FAB2_LIB.BASEBOARD_FAB2(SCH_1):M_B_DQ(54)
 262 M_B_DQ<53> DQ<53> @BASEBOARD_FAB2_LIB.BASEBOARD_FAB2(SCH_1):M_B_DQ(53)
 117 M_B_DQ<52> DQ<52> @BASEBOARD_FAB2_LIB.BASEBOARD_FAB2(SCH_1):M_B_DQ(52)
 271 M_B_DQ<51> DQ<51> @BASEBOARD_FAB2_LIB.BASEBOARD_FAB2(SCH_1):M_B_DQ(51)
 126 M_B_DQ<50> DQ<50> @BASEBOARD_FAB2_LIB.BASEBOARD_FAB2(SCH_1):M_B_DQ(50)
 264 M_B_DQ<49> DQ<49> @BASEBOARD_FAB2_LIB.BASEBOARD_FAB2(SCH_1):M_B_DQ(49)
 119 M_B_DQ<48> DQ<48> @BASEBOARD_FAB2_LIB.BASEBOARD_FAB2(SCH_1):M_B_DQ(48)
 258 M_B_DQ<47> DQ<47> @BASEBOARD_FAB2_LIB.BASEBOARD_FAB2(SCH_1):M_B_DQ(47)
 113 M_B_DQ<46> DQ<46> @BASEBOARD_FAB2_LIB.BASEBOARD_FAB2(SCH_1):M_B_DQ(46)
 251 M_B_DQ<45> DQ<45> @BASEBOARD_FAB2_LIB.BASEBOARD_FAB2(SCH_1):M_B_DQ(45)
 106 M_B_DQ<44> DQ<44> @BASEBOARD_FAB2_LIB.BASEBOARD_FAB2(SCH_1):M_B_DQ(44)
 260 M_B_DQ<43> DQ<43> @BASEBOARD_FAB2_LIB.BASEBOARD_FAB2(SCH_1):M_B_DQ(43)
 115 M_B_DQ<42> DQ<42> @BASEBOARD_FAB2_LIB.BASEBOARD_FAB2(SCH_1):M_B_DQ(42)
 253 M_B_DQ<41> DQ<41> @BASEBOARD_FAB2_LIB.BASEBOARD_FAB2(SCH_1):M_B_DQ(41)
 108 M_B_DQ<40> DQ<40> @BASEBOARD_FAB2_LIB.BASEBOARD_FAB2(SCH_1):M_B_DQ(40)
 247 M_B_DQ<39> DQ<39> @BASEBOARD_FAB2_LIB.BASEBOARD_FAB2(SCH_1):M_B_DQ(39)
 102 M_B_DQ<38> DQ<38> @BASEBOARD_FAB2_LIB.BASEBOARD_FAB2(SCH_1):M_B_DQ(38)
 240 M_B_DQ<37> DQ<37> @BASEBOARD_FAB2_LIB.BASEBOARD_FAB2(SCH_1):M_B_DQ(37)
  95 M_B_DQ<36> DQ<36> @BASEBOARD_FAB2_LIB.BASEBOARD_FAB2(SCH_1):M_B_DQ(36)
 249 M_B_DQ<35> DQ<35> @BASEBOARD_FAB2_LIB.BASEBOARD_FAB2(SCH_1):M_B_DQ(35)
 104 M_B_DQ<34> DQ<34> @BASEBOARD_FAB2_LIB.BASEBOARD_FAB2(SCH_1):M_B_DQ(34)
 242 M_B_DQ<33> DQ<33> @BASEBOARD_FAB2_LIB.BASEBOARD_FAB2(SCH_1):M_B_DQ(33)
  97 M_B_DQ<32> DQ<32> @BASEBOARD_FAB2_LIB.BASEBOARD_FAB2(SCH_1):M_B_DQ(32)
 188 M_B_DQ<31> DQ<31> @BASEBOARD_FAB2_LIB.BASEBOARD_FAB2(SCH_1):M_B_DQ(31)
  43 M_B_DQ<30> DQ<30> @BASEBOARD_FAB2_LIB.BASEBOARD_FAB2(SCH_1):M_B_DQ(30)
 181 M_B_DQ<29> DQ<29> @BASEBOARD_FAB2_LIB.BASEBOARD_FAB2(SCH_1):M_B_DQ(29)
  36 M_B_DQ<28> DQ<28> @BASEBOARD_FAB2_LIB.BASEBOARD_FAB2(SCH_1):M_B_DQ(28)
 190 M_B_DQ<27> DQ<27> @BASEBOARD_FAB2_LIB.BASEBOARD_FAB2(SCH_1):M_B_DQ(27)
  45 M_B_DQ<26> DQ<26> @BASEBOARD_FAB2_LIB.BASEBOARD_FAB2(SCH_1):M_B_DQ(26)
 183 M_B_DQ<25> DQ<25> @BASEBOARD_FAB2_LIB.BASEBOARD_FAB2(SCH_1):M_B_DQ(25)
  38 M_B_DQ<24> DQ<24> @BASEBOARD_FAB2_LIB.BASEBOARD_FAB2(SCH_1):M_B_DQ(24)
 177 M_B_DQ<23> DQ<23> @BASEBOARD_FAB2_LIB.BASEBOARD_FAB2(SCH_1):M_B_DQ(23)
  32 M_B_DQ<22> DQ<22> @BASEBOARD_FAB2_LIB.BASEBOARD_FAB2(SCH_1):M_B_DQ(22)
 170 M_B_DQ<21> DQ<21> @BASEBOARD_FAB2_LIB.BASEBOARD_FAB2(SCH_1):M_B_DQ(21)
  25 M_B_DQ<20> DQ<20> @BASEBOARD_FAB2_LIB.BASEBOARD_FAB2(SCH_1):M_B_DQ(20)
 179 M_B_DQ<19> DQ<19> @BASEBOARD_FAB2_LIB.BASEBOARD_FAB2(SCH_1):M_B_DQ(19)
  34 M_B_DQ<18> DQ<18> @BASEBOARD_FAB2_LIB.BASEBOARD_FAB2(SCH_1):M_B_DQ(18)
 172 M_B_DQ<17> DQ<17> @BASEBOARD_FAB2_LIB.BASEBOARD_FAB2(SCH_1):M_B_DQ(17)
  27 M_B_DQ<16> DQ<16> @BASEBOARD_FAB2_LIB.BASEBOARD_FAB2(SCH_1):M_B_DQ(16)
 166 M_B_DQ<15> DQ<15> @BASEBOARD_FAB2_LIB.BASEBOARD_FAB2(SCH_1):M_B_DQ(15)
  21 M_B_DQ<14> DQ<14> @BASEBOARD_FAB2_LIB.BASEBOARD_FAB2(SCH_1):M_B_DQ(14)
 159 M_B_DQ<13> DQ<13> @BASEBOARD_FAB2_LIB.BASEBOARD_FAB2(SCH_1):M_B_DQ(13)
  14 M_B_DQ<12> DQ<12> @BASEBOARD_FAB2_LIB.BASEBOARD_FAB2(SCH_1):M_B_DQ(12)
 168 M_B_DQ<11> DQ<11> @BASEBOARD_FAB2_LIB.BASEBOARD_FAB2(SCH_1):M_B_DQ(11)
  23 M_B_DQ<10> DQ<10> @BASEBOARD_FAB2_LIB.BASEBOARD_FAB2(SCH_1):M_B_DQ(10)
 161 M_B_DQ<9>  DQ<9> @BASEBOARD_FAB2_LIB.BASEBOARD_FAB2(SCH_1):M_B_DQ(9)
  16 M_B_DQ<8>  DQ<8> @BASEBOARD_FAB2_LIB.BASEBOARD_FAB2(SCH_1):M_B_DQ(8)
 155 M_B_DQ<7>  DQ<7> @BASEBOARD_FAB2_LIB.BASEBOARD_FAB2(SCH_1):M_B_DQ(7)
  10 M_B_DQ<6>  DQ<6> @BASEBOARD_FAB2_LIB.BASEBOARD_FAB2(SCH_1):M_B_DQ(6)
 148 M_B_DQ<5>  DQ<5> @BASEBOARD_FAB2_LIB.BASEBOARD_FAB2(SCH_1):M_B_DQ(5)
   3 M_B_DQ<4>  DQ<4> @BASEBOARD_FAB2_LIB.BASEBOARD_FAB2(SCH_1):M_B_DQ(4)
 157 M_B_DQ<3>  DQ<3> @BASEBOARD_FAB2_LIB.BASEBOARD_FAB2(SCH_1):M_B_DQ(3)
  12 M_B_DQ<2>  DQ<2> @BASEBOARD_FAB2_LIB.BASEBOARD_FAB2(SCH_1):M_B_DQ(2)
 150 M_B_DQ<1>  DQ<1> @BASEBOARD_FAB2_LIB.BASEBOARD_FAB2(SCH_1):M_B_DQ(1)
   5 M_B_DQ<0>  DQ<0> @BASEBOARD_FAB2_LIB.BASEBOARD_FAB2(SCH_1):M_B_DQ(0)
  78 FM_DIMM_EVENT_COD_N EVENT_N @BASEBOARD_FAB2_LIB.BASEBOARD_FAB2(SCH_1):FM_DIMM_EVENT_COD_N
  91 M_B_ODT<3> ODT<1> @BASEBOARD_FAB2_LIB.BASEBOARD_FAB2(SCH_1):M_B_ODT(3)
  87 M_B_ODT<2> ODT<0> @BASEBOARD_FAB2_LIB.BASEBOARD_FAB2(SCH_1):M_B_ODT(2)
 222 M_B_PAR    PAR @BASEBOARD_FAB2_LIB.BASEBOARD_FAB2(SCH_1):M_B_PAR
  58 M_ABC_RST_N RESET_N @BASEBOARD_FAB2_LIB.BASEBOARD_FAB2(SCH_1):M_ABC_RST_N
 144 TP_CH_B_DIMM_B1_RFU_2 RFU<2> @BASEBOARD_FAB2_LIB.BASEBOARD_FAB2(SCH_1):TP_CH_B_DIMM_B1_RFU_2
 227 TP_CH_B_DIMM_B1_RFU_1 RFU<1> @BASEBOARD_FAB2_LIB.BASEBOARD_FAB2(SCH_1):TP_CH_B_DIMM_B1_RFU_1
 205 TP_CH_B_DIMM_B1_RFU_0 RFU<0> @BASEBOARD_FAB2_LIB.BASEBOARD_FAB2(SCH_1):TP_CH_B_DIMM_B1_RFU_0
  84 M_B_CS_N<4>   S0_N @BASEBOARD_FAB2_LIB.BASEBOARD_FAB2(SCH_1):M_B_CS_N(4)
  89 M_B_CS_N<5>   S1_N @BASEBOARD_FAB2_LIB.BASEBOARD_FAB2(SCH_1):M_B_CS_N(5)
  93 M_B_CS_N<6> S2_N_C<0> @BASEBOARD_FAB2_LIB.BASEBOARD_FAB2(SCH_1):M_B_CS_N(6)
 237 M_B_CS_N<7> S3_N_C<1> @BASEBOARD_FAB2_LIB.BASEBOARD_FAB2(SCH_1):M_B_CS_N(7)
 238    GND  SA<2> @BASEBOARD_FAB2_LIB.BASEBOARD_FAB2(SCH_1):GND
 140 PVPP_ABC  SA<1> @BASEBOARD_FAB2_LIB.BASEBOARD_FAB2(SCH_1):PVPP_ABC
 139 PVPP_ABC  SA<0> @BASEBOARD_FAB2_LIB.BASEBOARD_FAB2(SCH_1):PVPP_ABC
 230 FM_ADR_COMPLETE_ABC_N SAVE_N_NC @BASEBOARD_FAB2_LIB.BASEBOARD_FAB2(SCH_1):FM_ADR_COMPLETE_ABC_N
 141 SMB_DDR_ABC_VPP_SCL    SCL @BASEBOARD_FAB2_LIB.BASEBOARD_FAB2(SCH_1):SMB_DDR_ABC_VPP_SCL
 285 SMB_DDR_ABC_VPP_SDA    SDA @BASEBOARD_FAB2_LIB.BASEBOARD_FAB2(SCH_1):SMB_DDR_ABC_VPP_SDA
 284 PVPP_ABC VDDSPD @BASEBOARD_FAB2_LIB.BASEBOARD_FAB2(SCH_1):PVPP_ABC
 146 M_B_VREF VREFCA @BASEBOARD_FAB2_LIB.BASEBOARD_FAB2(SCH_1):M_B_VREF

SCONN288_H44441003_PIP-SCONN,HA  I67  J6U1
   1 P12V_NVDIMM_ABC 12V<1> @BASEBOARD_FAB2_LIB.BASEBOARD_FAB2(SCH_1):P12V_NVDIMM_ABC
 145 P12V_NVDIMM_ABC 12V<0> @BASEBOARD_FAB2_LIB.BASEBOARD_FAB2(SCH_1):P12V_NVDIMM_ABC
  59 PVDDQ_ABC VDD<25> @BASEBOARD_FAB2_LIB.BASEBOARD_FAB2(SCH_1):PVDDQ_ABC
  61 PVDDQ_ABC VDD<24> @BASEBOARD_FAB2_LIB.BASEBOARD_FAB2(SCH_1):PVDDQ_ABC
  64 PVDDQ_ABC VDD<23> @BASEBOARD_FAB2_LIB.BASEBOARD_FAB2(SCH_1):PVDDQ_ABC
  67 PVDDQ_ABC VDD<22> @BASEBOARD_FAB2_LIB.BASEBOARD_FAB2(SCH_1):PVDDQ_ABC
  70 PVDDQ_ABC VDD<21> @BASEBOARD_FAB2_LIB.BASEBOARD_FAB2(SCH_1):PVDDQ_ABC
  73 PVDDQ_ABC VDD<20> @BASEBOARD_FAB2_LIB.BASEBOARD_FAB2(SCH_1):PVDDQ_ABC
  76 PVDDQ_ABC VDD<19> @BASEBOARD_FAB2_LIB.BASEBOARD_FAB2(SCH_1):PVDDQ_ABC
  80 PVDDQ_ABC VDD<18> @BASEBOARD_FAB2_LIB.BASEBOARD_FAB2(SCH_1):PVDDQ_ABC
  83 PVDDQ_ABC VDD<17> @BASEBOARD_FAB2_LIB.BASEBOARD_FAB2(SCH_1):PVDDQ_ABC
  85 PVDDQ_ABC VDD<16> @BASEBOARD_FAB2_LIB.BASEBOARD_FAB2(SCH_1):PVDDQ_ABC
  88 PVDDQ_ABC VDD<15> @BASEBOARD_FAB2_LIB.BASEBOARD_FAB2(SCH_1):PVDDQ_ABC
  90 PVDDQ_ABC VDD<14> @BASEBOARD_FAB2_LIB.BASEBOARD_FAB2(SCH_1):PVDDQ_ABC
  92 PVDDQ_ABC VDD<13> @BASEBOARD_FAB2_LIB.BASEBOARD_FAB2(SCH_1):PVDDQ_ABC
 204 PVDDQ_ABC VDD<12> @BASEBOARD_FAB2_LIB.BASEBOARD_FAB2(SCH_1):PVDDQ_ABC
 206 PVDDQ_ABC VDD<11> @BASEBOARD_FAB2_LIB.BASEBOARD_FAB2(SCH_1):PVDDQ_ABC
 209 PVDDQ_ABC VDD<10> @BASEBOARD_FAB2_LIB.BASEBOARD_FAB2(SCH_1):PVDDQ_ABC
 212 PVDDQ_ABC VDD<9> @BASEBOARD_FAB2_LIB.BASEBOARD_FAB2(SCH_1):PVDDQ_ABC
 215 PVDDQ_ABC VDD<8> @BASEBOARD_FAB2_LIB.BASEBOARD_FAB2(SCH_1):PVDDQ_ABC
 217 PVDDQ_ABC VDD<7> @BASEBOARD_FAB2_LIB.BASEBOARD_FAB2(SCH_1):PVDDQ_ABC
 220 PVDDQ_ABC VDD<6> @BASEBOARD_FAB2_LIB.BASEBOARD_FAB2(SCH_1):PVDDQ_ABC
 223 PVDDQ_ABC VDD<5> @BASEBOARD_FAB2_LIB.BASEBOARD_FAB2(SCH_1):PVDDQ_ABC
 226 PVDDQ_ABC VDD<4> @BASEBOARD_FAB2_LIB.BASEBOARD_FAB2(SCH_1):PVDDQ_ABC
 229 PVDDQ_ABC VDD<3> @BASEBOARD_FAB2_LIB.BASEBOARD_FAB2(SCH_1):PVDDQ_ABC
 231 PVDDQ_ABC VDD<2> @BASEBOARD_FAB2_LIB.BASEBOARD_FAB2(SCH_1):PVDDQ_ABC
 233 PVDDQ_ABC VDD<1> @BASEBOARD_FAB2_LIB.BASEBOARD_FAB2(SCH_1):PVDDQ_ABC
 236 PVDDQ_ABC VDD<0> @BASEBOARD_FAB2_LIB.BASEBOARD_FAB2(SCH_1):PVDDQ_ABC
 142 PVPP_ABC VPP<4> @BASEBOARD_FAB2_LIB.BASEBOARD_FAB2(SCH_1):PVPP_ABC
 143 PVPP_ABC VPP<3> @BASEBOARD_FAB2_LIB.BASEBOARD_FAB2(SCH_1):PVPP_ABC
 288 PVPP_ABC VPP<2> @BASEBOARD_FAB2_LIB.BASEBOARD_FAB2(SCH_1):PVPP_ABC
 286 PVPP_ABC VPP<1> @BASEBOARD_FAB2_LIB.BASEBOARD_FAB2(SCH_1):PVPP_ABC
 287 PVPP_ABC VPP<0> @BASEBOARD_FAB2_LIB.BASEBOARD_FAB2(SCH_1):PVPP_ABC
  77 PVTT_ABC VTT<1> @BASEBOARD_FAB2_LIB.BASEBOARD_FAB2(SCH_1):PVTT_ABC
 221 PVTT_ABC VTT<0> @BASEBOARD_FAB2_LIB.BASEBOARD_FAB2(SCH_1):PVTT_ABC

SCONN288_H44441003_PIP-SCONN,HA  I112  J6U1
 152 M_B_DQS_DN<0>  DQS0N @BASEBOARD_FAB2_LIB.BASEBOARD_FAB2(SCH_1):M_B_DQS_DN(0)
 153 M_B_DQS_DP<0>  DQS0P @BASEBOARD_FAB2_LIB.BASEBOARD_FAB2(SCH_1):M_B_DQS_DP(0)
  19 M_B_DQS_DN<10> DQS10N @BASEBOARD_FAB2_LIB.BASEBOARD_FAB2(SCH_1):M_B_DQS_DN(10)
  18 M_B_DQS_DP<10> DQS10P @BASEBOARD_FAB2_LIB.BASEBOARD_FAB2(SCH_1):M_B_DQS_DP(10)
  30 M_B_DQS_DN<11> DQS11N @BASEBOARD_FAB2_LIB.BASEBOARD_FAB2(SCH_1):M_B_DQS_DN(11)
  29 M_B_DQS_DP<11> DQS11P @BASEBOARD_FAB2_LIB.BASEBOARD_FAB2(SCH_1):M_B_DQS_DP(11)
  41 M_B_DQS_DN<12> DQS12N @BASEBOARD_FAB2_LIB.BASEBOARD_FAB2(SCH_1):M_B_DQS_DN(12)
  40 M_B_DQS_DP<12> DQS12P @BASEBOARD_FAB2_LIB.BASEBOARD_FAB2(SCH_1):M_B_DQS_DP(12)
 100 M_B_DQS_DN<13> DQS13N @BASEBOARD_FAB2_LIB.BASEBOARD_FAB2(SCH_1):M_B_DQS_DN(13)
  99 M_B_DQS_DP<13> DQS13P @BASEBOARD_FAB2_LIB.BASEBOARD_FAB2(SCH_1):M_B_DQS_DP(13)
 111 M_B_DQS_DN<14> DQS14N @BASEBOARD_FAB2_LIB.BASEBOARD_FAB2(SCH_1):M_B_DQS_DN(14)
 110 M_B_DQS_DP<14> DQS14P @BASEBOARD_FAB2_LIB.BASEBOARD_FAB2(SCH_1):M_B_DQS_DP(14)
 122 M_B_DQS_DN<15> DQS15N @BASEBOARD_FAB2_LIB.BASEBOARD_FAB2(SCH_1):M_B_DQS_DN(15)
 121 M_B_DQS_DP<15> DQS15P @BASEBOARD_FAB2_LIB.BASEBOARD_FAB2(SCH_1):M_B_DQS_DP(15)
 133 M_B_DQS_DN<16> DQS16N @BASEBOARD_FAB2_LIB.BASEBOARD_FAB2(SCH_1):M_B_DQS_DN(16)
 132 M_B_DQS_DP<16> DQS16P @BASEBOARD_FAB2_LIB.BASEBOARD_FAB2(SCH_1):M_B_DQS_DP(16)
  52 M_B_DQS_DN<17> DQS17N @BASEBOARD_FAB2_LIB.BASEBOARD_FAB2(SCH_1):M_B_DQS_DN(17)
  51 M_B_DQS_DP<17> DQS17P @BASEBOARD_FAB2_LIB.BASEBOARD_FAB2(SCH_1):M_B_DQS_DP(17)
 163 M_B_DQS_DN<1>  DQS1N @BASEBOARD_FAB2_LIB.BASEBOARD_FAB2(SCH_1):M_B_DQS_DN(1)
 164 M_B_DQS_DP<1>  DQS1P @BASEBOARD_FAB2_LIB.BASEBOARD_FAB2(SCH_1):M_B_DQS_DP(1)
 174 M_B_DQS_DN<2>  DQS2N @BASEBOARD_FAB2_LIB.BASEBOARD_FAB2(SCH_1):M_B_DQS_DN(2)
 175 M_B_DQS_DP<2>  DQS2P @BASEBOARD_FAB2_LIB.BASEBOARD_FAB2(SCH_1):M_B_DQS_DP(2)
 185 M_B_DQS_DN<3>  DQS3N @BASEBOARD_FAB2_LIB.BASEBOARD_FAB2(SCH_1):M_B_DQS_DN(3)
 186 M_B_DQS_DP<3>  DQS3P @BASEBOARD_FAB2_LIB.BASEBOARD_FAB2(SCH_1):M_B_DQS_DP(3)
 244 M_B_DQS_DN<4>  DQS4N @BASEBOARD_FAB2_LIB.BASEBOARD_FAB2(SCH_1):M_B_DQS_DN(4)
 245 M_B_DQS_DP<4>  DQS4P @BASEBOARD_FAB2_LIB.BASEBOARD_FAB2(SCH_1):M_B_DQS_DP(4)
 255 M_B_DQS_DN<5>  DQS5N @BASEBOARD_FAB2_LIB.BASEBOARD_FAB2(SCH_1):M_B_DQS_DN(5)
 256 M_B_DQS_DP<5>  DQS5P @BASEBOARD_FAB2_LIB.BASEBOARD_FAB2(SCH_1):M_B_DQS_DP(5)
 266 M_B_DQS_DN<6>  DQS6N @BASEBOARD_FAB2_LIB.BASEBOARD_FAB2(SCH_1):M_B_DQS_DN(6)
 267 M_B_DQS_DP<6>  DQS6P @BASEBOARD_FAB2_LIB.BASEBOARD_FAB2(SCH_1):M_B_DQS_DP(6)
 277 M_B_DQS_DN<7>  DQS7N @BASEBOARD_FAB2_LIB.BASEBOARD_FAB2(SCH_1):M_B_DQS_DN(7)
 278 M_B_DQS_DP<7>  DQS7P @BASEBOARD_FAB2_LIB.BASEBOARD_FAB2(SCH_1):M_B_DQS_DP(7)
 196 M_B_DQS_DN<8>  DQS8N @BASEBOARD_FAB2_LIB.BASEBOARD_FAB2(SCH_1):M_B_DQS_DN(8)
 197 M_B_DQS_DP<8>  DQS8P @BASEBOARD_FAB2_LIB.BASEBOARD_FAB2(SCH_1):M_B_DQS_DP(8)
   8 M_B_DQS_DN<9>  DQS9N @BASEBOARD_FAB2_LIB.BASEBOARD_FAB2(SCH_1):M_B_DQS_DN(9)
   7 M_B_DQS_DP<9>  DQS9P @BASEBOARD_FAB2_LIB.BASEBOARD_FAB2(SCH_1):M_B_DQS_DP(9)

SCONN288_H44441003_PIP-SCONN,HA  I138  J6U1
   2    GND VSS<93> @BASEBOARD_FAB2_LIB.BASEBOARD_FAB2(SCH_1):GND
   4    GND VSS<92> @BASEBOARD_FAB2_LIB.BASEBOARD_FAB2(SCH_1):GND
   6    GND VSS<91> @BASEBOARD_FAB2_LIB.BASEBOARD_FAB2(SCH_1):GND
   9    GND VSS<90> @BASEBOARD_FAB2_LIB.BASEBOARD_FAB2(SCH_1):GND
  11    GND VSS<89> @BASEBOARD_FAB2_LIB.BASEBOARD_FAB2(SCH_1):GND
  13    GND VSS<88> @BASEBOARD_FAB2_LIB.BASEBOARD_FAB2(SCH_1):GND
  15    GND VSS<87> @BASEBOARD_FAB2_LIB.BASEBOARD_FAB2(SCH_1):GND
  17    GND VSS<86> @BASEBOARD_FAB2_LIB.BASEBOARD_FAB2(SCH_1):GND
  20    GND VSS<85> @BASEBOARD_FAB2_LIB.BASEBOARD_FAB2(SCH_1):GND
  22    GND VSS<84> @BASEBOARD_FAB2_LIB.BASEBOARD_FAB2(SCH_1):GND
  24    GND VSS<83> @BASEBOARD_FAB2_LIB.BASEBOARD_FAB2(SCH_1):GND
  26    GND VSS<82> @BASEBOARD_FAB2_LIB.BASEBOARD_FAB2(SCH_1):GND
  28    GND VSS<81> @BASEBOARD_FAB2_LIB.BASEBOARD_FAB2(SCH_1):GND
  31    GND VSS<80> @BASEBOARD_FAB2_LIB.BASEBOARD_FAB2(SCH_1):GND
  33    GND VSS<79> @BASEBOARD_FAB2_LIB.BASEBOARD_FAB2(SCH_1):GND
  35    GND VSS<78> @BASEBOARD_FAB2_LIB.BASEBOARD_FAB2(SCH_1):GND
  37    GND VSS<77> @BASEBOARD_FAB2_LIB.BASEBOARD_FAB2(SCH_1):GND
  39    GND VSS<76> @BASEBOARD_FAB2_LIB.BASEBOARD_FAB2(SCH_1):GND
  42    GND VSS<75> @BASEBOARD_FAB2_LIB.BASEBOARD_FAB2(SCH_1):GND
  44    GND VSS<74> @BASEBOARD_FAB2_LIB.BASEBOARD_FAB2(SCH_1):GND
  46    GND VSS<73> @BASEBOARD_FAB2_LIB.BASEBOARD_FAB2(SCH_1):GND
  48    GND VSS<72> @BASEBOARD_FAB2_LIB.BASEBOARD_FAB2(SCH_1):GND
  50    GND VSS<71> @BASEBOARD_FAB2_LIB.BASEBOARD_FAB2(SCH_1):GND
  53    GND VSS<70> @BASEBOARD_FAB2_LIB.BASEBOARD_FAB2(SCH_1):GND
  55    GND VSS<69> @BASEBOARD_FAB2_LIB.BASEBOARD_FAB2(SCH_1):GND
  57    GND VSS<68> @BASEBOARD_FAB2_LIB.BASEBOARD_FAB2(SCH_1):GND
  94    GND VSS<67> @BASEBOARD_FAB2_LIB.BASEBOARD_FAB2(SCH_1):GND
  96    GND VSS<66> @BASEBOARD_FAB2_LIB.BASEBOARD_FAB2(SCH_1):GND
  98    GND VSS<65> @BASEBOARD_FAB2_LIB.BASEBOARD_FAB2(SCH_1):GND
 101    GND VSS<64> @BASEBOARD_FAB2_LIB.BASEBOARD_FAB2(SCH_1):GND
 103    GND VSS<63> @BASEBOARD_FAB2_LIB.BASEBOARD_FAB2(SCH_1):GND
 105    GND VSS<62> @BASEBOARD_FAB2_LIB.BASEBOARD_FAB2(SCH_1):GND
 107    GND VSS<61> @BASEBOARD_FAB2_LIB.BASEBOARD_FAB2(SCH_1):GND
 109    GND VSS<60> @BASEBOARD_FAB2_LIB.BASEBOARD_FAB2(SCH_1):GND
 112    GND VSS<59> @BASEBOARD_FAB2_LIB.BASEBOARD_FAB2(SCH_1):GND
 114    GND VSS<58> @BASEBOARD_FAB2_LIB.BASEBOARD_FAB2(SCH_1):GND
 116    GND VSS<57> @BASEBOARD_FAB2_LIB.BASEBOARD_FAB2(SCH_1):GND
 118    GND VSS<56> @BASEBOARD_FAB2_LIB.BASEBOARD_FAB2(SCH_1):GND
 120    GND VSS<55> @BASEBOARD_FAB2_LIB.BASEBOARD_FAB2(SCH_1):GND
 123    GND VSS<54> @BASEBOARD_FAB2_LIB.BASEBOARD_FAB2(SCH_1):GND
 125    GND VSS<53> @BASEBOARD_FAB2_LIB.BASEBOARD_FAB2(SCH_1):GND
 127    GND VSS<52> @BASEBOARD_FAB2_LIB.BASEBOARD_FAB2(SCH_1):GND
 129    GND VSS<51> @BASEBOARD_FAB2_LIB.BASEBOARD_FAB2(SCH_1):GND
 131    GND VSS<50> @BASEBOARD_FAB2_LIB.BASEBOARD_FAB2(SCH_1):GND
 134    GND VSS<49> @BASEBOARD_FAB2_LIB.BASEBOARD_FAB2(SCH_1):GND
 136    GND VSS<48> @BASEBOARD_FAB2_LIB.BASEBOARD_FAB2(SCH_1):GND
 138    GND VSS<47> @BASEBOARD_FAB2_LIB.BASEBOARD_FAB2(SCH_1):GND
 147    GND VSS<46> @BASEBOARD_FAB2_LIB.BASEBOARD_FAB2(SCH_1):GND
 149    GND VSS<45> @BASEBOARD_FAB2_LIB.BASEBOARD_FAB2(SCH_1):GND
 151    GND VSS<44> @BASEBOARD_FAB2_LIB.BASEBOARD_FAB2(SCH_1):GND
 154    GND VSS<43> @BASEBOARD_FAB2_LIB.BASEBOARD_FAB2(SCH_1):GND
 156    GND VSS<42> @BASEBOARD_FAB2_LIB.BASEBOARD_FAB2(SCH_1):GND
 158    GND VSS<41> @BASEBOARD_FAB2_LIB.BASEBOARD_FAB2(SCH_1):GND
 160    GND VSS<40> @BASEBOARD_FAB2_LIB.BASEBOARD_FAB2(SCH_1):GND
 162    GND VSS<39> @BASEBOARD_FAB2_LIB.BASEBOARD_FAB2(SCH_1):GND
 165    GND VSS<38> @BASEBOARD_FAB2_LIB.BASEBOARD_FAB2(SCH_1):GND
 167    GND VSS<37> @BASEBOARD_FAB2_LIB.BASEBOARD_FAB2(SCH_1):GND
 169    GND VSS<36> @BASEBOARD_FAB2_LIB.BASEBOARD_FAB2(SCH_1):GND
 171    GND VSS<35> @BASEBOARD_FAB2_LIB.BASEBOARD_FAB2(SCH_1):GND
 173    GND VSS<34> @BASEBOARD_FAB2_LIB.BASEBOARD_FAB2(SCH_1):GND
 176    GND VSS<33> @BASEBOARD_FAB2_LIB.BASEBOARD_FAB2(SCH_1):GND
 178    GND VSS<32> @BASEBOARD_FAB2_LIB.BASEBOARD_FAB2(SCH_1):GND
 180    GND VSS<31> @BASEBOARD_FAB2_LIB.BASEBOARD_FAB2(SCH_1):GND
 182    GND VSS<30> @BASEBOARD_FAB2_LIB.BASEBOARD_FAB2(SCH_1):GND
 184    GND VSS<29> @BASEBOARD_FAB2_LIB.BASEBOARD_FAB2(SCH_1):GND
 187    GND VSS<28> @BASEBOARD_FAB2_LIB.BASEBOARD_FAB2(SCH_1):GND
 189    GND VSS<27> @BASEBOARD_FAB2_LIB.BASEBOARD_FAB2(SCH_1):GND
 191    GND VSS<26> @BASEBOARD_FAB2_LIB.BASEBOARD_FAB2(SCH_1):GND
 193    GND VSS<25> @BASEBOARD_FAB2_LIB.BASEBOARD_FAB2(SCH_1):GND
 195    GND VSS<24> @BASEBOARD_FAB2_LIB.BASEBOARD_FAB2(SCH_1):GND
 198    GND VSS<23> @BASEBOARD_FAB2_LIB.BASEBOARD_FAB2(SCH_1):GND
 200    GND VSS<22> @BASEBOARD_FAB2_LIB.BASEBOARD_FAB2(SCH_1):GND
 202    GND VSS<21> @BASEBOARD_FAB2_LIB.BASEBOARD_FAB2(SCH_1):GND
 239    GND VSS<20> @BASEBOARD_FAB2_LIB.BASEBOARD_FAB2(SCH_1):GND
 241    GND VSS<19> @BASEBOARD_FAB2_LIB.BASEBOARD_FAB2(SCH_1):GND
 243    GND VSS<18> @BASEBOARD_FAB2_LIB.BASEBOARD_FAB2(SCH_1):GND
 246    GND VSS<17> @BASEBOARD_FAB2_LIB.BASEBOARD_FAB2(SCH_1):GND
 248    GND VSS<16> @BASEBOARD_FAB2_LIB.BASEBOARD_FAB2(SCH_1):GND
 250    GND VSS<15> @BASEBOARD_FAB2_LIB.BASEBOARD_FAB2(SCH_1):GND
 252    GND VSS<14> @BASEBOARD_FAB2_LIB.BASEBOARD_FAB2(SCH_1):GND
 254    GND VSS<13> @BASEBOARD_FAB2_LIB.BASEBOARD_FAB2(SCH_1):GND
 257    GND VSS<12> @BASEBOARD_FAB2_LIB.BASEBOARD_FAB2(SCH_1):GND
 259    GND VSS<11> @BASEBOARD_FAB2_LIB.BASEBOARD_FAB2(SCH_1):GND
 261    GND VSS<10> @BASEBOARD_FAB2_LIB.BASEBOARD_FAB2(SCH_1):GND
 263    GND VSS<9> @BASEBOARD_FAB2_LIB.BASEBOARD_FAB2(SCH_1):GND
 265    GND VSS<8> @BASEBOARD_FAB2_LIB.BASEBOARD_FAB2(SCH_1):GND
 268    GND VSS<7> @BASEBOARD_FAB2_LIB.BASEBOARD_FAB2(SCH_1):GND
 270    GND VSS<6> @BASEBOARD_FAB2_LIB.BASEBOARD_FAB2(SCH_1):GND
 272    GND VSS<5> @BASEBOARD_FAB2_LIB.BASEBOARD_FAB2(SCH_1):GND
 274    GND VSS<4> @BASEBOARD_FAB2_LIB.BASEBOARD_FAB2(SCH_1):GND
 276    GND VSS<3> @BASEBOARD_FAB2_LIB.BASEBOARD_FAB2(SCH_1):GND
 279    GND VSS<2> @BASEBOARD_FAB2_LIB.BASEBOARD_FAB2(SCH_1):GND
 281    GND VSS<1> @BASEBOARD_FAB2_LIB.BASEBOARD_FAB2(SCH_1):GND
 283    GND VSS<0> @BASEBOARD_FAB2_LIB.BASEBOARD_FAB2(SCH_1):GND


DRAWING: @BASEBOARD_FAB2_LIB.BASEBOARD_FAB2(SCH_1):PAGE47 

SCONN288_H44441004_PIP-SCONN,HA  I43  J4G3
   2    GND VSS<93> @BASEBOARD_FAB2_LIB.BASEBOARD_FAB2(SCH_1):GND
   4    GND VSS<92> @BASEBOARD_FAB2_LIB.BASEBOARD_FAB2(SCH_1):GND
   6    GND VSS<91> @BASEBOARD_FAB2_LIB.BASEBOARD_FAB2(SCH_1):GND
   9    GND VSS<90> @BASEBOARD_FAB2_LIB.BASEBOARD_FAB2(SCH_1):GND
  11    GND VSS<89> @BASEBOARD_FAB2_LIB.BASEBOARD_FAB2(SCH_1):GND
  13    GND VSS<88> @BASEBOARD_FAB2_LIB.BASEBOARD_FAB2(SCH_1):GND
  15    GND VSS<87> @BASEBOARD_FAB2_LIB.BASEBOARD_FAB2(SCH_1):GND
  17    GND VSS<86> @BASEBOARD_FAB2_LIB.BASEBOARD_FAB2(SCH_1):GND
  20    GND VSS<85> @BASEBOARD_FAB2_LIB.BASEBOARD_FAB2(SCH_1):GND
  22    GND VSS<84> @BASEBOARD_FAB2_LIB.BASEBOARD_FAB2(SCH_1):GND
  24    GND VSS<83> @BASEBOARD_FAB2_LIB.BASEBOARD_FAB2(SCH_1):GND
  26    GND VSS<82> @BASEBOARD_FAB2_LIB.BASEBOARD_FAB2(SCH_1):GND
  28    GND VSS<81> @BASEBOARD_FAB2_LIB.BASEBOARD_FAB2(SCH_1):GND
  31    GND VSS<80> @BASEBOARD_FAB2_LIB.BASEBOARD_FAB2(SCH_1):GND
  33    GND VSS<79> @BASEBOARD_FAB2_LIB.BASEBOARD_FAB2(SCH_1):GND
  35    GND VSS<78> @BASEBOARD_FAB2_LIB.BASEBOARD_FAB2(SCH_1):GND
  37    GND VSS<77> @BASEBOARD_FAB2_LIB.BASEBOARD_FAB2(SCH_1):GND
  39    GND VSS<76> @BASEBOARD_FAB2_LIB.BASEBOARD_FAB2(SCH_1):GND
  42    GND VSS<75> @BASEBOARD_FAB2_LIB.BASEBOARD_FAB2(SCH_1):GND
  44    GND VSS<74> @BASEBOARD_FAB2_LIB.BASEBOARD_FAB2(SCH_1):GND
  46    GND VSS<73> @BASEBOARD_FAB2_LIB.BASEBOARD_FAB2(SCH_1):GND
  48    GND VSS<72> @BASEBOARD_FAB2_LIB.BASEBOARD_FAB2(SCH_1):GND
  50    GND VSS<71> @BASEBOARD_FAB2_LIB.BASEBOARD_FAB2(SCH_1):GND
  53    GND VSS<70> @BASEBOARD_FAB2_LIB.BASEBOARD_FAB2(SCH_1):GND
  55    GND VSS<69> @BASEBOARD_FAB2_LIB.BASEBOARD_FAB2(SCH_1):GND
  57    GND VSS<68> @BASEBOARD_FAB2_LIB.BASEBOARD_FAB2(SCH_1):GND
  94    GND VSS<67> @BASEBOARD_FAB2_LIB.BASEBOARD_FAB2(SCH_1):GND
  96    GND VSS<66> @BASEBOARD_FAB2_LIB.BASEBOARD_FAB2(SCH_1):GND
  98    GND VSS<65> @BASEBOARD_FAB2_LIB.BASEBOARD_FAB2(SCH_1):GND
 101    GND VSS<64> @BASEBOARD_FAB2_LIB.BASEBOARD_FAB2(SCH_1):GND
 103    GND VSS<63> @BASEBOARD_FAB2_LIB.BASEBOARD_FAB2(SCH_1):GND
 105    GND VSS<62> @BASEBOARD_FAB2_LIB.BASEBOARD_FAB2(SCH_1):GND
 107    GND VSS<61> @BASEBOARD_FAB2_LIB.BASEBOARD_FAB2(SCH_1):GND
 109    GND VSS<60> @BASEBOARD_FAB2_LIB.BASEBOARD_FAB2(SCH_1):GND
 112    GND VSS<59> @BASEBOARD_FAB2_LIB.BASEBOARD_FAB2(SCH_1):GND
 114    GND VSS<58> @BASEBOARD_FAB2_LIB.BASEBOARD_FAB2(SCH_1):GND
 116    GND VSS<57> @BASEBOARD_FAB2_LIB.BASEBOARD_FAB2(SCH_1):GND
 118    GND VSS<56> @BASEBOARD_FAB2_LIB.BASEBOARD_FAB2(SCH_1):GND
 120    GND VSS<55> @BASEBOARD_FAB2_LIB.BASEBOARD_FAB2(SCH_1):GND
 123    GND VSS<54> @BASEBOARD_FAB2_LIB.BASEBOARD_FAB2(SCH_1):GND
 125    GND VSS<53> @BASEBOARD_FAB2_LIB.BASEBOARD_FAB2(SCH_1):GND
 127    GND VSS<52> @BASEBOARD_FAB2_LIB.BASEBOARD_FAB2(SCH_1):GND
 129    GND VSS<51> @BASEBOARD_FAB2_LIB.BASEBOARD_FAB2(SCH_1):GND
 131    GND VSS<50> @BASEBOARD_FAB2_LIB.BASEBOARD_FAB2(SCH_1):GND
 134    GND VSS<49> @BASEBOARD_FAB2_LIB.BASEBOARD_FAB2(SCH_1):GND
 136    GND VSS<48> @BASEBOARD_FAB2_LIB.BASEBOARD_FAB2(SCH_1):GND
 138    GND VSS<47> @BASEBOARD_FAB2_LIB.BASEBOARD_FAB2(SCH_1):GND
 147    GND VSS<46> @BASEBOARD_FAB2_LIB.BASEBOARD_FAB2(SCH_1):GND
 149    GND VSS<45> @BASEBOARD_FAB2_LIB.BASEBOARD_FAB2(SCH_1):GND
 151    GND VSS<44> @BASEBOARD_FAB2_LIB.BASEBOARD_FAB2(SCH_1):GND
 154    GND VSS<43> @BASEBOARD_FAB2_LIB.BASEBOARD_FAB2(SCH_1):GND
 156    GND VSS<42> @BASEBOARD_FAB2_LIB.BASEBOARD_FAB2(SCH_1):GND
 158    GND VSS<41> @BASEBOARD_FAB2_LIB.BASEBOARD_FAB2(SCH_1):GND
 160    GND VSS<40> @BASEBOARD_FAB2_LIB.BASEBOARD_FAB2(SCH_1):GND
 162    GND VSS<39> @BASEBOARD_FAB2_LIB.BASEBOARD_FAB2(SCH_1):GND
 165    GND VSS<38> @BASEBOARD_FAB2_LIB.BASEBOARD_FAB2(SCH_1):GND
 167    GND VSS<37> @BASEBOARD_FAB2_LIB.BASEBOARD_FAB2(SCH_1):GND
 169    GND VSS<36> @BASEBOARD_FAB2_LIB.BASEBOARD_FAB2(SCH_1):GND
 171    GND VSS<35> @BASEBOARD_FAB2_LIB.BASEBOARD_FAB2(SCH_1):GND
 173    GND VSS<34> @BASEBOARD_FAB2_LIB.BASEBOARD_FAB2(SCH_1):GND
 176    GND VSS<33> @BASEBOARD_FAB2_LIB.BASEBOARD_FAB2(SCH_1):GND
 178    GND VSS<32> @BASEBOARD_FAB2_LIB.BASEBOARD_FAB2(SCH_1):GND
 180    GND VSS<31> @BASEBOARD_FAB2_LIB.BASEBOARD_FAB2(SCH_1):GND
 182    GND VSS<30> @BASEBOARD_FAB2_LIB.BASEBOARD_FAB2(SCH_1):GND
 184    GND VSS<29> @BASEBOARD_FAB2_LIB.BASEBOARD_FAB2(SCH_1):GND
 187    GND VSS<28> @BASEBOARD_FAB2_LIB.BASEBOARD_FAB2(SCH_1):GND
 189    GND VSS<27> @BASEBOARD_FAB2_LIB.BASEBOARD_FAB2(SCH_1):GND
 191    GND VSS<26> @BASEBOARD_FAB2_LIB.BASEBOARD_FAB2(SCH_1):GND
 193    GND VSS<25> @BASEBOARD_FAB2_LIB.BASEBOARD_FAB2(SCH_1):GND
 195    GND VSS<24> @BASEBOARD_FAB2_LIB.BASEBOARD_FAB2(SCH_1):GND
 198    GND VSS<23> @BASEBOARD_FAB2_LIB.BASEBOARD_FAB2(SCH_1):GND
 200    GND VSS<22> @BASEBOARD_FAB2_LIB.BASEBOARD_FAB2(SCH_1):GND
 202    GND VSS<21> @BASEBOARD_FAB2_LIB.BASEBOARD_FAB2(SCH_1):GND
 239    GND VSS<20> @BASEBOARD_FAB2_LIB.BASEBOARD_FAB2(SCH_1):GND
 241    GND VSS<19> @BASEBOARD_FAB2_LIB.BASEBOARD_FAB2(SCH_1):GND
 243    GND VSS<18> @BASEBOARD_FAB2_LIB.BASEBOARD_FAB2(SCH_1):GND
 246    GND VSS<17> @BASEBOARD_FAB2_LIB.BASEBOARD_FAB2(SCH_1):GND
 248    GND VSS<16> @BASEBOARD_FAB2_LIB.BASEBOARD_FAB2(SCH_1):GND
 250    GND VSS<15> @BASEBOARD_FAB2_LIB.BASEBOARD_FAB2(SCH_1):GND
 252    GND VSS<14> @BASEBOARD_FAB2_LIB.BASEBOARD_FAB2(SCH_1):GND
 254    GND VSS<13> @BASEBOARD_FAB2_LIB.BASEBOARD_FAB2(SCH_1):GND
 257    GND VSS<12> @BASEBOARD_FAB2_LIB.BASEBOARD_FAB2(SCH_1):GND
 259    GND VSS<11> @BASEBOARD_FAB2_LIB.BASEBOARD_FAB2(SCH_1):GND
 261    GND VSS<10> @BASEBOARD_FAB2_LIB.BASEBOARD_FAB2(SCH_1):GND
 263    GND VSS<9> @BASEBOARD_FAB2_LIB.BASEBOARD_FAB2(SCH_1):GND
 265    GND VSS<8> @BASEBOARD_FAB2_LIB.BASEBOARD_FAB2(SCH_1):GND
 268    GND VSS<7> @BASEBOARD_FAB2_LIB.BASEBOARD_FAB2(SCH_1):GND
 270    GND VSS<6> @BASEBOARD_FAB2_LIB.BASEBOARD_FAB2(SCH_1):GND
 272    GND VSS<5> @BASEBOARD_FAB2_LIB.BASEBOARD_FAB2(SCH_1):GND
 274    GND VSS<4> @BASEBOARD_FAB2_LIB.BASEBOARD_FAB2(SCH_1):GND
 276    GND VSS<3> @BASEBOARD_FAB2_LIB.BASEBOARD_FAB2(SCH_1):GND
 279    GND VSS<2> @BASEBOARD_FAB2_LIB.BASEBOARD_FAB2(SCH_1):GND
 281    GND VSS<1> @BASEBOARD_FAB2_LIB.BASEBOARD_FAB2(SCH_1):GND
 283    GND VSS<0> @BASEBOARD_FAB2_LIB.BASEBOARD_FAB2(SCH_1):GND

SCONN288_H44441004_PIP-SCONN,HA  I61  J4G3
 152 M_C_DQS_DN<0>  DQS0N @BASEBOARD_FAB2_LIB.BASEBOARD_FAB2(SCH_1):M_C_DQS_DN(0)
 153 M_C_DQS_DP<0>  DQS0P @BASEBOARD_FAB2_LIB.BASEBOARD_FAB2(SCH_1):M_C_DQS_DP(0)
  19 M_C_DQS_DN<10> DQS10N @BASEBOARD_FAB2_LIB.BASEBOARD_FAB2(SCH_1):M_C_DQS_DN(10)
  18 M_C_DQS_DP<10> DQS10P @BASEBOARD_FAB2_LIB.BASEBOARD_FAB2(SCH_1):M_C_DQS_DP(10)
  30 M_C_DQS_DN<11> DQS11N @BASEBOARD_FAB2_LIB.BASEBOARD_FAB2(SCH_1):M_C_DQS_DN(11)
  29 M_C_DQS_DP<11> DQS11P @BASEBOARD_FAB2_LIB.BASEBOARD_FAB2(SCH_1):M_C_DQS_DP(11)
  41 M_C_DQS_DN<12> DQS12N @BASEBOARD_FAB2_LIB.BASEBOARD_FAB2(SCH_1):M_C_DQS_DN(12)
  40 M_C_DQS_DP<12> DQS12P @BASEBOARD_FAB2_LIB.BASEBOARD_FAB2(SCH_1):M_C_DQS_DP(12)
 100 M_C_DQS_DN<13> DQS13N @BASEBOARD_FAB2_LIB.BASEBOARD_FAB2(SCH_1):M_C_DQS_DN(13)
  99 M_C_DQS_DP<13> DQS13P @BASEBOARD_FAB2_LIB.BASEBOARD_FAB2(SCH_1):M_C_DQS_DP(13)
 111 M_C_DQS_DN<14> DQS14N @BASEBOARD_FAB2_LIB.BASEBOARD_FAB2(SCH_1):M_C_DQS_DN(14)
 110 M_C_DQS_DP<14> DQS14P @BASEBOARD_FAB2_LIB.BASEBOARD_FAB2(SCH_1):M_C_DQS_DP(14)
 122 M_C_DQS_DN<15> DQS15N @BASEBOARD_FAB2_LIB.BASEBOARD_FAB2(SCH_1):M_C_DQS_DN(15)
 121 M_C_DQS_DP<15> DQS15P @BASEBOARD_FAB2_LIB.BASEBOARD_FAB2(SCH_1):M_C_DQS_DP(15)
 133 M_C_DQS_DN<16> DQS16N @BASEBOARD_FAB2_LIB.BASEBOARD_FAB2(SCH_1):M_C_DQS_DN(16)
 132 M_C_DQS_DP<16> DQS16P @BASEBOARD_FAB2_LIB.BASEBOARD_FAB2(SCH_1):M_C_DQS_DP(16)
  52 M_C_DQS_DN<17> DQS17N @BASEBOARD_FAB2_LIB.BASEBOARD_FAB2(SCH_1):M_C_DQS_DN(17)
  51 M_C_DQS_DP<17> DQS17P @BASEBOARD_FAB2_LIB.BASEBOARD_FAB2(SCH_1):M_C_DQS_DP(17)
 163 M_C_DQS_DN<1>  DQS1N @BASEBOARD_FAB2_LIB.BASEBOARD_FAB2(SCH_1):M_C_DQS_DN(1)
 164 M_C_DQS_DP<1>  DQS1P @BASEBOARD_FAB2_LIB.BASEBOARD_FAB2(SCH_1):M_C_DQS_DP(1)
 174 M_C_DQS_DN<2>  DQS2N @BASEBOARD_FAB2_LIB.BASEBOARD_FAB2(SCH_1):M_C_DQS_DN(2)
 175 M_C_DQS_DP<2>  DQS2P @BASEBOARD_FAB2_LIB.BASEBOARD_FAB2(SCH_1):M_C_DQS_DP(2)
 185 M_C_DQS_DN<3>  DQS3N @BASEBOARD_FAB2_LIB.BASEBOARD_FAB2(SCH_1):M_C_DQS_DN(3)
 186 M_C_DQS_DP<3>  DQS3P @BASEBOARD_FAB2_LIB.BASEBOARD_FAB2(SCH_1):M_C_DQS_DP(3)
 244 M_C_DQS_DN<4>  DQS4N @BASEBOARD_FAB2_LIB.BASEBOARD_FAB2(SCH_1):M_C_DQS_DN(4)
 245 M_C_DQS_DP<4>  DQS4P @BASEBOARD_FAB2_LIB.BASEBOARD_FAB2(SCH_1):M_C_DQS_DP(4)
 255 M_C_DQS_DN<5>  DQS5N @BASEBOARD_FAB2_LIB.BASEBOARD_FAB2(SCH_1):M_C_DQS_DN(5)
 256 M_C_DQS_DP<5>  DQS5P @BASEBOARD_FAB2_LIB.BASEBOARD_FAB2(SCH_1):M_C_DQS_DP(5)
 266 M_C_DQS_DN<6>  DQS6N @BASEBOARD_FAB2_LIB.BASEBOARD_FAB2(SCH_1):M_C_DQS_DN(6)
 267 M_C_DQS_DP<6>  DQS6P @BASEBOARD_FAB2_LIB.BASEBOARD_FAB2(SCH_1):M_C_DQS_DP(6)
 277 M_C_DQS_DN<7>  DQS7N @BASEBOARD_FAB2_LIB.BASEBOARD_FAB2(SCH_1):M_C_DQS_DN(7)
 278 M_C_DQS_DP<7>  DQS7P @BASEBOARD_FAB2_LIB.BASEBOARD_FAB2(SCH_1):M_C_DQS_DP(7)
 196 M_C_DQS_DN<8>  DQS8N @BASEBOARD_FAB2_LIB.BASEBOARD_FAB2(SCH_1):M_C_DQS_DN(8)
 197 M_C_DQS_DP<8>  DQS8P @BASEBOARD_FAB2_LIB.BASEBOARD_FAB2(SCH_1):M_C_DQS_DP(8)
   8 M_C_DQS_DN<9>  DQS9N @BASEBOARD_FAB2_LIB.BASEBOARD_FAB2(SCH_1):M_C_DQS_DN(9)
   7 M_C_DQS_DP<9>  DQS9P @BASEBOARD_FAB2_LIB.BASEBOARD_FAB2(SCH_1):M_C_DQS_DP(9)

SCONN288_H44441004_PIP-SCONN,HA  I111  J4G3
  79 M_C_MA<0>     A0 @BASEBOARD_FAB2_LIB.BASEBOARD_FAB2(SCH_1):M_C_MA(0)
  72 M_C_MA<1>     A1 @BASEBOARD_FAB2_LIB.BASEBOARD_FAB2(SCH_1):M_C_MA(1)
 225 M_C_MA<10>    A10 @BASEBOARD_FAB2_LIB.BASEBOARD_FAB2(SCH_1):M_C_MA(10)
 210 M_C_MA<11>    A11 @BASEBOARD_FAB2_LIB.BASEBOARD_FAB2(SCH_1):M_C_MA(11)
  65 M_C_MA<12>    A12 @BASEBOARD_FAB2_LIB.BASEBOARD_FAB2(SCH_1):M_C_MA(12)
 232 M_C_MA<13>    A13 @BASEBOARD_FAB2_LIB.BASEBOARD_FAB2(SCH_1):M_C_MA(13)
 228 M_C_MA<14> A14_WE_N @BASEBOARD_FAB2_LIB.BASEBOARD_FAB2(SCH_1):M_C_MA(14)
  86 M_C_MA<15> A15_CAS_N @BASEBOARD_FAB2_LIB.BASEBOARD_FAB2(SCH_1):M_C_MA(15)
  82 M_C_MA<16> A16_RAS_N @BASEBOARD_FAB2_LIB.BASEBOARD_FAB2(SCH_1):M_C_MA(16)
 234 M_C_MA<17>    A17 @BASEBOARD_FAB2_LIB.BASEBOARD_FAB2(SCH_1):M_C_MA(17)
 216 M_C_MA<2>     A2 @BASEBOARD_FAB2_LIB.BASEBOARD_FAB2(SCH_1):M_C_MA(2)
  71 M_C_MA<3>     A3 @BASEBOARD_FAB2_LIB.BASEBOARD_FAB2(SCH_1):M_C_MA(3)
 214 M_C_MA<4>     A4 @BASEBOARD_FAB2_LIB.BASEBOARD_FAB2(SCH_1):M_C_MA(4)
 213 M_C_MA<5>     A5 @BASEBOARD_FAB2_LIB.BASEBOARD_FAB2(SCH_1):M_C_MA(5)
  69 M_C_MA<6>     A6 @BASEBOARD_FAB2_LIB.BASEBOARD_FAB2(SCH_1):M_C_MA(6)
 211 M_C_MA<7>     A7 @BASEBOARD_FAB2_LIB.BASEBOARD_FAB2(SCH_1):M_C_MA(7)
  68 M_C_MA<8>     A8 @BASEBOARD_FAB2_LIB.BASEBOARD_FAB2(SCH_1):M_C_MA(8)
  66 M_C_MA<9>     A9 @BASEBOARD_FAB2_LIB.BASEBOARD_FAB2(SCH_1):M_C_MA(9)
  62 M_C_ACT_N  ACT_N @BASEBOARD_FAB2_LIB.BASEBOARD_FAB2(SCH_1):M_C_ACT_N
 208 M_C_ALERT_N ALERT_N @BASEBOARD_FAB2_LIB.BASEBOARD_FAB2(SCH_1):M_C_ALERT_N
 224 M_C_BA<1>  BA<1> @BASEBOARD_FAB2_LIB.BASEBOARD_FAB2(SCH_1):M_C_BA(1)
  81 M_C_BA<0>  BA<0> @BASEBOARD_FAB2_LIB.BASEBOARD_FAB2(SCH_1):M_C_BA(0)
 207 M_C_BG<1>  BG<1> @BASEBOARD_FAB2_LIB.BASEBOARD_FAB2(SCH_1):M_C_BG(1)
  63 M_C_BG<0>  BG<0> @BASEBOARD_FAB2_LIB.BASEBOARD_FAB2(SCH_1):M_C_BG(0)
 235 M_C_C<2>   C<2> @BASEBOARD_FAB2_LIB.BASEBOARD_FAB2(SCH_1):M_C_C(2)
 199 M_C_ECC<6>  CB<7> @BASEBOARD_FAB2_LIB.BASEBOARD_FAB2(SCH_1):M_C_ECC(6)
  54 M_C_ECC<7>  CB<6> @BASEBOARD_FAB2_LIB.BASEBOARD_FAB2(SCH_1):M_C_ECC(7)
 192 M_C_ECC<4>  CB<5> @BASEBOARD_FAB2_LIB.BASEBOARD_FAB2(SCH_1):M_C_ECC(4)
  47 M_C_ECC<5>  CB<4> @BASEBOARD_FAB2_LIB.BASEBOARD_FAB2(SCH_1):M_C_ECC(5)
 201 M_C_ECC<2>  CB<3> @BASEBOARD_FAB2_LIB.BASEBOARD_FAB2(SCH_1):M_C_ECC(2)
  56 M_C_ECC<3>  CB<2> @BASEBOARD_FAB2_LIB.BASEBOARD_FAB2(SCH_1):M_C_ECC(3)
 194 M_C_ECC<0>  CB<1> @BASEBOARD_FAB2_LIB.BASEBOARD_FAB2(SCH_1):M_C_ECC(0)
  49 M_C_ECC<1>  CB<0> @BASEBOARD_FAB2_LIB.BASEBOARD_FAB2(SCH_1):M_C_ECC(1)
  75 M_C_CLK_DN<0>   CK0N @BASEBOARD_FAB2_LIB.BASEBOARD_FAB2(SCH_1):M_C_CLK_DN(0)
  74 M_C_CLK_DP<0>   CK0P @BASEBOARD_FAB2_LIB.BASEBOARD_FAB2(SCH_1):M_C_CLK_DP(0)
 219 M_C_CLK_DN<1>   CK1N @BASEBOARD_FAB2_LIB.BASEBOARD_FAB2(SCH_1):M_C_CLK_DN(1)
 218 M_C_CLK_DP<1>   CK1P @BASEBOARD_FAB2_LIB.BASEBOARD_FAB2(SCH_1):M_C_CLK_DP(1)
 203 M_C_CKE<1> CKE<1> @BASEBOARD_FAB2_LIB.BASEBOARD_FAB2(SCH_1):M_C_CKE(1)
  60 M_C_CKE<0> CKE<0> @BASEBOARD_FAB2_LIB.BASEBOARD_FAB2(SCH_1):M_C_CKE(0)
 280 M_C_DQ<62> DQ<63> @BASEBOARD_FAB2_LIB.BASEBOARD_FAB2(SCH_1):M_C_DQ(62)
 135 M_C_DQ<63> DQ<62> @BASEBOARD_FAB2_LIB.BASEBOARD_FAB2(SCH_1):M_C_DQ(63)
 273 M_C_DQ<60> DQ<61> @BASEBOARD_FAB2_LIB.BASEBOARD_FAB2(SCH_1):M_C_DQ(60)
 128 M_C_DQ<61> DQ<60> @BASEBOARD_FAB2_LIB.BASEBOARD_FAB2(SCH_1):M_C_DQ(61)
 282 M_C_DQ<58> DQ<59> @BASEBOARD_FAB2_LIB.BASEBOARD_FAB2(SCH_1):M_C_DQ(58)
 137 M_C_DQ<59> DQ<58> @BASEBOARD_FAB2_LIB.BASEBOARD_FAB2(SCH_1):M_C_DQ(59)
 275 M_C_DQ<56> DQ<57> @BASEBOARD_FAB2_LIB.BASEBOARD_FAB2(SCH_1):M_C_DQ(56)
 130 M_C_DQ<57> DQ<56> @BASEBOARD_FAB2_LIB.BASEBOARD_FAB2(SCH_1):M_C_DQ(57)
 269 M_C_DQ<54> DQ<55> @BASEBOARD_FAB2_LIB.BASEBOARD_FAB2(SCH_1):M_C_DQ(54)
 124 M_C_DQ<55> DQ<54> @BASEBOARD_FAB2_LIB.BASEBOARD_FAB2(SCH_1):M_C_DQ(55)
 262 M_C_DQ<52> DQ<53> @BASEBOARD_FAB2_LIB.BASEBOARD_FAB2(SCH_1):M_C_DQ(52)
 117 M_C_DQ<53> DQ<52> @BASEBOARD_FAB2_LIB.BASEBOARD_FAB2(SCH_1):M_C_DQ(53)
 271 M_C_DQ<50> DQ<51> @BASEBOARD_FAB2_LIB.BASEBOARD_FAB2(SCH_1):M_C_DQ(50)
 126 M_C_DQ<51> DQ<50> @BASEBOARD_FAB2_LIB.BASEBOARD_FAB2(SCH_1):M_C_DQ(51)
 264 M_C_DQ<48> DQ<49> @BASEBOARD_FAB2_LIB.BASEBOARD_FAB2(SCH_1):M_C_DQ(48)
 119 M_C_DQ<49> DQ<48> @BASEBOARD_FAB2_LIB.BASEBOARD_FAB2(SCH_1):M_C_DQ(49)
 258 M_C_DQ<46> DQ<47> @BASEBOARD_FAB2_LIB.BASEBOARD_FAB2(SCH_1):M_C_DQ(46)
 113 M_C_DQ<47> DQ<46> @BASEBOARD_FAB2_LIB.BASEBOARD_FAB2(SCH_1):M_C_DQ(47)
 251 M_C_DQ<44> DQ<45> @BASEBOARD_FAB2_LIB.BASEBOARD_FAB2(SCH_1):M_C_DQ(44)
 106 M_C_DQ<45> DQ<44> @BASEBOARD_FAB2_LIB.BASEBOARD_FAB2(SCH_1):M_C_DQ(45)
 260 M_C_DQ<42> DQ<43> @BASEBOARD_FAB2_LIB.BASEBOARD_FAB2(SCH_1):M_C_DQ(42)
 115 M_C_DQ<43> DQ<42> @BASEBOARD_FAB2_LIB.BASEBOARD_FAB2(SCH_1):M_C_DQ(43)
 253 M_C_DQ<40> DQ<41> @BASEBOARD_FAB2_LIB.BASEBOARD_FAB2(SCH_1):M_C_DQ(40)
 108 M_C_DQ<41> DQ<40> @BASEBOARD_FAB2_LIB.BASEBOARD_FAB2(SCH_1):M_C_DQ(41)
 247 M_C_DQ<38> DQ<39> @BASEBOARD_FAB2_LIB.BASEBOARD_FAB2(SCH_1):M_C_DQ(38)
 102 M_C_DQ<39> DQ<38> @BASEBOARD_FAB2_LIB.BASEBOARD_FAB2(SCH_1):M_C_DQ(39)
 240 M_C_DQ<36> DQ<37> @BASEBOARD_FAB2_LIB.BASEBOARD_FAB2(SCH_1):M_C_DQ(36)
  95 M_C_DQ<37> DQ<36> @BASEBOARD_FAB2_LIB.BASEBOARD_FAB2(SCH_1):M_C_DQ(37)
 249 M_C_DQ<34> DQ<35> @BASEBOARD_FAB2_LIB.BASEBOARD_FAB2(SCH_1):M_C_DQ(34)
 104 M_C_DQ<35> DQ<34> @BASEBOARD_FAB2_LIB.BASEBOARD_FAB2(SCH_1):M_C_DQ(35)
 242 M_C_DQ<32> DQ<33> @BASEBOARD_FAB2_LIB.BASEBOARD_FAB2(SCH_1):M_C_DQ(32)
  97 M_C_DQ<33> DQ<32> @BASEBOARD_FAB2_LIB.BASEBOARD_FAB2(SCH_1):M_C_DQ(33)
 188 M_C_DQ<30> DQ<31> @BASEBOARD_FAB2_LIB.BASEBOARD_FAB2(SCH_1):M_C_DQ(30)
  43 M_C_DQ<31> DQ<30> @BASEBOARD_FAB2_LIB.BASEBOARD_FAB2(SCH_1):M_C_DQ(31)
 181 M_C_DQ<28> DQ<29> @BASEBOARD_FAB2_LIB.BASEBOARD_FAB2(SCH_1):M_C_DQ(28)
  36 M_C_DQ<29> DQ<28> @BASEBOARD_FAB2_LIB.BASEBOARD_FAB2(SCH_1):M_C_DQ(29)
 190 M_C_DQ<26> DQ<27> @BASEBOARD_FAB2_LIB.BASEBOARD_FAB2(SCH_1):M_C_DQ(26)
  45 M_C_DQ<27> DQ<26> @BASEBOARD_FAB2_LIB.BASEBOARD_FAB2(SCH_1):M_C_DQ(27)
 183 M_C_DQ<24> DQ<25> @BASEBOARD_FAB2_LIB.BASEBOARD_FAB2(SCH_1):M_C_DQ(24)
  38 M_C_DQ<25> DQ<24> @BASEBOARD_FAB2_LIB.BASEBOARD_FAB2(SCH_1):M_C_DQ(25)
 177 M_C_DQ<22> DQ<23> @BASEBOARD_FAB2_LIB.BASEBOARD_FAB2(SCH_1):M_C_DQ(22)
  32 M_C_DQ<23> DQ<22> @BASEBOARD_FAB2_LIB.BASEBOARD_FAB2(SCH_1):M_C_DQ(23)
 170 M_C_DQ<20> DQ<21> @BASEBOARD_FAB2_LIB.BASEBOARD_FAB2(SCH_1):M_C_DQ(20)
  25 M_C_DQ<21> DQ<20> @BASEBOARD_FAB2_LIB.BASEBOARD_FAB2(SCH_1):M_C_DQ(21)
 179 M_C_DQ<18> DQ<19> @BASEBOARD_FAB2_LIB.BASEBOARD_FAB2(SCH_1):M_C_DQ(18)
  34 M_C_DQ<19> DQ<18> @BASEBOARD_FAB2_LIB.BASEBOARD_FAB2(SCH_1):M_C_DQ(19)
 172 M_C_DQ<16> DQ<17> @BASEBOARD_FAB2_LIB.BASEBOARD_FAB2(SCH_1):M_C_DQ(16)
  27 M_C_DQ<17> DQ<16> @BASEBOARD_FAB2_LIB.BASEBOARD_FAB2(SCH_1):M_C_DQ(17)
 166 M_C_DQ<14> DQ<15> @BASEBOARD_FAB2_LIB.BASEBOARD_FAB2(SCH_1):M_C_DQ(14)
  21 M_C_DQ<15> DQ<14> @BASEBOARD_FAB2_LIB.BASEBOARD_FAB2(SCH_1):M_C_DQ(15)
 159 M_C_DQ<12> DQ<13> @BASEBOARD_FAB2_LIB.BASEBOARD_FAB2(SCH_1):M_C_DQ(12)
  14 M_C_DQ<13> DQ<12> @BASEBOARD_FAB2_LIB.BASEBOARD_FAB2(SCH_1):M_C_DQ(13)
 168 M_C_DQ<10> DQ<11> @BASEBOARD_FAB2_LIB.BASEBOARD_FAB2(SCH_1):M_C_DQ(10)
  23 M_C_DQ<11> DQ<10> @BASEBOARD_FAB2_LIB.BASEBOARD_FAB2(SCH_1):M_C_DQ(11)
 161 M_C_DQ<8>  DQ<9> @BASEBOARD_FAB2_LIB.BASEBOARD_FAB2(SCH_1):M_C_DQ(8)
  16 M_C_DQ<9>  DQ<8> @BASEBOARD_FAB2_LIB.BASEBOARD_FAB2(SCH_1):M_C_DQ(9)
 155 M_C_DQ<6>  DQ<7> @BASEBOARD_FAB2_LIB.BASEBOARD_FAB2(SCH_1):M_C_DQ(6)
  10 M_C_DQ<7>  DQ<6> @BASEBOARD_FAB2_LIB.BASEBOARD_FAB2(SCH_1):M_C_DQ(7)
 148 M_C_DQ<4>  DQ<5> @BASEBOARD_FAB2_LIB.BASEBOARD_FAB2(SCH_1):M_C_DQ(4)
   3 M_C_DQ<5>  DQ<4> @BASEBOARD_FAB2_LIB.BASEBOARD_FAB2(SCH_1):M_C_DQ(5)
 157 M_C_DQ<2>  DQ<3> @BASEBOARD_FAB2_LIB.BASEBOARD_FAB2(SCH_1):M_C_DQ(2)
  12 M_C_DQ<3>  DQ<2> @BASEBOARD_FAB2_LIB.BASEBOARD_FAB2(SCH_1):M_C_DQ(3)
 150 M_C_DQ<0>  DQ<1> @BASEBOARD_FAB2_LIB.BASEBOARD_FAB2(SCH_1):M_C_DQ(0)
   5 M_C_DQ<1>  DQ<0> @BASEBOARD_FAB2_LIB.BASEBOARD_FAB2(SCH_1):M_C_DQ(1)
  78 FM_DIMM_EVENT_COD_N EVENT_N @BASEBOARD_FAB2_LIB.BASEBOARD_FAB2(SCH_1):FM_DIMM_EVENT_COD_N
  91 M_C_ODT<1> ODT<1> @BASEBOARD_FAB2_LIB.BASEBOARD_FAB2(SCH_1):M_C_ODT(1)
  87 M_C_ODT<0> ODT<0> @BASEBOARD_FAB2_LIB.BASEBOARD_FAB2(SCH_1):M_C_ODT(0)
 222 M_C_PAR    PAR @BASEBOARD_FAB2_LIB.BASEBOARD_FAB2(SCH_1):M_C_PAR
  58 M_ABC_RST_N RESET_N @BASEBOARD_FAB2_LIB.BASEBOARD_FAB2(SCH_1):M_ABC_RST_N
 144 TP_CH_C_DIMM_C0_RFU_2 RFU<2> @BASEBOARD_FAB2_LIB.BASEBOARD_FAB2(SCH_1):TP_CH_C_DIMM_C0_RFU_2
 227 TP_CH_C_DIMM_C0_RFU_1 RFU<1> @BASEBOARD_FAB2_LIB.BASEBOARD_FAB2(SCH_1):TP_CH_C_DIMM_C0_RFU_1
 205 TP_CH_C_DIMM_C0_RFU_0 RFU<0> @BASEBOARD_FAB2_LIB.BASEBOARD_FAB2(SCH_1):TP_CH_C_DIMM_C0_RFU_0
  84 M_C_CS_N<0>   S0_N @BASEBOARD_FAB2_LIB.BASEBOARD_FAB2(SCH_1):M_C_CS_N(0)
  89 M_C_CS_N<1>   S1_N @BASEBOARD_FAB2_LIB.BASEBOARD_FAB2(SCH_1):M_C_CS_N(1)
  93 M_C_CS_N<2> S2_N_C<0> @BASEBOARD_FAB2_LIB.BASEBOARD_FAB2(SCH_1):M_C_CS_N(2)
 237 M_C_CS_N<3> S3_N_C<1> @BASEBOARD_FAB2_LIB.BASEBOARD_FAB2(SCH_1):M_C_CS_N(3)
 238 PVPP_ABC  SA<2> @BASEBOARD_FAB2_LIB.BASEBOARD_FAB2(SCH_1):PVPP_ABC
 140    GND  SA<1> @BASEBOARD_FAB2_LIB.BASEBOARD_FAB2(SCH_1):GND
 139    GND  SA<0> @BASEBOARD_FAB2_LIB.BASEBOARD_FAB2(SCH_1):GND
 230 FM_ADR_COMPLETE_ABC_N SAVE_N_NC @BASEBOARD_FAB2_LIB.BASEBOARD_FAB2(SCH_1):FM_ADR_COMPLETE_ABC_N
 141 SMB_DDR_ABC_VPP_SCL    SCL @BASEBOARD_FAB2_LIB.BASEBOARD_FAB2(SCH_1):SMB_DDR_ABC_VPP_SCL
 285 SMB_DDR_ABC_VPP_SDA    SDA @BASEBOARD_FAB2_LIB.BASEBOARD_FAB2(SCH_1):SMB_DDR_ABC_VPP_SDA
 284 PVPP_ABC VDDSPD @BASEBOARD_FAB2_LIB.BASEBOARD_FAB2(SCH_1):PVPP_ABC
 146 M_C_VREF VREFCA @BASEBOARD_FAB2_LIB.BASEBOARD_FAB2(SCH_1):M_C_VREF

SCONN288_H44441004_PIP-SCONN,HA  I179  J4G3
   1 P12V_NVDIMM_ABC 12V<1> @BASEBOARD_FAB2_LIB.BASEBOARD_FAB2(SCH_1):P12V_NVDIMM_ABC
 145 P12V_NVDIMM_ABC 12V<0> @BASEBOARD_FAB2_LIB.BASEBOARD_FAB2(SCH_1):P12V_NVDIMM_ABC
  59 PVDDQ_ABC VDD<25> @BASEBOARD_FAB2_LIB.BASEBOARD_FAB2(SCH_1):PVDDQ_ABC
  61 PVDDQ_ABC VDD<24> @BASEBOARD_FAB2_LIB.BASEBOARD_FAB2(SCH_1):PVDDQ_ABC
  64 PVDDQ_ABC VDD<23> @BASEBOARD_FAB2_LIB.BASEBOARD_FAB2(SCH_1):PVDDQ_ABC
  67 PVDDQ_ABC VDD<22> @BASEBOARD_FAB2_LIB.BASEBOARD_FAB2(SCH_1):PVDDQ_ABC
  70 PVDDQ_ABC VDD<21> @BASEBOARD_FAB2_LIB.BASEBOARD_FAB2(SCH_1):PVDDQ_ABC
  73 PVDDQ_ABC VDD<20> @BASEBOARD_FAB2_LIB.BASEBOARD_FAB2(SCH_1):PVDDQ_ABC
  76 PVDDQ_ABC VDD<19> @BASEBOARD_FAB2_LIB.BASEBOARD_FAB2(SCH_1):PVDDQ_ABC
  80 PVDDQ_ABC VDD<18> @BASEBOARD_FAB2_LIB.BASEBOARD_FAB2(SCH_1):PVDDQ_ABC
  83 PVDDQ_ABC VDD<17> @BASEBOARD_FAB2_LIB.BASEBOARD_FAB2(SCH_1):PVDDQ_ABC
  85 PVDDQ_ABC VDD<16> @BASEBOARD_FAB2_LIB.BASEBOARD_FAB2(SCH_1):PVDDQ_ABC
  88 PVDDQ_ABC VDD<15> @BASEBOARD_FAB2_LIB.BASEBOARD_FAB2(SCH_1):PVDDQ_ABC
  90 PVDDQ_ABC VDD<14> @BASEBOARD_FAB2_LIB.BASEBOARD_FAB2(SCH_1):PVDDQ_ABC
  92 PVDDQ_ABC VDD<13> @BASEBOARD_FAB2_LIB.BASEBOARD_FAB2(SCH_1):PVDDQ_ABC
 204 PVDDQ_ABC VDD<12> @BASEBOARD_FAB2_LIB.BASEBOARD_FAB2(SCH_1):PVDDQ_ABC
 206 PVDDQ_ABC VDD<11> @BASEBOARD_FAB2_LIB.BASEBOARD_FAB2(SCH_1):PVDDQ_ABC
 209 PVDDQ_ABC VDD<10> @BASEBOARD_FAB2_LIB.BASEBOARD_FAB2(SCH_1):PVDDQ_ABC
 212 PVDDQ_ABC VDD<9> @BASEBOARD_FAB2_LIB.BASEBOARD_FAB2(SCH_1):PVDDQ_ABC
 215 PVDDQ_ABC VDD<8> @BASEBOARD_FAB2_LIB.BASEBOARD_FAB2(SCH_1):PVDDQ_ABC
 217 PVDDQ_ABC VDD<7> @BASEBOARD_FAB2_LIB.BASEBOARD_FAB2(SCH_1):PVDDQ_ABC
 220 PVDDQ_ABC VDD<6> @BASEBOARD_FAB2_LIB.BASEBOARD_FAB2(SCH_1):PVDDQ_ABC
 223 PVDDQ_ABC VDD<5> @BASEBOARD_FAB2_LIB.BASEBOARD_FAB2(SCH_1):PVDDQ_ABC
 226 PVDDQ_ABC VDD<4> @BASEBOARD_FAB2_LIB.BASEBOARD_FAB2(SCH_1):PVDDQ_ABC
 229 PVDDQ_ABC VDD<3> @BASEBOARD_FAB2_LIB.BASEBOARD_FAB2(SCH_1):PVDDQ_ABC
 231 PVDDQ_ABC VDD<2> @BASEBOARD_FAB2_LIB.BASEBOARD_FAB2(SCH_1):PVDDQ_ABC
 233 PVDDQ_ABC VDD<1> @BASEBOARD_FAB2_LIB.BASEBOARD_FAB2(SCH_1):PVDDQ_ABC
 236 PVDDQ_ABC VDD<0> @BASEBOARD_FAB2_LIB.BASEBOARD_FAB2(SCH_1):PVDDQ_ABC
 142 PVPP_ABC VPP<4> @BASEBOARD_FAB2_LIB.BASEBOARD_FAB2(SCH_1):PVPP_ABC
 143 PVPP_ABC VPP<3> @BASEBOARD_FAB2_LIB.BASEBOARD_FAB2(SCH_1):PVPP_ABC
 288 PVPP_ABC VPP<2> @BASEBOARD_FAB2_LIB.BASEBOARD_FAB2(SCH_1):PVPP_ABC
 286 PVPP_ABC VPP<1> @BASEBOARD_FAB2_LIB.BASEBOARD_FAB2(SCH_1):PVPP_ABC
 287 PVPP_ABC VPP<0> @BASEBOARD_FAB2_LIB.BASEBOARD_FAB2(SCH_1):PVPP_ABC
  77 PVTT_ABC VTT<1> @BASEBOARD_FAB2_LIB.BASEBOARD_FAB2(SCH_1):PVTT_ABC
 221 PVTT_ABC VTT<0> @BASEBOARD_FAB2_LIB.BASEBOARD_FAB2(SCH_1):PVTT_ABC

CAP_A_0402V-0.01UF,25V,10%,X7RA  I188  C4G19
   1 M_C_VREF      A @BASEBOARD_FAB2_LIB.BASEBOARD_FAB2(SCH_1):M_C_VREF
   2    GND      B @BASEBOARD_FAB2_LIB.BASEBOARD_FAB2(SCH_1):GND


DRAWING: @BASEBOARD_FAB2_LIB.BASEBOARD_FAB2(SCH_1):PAGE48 

SCONN288_H44441003_PIP-SCONN,HA  I43  J6U2
   2    GND VSS<93> @BASEBOARD_FAB2_LIB.BASEBOARD_FAB2(SCH_1):GND
   4    GND VSS<92> @BASEBOARD_FAB2_LIB.BASEBOARD_FAB2(SCH_1):GND
   6    GND VSS<91> @BASEBOARD_FAB2_LIB.BASEBOARD_FAB2(SCH_1):GND
   9    GND VSS<90> @BASEBOARD_FAB2_LIB.BASEBOARD_FAB2(SCH_1):GND
  11    GND VSS<89> @BASEBOARD_FAB2_LIB.BASEBOARD_FAB2(SCH_1):GND
  13    GND VSS<88> @BASEBOARD_FAB2_LIB.BASEBOARD_FAB2(SCH_1):GND
  15    GND VSS<87> @BASEBOARD_FAB2_LIB.BASEBOARD_FAB2(SCH_1):GND
  17    GND VSS<86> @BASEBOARD_FAB2_LIB.BASEBOARD_FAB2(SCH_1):GND
  20    GND VSS<85> @BASEBOARD_FAB2_LIB.BASEBOARD_FAB2(SCH_1):GND
  22    GND VSS<84> @BASEBOARD_FAB2_LIB.BASEBOARD_FAB2(SCH_1):GND
  24    GND VSS<83> @BASEBOARD_FAB2_LIB.BASEBOARD_FAB2(SCH_1):GND
  26    GND VSS<82> @BASEBOARD_FAB2_LIB.BASEBOARD_FAB2(SCH_1):GND
  28    GND VSS<81> @BASEBOARD_FAB2_LIB.BASEBOARD_FAB2(SCH_1):GND
  31    GND VSS<80> @BASEBOARD_FAB2_LIB.BASEBOARD_FAB2(SCH_1):GND
  33    GND VSS<79> @BASEBOARD_FAB2_LIB.BASEBOARD_FAB2(SCH_1):GND
  35    GND VSS<78> @BASEBOARD_FAB2_LIB.BASEBOARD_FAB2(SCH_1):GND
  37    GND VSS<77> @BASEBOARD_FAB2_LIB.BASEBOARD_FAB2(SCH_1):GND
  39    GND VSS<76> @BASEBOARD_FAB2_LIB.BASEBOARD_FAB2(SCH_1):GND
  42    GND VSS<75> @BASEBOARD_FAB2_LIB.BASEBOARD_FAB2(SCH_1):GND
  44    GND VSS<74> @BASEBOARD_FAB2_LIB.BASEBOARD_FAB2(SCH_1):GND
  46    GND VSS<73> @BASEBOARD_FAB2_LIB.BASEBOARD_FAB2(SCH_1):GND
  48    GND VSS<72> @BASEBOARD_FAB2_LIB.BASEBOARD_FAB2(SCH_1):GND
  50    GND VSS<71> @BASEBOARD_FAB2_LIB.BASEBOARD_FAB2(SCH_1):GND
  53    GND VSS<70> @BASEBOARD_FAB2_LIB.BASEBOARD_FAB2(SCH_1):GND
  55    GND VSS<69> @BASEBOARD_FAB2_LIB.BASEBOARD_FAB2(SCH_1):GND
  57    GND VSS<68> @BASEBOARD_FAB2_LIB.BASEBOARD_FAB2(SCH_1):GND
  94    GND VSS<67> @BASEBOARD_FAB2_LIB.BASEBOARD_FAB2(SCH_1):GND
  96    GND VSS<66> @BASEBOARD_FAB2_LIB.BASEBOARD_FAB2(SCH_1):GND
  98    GND VSS<65> @BASEBOARD_FAB2_LIB.BASEBOARD_FAB2(SCH_1):GND
 101    GND VSS<64> @BASEBOARD_FAB2_LIB.BASEBOARD_FAB2(SCH_1):GND
 103    GND VSS<63> @BASEBOARD_FAB2_LIB.BASEBOARD_FAB2(SCH_1):GND
 105    GND VSS<62> @BASEBOARD_FAB2_LIB.BASEBOARD_FAB2(SCH_1):GND
 107    GND VSS<61> @BASEBOARD_FAB2_LIB.BASEBOARD_FAB2(SCH_1):GND
 109    GND VSS<60> @BASEBOARD_FAB2_LIB.BASEBOARD_FAB2(SCH_1):GND
 112    GND VSS<59> @BASEBOARD_FAB2_LIB.BASEBOARD_FAB2(SCH_1):GND
 114    GND VSS<58> @BASEBOARD_FAB2_LIB.BASEBOARD_FAB2(SCH_1):GND
 116    GND VSS<57> @BASEBOARD_FAB2_LIB.BASEBOARD_FAB2(SCH_1):GND
 118    GND VSS<56> @BASEBOARD_FAB2_LIB.BASEBOARD_FAB2(SCH_1):GND
 120    GND VSS<55> @BASEBOARD_FAB2_LIB.BASEBOARD_FAB2(SCH_1):GND
 123    GND VSS<54> @BASEBOARD_FAB2_LIB.BASEBOARD_FAB2(SCH_1):GND
 125    GND VSS<53> @BASEBOARD_FAB2_LIB.BASEBOARD_FAB2(SCH_1):GND
 127    GND VSS<52> @BASEBOARD_FAB2_LIB.BASEBOARD_FAB2(SCH_1):GND
 129    GND VSS<51> @BASEBOARD_FAB2_LIB.BASEBOARD_FAB2(SCH_1):GND
 131    GND VSS<50> @BASEBOARD_FAB2_LIB.BASEBOARD_FAB2(SCH_1):GND
 134    GND VSS<49> @BASEBOARD_FAB2_LIB.BASEBOARD_FAB2(SCH_1):GND
 136    GND VSS<48> @BASEBOARD_FAB2_LIB.BASEBOARD_FAB2(SCH_1):GND
 138    GND VSS<47> @BASEBOARD_FAB2_LIB.BASEBOARD_FAB2(SCH_1):GND
 147    GND VSS<46> @BASEBOARD_FAB2_LIB.BASEBOARD_FAB2(SCH_1):GND
 149    GND VSS<45> @BASEBOARD_FAB2_LIB.BASEBOARD_FAB2(SCH_1):GND
 151    GND VSS<44> @BASEBOARD_FAB2_LIB.BASEBOARD_FAB2(SCH_1):GND
 154    GND VSS<43> @BASEBOARD_FAB2_LIB.BASEBOARD_FAB2(SCH_1):GND
 156    GND VSS<42> @BASEBOARD_FAB2_LIB.BASEBOARD_FAB2(SCH_1):GND
 158    GND VSS<41> @BASEBOARD_FAB2_LIB.BASEBOARD_FAB2(SCH_1):GND
 160    GND VSS<40> @BASEBOARD_FAB2_LIB.BASEBOARD_FAB2(SCH_1):GND
 162    GND VSS<39> @BASEBOARD_FAB2_LIB.BASEBOARD_FAB2(SCH_1):GND
 165    GND VSS<38> @BASEBOARD_FAB2_LIB.BASEBOARD_FAB2(SCH_1):GND
 167    GND VSS<37> @BASEBOARD_FAB2_LIB.BASEBOARD_FAB2(SCH_1):GND
 169    GND VSS<36> @BASEBOARD_FAB2_LIB.BASEBOARD_FAB2(SCH_1):GND
 171    GND VSS<35> @BASEBOARD_FAB2_LIB.BASEBOARD_FAB2(SCH_1):GND
 173    GND VSS<34> @BASEBOARD_FAB2_LIB.BASEBOARD_FAB2(SCH_1):GND
 176    GND VSS<33> @BASEBOARD_FAB2_LIB.BASEBOARD_FAB2(SCH_1):GND
 178    GND VSS<32> @BASEBOARD_FAB2_LIB.BASEBOARD_FAB2(SCH_1):GND
 180    GND VSS<31> @BASEBOARD_FAB2_LIB.BASEBOARD_FAB2(SCH_1):GND
 182    GND VSS<30> @BASEBOARD_FAB2_LIB.BASEBOARD_FAB2(SCH_1):GND
 184    GND VSS<29> @BASEBOARD_FAB2_LIB.BASEBOARD_FAB2(SCH_1):GND
 187    GND VSS<28> @BASEBOARD_FAB2_LIB.BASEBOARD_FAB2(SCH_1):GND
 189    GND VSS<27> @BASEBOARD_FAB2_LIB.BASEBOARD_FAB2(SCH_1):GND
 191    GND VSS<26> @BASEBOARD_FAB2_LIB.BASEBOARD_FAB2(SCH_1):GND
 193    GND VSS<25> @BASEBOARD_FAB2_LIB.BASEBOARD_FAB2(SCH_1):GND
 195    GND VSS<24> @BASEBOARD_FAB2_LIB.BASEBOARD_FAB2(SCH_1):GND
 198    GND VSS<23> @BASEBOARD_FAB2_LIB.BASEBOARD_FAB2(SCH_1):GND
 200    GND VSS<22> @BASEBOARD_FAB2_LIB.BASEBOARD_FAB2(SCH_1):GND
 202    GND VSS<21> @BASEBOARD_FAB2_LIB.BASEBOARD_FAB2(SCH_1):GND
 239    GND VSS<20> @BASEBOARD_FAB2_LIB.BASEBOARD_FAB2(SCH_1):GND
 241    GND VSS<19> @BASEBOARD_FAB2_LIB.BASEBOARD_FAB2(SCH_1):GND
 243    GND VSS<18> @BASEBOARD_FAB2_LIB.BASEBOARD_FAB2(SCH_1):GND
 246    GND VSS<17> @BASEBOARD_FAB2_LIB.BASEBOARD_FAB2(SCH_1):GND
 248    GND VSS<16> @BASEBOARD_FAB2_LIB.BASEBOARD_FAB2(SCH_1):GND
 250    GND VSS<15> @BASEBOARD_FAB2_LIB.BASEBOARD_FAB2(SCH_1):GND
 252    GND VSS<14> @BASEBOARD_FAB2_LIB.BASEBOARD_FAB2(SCH_1):GND
 254    GND VSS<13> @BASEBOARD_FAB2_LIB.BASEBOARD_FAB2(SCH_1):GND
 257    GND VSS<12> @BASEBOARD_FAB2_LIB.BASEBOARD_FAB2(SCH_1):GND
 259    GND VSS<11> @BASEBOARD_FAB2_LIB.BASEBOARD_FAB2(SCH_1):GND
 261    GND VSS<10> @BASEBOARD_FAB2_LIB.BASEBOARD_FAB2(SCH_1):GND
 263    GND VSS<9> @BASEBOARD_FAB2_LIB.BASEBOARD_FAB2(SCH_1):GND
 265    GND VSS<8> @BASEBOARD_FAB2_LIB.BASEBOARD_FAB2(SCH_1):GND
 268    GND VSS<7> @BASEBOARD_FAB2_LIB.BASEBOARD_FAB2(SCH_1):GND
 270    GND VSS<6> @BASEBOARD_FAB2_LIB.BASEBOARD_FAB2(SCH_1):GND
 272    GND VSS<5> @BASEBOARD_FAB2_LIB.BASEBOARD_FAB2(SCH_1):GND
 274    GND VSS<4> @BASEBOARD_FAB2_LIB.BASEBOARD_FAB2(SCH_1):GND
 276    GND VSS<3> @BASEBOARD_FAB2_LIB.BASEBOARD_FAB2(SCH_1):GND
 279    GND VSS<2> @BASEBOARD_FAB2_LIB.BASEBOARD_FAB2(SCH_1):GND
 281    GND VSS<1> @BASEBOARD_FAB2_LIB.BASEBOARD_FAB2(SCH_1):GND
 283    GND VSS<0> @BASEBOARD_FAB2_LIB.BASEBOARD_FAB2(SCH_1):GND

SCONN288_H44441003_PIP-SCONN,HA  I61  J6U2
 152 M_C_DQS_DN<0>  DQS0N @BASEBOARD_FAB2_LIB.BASEBOARD_FAB2(SCH_1):M_C_DQS_DN(0)
 153 M_C_DQS_DP<0>  DQS0P @BASEBOARD_FAB2_LIB.BASEBOARD_FAB2(SCH_1):M_C_DQS_DP(0)
  19 M_C_DQS_DN<10> DQS10N @BASEBOARD_FAB2_LIB.BASEBOARD_FAB2(SCH_1):M_C_DQS_DN(10)
  18 M_C_DQS_DP<10> DQS10P @BASEBOARD_FAB2_LIB.BASEBOARD_FAB2(SCH_1):M_C_DQS_DP(10)
  30 M_C_DQS_DN<11> DQS11N @BASEBOARD_FAB2_LIB.BASEBOARD_FAB2(SCH_1):M_C_DQS_DN(11)
  29 M_C_DQS_DP<11> DQS11P @BASEBOARD_FAB2_LIB.BASEBOARD_FAB2(SCH_1):M_C_DQS_DP(11)
  41 M_C_DQS_DN<12> DQS12N @BASEBOARD_FAB2_LIB.BASEBOARD_FAB2(SCH_1):M_C_DQS_DN(12)
  40 M_C_DQS_DP<12> DQS12P @BASEBOARD_FAB2_LIB.BASEBOARD_FAB2(SCH_1):M_C_DQS_DP(12)
 100 M_C_DQS_DN<13> DQS13N @BASEBOARD_FAB2_LIB.BASEBOARD_FAB2(SCH_1):M_C_DQS_DN(13)
  99 M_C_DQS_DP<13> DQS13P @BASEBOARD_FAB2_LIB.BASEBOARD_FAB2(SCH_1):M_C_DQS_DP(13)
 111 M_C_DQS_DN<14> DQS14N @BASEBOARD_FAB2_LIB.BASEBOARD_FAB2(SCH_1):M_C_DQS_DN(14)
 110 M_C_DQS_DP<14> DQS14P @BASEBOARD_FAB2_LIB.BASEBOARD_FAB2(SCH_1):M_C_DQS_DP(14)
 122 M_C_DQS_DN<15> DQS15N @BASEBOARD_FAB2_LIB.BASEBOARD_FAB2(SCH_1):M_C_DQS_DN(15)
 121 M_C_DQS_DP<15> DQS15P @BASEBOARD_FAB2_LIB.BASEBOARD_FAB2(SCH_1):M_C_DQS_DP(15)
 133 M_C_DQS_DN<16> DQS16N @BASEBOARD_FAB2_LIB.BASEBOARD_FAB2(SCH_1):M_C_DQS_DN(16)
 132 M_C_DQS_DP<16> DQS16P @BASEBOARD_FAB2_LIB.BASEBOARD_FAB2(SCH_1):M_C_DQS_DP(16)
  52 M_C_DQS_DN<17> DQS17N @BASEBOARD_FAB2_LIB.BASEBOARD_FAB2(SCH_1):M_C_DQS_DN(17)
  51 M_C_DQS_DP<17> DQS17P @BASEBOARD_FAB2_LIB.BASEBOARD_FAB2(SCH_1):M_C_DQS_DP(17)
 163 M_C_DQS_DN<1>  DQS1N @BASEBOARD_FAB2_LIB.BASEBOARD_FAB2(SCH_1):M_C_DQS_DN(1)
 164 M_C_DQS_DP<1>  DQS1P @BASEBOARD_FAB2_LIB.BASEBOARD_FAB2(SCH_1):M_C_DQS_DP(1)
 174 M_C_DQS_DN<2>  DQS2N @BASEBOARD_FAB2_LIB.BASEBOARD_FAB2(SCH_1):M_C_DQS_DN(2)
 175 M_C_DQS_DP<2>  DQS2P @BASEBOARD_FAB2_LIB.BASEBOARD_FAB2(SCH_1):M_C_DQS_DP(2)
 185 M_C_DQS_DN<3>  DQS3N @BASEBOARD_FAB2_LIB.BASEBOARD_FAB2(SCH_1):M_C_DQS_DN(3)
 186 M_C_DQS_DP<3>  DQS3P @BASEBOARD_FAB2_LIB.BASEBOARD_FAB2(SCH_1):M_C_DQS_DP(3)
 244 M_C_DQS_DN<4>  DQS4N @BASEBOARD_FAB2_LIB.BASEBOARD_FAB2(SCH_1):M_C_DQS_DN(4)
 245 M_C_DQS_DP<4>  DQS4P @BASEBOARD_FAB2_LIB.BASEBOARD_FAB2(SCH_1):M_C_DQS_DP(4)
 255 M_C_DQS_DN<5>  DQS5N @BASEBOARD_FAB2_LIB.BASEBOARD_FAB2(SCH_1):M_C_DQS_DN(5)
 256 M_C_DQS_DP<5>  DQS5P @BASEBOARD_FAB2_LIB.BASEBOARD_FAB2(SCH_1):M_C_DQS_DP(5)
 266 M_C_DQS_DN<6>  DQS6N @BASEBOARD_FAB2_LIB.BASEBOARD_FAB2(SCH_1):M_C_DQS_DN(6)
 267 M_C_DQS_DP<6>  DQS6P @BASEBOARD_FAB2_LIB.BASEBOARD_FAB2(SCH_1):M_C_DQS_DP(6)
 277 M_C_DQS_DN<7>  DQS7N @BASEBOARD_FAB2_LIB.BASEBOARD_FAB2(SCH_1):M_C_DQS_DN(7)
 278 M_C_DQS_DP<7>  DQS7P @BASEBOARD_FAB2_LIB.BASEBOARD_FAB2(SCH_1):M_C_DQS_DP(7)
 196 M_C_DQS_DN<8>  DQS8N @BASEBOARD_FAB2_LIB.BASEBOARD_FAB2(SCH_1):M_C_DQS_DN(8)
 197 M_C_DQS_DP<8>  DQS8P @BASEBOARD_FAB2_LIB.BASEBOARD_FAB2(SCH_1):M_C_DQS_DP(8)
   8 M_C_DQS_DN<9>  DQS9N @BASEBOARD_FAB2_LIB.BASEBOARD_FAB2(SCH_1):M_C_DQS_DN(9)
   7 M_C_DQS_DP<9>  DQS9P @BASEBOARD_FAB2_LIB.BASEBOARD_FAB2(SCH_1):M_C_DQS_DP(9)

SCONN288_H44441003_PIP-SCONN,HA  I111  J6U2
  79 M_C_MA<0>     A0 @BASEBOARD_FAB2_LIB.BASEBOARD_FAB2(SCH_1):M_C_MA(0)
  72 M_C_MA<1>     A1 @BASEBOARD_FAB2_LIB.BASEBOARD_FAB2(SCH_1):M_C_MA(1)
 225 M_C_MA<10>    A10 @BASEBOARD_FAB2_LIB.BASEBOARD_FAB2(SCH_1):M_C_MA(10)
 210 M_C_MA<11>    A11 @BASEBOARD_FAB2_LIB.BASEBOARD_FAB2(SCH_1):M_C_MA(11)
  65 M_C_MA<12>    A12 @BASEBOARD_FAB2_LIB.BASEBOARD_FAB2(SCH_1):M_C_MA(12)
 232 M_C_MA<13>    A13 @BASEBOARD_FAB2_LIB.BASEBOARD_FAB2(SCH_1):M_C_MA(13)
 228 M_C_MA<14> A14_WE_N @BASEBOARD_FAB2_LIB.BASEBOARD_FAB2(SCH_1):M_C_MA(14)
  86 M_C_MA<15> A15_CAS_N @BASEBOARD_FAB2_LIB.BASEBOARD_FAB2(SCH_1):M_C_MA(15)
  82 M_C_MA<16> A16_RAS_N @BASEBOARD_FAB2_LIB.BASEBOARD_FAB2(SCH_1):M_C_MA(16)
 234 M_C_MA<17>    A17 @BASEBOARD_FAB2_LIB.BASEBOARD_FAB2(SCH_1):M_C_MA(17)
 216 M_C_MA<2>     A2 @BASEBOARD_FAB2_LIB.BASEBOARD_FAB2(SCH_1):M_C_MA(2)
  71 M_C_MA<3>     A3 @BASEBOARD_FAB2_LIB.BASEBOARD_FAB2(SCH_1):M_C_MA(3)
 214 M_C_MA<4>     A4 @BASEBOARD_FAB2_LIB.BASEBOARD_FAB2(SCH_1):M_C_MA(4)
 213 M_C_MA<5>     A5 @BASEBOARD_FAB2_LIB.BASEBOARD_FAB2(SCH_1):M_C_MA(5)
  69 M_C_MA<6>     A6 @BASEBOARD_FAB2_LIB.BASEBOARD_FAB2(SCH_1):M_C_MA(6)
 211 M_C_MA<7>     A7 @BASEBOARD_FAB2_LIB.BASEBOARD_FAB2(SCH_1):M_C_MA(7)
  68 M_C_MA<8>     A8 @BASEBOARD_FAB2_LIB.BASEBOARD_FAB2(SCH_1):M_C_MA(8)
  66 M_C_MA<9>     A9 @BASEBOARD_FAB2_LIB.BASEBOARD_FAB2(SCH_1):M_C_MA(9)
  62 M_C_ACT_N  ACT_N @BASEBOARD_FAB2_LIB.BASEBOARD_FAB2(SCH_1):M_C_ACT_N
 208 M_C_ALERT_N ALERT_N @BASEBOARD_FAB2_LIB.BASEBOARD_FAB2(SCH_1):M_C_ALERT_N
 224 M_C_BA<1>  BA<1> @BASEBOARD_FAB2_LIB.BASEBOARD_FAB2(SCH_1):M_C_BA(1)
  81 M_C_BA<0>  BA<0> @BASEBOARD_FAB2_LIB.BASEBOARD_FAB2(SCH_1):M_C_BA(0)
 207 M_C_BG<1>  BG<1> @BASEBOARD_FAB2_LIB.BASEBOARD_FAB2(SCH_1):M_C_BG(1)
  63 M_C_BG<0>  BG<0> @BASEBOARD_FAB2_LIB.BASEBOARD_FAB2(SCH_1):M_C_BG(0)
 235 M_C_C<2>   C<2> @BASEBOARD_FAB2_LIB.BASEBOARD_FAB2(SCH_1):M_C_C(2)
 199 M_C_ECC<7>  CB<7> @BASEBOARD_FAB2_LIB.BASEBOARD_FAB2(SCH_1):M_C_ECC(7)
  54 M_C_ECC<6>  CB<6> @BASEBOARD_FAB2_LIB.BASEBOARD_FAB2(SCH_1):M_C_ECC(6)
 192 M_C_ECC<5>  CB<5> @BASEBOARD_FAB2_LIB.BASEBOARD_FAB2(SCH_1):M_C_ECC(5)
  47 M_C_ECC<4>  CB<4> @BASEBOARD_FAB2_LIB.BASEBOARD_FAB2(SCH_1):M_C_ECC(4)
 201 M_C_ECC<3>  CB<3> @BASEBOARD_FAB2_LIB.BASEBOARD_FAB2(SCH_1):M_C_ECC(3)
  56 M_C_ECC<2>  CB<2> @BASEBOARD_FAB2_LIB.BASEBOARD_FAB2(SCH_1):M_C_ECC(2)
 194 M_C_ECC<1>  CB<1> @BASEBOARD_FAB2_LIB.BASEBOARD_FAB2(SCH_1):M_C_ECC(1)
  49 M_C_ECC<0>  CB<0> @BASEBOARD_FAB2_LIB.BASEBOARD_FAB2(SCH_1):M_C_ECC(0)
  75 M_C_CLK_DN<2>   CK0N @BASEBOARD_FAB2_LIB.BASEBOARD_FAB2(SCH_1):M_C_CLK_DN(2)
  74 M_C_CLK_DP<2>   CK0P @BASEBOARD_FAB2_LIB.BASEBOARD_FAB2(SCH_1):M_C_CLK_DP(2)
 219 M_C_CLK_DN<3>   CK1N @BASEBOARD_FAB2_LIB.BASEBOARD_FAB2(SCH_1):M_C_CLK_DN(3)
 218 M_C_CLK_DP<3>   CK1P @BASEBOARD_FAB2_LIB.BASEBOARD_FAB2(SCH_1):M_C_CLK_DP(3)
 203 M_C_CKE<3> CKE<1> @BASEBOARD_FAB2_LIB.BASEBOARD_FAB2(SCH_1):M_C_CKE(3)
  60 M_C_CKE<2> CKE<0> @BASEBOARD_FAB2_LIB.BASEBOARD_FAB2(SCH_1):M_C_CKE(2)
 280 M_C_DQ<63> DQ<63> @BASEBOARD_FAB2_LIB.BASEBOARD_FAB2(SCH_1):M_C_DQ(63)
 135 M_C_DQ<62> DQ<62> @BASEBOARD_FAB2_LIB.BASEBOARD_FAB2(SCH_1):M_C_DQ(62)
 273 M_C_DQ<61> DQ<61> @BASEBOARD_FAB2_LIB.BASEBOARD_FAB2(SCH_1):M_C_DQ(61)
 128 M_C_DQ<60> DQ<60> @BASEBOARD_FAB2_LIB.BASEBOARD_FAB2(SCH_1):M_C_DQ(60)
 282 M_C_DQ<59> DQ<59> @BASEBOARD_FAB2_LIB.BASEBOARD_FAB2(SCH_1):M_C_DQ(59)
 137 M_C_DQ<58> DQ<58> @BASEBOARD_FAB2_LIB.BASEBOARD_FAB2(SCH_1):M_C_DQ(58)
 275 M_C_DQ<57> DQ<57> @BASEBOARD_FAB2_LIB.BASEBOARD_FAB2(SCH_1):M_C_DQ(57)
 130 M_C_DQ<56> DQ<56> @BASEBOARD_FAB2_LIB.BASEBOARD_FAB2(SCH_1):M_C_DQ(56)
 269 M_C_DQ<55> DQ<55> @BASEBOARD_FAB2_LIB.BASEBOARD_FAB2(SCH_1):M_C_DQ(55)
 124 M_C_DQ<54> DQ<54> @BASEBOARD_FAB2_LIB.BASEBOARD_FAB2(SCH_1):M_C_DQ(54)
 262 M_C_DQ<53> DQ<53> @BASEBOARD_FAB2_LIB.BASEBOARD_FAB2(SCH_1):M_C_DQ(53)
 117 M_C_DQ<52> DQ<52> @BASEBOARD_FAB2_LIB.BASEBOARD_FAB2(SCH_1):M_C_DQ(52)
 271 M_C_DQ<51> DQ<51> @BASEBOARD_FAB2_LIB.BASEBOARD_FAB2(SCH_1):M_C_DQ(51)
 126 M_C_DQ<50> DQ<50> @BASEBOARD_FAB2_LIB.BASEBOARD_FAB2(SCH_1):M_C_DQ(50)
 264 M_C_DQ<49> DQ<49> @BASEBOARD_FAB2_LIB.BASEBOARD_FAB2(SCH_1):M_C_DQ(49)
 119 M_C_DQ<48> DQ<48> @BASEBOARD_FAB2_LIB.BASEBOARD_FAB2(SCH_1):M_C_DQ(48)
 258 M_C_DQ<47> DQ<47> @BASEBOARD_FAB2_LIB.BASEBOARD_FAB2(SCH_1):M_C_DQ(47)
 113 M_C_DQ<46> DQ<46> @BASEBOARD_FAB2_LIB.BASEBOARD_FAB2(SCH_1):M_C_DQ(46)
 251 M_C_DQ<45> DQ<45> @BASEBOARD_FAB2_LIB.BASEBOARD_FAB2(SCH_1):M_C_DQ(45)
 106 M_C_DQ<44> DQ<44> @BASEBOARD_FAB2_LIB.BASEBOARD_FAB2(SCH_1):M_C_DQ(44)
 260 M_C_DQ<43> DQ<43> @BASEBOARD_FAB2_LIB.BASEBOARD_FAB2(SCH_1):M_C_DQ(43)
 115 M_C_DQ<42> DQ<42> @BASEBOARD_FAB2_LIB.BASEBOARD_FAB2(SCH_1):M_C_DQ(42)
 253 M_C_DQ<41> DQ<41> @BASEBOARD_FAB2_LIB.BASEBOARD_FAB2(SCH_1):M_C_DQ(41)
 108 M_C_DQ<40> DQ<40> @BASEBOARD_FAB2_LIB.BASEBOARD_FAB2(SCH_1):M_C_DQ(40)
 247 M_C_DQ<39> DQ<39> @BASEBOARD_FAB2_LIB.BASEBOARD_FAB2(SCH_1):M_C_DQ(39)
 102 M_C_DQ<38> DQ<38> @BASEBOARD_FAB2_LIB.BASEBOARD_FAB2(SCH_1):M_C_DQ(38)
 240 M_C_DQ<37> DQ<37> @BASEBOARD_FAB2_LIB.BASEBOARD_FAB2(SCH_1):M_C_DQ(37)
  95 M_C_DQ<36> DQ<36> @BASEBOARD_FAB2_LIB.BASEBOARD_FAB2(SCH_1):M_C_DQ(36)
 249 M_C_DQ<35> DQ<35> @BASEBOARD_FAB2_LIB.BASEBOARD_FAB2(SCH_1):M_C_DQ(35)
 104 M_C_DQ<34> DQ<34> @BASEBOARD_FAB2_LIB.BASEBOARD_FAB2(SCH_1):M_C_DQ(34)
 242 M_C_DQ<33> DQ<33> @BASEBOARD_FAB2_LIB.BASEBOARD_FAB2(SCH_1):M_C_DQ(33)
  97 M_C_DQ<32> DQ<32> @BASEBOARD_FAB2_LIB.BASEBOARD_FAB2(SCH_1):M_C_DQ(32)
 188 M_C_DQ<31> DQ<31> @BASEBOARD_FAB2_LIB.BASEBOARD_FAB2(SCH_1):M_C_DQ(31)
  43 M_C_DQ<30> DQ<30> @BASEBOARD_FAB2_LIB.BASEBOARD_FAB2(SCH_1):M_C_DQ(30)
 181 M_C_DQ<29> DQ<29> @BASEBOARD_FAB2_LIB.BASEBOARD_FAB2(SCH_1):M_C_DQ(29)
  36 M_C_DQ<28> DQ<28> @BASEBOARD_FAB2_LIB.BASEBOARD_FAB2(SCH_1):M_C_DQ(28)
 190 M_C_DQ<27> DQ<27> @BASEBOARD_FAB2_LIB.BASEBOARD_FAB2(SCH_1):M_C_DQ(27)
  45 M_C_DQ<26> DQ<26> @BASEBOARD_FAB2_LIB.BASEBOARD_FAB2(SCH_1):M_C_DQ(26)
 183 M_C_DQ<25> DQ<25> @BASEBOARD_FAB2_LIB.BASEBOARD_FAB2(SCH_1):M_C_DQ(25)
  38 M_C_DQ<24> DQ<24> @BASEBOARD_FAB2_LIB.BASEBOARD_FAB2(SCH_1):M_C_DQ(24)
 177 M_C_DQ<23> DQ<23> @BASEBOARD_FAB2_LIB.BASEBOARD_FAB2(SCH_1):M_C_DQ(23)
  32 M_C_DQ<22> DQ<22> @BASEBOARD_FAB2_LIB.BASEBOARD_FAB2(SCH_1):M_C_DQ(22)
 170 M_C_DQ<21> DQ<21> @BASEBOARD_FAB2_LIB.BASEBOARD_FAB2(SCH_1):M_C_DQ(21)
  25 M_C_DQ<20> DQ<20> @BASEBOARD_FAB2_LIB.BASEBOARD_FAB2(SCH_1):M_C_DQ(20)
 179 M_C_DQ<19> DQ<19> @BASEBOARD_FAB2_LIB.BASEBOARD_FAB2(SCH_1):M_C_DQ(19)
  34 M_C_DQ<18> DQ<18> @BASEBOARD_FAB2_LIB.BASEBOARD_FAB2(SCH_1):M_C_DQ(18)
 172 M_C_DQ<17> DQ<17> @BASEBOARD_FAB2_LIB.BASEBOARD_FAB2(SCH_1):M_C_DQ(17)
  27 M_C_DQ<16> DQ<16> @BASEBOARD_FAB2_LIB.BASEBOARD_FAB2(SCH_1):M_C_DQ(16)
 166 M_C_DQ<15> DQ<15> @BASEBOARD_FAB2_LIB.BASEBOARD_FAB2(SCH_1):M_C_DQ(15)
  21 M_C_DQ<14> DQ<14> @BASEBOARD_FAB2_LIB.BASEBOARD_FAB2(SCH_1):M_C_DQ(14)
 159 M_C_DQ<13> DQ<13> @BASEBOARD_FAB2_LIB.BASEBOARD_FAB2(SCH_1):M_C_DQ(13)
  14 M_C_DQ<12> DQ<12> @BASEBOARD_FAB2_LIB.BASEBOARD_FAB2(SCH_1):M_C_DQ(12)
 168 M_C_DQ<11> DQ<11> @BASEBOARD_FAB2_LIB.BASEBOARD_FAB2(SCH_1):M_C_DQ(11)
  23 M_C_DQ<10> DQ<10> @BASEBOARD_FAB2_LIB.BASEBOARD_FAB2(SCH_1):M_C_DQ(10)
 161 M_C_DQ<9>  DQ<9> @BASEBOARD_FAB2_LIB.BASEBOARD_FAB2(SCH_1):M_C_DQ(9)
  16 M_C_DQ<8>  DQ<8> @BASEBOARD_FAB2_LIB.BASEBOARD_FAB2(SCH_1):M_C_DQ(8)
 155 M_C_DQ<7>  DQ<7> @BASEBOARD_FAB2_LIB.BASEBOARD_FAB2(SCH_1):M_C_DQ(7)
  10 M_C_DQ<6>  DQ<6> @BASEBOARD_FAB2_LIB.BASEBOARD_FAB2(SCH_1):M_C_DQ(6)
 148 M_C_DQ<5>  DQ<5> @BASEBOARD_FAB2_LIB.BASEBOARD_FAB2(SCH_1):M_C_DQ(5)
   3 M_C_DQ<4>  DQ<4> @BASEBOARD_FAB2_LIB.BASEBOARD_FAB2(SCH_1):M_C_DQ(4)
 157 M_C_DQ<3>  DQ<3> @BASEBOARD_FAB2_LIB.BASEBOARD_FAB2(SCH_1):M_C_DQ(3)
  12 M_C_DQ<2>  DQ<2> @BASEBOARD_FAB2_LIB.BASEBOARD_FAB2(SCH_1):M_C_DQ(2)
 150 M_C_DQ<1>  DQ<1> @BASEBOARD_FAB2_LIB.BASEBOARD_FAB2(SCH_1):M_C_DQ(1)
   5 M_C_DQ<0>  DQ<0> @BASEBOARD_FAB2_LIB.BASEBOARD_FAB2(SCH_1):M_C_DQ(0)
  78 FM_DIMM_EVENT_COD_N EVENT_N @BASEBOARD_FAB2_LIB.BASEBOARD_FAB2(SCH_1):FM_DIMM_EVENT_COD_N
  91 M_C_ODT<3> ODT<1> @BASEBOARD_FAB2_LIB.BASEBOARD_FAB2(SCH_1):M_C_ODT(3)
  87 M_C_ODT<2> ODT<0> @BASEBOARD_FAB2_LIB.BASEBOARD_FAB2(SCH_1):M_C_ODT(2)
 222 M_C_PAR    PAR @BASEBOARD_FAB2_LIB.BASEBOARD_FAB2(SCH_1):M_C_PAR
  58 M_ABC_RST_N RESET_N @BASEBOARD_FAB2_LIB.BASEBOARD_FAB2(SCH_1):M_ABC_RST_N
 144 TP_CH_C_DIMM_C1_RFU_2 RFU<2> @BASEBOARD_FAB2_LIB.BASEBOARD_FAB2(SCH_1):TP_CH_C_DIMM_C1_RFU_2
 227 TP_CH_C_DIMM_C1_RFU_1 RFU<1> @BASEBOARD_FAB2_LIB.BASEBOARD_FAB2(SCH_1):TP_CH_C_DIMM_C1_RFU_1
 205 TP_CH_C_DIMM_C1_RFU_0 RFU<0> @BASEBOARD_FAB2_LIB.BASEBOARD_FAB2(SCH_1):TP_CH_C_DIMM_C1_RFU_0
  84 M_C_CS_N<4>   S0_N @BASEBOARD_FAB2_LIB.BASEBOARD_FAB2(SCH_1):M_C_CS_N(4)
  89 M_C_CS_N<5>   S1_N @BASEBOARD_FAB2_LIB.BASEBOARD_FAB2(SCH_1):M_C_CS_N(5)
  93 M_C_CS_N<6> S2_N_C<0> @BASEBOARD_FAB2_LIB.BASEBOARD_FAB2(SCH_1):M_C_CS_N(6)
 237 M_C_CS_N<7> S3_N_C<1> @BASEBOARD_FAB2_LIB.BASEBOARD_FAB2(SCH_1):M_C_CS_N(7)
 238 PVPP_ABC  SA<2> @BASEBOARD_FAB2_LIB.BASEBOARD_FAB2(SCH_1):PVPP_ABC
 140    GND  SA<1> @BASEBOARD_FAB2_LIB.BASEBOARD_FAB2(SCH_1):GND
 139 PVPP_ABC  SA<0> @BASEBOARD_FAB2_LIB.BASEBOARD_FAB2(SCH_1):PVPP_ABC
 230 FM_ADR_COMPLETE_ABC_N SAVE_N_NC @BASEBOARD_FAB2_LIB.BASEBOARD_FAB2(SCH_1):FM_ADR_COMPLETE_ABC_N
 141 SMB_DDR_ABC_VPP_SCL    SCL @BASEBOARD_FAB2_LIB.BASEBOARD_FAB2(SCH_1):SMB_DDR_ABC_VPP_SCL
 285 SMB_DDR_ABC_VPP_SDA    SDA @BASEBOARD_FAB2_LIB.BASEBOARD_FAB2(SCH_1):SMB_DDR_ABC_VPP_SDA
 284 PVPP_ABC VDDSPD @BASEBOARD_FAB2_LIB.BASEBOARD_FAB2(SCH_1):PVPP_ABC
 146 M_C_VREF VREFCA @BASEBOARD_FAB2_LIB.BASEBOARD_FAB2(SCH_1):M_C_VREF

SCONN288_H44441003_PIP-SCONN,HA  I171  J6U2
   1 P12V_NVDIMM_ABC 12V<1> @BASEBOARD_FAB2_LIB.BASEBOARD_FAB2(SCH_1):P12V_NVDIMM_ABC
 145 P12V_NVDIMM_ABC 12V<0> @BASEBOARD_FAB2_LIB.BASEBOARD_FAB2(SCH_1):P12V_NVDIMM_ABC
  59 PVDDQ_ABC VDD<25> @BASEBOARD_FAB2_LIB.BASEBOARD_FAB2(SCH_1):PVDDQ_ABC
  61 PVDDQ_ABC VDD<24> @BASEBOARD_FAB2_LIB.BASEBOARD_FAB2(SCH_1):PVDDQ_ABC
  64 PVDDQ_ABC VDD<23> @BASEBOARD_FAB2_LIB.BASEBOARD_FAB2(SCH_1):PVDDQ_ABC
  67 PVDDQ_ABC VDD<22> @BASEBOARD_FAB2_LIB.BASEBOARD_FAB2(SCH_1):PVDDQ_ABC
  70 PVDDQ_ABC VDD<21> @BASEBOARD_FAB2_LIB.BASEBOARD_FAB2(SCH_1):PVDDQ_ABC
  73 PVDDQ_ABC VDD<20> @BASEBOARD_FAB2_LIB.BASEBOARD_FAB2(SCH_1):PVDDQ_ABC
  76 PVDDQ_ABC VDD<19> @BASEBOARD_FAB2_LIB.BASEBOARD_FAB2(SCH_1):PVDDQ_ABC
  80 PVDDQ_ABC VDD<18> @BASEBOARD_FAB2_LIB.BASEBOARD_FAB2(SCH_1):PVDDQ_ABC
  83 PVDDQ_ABC VDD<17> @BASEBOARD_FAB2_LIB.BASEBOARD_FAB2(SCH_1):PVDDQ_ABC
  85 PVDDQ_ABC VDD<16> @BASEBOARD_FAB2_LIB.BASEBOARD_FAB2(SCH_1):PVDDQ_ABC
  88 PVDDQ_ABC VDD<15> @BASEBOARD_FAB2_LIB.BASEBOARD_FAB2(SCH_1):PVDDQ_ABC
  90 PVDDQ_ABC VDD<14> @BASEBOARD_FAB2_LIB.BASEBOARD_FAB2(SCH_1):PVDDQ_ABC
  92 PVDDQ_ABC VDD<13> @BASEBOARD_FAB2_LIB.BASEBOARD_FAB2(SCH_1):PVDDQ_ABC
 204 PVDDQ_ABC VDD<12> @BASEBOARD_FAB2_LIB.BASEBOARD_FAB2(SCH_1):PVDDQ_ABC
 206 PVDDQ_ABC VDD<11> @BASEBOARD_FAB2_LIB.BASEBOARD_FAB2(SCH_1):PVDDQ_ABC
 209 PVDDQ_ABC VDD<10> @BASEBOARD_FAB2_LIB.BASEBOARD_FAB2(SCH_1):PVDDQ_ABC
 212 PVDDQ_ABC VDD<9> @BASEBOARD_FAB2_LIB.BASEBOARD_FAB2(SCH_1):PVDDQ_ABC
 215 PVDDQ_ABC VDD<8> @BASEBOARD_FAB2_LIB.BASEBOARD_FAB2(SCH_1):PVDDQ_ABC
 217 PVDDQ_ABC VDD<7> @BASEBOARD_FAB2_LIB.BASEBOARD_FAB2(SCH_1):PVDDQ_ABC
 220 PVDDQ_ABC VDD<6> @BASEBOARD_FAB2_LIB.BASEBOARD_FAB2(SCH_1):PVDDQ_ABC
 223 PVDDQ_ABC VDD<5> @BASEBOARD_FAB2_LIB.BASEBOARD_FAB2(SCH_1):PVDDQ_ABC
 226 PVDDQ_ABC VDD<4> @BASEBOARD_FAB2_LIB.BASEBOARD_FAB2(SCH_1):PVDDQ_ABC
 229 PVDDQ_ABC VDD<3> @BASEBOARD_FAB2_LIB.BASEBOARD_FAB2(SCH_1):PVDDQ_ABC
 231 PVDDQ_ABC VDD<2> @BASEBOARD_FAB2_LIB.BASEBOARD_FAB2(SCH_1):PVDDQ_ABC
 233 PVDDQ_ABC VDD<1> @BASEBOARD_FAB2_LIB.BASEBOARD_FAB2(SCH_1):PVDDQ_ABC
 236 PVDDQ_ABC VDD<0> @BASEBOARD_FAB2_LIB.BASEBOARD_FAB2(SCH_1):PVDDQ_ABC
 142 PVPP_ABC VPP<4> @BASEBOARD_FAB2_LIB.BASEBOARD_FAB2(SCH_1):PVPP_ABC
 143 PVPP_ABC VPP<3> @BASEBOARD_FAB2_LIB.BASEBOARD_FAB2(SCH_1):PVPP_ABC
 288 PVPP_ABC VPP<2> @BASEBOARD_FAB2_LIB.BASEBOARD_FAB2(SCH_1):PVPP_ABC
 286 PVPP_ABC VPP<1> @BASEBOARD_FAB2_LIB.BASEBOARD_FAB2(SCH_1):PVPP_ABC
 287 PVPP_ABC VPP<0> @BASEBOARD_FAB2_LIB.BASEBOARD_FAB2(SCH_1):PVPP_ABC
  77 PVTT_ABC VTT<1> @BASEBOARD_FAB2_LIB.BASEBOARD_FAB2(SCH_1):PVTT_ABC
 221 PVTT_ABC VTT<0> @BASEBOARD_FAB2_LIB.BASEBOARD_FAB2(SCH_1):PVTT_ABC

CAP_A_0402V-0.01UF,25V,10%,X7RA  I176  C6U17
   1 M_C_VREF      A @BASEBOARD_FAB2_LIB.BASEBOARD_FAB2(SCH_1):M_C_VREF
   2    GND      B @BASEBOARD_FAB2_LIB.BASEBOARD_FAB2(SCH_1):GND


DRAWING: @BASEBOARD_FAB2_LIB.BASEBOARD_FAB2(SCH_1):PAGE49 

SCONN288_H44441004_PIP-SCONN,HA  I43  J4B1
   2    GND VSS<93> @BASEBOARD_FAB2_LIB.BASEBOARD_FAB2(SCH_1):GND
   4    GND VSS<92> @BASEBOARD_FAB2_LIB.BASEBOARD_FAB2(SCH_1):GND
   6    GND VSS<91> @BASEBOARD_FAB2_LIB.BASEBOARD_FAB2(SCH_1):GND
   9    GND VSS<90> @BASEBOARD_FAB2_LIB.BASEBOARD_FAB2(SCH_1):GND
  11    GND VSS<89> @BASEBOARD_FAB2_LIB.BASEBOARD_FAB2(SCH_1):GND
  13    GND VSS<88> @BASEBOARD_FAB2_LIB.BASEBOARD_FAB2(SCH_1):GND
  15    GND VSS<87> @BASEBOARD_FAB2_LIB.BASEBOARD_FAB2(SCH_1):GND
  17    GND VSS<86> @BASEBOARD_FAB2_LIB.BASEBOARD_FAB2(SCH_1):GND
  20    GND VSS<85> @BASEBOARD_FAB2_LIB.BASEBOARD_FAB2(SCH_1):GND
  22    GND VSS<84> @BASEBOARD_FAB2_LIB.BASEBOARD_FAB2(SCH_1):GND
  24    GND VSS<83> @BASEBOARD_FAB2_LIB.BASEBOARD_FAB2(SCH_1):GND
  26    GND VSS<82> @BASEBOARD_FAB2_LIB.BASEBOARD_FAB2(SCH_1):GND
  28    GND VSS<81> @BASEBOARD_FAB2_LIB.BASEBOARD_FAB2(SCH_1):GND
  31    GND VSS<80> @BASEBOARD_FAB2_LIB.BASEBOARD_FAB2(SCH_1):GND
  33    GND VSS<79> @BASEBOARD_FAB2_LIB.BASEBOARD_FAB2(SCH_1):GND
  35    GND VSS<78> @BASEBOARD_FAB2_LIB.BASEBOARD_FAB2(SCH_1):GND
  37    GND VSS<77> @BASEBOARD_FAB2_LIB.BASEBOARD_FAB2(SCH_1):GND
  39    GND VSS<76> @BASEBOARD_FAB2_LIB.BASEBOARD_FAB2(SCH_1):GND
  42    GND VSS<75> @BASEBOARD_FAB2_LIB.BASEBOARD_FAB2(SCH_1):GND
  44    GND VSS<74> @BASEBOARD_FAB2_LIB.BASEBOARD_FAB2(SCH_1):GND
  46    GND VSS<73> @BASEBOARD_FAB2_LIB.BASEBOARD_FAB2(SCH_1):GND
  48    GND VSS<72> @BASEBOARD_FAB2_LIB.BASEBOARD_FAB2(SCH_1):GND
  50    GND VSS<71> @BASEBOARD_FAB2_LIB.BASEBOARD_FAB2(SCH_1):GND
  53    GND VSS<70> @BASEBOARD_FAB2_LIB.BASEBOARD_FAB2(SCH_1):GND
  55    GND VSS<69> @BASEBOARD_FAB2_LIB.BASEBOARD_FAB2(SCH_1):GND
  57    GND VSS<68> @BASEBOARD_FAB2_LIB.BASEBOARD_FAB2(SCH_1):GND
  94    GND VSS<67> @BASEBOARD_FAB2_LIB.BASEBOARD_FAB2(SCH_1):GND
  96    GND VSS<66> @BASEBOARD_FAB2_LIB.BASEBOARD_FAB2(SCH_1):GND
  98    GND VSS<65> @BASEBOARD_FAB2_LIB.BASEBOARD_FAB2(SCH_1):GND
 101    GND VSS<64> @BASEBOARD_FAB2_LIB.BASEBOARD_FAB2(SCH_1):GND
 103    GND VSS<63> @BASEBOARD_FAB2_LIB.BASEBOARD_FAB2(SCH_1):GND
 105    GND VSS<62> @BASEBOARD_FAB2_LIB.BASEBOARD_FAB2(SCH_1):GND
 107    GND VSS<61> @BASEBOARD_FAB2_LIB.BASEBOARD_FAB2(SCH_1):GND
 109    GND VSS<60> @BASEBOARD_FAB2_LIB.BASEBOARD_FAB2(SCH_1):GND
 112    GND VSS<59> @BASEBOARD_FAB2_LIB.BASEBOARD_FAB2(SCH_1):GND
 114    GND VSS<58> @BASEBOARD_FAB2_LIB.BASEBOARD_FAB2(SCH_1):GND
 116    GND VSS<57> @BASEBOARD_FAB2_LIB.BASEBOARD_FAB2(SCH_1):GND
 118    GND VSS<56> @BASEBOARD_FAB2_LIB.BASEBOARD_FAB2(SCH_1):GND
 120    GND VSS<55> @BASEBOARD_FAB2_LIB.BASEBOARD_FAB2(SCH_1):GND
 123    GND VSS<54> @BASEBOARD_FAB2_LIB.BASEBOARD_FAB2(SCH_1):GND
 125    GND VSS<53> @BASEBOARD_FAB2_LIB.BASEBOARD_FAB2(SCH_1):GND
 127    GND VSS<52> @BASEBOARD_FAB2_LIB.BASEBOARD_FAB2(SCH_1):GND
 129    GND VSS<51> @BASEBOARD_FAB2_LIB.BASEBOARD_FAB2(SCH_1):GND
 131    GND VSS<50> @BASEBOARD_FAB2_LIB.BASEBOARD_FAB2(SCH_1):GND
 134    GND VSS<49> @BASEBOARD_FAB2_LIB.BASEBOARD_FAB2(SCH_1):GND
 136    GND VSS<48> @BASEBOARD_FAB2_LIB.BASEBOARD_FAB2(SCH_1):GND
 138    GND VSS<47> @BASEBOARD_FAB2_LIB.BASEBOARD_FAB2(SCH_1):GND
 147    GND VSS<46> @BASEBOARD_FAB2_LIB.BASEBOARD_FAB2(SCH_1):GND
 149    GND VSS<45> @BASEBOARD_FAB2_LIB.BASEBOARD_FAB2(SCH_1):GND
 151    GND VSS<44> @BASEBOARD_FAB2_LIB.BASEBOARD_FAB2(SCH_1):GND
 154    GND VSS<43> @BASEBOARD_FAB2_LIB.BASEBOARD_FAB2(SCH_1):GND
 156    GND VSS<42> @BASEBOARD_FAB2_LIB.BASEBOARD_FAB2(SCH_1):GND
 158    GND VSS<41> @BASEBOARD_FAB2_LIB.BASEBOARD_FAB2(SCH_1):GND
 160    GND VSS<40> @BASEBOARD_FAB2_LIB.BASEBOARD_FAB2(SCH_1):GND
 162    GND VSS<39> @BASEBOARD_FAB2_LIB.BASEBOARD_FAB2(SCH_1):GND
 165    GND VSS<38> @BASEBOARD_FAB2_LIB.BASEBOARD_FAB2(SCH_1):GND
 167    GND VSS<37> @BASEBOARD_FAB2_LIB.BASEBOARD_FAB2(SCH_1):GND
 169    GND VSS<36> @BASEBOARD_FAB2_LIB.BASEBOARD_FAB2(SCH_1):GND
 171    GND VSS<35> @BASEBOARD_FAB2_LIB.BASEBOARD_FAB2(SCH_1):GND
 173    GND VSS<34> @BASEBOARD_FAB2_LIB.BASEBOARD_FAB2(SCH_1):GND
 176    GND VSS<33> @BASEBOARD_FAB2_LIB.BASEBOARD_FAB2(SCH_1):GND
 178    GND VSS<32> @BASEBOARD_FAB2_LIB.BASEBOARD_FAB2(SCH_1):GND
 180    GND VSS<31> @BASEBOARD_FAB2_LIB.BASEBOARD_FAB2(SCH_1):GND
 182    GND VSS<30> @BASEBOARD_FAB2_LIB.BASEBOARD_FAB2(SCH_1):GND
 184    GND VSS<29> @BASEBOARD_FAB2_LIB.BASEBOARD_FAB2(SCH_1):GND
 187    GND VSS<28> @BASEBOARD_FAB2_LIB.BASEBOARD_FAB2(SCH_1):GND
 189    GND VSS<27> @BASEBOARD_FAB2_LIB.BASEBOARD_FAB2(SCH_1):GND
 191    GND VSS<26> @BASEBOARD_FAB2_LIB.BASEBOARD_FAB2(SCH_1):GND
 193    GND VSS<25> @BASEBOARD_FAB2_LIB.BASEBOARD_FAB2(SCH_1):GND
 195    GND VSS<24> @BASEBOARD_FAB2_LIB.BASEBOARD_FAB2(SCH_1):GND
 198    GND VSS<23> @BASEBOARD_FAB2_LIB.BASEBOARD_FAB2(SCH_1):GND
 200    GND VSS<22> @BASEBOARD_FAB2_LIB.BASEBOARD_FAB2(SCH_1):GND
 202    GND VSS<21> @BASEBOARD_FAB2_LIB.BASEBOARD_FAB2(SCH_1):GND
 239    GND VSS<20> @BASEBOARD_FAB2_LIB.BASEBOARD_FAB2(SCH_1):GND
 241    GND VSS<19> @BASEBOARD_FAB2_LIB.BASEBOARD_FAB2(SCH_1):GND
 243    GND VSS<18> @BASEBOARD_FAB2_LIB.BASEBOARD_FAB2(SCH_1):GND
 246    GND VSS<17> @BASEBOARD_FAB2_LIB.BASEBOARD_FAB2(SCH_1):GND
 248    GND VSS<16> @BASEBOARD_FAB2_LIB.BASEBOARD_FAB2(SCH_1):GND
 250    GND VSS<15> @BASEBOARD_FAB2_LIB.BASEBOARD_FAB2(SCH_1):GND
 252    GND VSS<14> @BASEBOARD_FAB2_LIB.BASEBOARD_FAB2(SCH_1):GND
 254    GND VSS<13> @BASEBOARD_FAB2_LIB.BASEBOARD_FAB2(SCH_1):GND
 257    GND VSS<12> @BASEBOARD_FAB2_LIB.BASEBOARD_FAB2(SCH_1):GND
 259    GND VSS<11> @BASEBOARD_FAB2_LIB.BASEBOARD_FAB2(SCH_1):GND
 261    GND VSS<10> @BASEBOARD_FAB2_LIB.BASEBOARD_FAB2(SCH_1):GND
 263    GND VSS<9> @BASEBOARD_FAB2_LIB.BASEBOARD_FAB2(SCH_1):GND
 265    GND VSS<8> @BASEBOARD_FAB2_LIB.BASEBOARD_FAB2(SCH_1):GND
 268    GND VSS<7> @BASEBOARD_FAB2_LIB.BASEBOARD_FAB2(SCH_1):GND
 270    GND VSS<6> @BASEBOARD_FAB2_LIB.BASEBOARD_FAB2(SCH_1):GND
 272    GND VSS<5> @BASEBOARD_FAB2_LIB.BASEBOARD_FAB2(SCH_1):GND
 274    GND VSS<4> @BASEBOARD_FAB2_LIB.BASEBOARD_FAB2(SCH_1):GND
 276    GND VSS<3> @BASEBOARD_FAB2_LIB.BASEBOARD_FAB2(SCH_1):GND
 279    GND VSS<2> @BASEBOARD_FAB2_LIB.BASEBOARD_FAB2(SCH_1):GND
 281    GND VSS<1> @BASEBOARD_FAB2_LIB.BASEBOARD_FAB2(SCH_1):GND
 283    GND VSS<0> @BASEBOARD_FAB2_LIB.BASEBOARD_FAB2(SCH_1):GND

SCONN288_H44441004_PIP-SCONN,HA  I66  J4B1
 152 M_D_DQS_DN<0>  DQS0N @BASEBOARD_FAB2_LIB.BASEBOARD_FAB2(SCH_1):M_D_DQS_DN(0)
 153 M_D_DQS_DP<0>  DQS0P @BASEBOARD_FAB2_LIB.BASEBOARD_FAB2(SCH_1):M_D_DQS_DP(0)
  19 M_D_DQS_DN<10> DQS10N @BASEBOARD_FAB2_LIB.BASEBOARD_FAB2(SCH_1):M_D_DQS_DN(10)
  18 M_D_DQS_DP<10> DQS10P @BASEBOARD_FAB2_LIB.BASEBOARD_FAB2(SCH_1):M_D_DQS_DP(10)
  30 M_D_DQS_DN<11> DQS11N @BASEBOARD_FAB2_LIB.BASEBOARD_FAB2(SCH_1):M_D_DQS_DN(11)
  29 M_D_DQS_DP<11> DQS11P @BASEBOARD_FAB2_LIB.BASEBOARD_FAB2(SCH_1):M_D_DQS_DP(11)
  41 M_D_DQS_DN<12> DQS12N @BASEBOARD_FAB2_LIB.BASEBOARD_FAB2(SCH_1):M_D_DQS_DN(12)
  40 M_D_DQS_DP<12> DQS12P @BASEBOARD_FAB2_LIB.BASEBOARD_FAB2(SCH_1):M_D_DQS_DP(12)
 100 M_D_DQS_DN<13> DQS13N @BASEBOARD_FAB2_LIB.BASEBOARD_FAB2(SCH_1):M_D_DQS_DN(13)
  99 M_D_DQS_DP<13> DQS13P @BASEBOARD_FAB2_LIB.BASEBOARD_FAB2(SCH_1):M_D_DQS_DP(13)
 111 M_D_DQS_DN<14> DQS14N @BASEBOARD_FAB2_LIB.BASEBOARD_FAB2(SCH_1):M_D_DQS_DN(14)
 110 M_D_DQS_DP<14> DQS14P @BASEBOARD_FAB2_LIB.BASEBOARD_FAB2(SCH_1):M_D_DQS_DP(14)
 122 M_D_DQS_DN<15> DQS15N @BASEBOARD_FAB2_LIB.BASEBOARD_FAB2(SCH_1):M_D_DQS_DN(15)
 121 M_D_DQS_DP<15> DQS15P @BASEBOARD_FAB2_LIB.BASEBOARD_FAB2(SCH_1):M_D_DQS_DP(15)
 133 M_D_DQS_DN<16> DQS16N @BASEBOARD_FAB2_LIB.BASEBOARD_FAB2(SCH_1):M_D_DQS_DN(16)
 132 M_D_DQS_DP<16> DQS16P @BASEBOARD_FAB2_LIB.BASEBOARD_FAB2(SCH_1):M_D_DQS_DP(16)
  52 M_D_DQS_DN<17> DQS17N @BASEBOARD_FAB2_LIB.BASEBOARD_FAB2(SCH_1):M_D_DQS_DN(17)
  51 M_D_DQS_DP<17> DQS17P @BASEBOARD_FAB2_LIB.BASEBOARD_FAB2(SCH_1):M_D_DQS_DP(17)
 163 M_D_DQS_DN<1>  DQS1N @BASEBOARD_FAB2_LIB.BASEBOARD_FAB2(SCH_1):M_D_DQS_DN(1)
 164 M_D_DQS_DP<1>  DQS1P @BASEBOARD_FAB2_LIB.BASEBOARD_FAB2(SCH_1):M_D_DQS_DP(1)
 174 M_D_DQS_DN<2>  DQS2N @BASEBOARD_FAB2_LIB.BASEBOARD_FAB2(SCH_1):M_D_DQS_DN(2)
 175 M_D_DQS_DP<2>  DQS2P @BASEBOARD_FAB2_LIB.BASEBOARD_FAB2(SCH_1):M_D_DQS_DP(2)
 185 M_D_DQS_DN<3>  DQS3N @BASEBOARD_FAB2_LIB.BASEBOARD_FAB2(SCH_1):M_D_DQS_DN(3)
 186 M_D_DQS_DP<3>  DQS3P @BASEBOARD_FAB2_LIB.BASEBOARD_FAB2(SCH_1):M_D_DQS_DP(3)
 244 M_D_DQS_DN<4>  DQS4N @BASEBOARD_FAB2_LIB.BASEBOARD_FAB2(SCH_1):M_D_DQS_DN(4)
 245 M_D_DQS_DP<4>  DQS4P @BASEBOARD_FAB2_LIB.BASEBOARD_FAB2(SCH_1):M_D_DQS_DP(4)
 255 M_D_DQS_DN<5>  DQS5N @BASEBOARD_FAB2_LIB.BASEBOARD_FAB2(SCH_1):M_D_DQS_DN(5)
 256 M_D_DQS_DP<5>  DQS5P @BASEBOARD_FAB2_LIB.BASEBOARD_FAB2(SCH_1):M_D_DQS_DP(5)
 266 M_D_DQS_DN<6>  DQS6N @BASEBOARD_FAB2_LIB.BASEBOARD_FAB2(SCH_1):M_D_DQS_DN(6)
 267 M_D_DQS_DP<6>  DQS6P @BASEBOARD_FAB2_LIB.BASEBOARD_FAB2(SCH_1):M_D_DQS_DP(6)
 277 M_D_DQS_DN<7>  DQS7N @BASEBOARD_FAB2_LIB.BASEBOARD_FAB2(SCH_1):M_D_DQS_DN(7)
 278 M_D_DQS_DP<7>  DQS7P @BASEBOARD_FAB2_LIB.BASEBOARD_FAB2(SCH_1):M_D_DQS_DP(7)
 196 M_D_DQS_DN<8>  DQS8N @BASEBOARD_FAB2_LIB.BASEBOARD_FAB2(SCH_1):M_D_DQS_DN(8)
 197 M_D_DQS_DP<8>  DQS8P @BASEBOARD_FAB2_LIB.BASEBOARD_FAB2(SCH_1):M_D_DQS_DP(8)
   8 M_D_DQS_DN<9>  DQS9N @BASEBOARD_FAB2_LIB.BASEBOARD_FAB2(SCH_1):M_D_DQS_DN(9)
   7 M_D_DQS_DP<9>  DQS9P @BASEBOARD_FAB2_LIB.BASEBOARD_FAB2(SCH_1):M_D_DQS_DP(9)

SCONN288_H44441004_PIP-SCONN,HA  I111  J4B1
  79 M_D_MA<0>     A0 @BASEBOARD_FAB2_LIB.BASEBOARD_FAB2(SCH_1):M_D_MA(0)
  72 M_D_MA<1>     A1 @BASEBOARD_FAB2_LIB.BASEBOARD_FAB2(SCH_1):M_D_MA(1)
 225 M_D_MA<10>    A10 @BASEBOARD_FAB2_LIB.BASEBOARD_FAB2(SCH_1):M_D_MA(10)
 210 M_D_MA<11>    A11 @BASEBOARD_FAB2_LIB.BASEBOARD_FAB2(SCH_1):M_D_MA(11)
  65 M_D_MA<12>    A12 @BASEBOARD_FAB2_LIB.BASEBOARD_FAB2(SCH_1):M_D_MA(12)
 232 M_D_MA<13>    A13 @BASEBOARD_FAB2_LIB.BASEBOARD_FAB2(SCH_1):M_D_MA(13)
 228 M_D_MA<14> A14_WE_N @BASEBOARD_FAB2_LIB.BASEBOARD_FAB2(SCH_1):M_D_MA(14)
  86 M_D_MA<15> A15_CAS_N @BASEBOARD_FAB2_LIB.BASEBOARD_FAB2(SCH_1):M_D_MA(15)
  82 M_D_MA<16> A16_RAS_N @BASEBOARD_FAB2_LIB.BASEBOARD_FAB2(SCH_1):M_D_MA(16)
 234 M_D_MA<17>    A17 @BASEBOARD_FAB2_LIB.BASEBOARD_FAB2(SCH_1):M_D_MA(17)
 216 M_D_MA<2>     A2 @BASEBOARD_FAB2_LIB.BASEBOARD_FAB2(SCH_1):M_D_MA(2)
  71 M_D_MA<3>     A3 @BASEBOARD_FAB2_LIB.BASEBOARD_FAB2(SCH_1):M_D_MA(3)
 214 M_D_MA<4>     A4 @BASEBOARD_FAB2_LIB.BASEBOARD_FAB2(SCH_1):M_D_MA(4)
 213 M_D_MA<5>     A5 @BASEBOARD_FAB2_LIB.BASEBOARD_FAB2(SCH_1):M_D_MA(5)
  69 M_D_MA<6>     A6 @BASEBOARD_FAB2_LIB.BASEBOARD_FAB2(SCH_1):M_D_MA(6)
 211 M_D_MA<7>     A7 @BASEBOARD_FAB2_LIB.BASEBOARD_FAB2(SCH_1):M_D_MA(7)
  68 M_D_MA<8>     A8 @BASEBOARD_FAB2_LIB.BASEBOARD_FAB2(SCH_1):M_D_MA(8)
  66 M_D_MA<9>     A9 @BASEBOARD_FAB2_LIB.BASEBOARD_FAB2(SCH_1):M_D_MA(9)
  62 M_D_ACT_N  ACT_N @BASEBOARD_FAB2_LIB.BASEBOARD_FAB2(SCH_1):M_D_ACT_N
 208 M_D_ALERT_N ALERT_N @BASEBOARD_FAB2_LIB.BASEBOARD_FAB2(SCH_1):M_D_ALERT_N
 224 M_D_BA<1>  BA<1> @BASEBOARD_FAB2_LIB.BASEBOARD_FAB2(SCH_1):M_D_BA(1)
  81 M_D_BA<0>  BA<0> @BASEBOARD_FAB2_LIB.BASEBOARD_FAB2(SCH_1):M_D_BA(0)
 207 M_D_BG<1>  BG<1> @BASEBOARD_FAB2_LIB.BASEBOARD_FAB2(SCH_1):M_D_BG(1)
  63 M_D_BG<0>  BG<0> @BASEBOARD_FAB2_LIB.BASEBOARD_FAB2(SCH_1):M_D_BG(0)
 235 M_D_C<2>   C<2> @BASEBOARD_FAB2_LIB.BASEBOARD_FAB2(SCH_1):M_D_C(2)
 199 M_D_ECC<6>  CB<7> @BASEBOARD_FAB2_LIB.BASEBOARD_FAB2(SCH_1):M_D_ECC(6)
  54 M_D_ECC<7>  CB<6> @BASEBOARD_FAB2_LIB.BASEBOARD_FAB2(SCH_1):M_D_ECC(7)
 192 M_D_ECC<4>  CB<5> @BASEBOARD_FAB2_LIB.BASEBOARD_FAB2(SCH_1):M_D_ECC(4)
  47 M_D_ECC<5>  CB<4> @BASEBOARD_FAB2_LIB.BASEBOARD_FAB2(SCH_1):M_D_ECC(5)
 201 M_D_ECC<2>  CB<3> @BASEBOARD_FAB2_LIB.BASEBOARD_FAB2(SCH_1):M_D_ECC(2)
  56 M_D_ECC<3>  CB<2> @BASEBOARD_FAB2_LIB.BASEBOARD_FAB2(SCH_1):M_D_ECC(3)
 194 M_D_ECC<0>  CB<1> @BASEBOARD_FAB2_LIB.BASEBOARD_FAB2(SCH_1):M_D_ECC(0)
  49 M_D_ECC<1>  CB<0> @BASEBOARD_FAB2_LIB.BASEBOARD_FAB2(SCH_1):M_D_ECC(1)
  75 M_D_CLK_DN<0>   CK0N @BASEBOARD_FAB2_LIB.BASEBOARD_FAB2(SCH_1):M_D_CLK_DN(0)
  74 M_D_CLK_DP<0>   CK0P @BASEBOARD_FAB2_LIB.BASEBOARD_FAB2(SCH_1):M_D_CLK_DP(0)
 219 M_D_CLK_DN<1>   CK1N @BASEBOARD_FAB2_LIB.BASEBOARD_FAB2(SCH_1):M_D_CLK_DN(1)
 218 M_D_CLK_DP<1>   CK1P @BASEBOARD_FAB2_LIB.BASEBOARD_FAB2(SCH_1):M_D_CLK_DP(1)
 203 M_D_CKE<1> CKE<1> @BASEBOARD_FAB2_LIB.BASEBOARD_FAB2(SCH_1):M_D_CKE(1)
  60 M_D_CKE<0> CKE<0> @BASEBOARD_FAB2_LIB.BASEBOARD_FAB2(SCH_1):M_D_CKE(0)
 280 M_D_DQ<62> DQ<63> @BASEBOARD_FAB2_LIB.BASEBOARD_FAB2(SCH_1):M_D_DQ(62)
 135 M_D_DQ<63> DQ<62> @BASEBOARD_FAB2_LIB.BASEBOARD_FAB2(SCH_1):M_D_DQ(63)
 273 M_D_DQ<60> DQ<61> @BASEBOARD_FAB2_LIB.BASEBOARD_FAB2(SCH_1):M_D_DQ(60)
 128 M_D_DQ<61> DQ<60> @BASEBOARD_FAB2_LIB.BASEBOARD_FAB2(SCH_1):M_D_DQ(61)
 282 M_D_DQ<58> DQ<59> @BASEBOARD_FAB2_LIB.BASEBOARD_FAB2(SCH_1):M_D_DQ(58)
 137 M_D_DQ<59> DQ<58> @BASEBOARD_FAB2_LIB.BASEBOARD_FAB2(SCH_1):M_D_DQ(59)
 275 M_D_DQ<56> DQ<57> @BASEBOARD_FAB2_LIB.BASEBOARD_FAB2(SCH_1):M_D_DQ(56)
 130 M_D_DQ<57> DQ<56> @BASEBOARD_FAB2_LIB.BASEBOARD_FAB2(SCH_1):M_D_DQ(57)
 269 M_D_DQ<54> DQ<55> @BASEBOARD_FAB2_LIB.BASEBOARD_FAB2(SCH_1):M_D_DQ(54)
 124 M_D_DQ<55> DQ<54> @BASEBOARD_FAB2_LIB.BASEBOARD_FAB2(SCH_1):M_D_DQ(55)
 262 M_D_DQ<52> DQ<53> @BASEBOARD_FAB2_LIB.BASEBOARD_FAB2(SCH_1):M_D_DQ(52)
 117 M_D_DQ<53> DQ<52> @BASEBOARD_FAB2_LIB.BASEBOARD_FAB2(SCH_1):M_D_DQ(53)
 271 M_D_DQ<50> DQ<51> @BASEBOARD_FAB2_LIB.BASEBOARD_FAB2(SCH_1):M_D_DQ(50)
 126 M_D_DQ<51> DQ<50> @BASEBOARD_FAB2_LIB.BASEBOARD_FAB2(SCH_1):M_D_DQ(51)
 264 M_D_DQ<48> DQ<49> @BASEBOARD_FAB2_LIB.BASEBOARD_FAB2(SCH_1):M_D_DQ(48)
 119 M_D_DQ<49> DQ<48> @BASEBOARD_FAB2_LIB.BASEBOARD_FAB2(SCH_1):M_D_DQ(49)
 258 M_D_DQ<46> DQ<47> @BASEBOARD_FAB2_LIB.BASEBOARD_FAB2(SCH_1):M_D_DQ(46)
 113 M_D_DQ<47> DQ<46> @BASEBOARD_FAB2_LIB.BASEBOARD_FAB2(SCH_1):M_D_DQ(47)
 251 M_D_DQ<44> DQ<45> @BASEBOARD_FAB2_LIB.BASEBOARD_FAB2(SCH_1):M_D_DQ(44)
 106 M_D_DQ<45> DQ<44> @BASEBOARD_FAB2_LIB.BASEBOARD_FAB2(SCH_1):M_D_DQ(45)
 260 M_D_DQ<42> DQ<43> @BASEBOARD_FAB2_LIB.BASEBOARD_FAB2(SCH_1):M_D_DQ(42)
 115 M_D_DQ<43> DQ<42> @BASEBOARD_FAB2_LIB.BASEBOARD_FAB2(SCH_1):M_D_DQ(43)
 253 M_D_DQ<40> DQ<41> @BASEBOARD_FAB2_LIB.BASEBOARD_FAB2(SCH_1):M_D_DQ(40)
 108 M_D_DQ<41> DQ<40> @BASEBOARD_FAB2_LIB.BASEBOARD_FAB2(SCH_1):M_D_DQ(41)
 247 M_D_DQ<38> DQ<39> @BASEBOARD_FAB2_LIB.BASEBOARD_FAB2(SCH_1):M_D_DQ(38)
 102 M_D_DQ<39> DQ<38> @BASEBOARD_FAB2_LIB.BASEBOARD_FAB2(SCH_1):M_D_DQ(39)
 240 M_D_DQ<36> DQ<37> @BASEBOARD_FAB2_LIB.BASEBOARD_FAB2(SCH_1):M_D_DQ(36)
  95 M_D_DQ<37> DQ<36> @BASEBOARD_FAB2_LIB.BASEBOARD_FAB2(SCH_1):M_D_DQ(37)
 249 M_D_DQ<34> DQ<35> @BASEBOARD_FAB2_LIB.BASEBOARD_FAB2(SCH_1):M_D_DQ(34)
 104 M_D_DQ<35> DQ<34> @BASEBOARD_FAB2_LIB.BASEBOARD_FAB2(SCH_1):M_D_DQ(35)
 242 M_D_DQ<32> DQ<33> @BASEBOARD_FAB2_LIB.BASEBOARD_FAB2(SCH_1):M_D_DQ(32)
  97 M_D_DQ<33> DQ<32> @BASEBOARD_FAB2_LIB.BASEBOARD_FAB2(SCH_1):M_D_DQ(33)
 188 M_D_DQ<30> DQ<31> @BASEBOARD_FAB2_LIB.BASEBOARD_FAB2(SCH_1):M_D_DQ(30)
  43 M_D_DQ<31> DQ<30> @BASEBOARD_FAB2_LIB.BASEBOARD_FAB2(SCH_1):M_D_DQ(31)
 181 M_D_DQ<28> DQ<29> @BASEBOARD_FAB2_LIB.BASEBOARD_FAB2(SCH_1):M_D_DQ(28)
  36 M_D_DQ<29> DQ<28> @BASEBOARD_FAB2_LIB.BASEBOARD_FAB2(SCH_1):M_D_DQ(29)
 190 M_D_DQ<26> DQ<27> @BASEBOARD_FAB2_LIB.BASEBOARD_FAB2(SCH_1):M_D_DQ(26)
  45 M_D_DQ<27> DQ<26> @BASEBOARD_FAB2_LIB.BASEBOARD_FAB2(SCH_1):M_D_DQ(27)
 183 M_D_DQ<24> DQ<25> @BASEBOARD_FAB2_LIB.BASEBOARD_FAB2(SCH_1):M_D_DQ(24)
  38 M_D_DQ<25> DQ<24> @BASEBOARD_FAB2_LIB.BASEBOARD_FAB2(SCH_1):M_D_DQ(25)
 177 M_D_DQ<22> DQ<23> @BASEBOARD_FAB2_LIB.BASEBOARD_FAB2(SCH_1):M_D_DQ(22)
  32 M_D_DQ<23> DQ<22> @BASEBOARD_FAB2_LIB.BASEBOARD_FAB2(SCH_1):M_D_DQ(23)
 170 M_D_DQ<20> DQ<21> @BASEBOARD_FAB2_LIB.BASEBOARD_FAB2(SCH_1):M_D_DQ(20)
  25 M_D_DQ<21> DQ<20> @BASEBOARD_FAB2_LIB.BASEBOARD_FAB2(SCH_1):M_D_DQ(21)
 179 M_D_DQ<18> DQ<19> @BASEBOARD_FAB2_LIB.BASEBOARD_FAB2(SCH_1):M_D_DQ(18)
  34 M_D_DQ<19> DQ<18> @BASEBOARD_FAB2_LIB.BASEBOARD_FAB2(SCH_1):M_D_DQ(19)
 172 M_D_DQ<16> DQ<17> @BASEBOARD_FAB2_LIB.BASEBOARD_FAB2(SCH_1):M_D_DQ(16)
  27 M_D_DQ<17> DQ<16> @BASEBOARD_FAB2_LIB.BASEBOARD_FAB2(SCH_1):M_D_DQ(17)
 166 M_D_DQ<14> DQ<15> @BASEBOARD_FAB2_LIB.BASEBOARD_FAB2(SCH_1):M_D_DQ(14)
  21 M_D_DQ<15> DQ<14> @BASEBOARD_FAB2_LIB.BASEBOARD_FAB2(SCH_1):M_D_DQ(15)
 159 M_D_DQ<12> DQ<13> @BASEBOARD_FAB2_LIB.BASEBOARD_FAB2(SCH_1):M_D_DQ(12)
  14 M_D_DQ<13> DQ<12> @BASEBOARD_FAB2_LIB.BASEBOARD_FAB2(SCH_1):M_D_DQ(13)
 168 M_D_DQ<10> DQ<11> @BASEBOARD_FAB2_LIB.BASEBOARD_FAB2(SCH_1):M_D_DQ(10)
  23 M_D_DQ<11> DQ<10> @BASEBOARD_FAB2_LIB.BASEBOARD_FAB2(SCH_1):M_D_DQ(11)
 161 M_D_DQ<8>  DQ<9> @BASEBOARD_FAB2_LIB.BASEBOARD_FAB2(SCH_1):M_D_DQ(8)
  16 M_D_DQ<9>  DQ<8> @BASEBOARD_FAB2_LIB.BASEBOARD_FAB2(SCH_1):M_D_DQ(9)
 155 M_D_DQ<6>  DQ<7> @BASEBOARD_FAB2_LIB.BASEBOARD_FAB2(SCH_1):M_D_DQ(6)
  10 M_D_DQ<7>  DQ<6> @BASEBOARD_FAB2_LIB.BASEBOARD_FAB2(SCH_1):M_D_DQ(7)
 148 M_D_DQ<4>  DQ<5> @BASEBOARD_FAB2_LIB.BASEBOARD_FAB2(SCH_1):M_D_DQ(4)
   3 M_D_DQ<5>  DQ<4> @BASEBOARD_FAB2_LIB.BASEBOARD_FAB2(SCH_1):M_D_DQ(5)
 157 M_D_DQ<2>  DQ<3> @BASEBOARD_FAB2_LIB.BASEBOARD_FAB2(SCH_1):M_D_DQ(2)
  12 M_D_DQ<3>  DQ<2> @BASEBOARD_FAB2_LIB.BASEBOARD_FAB2(SCH_1):M_D_DQ(3)
 150 M_D_DQ<0>  DQ<1> @BASEBOARD_FAB2_LIB.BASEBOARD_FAB2(SCH_1):M_D_DQ(0)
   5 M_D_DQ<1>  DQ<0> @BASEBOARD_FAB2_LIB.BASEBOARD_FAB2(SCH_1):M_D_DQ(1)
  78 FM_DIMM_EVENT_COD_N EVENT_N @BASEBOARD_FAB2_LIB.BASEBOARD_FAB2(SCH_1):FM_DIMM_EVENT_COD_N
  91 M_D_ODT<1> ODT<1> @BASEBOARD_FAB2_LIB.BASEBOARD_FAB2(SCH_1):M_D_ODT(1)
  87 M_D_ODT<0> ODT<0> @BASEBOARD_FAB2_LIB.BASEBOARD_FAB2(SCH_1):M_D_ODT(0)
 222 M_D_PAR    PAR @BASEBOARD_FAB2_LIB.BASEBOARD_FAB2(SCH_1):M_D_PAR
  58 M_DEF_RST_N RESET_N @BASEBOARD_FAB2_LIB.BASEBOARD_FAB2(SCH_1):M_DEF_RST_N
 144 TP_CH_D_DIMM_D0_RFU_2 RFU<2> @BASEBOARD_FAB2_LIB.BASEBOARD_FAB2(SCH_1):TP_CH_D_DIMM_D0_RFU_2
 227 TP_CH_D_DIMM_D0_RFU_1 RFU<1> @BASEBOARD_FAB2_LIB.BASEBOARD_FAB2(SCH_1):TP_CH_D_DIMM_D0_RFU_1
 205 TP_CH_D_DIMM_D0_RFU_0 RFU<0> @BASEBOARD_FAB2_LIB.BASEBOARD_FAB2(SCH_1):TP_CH_D_DIMM_D0_RFU_0
  84 M_D_CS_N<0>   S0_N @BASEBOARD_FAB2_LIB.BASEBOARD_FAB2(SCH_1):M_D_CS_N(0)
  89 M_D_CS_N<1>   S1_N @BASEBOARD_FAB2_LIB.BASEBOARD_FAB2(SCH_1):M_D_CS_N(1)
  93 M_D_CS_N<2> S2_N_C<0> @BASEBOARD_FAB2_LIB.BASEBOARD_FAB2(SCH_1):M_D_CS_N(2)
 237 M_D_CS_N<3> S3_N_C<1> @BASEBOARD_FAB2_LIB.BASEBOARD_FAB2(SCH_1):M_D_CS_N(3)
 238    GND  SA<2> @BASEBOARD_FAB2_LIB.BASEBOARD_FAB2(SCH_1):GND
 140    GND  SA<1> @BASEBOARD_FAB2_LIB.BASEBOARD_FAB2(SCH_1):GND
 139    GND  SA<0> @BASEBOARD_FAB2_LIB.BASEBOARD_FAB2(SCH_1):GND
 230 FM_ADR_COMPLETE_DEF_N SAVE_N_NC @BASEBOARD_FAB2_LIB.BASEBOARD_FAB2(SCH_1):FM_ADR_COMPLETE_DEF_N
 141 SMB_DDR_DEF_VPP_SCL    SCL @BASEBOARD_FAB2_LIB.BASEBOARD_FAB2(SCH_1):SMB_DDR_DEF_VPP_SCL
 285 SMB_DDR_DEF_VPP_SDA    SDA @BASEBOARD_FAB2_LIB.BASEBOARD_FAB2(SCH_1):SMB_DDR_DEF_VPP_SDA
 284 PVPP_DEF VDDSPD @BASEBOARD_FAB2_LIB.BASEBOARD_FAB2(SCH_1):PVPP_DEF
 146 M_D_VREF VREFCA @BASEBOARD_FAB2_LIB.BASEBOARD_FAB2(SCH_1):M_D_VREF

SCONN288_H44441004_PIP-SCONN,HA  I169  J4B1
   1 P12V_NVDIMM_DEF 12V<1> @BASEBOARD_FAB2_LIB.BASEBOARD_FAB2(SCH_1):P12V_NVDIMM_DEF
 145 P12V_NVDIMM_DEF 12V<0> @BASEBOARD_FAB2_LIB.BASEBOARD_FAB2(SCH_1):P12V_NVDIMM_DEF
  59 PVDDQ_DEF VDD<25> @BASEBOARD_FAB2_LIB.BASEBOARD_FAB2(SCH_1):PVDDQ_DEF
  61 PVDDQ_DEF VDD<24> @BASEBOARD_FAB2_LIB.BASEBOARD_FAB2(SCH_1):PVDDQ_DEF
  64 PVDDQ_DEF VDD<23> @BASEBOARD_FAB2_LIB.BASEBOARD_FAB2(SCH_1):PVDDQ_DEF
  67 PVDDQ_DEF VDD<22> @BASEBOARD_FAB2_LIB.BASEBOARD_FAB2(SCH_1):PVDDQ_DEF
  70 PVDDQ_DEF VDD<21> @BASEBOARD_FAB2_LIB.BASEBOARD_FAB2(SCH_1):PVDDQ_DEF
  73 PVDDQ_DEF VDD<20> @BASEBOARD_FAB2_LIB.BASEBOARD_FAB2(SCH_1):PVDDQ_DEF
  76 PVDDQ_DEF VDD<19> @BASEBOARD_FAB2_LIB.BASEBOARD_FAB2(SCH_1):PVDDQ_DEF
  80 PVDDQ_DEF VDD<18> @BASEBOARD_FAB2_LIB.BASEBOARD_FAB2(SCH_1):PVDDQ_DEF
  83 PVDDQ_DEF VDD<17> @BASEBOARD_FAB2_LIB.BASEBOARD_FAB2(SCH_1):PVDDQ_DEF
  85 PVDDQ_DEF VDD<16> @BASEBOARD_FAB2_LIB.BASEBOARD_FAB2(SCH_1):PVDDQ_DEF
  88 PVDDQ_DEF VDD<15> @BASEBOARD_FAB2_LIB.BASEBOARD_FAB2(SCH_1):PVDDQ_DEF
  90 PVDDQ_DEF VDD<14> @BASEBOARD_FAB2_LIB.BASEBOARD_FAB2(SCH_1):PVDDQ_DEF
  92 PVDDQ_DEF VDD<13> @BASEBOARD_FAB2_LIB.BASEBOARD_FAB2(SCH_1):PVDDQ_DEF
 204 PVDDQ_DEF VDD<12> @BASEBOARD_FAB2_LIB.BASEBOARD_FAB2(SCH_1):PVDDQ_DEF
 206 PVDDQ_DEF VDD<11> @BASEBOARD_FAB2_LIB.BASEBOARD_FAB2(SCH_1):PVDDQ_DEF
 209 PVDDQ_DEF VDD<10> @BASEBOARD_FAB2_LIB.BASEBOARD_FAB2(SCH_1):PVDDQ_DEF
 212 PVDDQ_DEF VDD<9> @BASEBOARD_FAB2_LIB.BASEBOARD_FAB2(SCH_1):PVDDQ_DEF
 215 PVDDQ_DEF VDD<8> @BASEBOARD_FAB2_LIB.BASEBOARD_FAB2(SCH_1):PVDDQ_DEF
 217 PVDDQ_DEF VDD<7> @BASEBOARD_FAB2_LIB.BASEBOARD_FAB2(SCH_1):PVDDQ_DEF
 220 PVDDQ_DEF VDD<6> @BASEBOARD_FAB2_LIB.BASEBOARD_FAB2(SCH_1):PVDDQ_DEF
 223 PVDDQ_DEF VDD<5> @BASEBOARD_FAB2_LIB.BASEBOARD_FAB2(SCH_1):PVDDQ_DEF
 226 PVDDQ_DEF VDD<4> @BASEBOARD_FAB2_LIB.BASEBOARD_FAB2(SCH_1):PVDDQ_DEF
 229 PVDDQ_DEF VDD<3> @BASEBOARD_FAB2_LIB.BASEBOARD_FAB2(SCH_1):PVDDQ_DEF
 231 PVDDQ_DEF VDD<2> @BASEBOARD_FAB2_LIB.BASEBOARD_FAB2(SCH_1):PVDDQ_DEF
 233 PVDDQ_DEF VDD<1> @BASEBOARD_FAB2_LIB.BASEBOARD_FAB2(SCH_1):PVDDQ_DEF
 236 PVDDQ_DEF VDD<0> @BASEBOARD_FAB2_LIB.BASEBOARD_FAB2(SCH_1):PVDDQ_DEF
 142 PVPP_DEF VPP<4> @BASEBOARD_FAB2_LIB.BASEBOARD_FAB2(SCH_1):PVPP_DEF
 143 PVPP_DEF VPP<3> @BASEBOARD_FAB2_LIB.BASEBOARD_FAB2(SCH_1):PVPP_DEF
 288 PVPP_DEF VPP<2> @BASEBOARD_FAB2_LIB.BASEBOARD_FAB2(SCH_1):PVPP_DEF
 286 PVPP_DEF VPP<1> @BASEBOARD_FAB2_LIB.BASEBOARD_FAB2(SCH_1):PVPP_DEF
 287 PVPP_DEF VPP<0> @BASEBOARD_FAB2_LIB.BASEBOARD_FAB2(SCH_1):PVPP_DEF
  77 PVTT_DEF VTT<1> @BASEBOARD_FAB2_LIB.BASEBOARD_FAB2(SCH_1):PVTT_DEF
 221 PVTT_DEF VTT<0> @BASEBOARD_FAB2_LIB.BASEBOARD_FAB2(SCH_1):PVTT_DEF

CAP_A_0402V-0.01UF,25V,10%,X7RA  I179  C4B12
   1 M_D_VREF      A @BASEBOARD_FAB2_LIB.BASEBOARD_FAB2(SCH_1):M_D_VREF
   2    GND      B @BASEBOARD_FAB2_LIB.BASEBOARD_FAB2(SCH_1):GND


DRAWING: @BASEBOARD_FAB2_LIB.BASEBOARD_FAB2(SCH_1):PAGE50 

SCONN288_H44441003_PIP-SCONN,HA  I44  J6M1
   2    GND VSS<93> @BASEBOARD_FAB2_LIB.BASEBOARD_FAB2(SCH_1):GND
   4    GND VSS<92> @BASEBOARD_FAB2_LIB.BASEBOARD_FAB2(SCH_1):GND
   6    GND VSS<91> @BASEBOARD_FAB2_LIB.BASEBOARD_FAB2(SCH_1):GND
   9    GND VSS<90> @BASEBOARD_FAB2_LIB.BASEBOARD_FAB2(SCH_1):GND
  11    GND VSS<89> @BASEBOARD_FAB2_LIB.BASEBOARD_FAB2(SCH_1):GND
  13    GND VSS<88> @BASEBOARD_FAB2_LIB.BASEBOARD_FAB2(SCH_1):GND
  15    GND VSS<87> @BASEBOARD_FAB2_LIB.BASEBOARD_FAB2(SCH_1):GND
  17    GND VSS<86> @BASEBOARD_FAB2_LIB.BASEBOARD_FAB2(SCH_1):GND
  20    GND VSS<85> @BASEBOARD_FAB2_LIB.BASEBOARD_FAB2(SCH_1):GND
  22    GND VSS<84> @BASEBOARD_FAB2_LIB.BASEBOARD_FAB2(SCH_1):GND
  24    GND VSS<83> @BASEBOARD_FAB2_LIB.BASEBOARD_FAB2(SCH_1):GND
  26    GND VSS<82> @BASEBOARD_FAB2_LIB.BASEBOARD_FAB2(SCH_1):GND
  28    GND VSS<81> @BASEBOARD_FAB2_LIB.BASEBOARD_FAB2(SCH_1):GND
  31    GND VSS<80> @BASEBOARD_FAB2_LIB.BASEBOARD_FAB2(SCH_1):GND
  33    GND VSS<79> @BASEBOARD_FAB2_LIB.BASEBOARD_FAB2(SCH_1):GND
  35    GND VSS<78> @BASEBOARD_FAB2_LIB.BASEBOARD_FAB2(SCH_1):GND
  37    GND VSS<77> @BASEBOARD_FAB2_LIB.BASEBOARD_FAB2(SCH_1):GND
  39    GND VSS<76> @BASEBOARD_FAB2_LIB.BASEBOARD_FAB2(SCH_1):GND
  42    GND VSS<75> @BASEBOARD_FAB2_LIB.BASEBOARD_FAB2(SCH_1):GND
  44    GND VSS<74> @BASEBOARD_FAB2_LIB.BASEBOARD_FAB2(SCH_1):GND
  46    GND VSS<73> @BASEBOARD_FAB2_LIB.BASEBOARD_FAB2(SCH_1):GND
  48    GND VSS<72> @BASEBOARD_FAB2_LIB.BASEBOARD_FAB2(SCH_1):GND
  50    GND VSS<71> @BASEBOARD_FAB2_LIB.BASEBOARD_FAB2(SCH_1):GND
  53    GND VSS<70> @BASEBOARD_FAB2_LIB.BASEBOARD_FAB2(SCH_1):GND
  55    GND VSS<69> @BASEBOARD_FAB2_LIB.BASEBOARD_FAB2(SCH_1):GND
  57    GND VSS<68> @BASEBOARD_FAB2_LIB.BASEBOARD_FAB2(SCH_1):GND
  94    GND VSS<67> @BASEBOARD_FAB2_LIB.BASEBOARD_FAB2(SCH_1):GND
  96    GND VSS<66> @BASEBOARD_FAB2_LIB.BASEBOARD_FAB2(SCH_1):GND
  98    GND VSS<65> @BASEBOARD_FAB2_LIB.BASEBOARD_FAB2(SCH_1):GND
 101    GND VSS<64> @BASEBOARD_FAB2_LIB.BASEBOARD_FAB2(SCH_1):GND
 103    GND VSS<63> @BASEBOARD_FAB2_LIB.BASEBOARD_FAB2(SCH_1):GND
 105    GND VSS<62> @BASEBOARD_FAB2_LIB.BASEBOARD_FAB2(SCH_1):GND
 107    GND VSS<61> @BASEBOARD_FAB2_LIB.BASEBOARD_FAB2(SCH_1):GND
 109    GND VSS<60> @BASEBOARD_FAB2_LIB.BASEBOARD_FAB2(SCH_1):GND
 112    GND VSS<59> @BASEBOARD_FAB2_LIB.BASEBOARD_FAB2(SCH_1):GND
 114    GND VSS<58> @BASEBOARD_FAB2_LIB.BASEBOARD_FAB2(SCH_1):GND
 116    GND VSS<57> @BASEBOARD_FAB2_LIB.BASEBOARD_FAB2(SCH_1):GND
 118    GND VSS<56> @BASEBOARD_FAB2_LIB.BASEBOARD_FAB2(SCH_1):GND
 120    GND VSS<55> @BASEBOARD_FAB2_LIB.BASEBOARD_FAB2(SCH_1):GND
 123    GND VSS<54> @BASEBOARD_FAB2_LIB.BASEBOARD_FAB2(SCH_1):GND
 125    GND VSS<53> @BASEBOARD_FAB2_LIB.BASEBOARD_FAB2(SCH_1):GND
 127    GND VSS<52> @BASEBOARD_FAB2_LIB.BASEBOARD_FAB2(SCH_1):GND
 129    GND VSS<51> @BASEBOARD_FAB2_LIB.BASEBOARD_FAB2(SCH_1):GND
 131    GND VSS<50> @BASEBOARD_FAB2_LIB.BASEBOARD_FAB2(SCH_1):GND
 134    GND VSS<49> @BASEBOARD_FAB2_LIB.BASEBOARD_FAB2(SCH_1):GND
 136    GND VSS<48> @BASEBOARD_FAB2_LIB.BASEBOARD_FAB2(SCH_1):GND
 138    GND VSS<47> @BASEBOARD_FAB2_LIB.BASEBOARD_FAB2(SCH_1):GND
 147    GND VSS<46> @BASEBOARD_FAB2_LIB.BASEBOARD_FAB2(SCH_1):GND
 149    GND VSS<45> @BASEBOARD_FAB2_LIB.BASEBOARD_FAB2(SCH_1):GND
 151    GND VSS<44> @BASEBOARD_FAB2_LIB.BASEBOARD_FAB2(SCH_1):GND
 154    GND VSS<43> @BASEBOARD_FAB2_LIB.BASEBOARD_FAB2(SCH_1):GND
 156    GND VSS<42> @BASEBOARD_FAB2_LIB.BASEBOARD_FAB2(SCH_1):GND
 158    GND VSS<41> @BASEBOARD_FAB2_LIB.BASEBOARD_FAB2(SCH_1):GND
 160    GND VSS<40> @BASEBOARD_FAB2_LIB.BASEBOARD_FAB2(SCH_1):GND
 162    GND VSS<39> @BASEBOARD_FAB2_LIB.BASEBOARD_FAB2(SCH_1):GND
 165    GND VSS<38> @BASEBOARD_FAB2_LIB.BASEBOARD_FAB2(SCH_1):GND
 167    GND VSS<37> @BASEBOARD_FAB2_LIB.BASEBOARD_FAB2(SCH_1):GND
 169    GND VSS<36> @BASEBOARD_FAB2_LIB.BASEBOARD_FAB2(SCH_1):GND
 171    GND VSS<35> @BASEBOARD_FAB2_LIB.BASEBOARD_FAB2(SCH_1):GND
 173    GND VSS<34> @BASEBOARD_FAB2_LIB.BASEBOARD_FAB2(SCH_1):GND
 176    GND VSS<33> @BASEBOARD_FAB2_LIB.BASEBOARD_FAB2(SCH_1):GND
 178    GND VSS<32> @BASEBOARD_FAB2_LIB.BASEBOARD_FAB2(SCH_1):GND
 180    GND VSS<31> @BASEBOARD_FAB2_LIB.BASEBOARD_FAB2(SCH_1):GND
 182    GND VSS<30> @BASEBOARD_FAB2_LIB.BASEBOARD_FAB2(SCH_1):GND
 184    GND VSS<29> @BASEBOARD_FAB2_LIB.BASEBOARD_FAB2(SCH_1):GND
 187    GND VSS<28> @BASEBOARD_FAB2_LIB.BASEBOARD_FAB2(SCH_1):GND
 189    GND VSS<27> @BASEBOARD_FAB2_LIB.BASEBOARD_FAB2(SCH_1):GND
 191    GND VSS<26> @BASEBOARD_FAB2_LIB.BASEBOARD_FAB2(SCH_1):GND
 193    GND VSS<25> @BASEBOARD_FAB2_LIB.BASEBOARD_FAB2(SCH_1):GND
 195    GND VSS<24> @BASEBOARD_FAB2_LIB.BASEBOARD_FAB2(SCH_1):GND
 198    GND VSS<23> @BASEBOARD_FAB2_LIB.BASEBOARD_FAB2(SCH_1):GND
 200    GND VSS<22> @BASEBOARD_FAB2_LIB.BASEBOARD_FAB2(SCH_1):GND
 202    GND VSS<21> @BASEBOARD_FAB2_LIB.BASEBOARD_FAB2(SCH_1):GND
 239    GND VSS<20> @BASEBOARD_FAB2_LIB.BASEBOARD_FAB2(SCH_1):GND
 241    GND VSS<19> @BASEBOARD_FAB2_LIB.BASEBOARD_FAB2(SCH_1):GND
 243    GND VSS<18> @BASEBOARD_FAB2_LIB.BASEBOARD_FAB2(SCH_1):GND
 246    GND VSS<17> @BASEBOARD_FAB2_LIB.BASEBOARD_FAB2(SCH_1):GND
 248    GND VSS<16> @BASEBOARD_FAB2_LIB.BASEBOARD_FAB2(SCH_1):GND
 250    GND VSS<15> @BASEBOARD_FAB2_LIB.BASEBOARD_FAB2(SCH_1):GND
 252    GND VSS<14> @BASEBOARD_FAB2_LIB.BASEBOARD_FAB2(SCH_1):GND
 254    GND VSS<13> @BASEBOARD_FAB2_LIB.BASEBOARD_FAB2(SCH_1):GND
 257    GND VSS<12> @BASEBOARD_FAB2_LIB.BASEBOARD_FAB2(SCH_1):GND
 259    GND VSS<11> @BASEBOARD_FAB2_LIB.BASEBOARD_FAB2(SCH_1):GND
 261    GND VSS<10> @BASEBOARD_FAB2_LIB.BASEBOARD_FAB2(SCH_1):GND
 263    GND VSS<9> @BASEBOARD_FAB2_LIB.BASEBOARD_FAB2(SCH_1):GND
 265    GND VSS<8> @BASEBOARD_FAB2_LIB.BASEBOARD_FAB2(SCH_1):GND
 268    GND VSS<7> @BASEBOARD_FAB2_LIB.BASEBOARD_FAB2(SCH_1):GND
 270    GND VSS<6> @BASEBOARD_FAB2_LIB.BASEBOARD_FAB2(SCH_1):GND
 272    GND VSS<5> @BASEBOARD_FAB2_LIB.BASEBOARD_FAB2(SCH_1):GND
 274    GND VSS<4> @BASEBOARD_FAB2_LIB.BASEBOARD_FAB2(SCH_1):GND
 276    GND VSS<3> @BASEBOARD_FAB2_LIB.BASEBOARD_FAB2(SCH_1):GND
 279    GND VSS<2> @BASEBOARD_FAB2_LIB.BASEBOARD_FAB2(SCH_1):GND
 281    GND VSS<1> @BASEBOARD_FAB2_LIB.BASEBOARD_FAB2(SCH_1):GND
 283    GND VSS<0> @BASEBOARD_FAB2_LIB.BASEBOARD_FAB2(SCH_1):GND

SCONN288_H44441003_PIP-SCONN,HA  I46  J6M1
 152 M_D_DQS_DN<0>  DQS0N @BASEBOARD_FAB2_LIB.BASEBOARD_FAB2(SCH_1):M_D_DQS_DN(0)
 153 M_D_DQS_DP<0>  DQS0P @BASEBOARD_FAB2_LIB.BASEBOARD_FAB2(SCH_1):M_D_DQS_DP(0)
  19 M_D_DQS_DN<10> DQS10N @BASEBOARD_FAB2_LIB.BASEBOARD_FAB2(SCH_1):M_D_DQS_DN(10)
  18 M_D_DQS_DP<10> DQS10P @BASEBOARD_FAB2_LIB.BASEBOARD_FAB2(SCH_1):M_D_DQS_DP(10)
  30 M_D_DQS_DN<11> DQS11N @BASEBOARD_FAB2_LIB.BASEBOARD_FAB2(SCH_1):M_D_DQS_DN(11)
  29 M_D_DQS_DP<11> DQS11P @BASEBOARD_FAB2_LIB.BASEBOARD_FAB2(SCH_1):M_D_DQS_DP(11)
  41 M_D_DQS_DN<12> DQS12N @BASEBOARD_FAB2_LIB.BASEBOARD_FAB2(SCH_1):M_D_DQS_DN(12)
  40 M_D_DQS_DP<12> DQS12P @BASEBOARD_FAB2_LIB.BASEBOARD_FAB2(SCH_1):M_D_DQS_DP(12)
 100 M_D_DQS_DN<13> DQS13N @BASEBOARD_FAB2_LIB.BASEBOARD_FAB2(SCH_1):M_D_DQS_DN(13)
  99 M_D_DQS_DP<13> DQS13P @BASEBOARD_FAB2_LIB.BASEBOARD_FAB2(SCH_1):M_D_DQS_DP(13)
 111 M_D_DQS_DN<14> DQS14N @BASEBOARD_FAB2_LIB.BASEBOARD_FAB2(SCH_1):M_D_DQS_DN(14)
 110 M_D_DQS_DP<14> DQS14P @BASEBOARD_FAB2_LIB.BASEBOARD_FAB2(SCH_1):M_D_DQS_DP(14)
 122 M_D_DQS_DN<15> DQS15N @BASEBOARD_FAB2_LIB.BASEBOARD_FAB2(SCH_1):M_D_DQS_DN(15)
 121 M_D_DQS_DP<15> DQS15P @BASEBOARD_FAB2_LIB.BASEBOARD_FAB2(SCH_1):M_D_DQS_DP(15)
 133 M_D_DQS_DN<16> DQS16N @BASEBOARD_FAB2_LIB.BASEBOARD_FAB2(SCH_1):M_D_DQS_DN(16)
 132 M_D_DQS_DP<16> DQS16P @BASEBOARD_FAB2_LIB.BASEBOARD_FAB2(SCH_1):M_D_DQS_DP(16)
  52 M_D_DQS_DN<17> DQS17N @BASEBOARD_FAB2_LIB.BASEBOARD_FAB2(SCH_1):M_D_DQS_DN(17)
  51 M_D_DQS_DP<17> DQS17P @BASEBOARD_FAB2_LIB.BASEBOARD_FAB2(SCH_1):M_D_DQS_DP(17)
 163 M_D_DQS_DN<1>  DQS1N @BASEBOARD_FAB2_LIB.BASEBOARD_FAB2(SCH_1):M_D_DQS_DN(1)
 164 M_D_DQS_DP<1>  DQS1P @BASEBOARD_FAB2_LIB.BASEBOARD_FAB2(SCH_1):M_D_DQS_DP(1)
 174 M_D_DQS_DN<2>  DQS2N @BASEBOARD_FAB2_LIB.BASEBOARD_FAB2(SCH_1):M_D_DQS_DN(2)
 175 M_D_DQS_DP<2>  DQS2P @BASEBOARD_FAB2_LIB.BASEBOARD_FAB2(SCH_1):M_D_DQS_DP(2)
 185 M_D_DQS_DN<3>  DQS3N @BASEBOARD_FAB2_LIB.BASEBOARD_FAB2(SCH_1):M_D_DQS_DN(3)
 186 M_D_DQS_DP<3>  DQS3P @BASEBOARD_FAB2_LIB.BASEBOARD_FAB2(SCH_1):M_D_DQS_DP(3)
 244 M_D_DQS_DN<4>  DQS4N @BASEBOARD_FAB2_LIB.BASEBOARD_FAB2(SCH_1):M_D_DQS_DN(4)
 245 M_D_DQS_DP<4>  DQS4P @BASEBOARD_FAB2_LIB.BASEBOARD_FAB2(SCH_1):M_D_DQS_DP(4)
 255 M_D_DQS_DN<5>  DQS5N @BASEBOARD_FAB2_LIB.BASEBOARD_FAB2(SCH_1):M_D_DQS_DN(5)
 256 M_D_DQS_DP<5>  DQS5P @BASEBOARD_FAB2_LIB.BASEBOARD_FAB2(SCH_1):M_D_DQS_DP(5)
 266 M_D_DQS_DN<6>  DQS6N @BASEBOARD_FAB2_LIB.BASEBOARD_FAB2(SCH_1):M_D_DQS_DN(6)
 267 M_D_DQS_DP<6>  DQS6P @BASEBOARD_FAB2_LIB.BASEBOARD_FAB2(SCH_1):M_D_DQS_DP(6)
 277 M_D_DQS_DN<7>  DQS7N @BASEBOARD_FAB2_LIB.BASEBOARD_FAB2(SCH_1):M_D_DQS_DN(7)
 278 M_D_DQS_DP<7>  DQS7P @BASEBOARD_FAB2_LIB.BASEBOARD_FAB2(SCH_1):M_D_DQS_DP(7)
 196 M_D_DQS_DN<8>  DQS8N @BASEBOARD_FAB2_LIB.BASEBOARD_FAB2(SCH_1):M_D_DQS_DN(8)
 197 M_D_DQS_DP<8>  DQS8P @BASEBOARD_FAB2_LIB.BASEBOARD_FAB2(SCH_1):M_D_DQS_DP(8)
   8 M_D_DQS_DN<9>  DQS9N @BASEBOARD_FAB2_LIB.BASEBOARD_FAB2(SCH_1):M_D_DQS_DN(9)
   7 M_D_DQS_DP<9>  DQS9P @BASEBOARD_FAB2_LIB.BASEBOARD_FAB2(SCH_1):M_D_DQS_DP(9)

SCONN288_H44441003_PIP-SCONN,HA  I50  J6M1
   1 P12V_NVDIMM_DEF 12V<1> @BASEBOARD_FAB2_LIB.BASEBOARD_FAB2(SCH_1):P12V_NVDIMM_DEF
 145 P12V_NVDIMM_DEF 12V<0> @BASEBOARD_FAB2_LIB.BASEBOARD_FAB2(SCH_1):P12V_NVDIMM_DEF
  59 PVDDQ_DEF VDD<25> @BASEBOARD_FAB2_LIB.BASEBOARD_FAB2(SCH_1):PVDDQ_DEF
  61 PVDDQ_DEF VDD<24> @BASEBOARD_FAB2_LIB.BASEBOARD_FAB2(SCH_1):PVDDQ_DEF
  64 PVDDQ_DEF VDD<23> @BASEBOARD_FAB2_LIB.BASEBOARD_FAB2(SCH_1):PVDDQ_DEF
  67 PVDDQ_DEF VDD<22> @BASEBOARD_FAB2_LIB.BASEBOARD_FAB2(SCH_1):PVDDQ_DEF
  70 PVDDQ_DEF VDD<21> @BASEBOARD_FAB2_LIB.BASEBOARD_FAB2(SCH_1):PVDDQ_DEF
  73 PVDDQ_DEF VDD<20> @BASEBOARD_FAB2_LIB.BASEBOARD_FAB2(SCH_1):PVDDQ_DEF
  76 PVDDQ_DEF VDD<19> @BASEBOARD_FAB2_LIB.BASEBOARD_FAB2(SCH_1):PVDDQ_DEF
  80 PVDDQ_DEF VDD<18> @BASEBOARD_FAB2_LIB.BASEBOARD_FAB2(SCH_1):PVDDQ_DEF
  83 PVDDQ_DEF VDD<17> @BASEBOARD_FAB2_LIB.BASEBOARD_FAB2(SCH_1):PVDDQ_DEF
  85 PVDDQ_DEF VDD<16> @BASEBOARD_FAB2_LIB.BASEBOARD_FAB2(SCH_1):PVDDQ_DEF
  88 PVDDQ_DEF VDD<15> @BASEBOARD_FAB2_LIB.BASEBOARD_FAB2(SCH_1):PVDDQ_DEF
  90 PVDDQ_DEF VDD<14> @BASEBOARD_FAB2_LIB.BASEBOARD_FAB2(SCH_1):PVDDQ_DEF
  92 PVDDQ_DEF VDD<13> @BASEBOARD_FAB2_LIB.BASEBOARD_FAB2(SCH_1):PVDDQ_DEF
 204 PVDDQ_DEF VDD<12> @BASEBOARD_FAB2_LIB.BASEBOARD_FAB2(SCH_1):PVDDQ_DEF
 206 PVDDQ_DEF VDD<11> @BASEBOARD_FAB2_LIB.BASEBOARD_FAB2(SCH_1):PVDDQ_DEF
 209 PVDDQ_DEF VDD<10> @BASEBOARD_FAB2_LIB.BASEBOARD_FAB2(SCH_1):PVDDQ_DEF
 212 PVDDQ_DEF VDD<9> @BASEBOARD_FAB2_LIB.BASEBOARD_FAB2(SCH_1):PVDDQ_DEF
 215 PVDDQ_DEF VDD<8> @BASEBOARD_FAB2_LIB.BASEBOARD_FAB2(SCH_1):PVDDQ_DEF
 217 PVDDQ_DEF VDD<7> @BASEBOARD_FAB2_LIB.BASEBOARD_FAB2(SCH_1):PVDDQ_DEF
 220 PVDDQ_DEF VDD<6> @BASEBOARD_FAB2_LIB.BASEBOARD_FAB2(SCH_1):PVDDQ_DEF
 223 PVDDQ_DEF VDD<5> @BASEBOARD_FAB2_LIB.BASEBOARD_FAB2(SCH_1):PVDDQ_DEF
 226 PVDDQ_DEF VDD<4> @BASEBOARD_FAB2_LIB.BASEBOARD_FAB2(SCH_1):PVDDQ_DEF
 229 PVDDQ_DEF VDD<3> @BASEBOARD_FAB2_LIB.BASEBOARD_FAB2(SCH_1):PVDDQ_DEF
 231 PVDDQ_DEF VDD<2> @BASEBOARD_FAB2_LIB.BASEBOARD_FAB2(SCH_1):PVDDQ_DEF
 233 PVDDQ_DEF VDD<1> @BASEBOARD_FAB2_LIB.BASEBOARD_FAB2(SCH_1):PVDDQ_DEF
 236 PVDDQ_DEF VDD<0> @BASEBOARD_FAB2_LIB.BASEBOARD_FAB2(SCH_1):PVDDQ_DEF
 142 PVPP_DEF VPP<4> @BASEBOARD_FAB2_LIB.BASEBOARD_FAB2(SCH_1):PVPP_DEF
 143 PVPP_DEF VPP<3> @BASEBOARD_FAB2_LIB.BASEBOARD_FAB2(SCH_1):PVPP_DEF
 288 PVPP_DEF VPP<2> @BASEBOARD_FAB2_LIB.BASEBOARD_FAB2(SCH_1):PVPP_DEF
 286 PVPP_DEF VPP<1> @BASEBOARD_FAB2_LIB.BASEBOARD_FAB2(SCH_1):PVPP_DEF
 287 PVPP_DEF VPP<0> @BASEBOARD_FAB2_LIB.BASEBOARD_FAB2(SCH_1):PVPP_DEF
  77 PVTT_DEF VTT<1> @BASEBOARD_FAB2_LIB.BASEBOARD_FAB2(SCH_1):PVTT_DEF
 221 PVTT_DEF VTT<0> @BASEBOARD_FAB2_LIB.BASEBOARD_FAB2(SCH_1):PVTT_DEF

SCONN288_H44441003_PIP-SCONN,HA  I158  J6M1
  79 M_D_MA<0>     A0 @BASEBOARD_FAB2_LIB.BASEBOARD_FAB2(SCH_1):M_D_MA(0)
  72 M_D_MA<1>     A1 @BASEBOARD_FAB2_LIB.BASEBOARD_FAB2(SCH_1):M_D_MA(1)
 225 M_D_MA<10>    A10 @BASEBOARD_FAB2_LIB.BASEBOARD_FAB2(SCH_1):M_D_MA(10)
 210 M_D_MA<11>    A11 @BASEBOARD_FAB2_LIB.BASEBOARD_FAB2(SCH_1):M_D_MA(11)
  65 M_D_MA<12>    A12 @BASEBOARD_FAB2_LIB.BASEBOARD_FAB2(SCH_1):M_D_MA(12)
 232 M_D_MA<13>    A13 @BASEBOARD_FAB2_LIB.BASEBOARD_FAB2(SCH_1):M_D_MA(13)
 228 M_D_MA<14> A14_WE_N @BASEBOARD_FAB2_LIB.BASEBOARD_FAB2(SCH_1):M_D_MA(14)
  86 M_D_MA<15> A15_CAS_N @BASEBOARD_FAB2_LIB.BASEBOARD_FAB2(SCH_1):M_D_MA(15)
  82 M_D_MA<16> A16_RAS_N @BASEBOARD_FAB2_LIB.BASEBOARD_FAB2(SCH_1):M_D_MA(16)
 234 M_D_MA<17>    A17 @BASEBOARD_FAB2_LIB.BASEBOARD_FAB2(SCH_1):M_D_MA(17)
 216 M_D_MA<2>     A2 @BASEBOARD_FAB2_LIB.BASEBOARD_FAB2(SCH_1):M_D_MA(2)
  71 M_D_MA<3>     A3 @BASEBOARD_FAB2_LIB.BASEBOARD_FAB2(SCH_1):M_D_MA(3)
 214 M_D_MA<4>     A4 @BASEBOARD_FAB2_LIB.BASEBOARD_FAB2(SCH_1):M_D_MA(4)
 213 M_D_MA<5>     A5 @BASEBOARD_FAB2_LIB.BASEBOARD_FAB2(SCH_1):M_D_MA(5)
  69 M_D_MA<6>     A6 @BASEBOARD_FAB2_LIB.BASEBOARD_FAB2(SCH_1):M_D_MA(6)
 211 M_D_MA<7>     A7 @BASEBOARD_FAB2_LIB.BASEBOARD_FAB2(SCH_1):M_D_MA(7)
  68 M_D_MA<8>     A8 @BASEBOARD_FAB2_LIB.BASEBOARD_FAB2(SCH_1):M_D_MA(8)
  66 M_D_MA<9>     A9 @BASEBOARD_FAB2_LIB.BASEBOARD_FAB2(SCH_1):M_D_MA(9)
  62 M_D_ACT_N  ACT_N @BASEBOARD_FAB2_LIB.BASEBOARD_FAB2(SCH_1):M_D_ACT_N
 208 M_D_ALERT_N ALERT_N @BASEBOARD_FAB2_LIB.BASEBOARD_FAB2(SCH_1):M_D_ALERT_N
 224 M_D_BA<1>  BA<1> @BASEBOARD_FAB2_LIB.BASEBOARD_FAB2(SCH_1):M_D_BA(1)
  81 M_D_BA<0>  BA<0> @BASEBOARD_FAB2_LIB.BASEBOARD_FAB2(SCH_1):M_D_BA(0)
 207 M_D_BG<1>  BG<1> @BASEBOARD_FAB2_LIB.BASEBOARD_FAB2(SCH_1):M_D_BG(1)
  63 M_D_BG<0>  BG<0> @BASEBOARD_FAB2_LIB.BASEBOARD_FAB2(SCH_1):M_D_BG(0)
 235 M_D_C<2>   C<2> @BASEBOARD_FAB2_LIB.BASEBOARD_FAB2(SCH_1):M_D_C(2)
 199 M_D_ECC<7>  CB<7> @BASEBOARD_FAB2_LIB.BASEBOARD_FAB2(SCH_1):M_D_ECC(7)
  54 M_D_ECC<6>  CB<6> @BASEBOARD_FAB2_LIB.BASEBOARD_FAB2(SCH_1):M_D_ECC(6)
 192 M_D_ECC<5>  CB<5> @BASEBOARD_FAB2_LIB.BASEBOARD_FAB2(SCH_1):M_D_ECC(5)
  47 M_D_ECC<4>  CB<4> @BASEBOARD_FAB2_LIB.BASEBOARD_FAB2(SCH_1):M_D_ECC(4)
 201 M_D_ECC<3>  CB<3> @BASEBOARD_FAB2_LIB.BASEBOARD_FAB2(SCH_1):M_D_ECC(3)
  56 M_D_ECC<2>  CB<2> @BASEBOARD_FAB2_LIB.BASEBOARD_FAB2(SCH_1):M_D_ECC(2)
 194 M_D_ECC<1>  CB<1> @BASEBOARD_FAB2_LIB.BASEBOARD_FAB2(SCH_1):M_D_ECC(1)
  49 M_D_ECC<0>  CB<0> @BASEBOARD_FAB2_LIB.BASEBOARD_FAB2(SCH_1):M_D_ECC(0)
  75 M_D_CLK_DN<2>   CK0N @BASEBOARD_FAB2_LIB.BASEBOARD_FAB2(SCH_1):M_D_CLK_DN(2)
  74 M_D_CLK_DP<2>   CK0P @BASEBOARD_FAB2_LIB.BASEBOARD_FAB2(SCH_1):M_D_CLK_DP(2)
 219 M_D_CLK_DN<3>   CK1N @BASEBOARD_FAB2_LIB.BASEBOARD_FAB2(SCH_1):M_D_CLK_DN(3)
 218 M_D_CLK_DP<3>   CK1P @BASEBOARD_FAB2_LIB.BASEBOARD_FAB2(SCH_1):M_D_CLK_DP(3)
 203 M_D_CKE<3> CKE<1> @BASEBOARD_FAB2_LIB.BASEBOARD_FAB2(SCH_1):M_D_CKE(3)
  60 M_D_CKE<2> CKE<0> @BASEBOARD_FAB2_LIB.BASEBOARD_FAB2(SCH_1):M_D_CKE(2)
 280 M_D_DQ<63> DQ<63> @BASEBOARD_FAB2_LIB.BASEBOARD_FAB2(SCH_1):M_D_DQ(63)
 135 M_D_DQ<62> DQ<62> @BASEBOARD_FAB2_LIB.BASEBOARD_FAB2(SCH_1):M_D_DQ(62)
 273 M_D_DQ<61> DQ<61> @BASEBOARD_FAB2_LIB.BASEBOARD_FAB2(SCH_1):M_D_DQ(61)
 128 M_D_DQ<60> DQ<60> @BASEBOARD_FAB2_LIB.BASEBOARD_FAB2(SCH_1):M_D_DQ(60)
 282 M_D_DQ<59> DQ<59> @BASEBOARD_FAB2_LIB.BASEBOARD_FAB2(SCH_1):M_D_DQ(59)
 137 M_D_DQ<58> DQ<58> @BASEBOARD_FAB2_LIB.BASEBOARD_FAB2(SCH_1):M_D_DQ(58)
 275 M_D_DQ<57> DQ<57> @BASEBOARD_FAB2_LIB.BASEBOARD_FAB2(SCH_1):M_D_DQ(57)
 130 M_D_DQ<56> DQ<56> @BASEBOARD_FAB2_LIB.BASEBOARD_FAB2(SCH_1):M_D_DQ(56)
 269 M_D_DQ<55> DQ<55> @BASEBOARD_FAB2_LIB.BASEBOARD_FAB2(SCH_1):M_D_DQ(55)
 124 M_D_DQ<54> DQ<54> @BASEBOARD_FAB2_LIB.BASEBOARD_FAB2(SCH_1):M_D_DQ(54)
 262 M_D_DQ<53> DQ<53> @BASEBOARD_FAB2_LIB.BASEBOARD_FAB2(SCH_1):M_D_DQ(53)
 117 M_D_DQ<52> DQ<52> @BASEBOARD_FAB2_LIB.BASEBOARD_FAB2(SCH_1):M_D_DQ(52)
 271 M_D_DQ<51> DQ<51> @BASEBOARD_FAB2_LIB.BASEBOARD_FAB2(SCH_1):M_D_DQ(51)
 126 M_D_DQ<50> DQ<50> @BASEBOARD_FAB2_LIB.BASEBOARD_FAB2(SCH_1):M_D_DQ(50)
 264 M_D_DQ<49> DQ<49> @BASEBOARD_FAB2_LIB.BASEBOARD_FAB2(SCH_1):M_D_DQ(49)
 119 M_D_DQ<48> DQ<48> @BASEBOARD_FAB2_LIB.BASEBOARD_FAB2(SCH_1):M_D_DQ(48)
 258 M_D_DQ<47> DQ<47> @BASEBOARD_FAB2_LIB.BASEBOARD_FAB2(SCH_1):M_D_DQ(47)
 113 M_D_DQ<46> DQ<46> @BASEBOARD_FAB2_LIB.BASEBOARD_FAB2(SCH_1):M_D_DQ(46)
 251 M_D_DQ<45> DQ<45> @BASEBOARD_FAB2_LIB.BASEBOARD_FAB2(SCH_1):M_D_DQ(45)
 106 M_D_DQ<44> DQ<44> @BASEBOARD_FAB2_LIB.BASEBOARD_FAB2(SCH_1):M_D_DQ(44)
 260 M_D_DQ<43> DQ<43> @BASEBOARD_FAB2_LIB.BASEBOARD_FAB2(SCH_1):M_D_DQ(43)
 115 M_D_DQ<42> DQ<42> @BASEBOARD_FAB2_LIB.BASEBOARD_FAB2(SCH_1):M_D_DQ(42)
 253 M_D_DQ<41> DQ<41> @BASEBOARD_FAB2_LIB.BASEBOARD_FAB2(SCH_1):M_D_DQ(41)
 108 M_D_DQ<40> DQ<40> @BASEBOARD_FAB2_LIB.BASEBOARD_FAB2(SCH_1):M_D_DQ(40)
 247 M_D_DQ<39> DQ<39> @BASEBOARD_FAB2_LIB.BASEBOARD_FAB2(SCH_1):M_D_DQ(39)
 102 M_D_DQ<38> DQ<38> @BASEBOARD_FAB2_LIB.BASEBOARD_FAB2(SCH_1):M_D_DQ(38)
 240 M_D_DQ<37> DQ<37> @BASEBOARD_FAB2_LIB.BASEBOARD_FAB2(SCH_1):M_D_DQ(37)
  95 M_D_DQ<36> DQ<36> @BASEBOARD_FAB2_LIB.BASEBOARD_FAB2(SCH_1):M_D_DQ(36)
 249 M_D_DQ<35> DQ<35> @BASEBOARD_FAB2_LIB.BASEBOARD_FAB2(SCH_1):M_D_DQ(35)
 104 M_D_DQ<34> DQ<34> @BASEBOARD_FAB2_LIB.BASEBOARD_FAB2(SCH_1):M_D_DQ(34)
 242 M_D_DQ<33> DQ<33> @BASEBOARD_FAB2_LIB.BASEBOARD_FAB2(SCH_1):M_D_DQ(33)
  97 M_D_DQ<32> DQ<32> @BASEBOARD_FAB2_LIB.BASEBOARD_FAB2(SCH_1):M_D_DQ(32)
 188 M_D_DQ<31> DQ<31> @BASEBOARD_FAB2_LIB.BASEBOARD_FAB2(SCH_1):M_D_DQ(31)
  43 M_D_DQ<30> DQ<30> @BASEBOARD_FAB2_LIB.BASEBOARD_FAB2(SCH_1):M_D_DQ(30)
 181 M_D_DQ<29> DQ<29> @BASEBOARD_FAB2_LIB.BASEBOARD_FAB2(SCH_1):M_D_DQ(29)
  36 M_D_DQ<28> DQ<28> @BASEBOARD_FAB2_LIB.BASEBOARD_FAB2(SCH_1):M_D_DQ(28)
 190 M_D_DQ<27> DQ<27> @BASEBOARD_FAB2_LIB.BASEBOARD_FAB2(SCH_1):M_D_DQ(27)
  45 M_D_DQ<26> DQ<26> @BASEBOARD_FAB2_LIB.BASEBOARD_FAB2(SCH_1):M_D_DQ(26)
 183 M_D_DQ<25> DQ<25> @BASEBOARD_FAB2_LIB.BASEBOARD_FAB2(SCH_1):M_D_DQ(25)
  38 M_D_DQ<24> DQ<24> @BASEBOARD_FAB2_LIB.BASEBOARD_FAB2(SCH_1):M_D_DQ(24)
 177 M_D_DQ<23> DQ<23> @BASEBOARD_FAB2_LIB.BASEBOARD_FAB2(SCH_1):M_D_DQ(23)
  32 M_D_DQ<22> DQ<22> @BASEBOARD_FAB2_LIB.BASEBOARD_FAB2(SCH_1):M_D_DQ(22)
 170 M_D_DQ<21> DQ<21> @BASEBOARD_FAB2_LIB.BASEBOARD_FAB2(SCH_1):M_D_DQ(21)
  25 M_D_DQ<20> DQ<20> @BASEBOARD_FAB2_LIB.BASEBOARD_FAB2(SCH_1):M_D_DQ(20)
 179 M_D_DQ<19> DQ<19> @BASEBOARD_FAB2_LIB.BASEBOARD_FAB2(SCH_1):M_D_DQ(19)
  34 M_D_DQ<18> DQ<18> @BASEBOARD_FAB2_LIB.BASEBOARD_FAB2(SCH_1):M_D_DQ(18)
 172 M_D_DQ<17> DQ<17> @BASEBOARD_FAB2_LIB.BASEBOARD_FAB2(SCH_1):M_D_DQ(17)
  27 M_D_DQ<16> DQ<16> @BASEBOARD_FAB2_LIB.BASEBOARD_FAB2(SCH_1):M_D_DQ(16)
 166 M_D_DQ<15> DQ<15> @BASEBOARD_FAB2_LIB.BASEBOARD_FAB2(SCH_1):M_D_DQ(15)
  21 M_D_DQ<14> DQ<14> @BASEBOARD_FAB2_LIB.BASEBOARD_FAB2(SCH_1):M_D_DQ(14)
 159 M_D_DQ<13> DQ<13> @BASEBOARD_FAB2_LIB.BASEBOARD_FAB2(SCH_1):M_D_DQ(13)
  14 M_D_DQ<12> DQ<12> @BASEBOARD_FAB2_LIB.BASEBOARD_FAB2(SCH_1):M_D_DQ(12)
 168 M_D_DQ<11> DQ<11> @BASEBOARD_FAB2_LIB.BASEBOARD_FAB2(SCH_1):M_D_DQ(11)
  23 M_D_DQ<10> DQ<10> @BASEBOARD_FAB2_LIB.BASEBOARD_FAB2(SCH_1):M_D_DQ(10)
 161 M_D_DQ<9>  DQ<9> @BASEBOARD_FAB2_LIB.BASEBOARD_FAB2(SCH_1):M_D_DQ(9)
  16 M_D_DQ<8>  DQ<8> @BASEBOARD_FAB2_LIB.BASEBOARD_FAB2(SCH_1):M_D_DQ(8)
 155 M_D_DQ<7>  DQ<7> @BASEBOARD_FAB2_LIB.BASEBOARD_FAB2(SCH_1):M_D_DQ(7)
  10 M_D_DQ<6>  DQ<6> @BASEBOARD_FAB2_LIB.BASEBOARD_FAB2(SCH_1):M_D_DQ(6)
 148 M_D_DQ<5>  DQ<5> @BASEBOARD_FAB2_LIB.BASEBOARD_FAB2(SCH_1):M_D_DQ(5)
   3 M_D_DQ<4>  DQ<4> @BASEBOARD_FAB2_LIB.BASEBOARD_FAB2(SCH_1):M_D_DQ(4)
 157 M_D_DQ<3>  DQ<3> @BASEBOARD_FAB2_LIB.BASEBOARD_FAB2(SCH_1):M_D_DQ(3)
  12 M_D_DQ<2>  DQ<2> @BASEBOARD_FAB2_LIB.BASEBOARD_FAB2(SCH_1):M_D_DQ(2)
 150 M_D_DQ<1>  DQ<1> @BASEBOARD_FAB2_LIB.BASEBOARD_FAB2(SCH_1):M_D_DQ(1)
   5 M_D_DQ<0>  DQ<0> @BASEBOARD_FAB2_LIB.BASEBOARD_FAB2(SCH_1):M_D_DQ(0)
  78 FM_DIMM_EVENT_COD_N EVENT_N @BASEBOARD_FAB2_LIB.BASEBOARD_FAB2(SCH_1):FM_DIMM_EVENT_COD_N
  91 M_D_ODT<3> ODT<1> @BASEBOARD_FAB2_LIB.BASEBOARD_FAB2(SCH_1):M_D_ODT(3)
  87 M_D_ODT<2> ODT<0> @BASEBOARD_FAB2_LIB.BASEBOARD_FAB2(SCH_1):M_D_ODT(2)
 222 M_D_PAR    PAR @BASEBOARD_FAB2_LIB.BASEBOARD_FAB2(SCH_1):M_D_PAR
  58 M_DEF_RST_N RESET_N @BASEBOARD_FAB2_LIB.BASEBOARD_FAB2(SCH_1):M_DEF_RST_N
 144 TP_CH_D_DIMM_D1_RFU_2 RFU<2> @BASEBOARD_FAB2_LIB.BASEBOARD_FAB2(SCH_1):TP_CH_D_DIMM_D1_RFU_2
 227 TP_CH_D_DIMM_D1_RFU_1 RFU<1> @BASEBOARD_FAB2_LIB.BASEBOARD_FAB2(SCH_1):TP_CH_D_DIMM_D1_RFU_1
 205 TP_CH_D_DIMM_D1_RFU_0 RFU<0> @BASEBOARD_FAB2_LIB.BASEBOARD_FAB2(SCH_1):TP_CH_D_DIMM_D1_RFU_0
  84 M_D_CS_N<4>   S0_N @BASEBOARD_FAB2_LIB.BASEBOARD_FAB2(SCH_1):M_D_CS_N(4)
  89 M_D_CS_N<5>   S1_N @BASEBOARD_FAB2_LIB.BASEBOARD_FAB2(SCH_1):M_D_CS_N(5)
  93 M_D_CS_N<6> S2_N_C<0> @BASEBOARD_FAB2_LIB.BASEBOARD_FAB2(SCH_1):M_D_CS_N(6)
 237 M_D_CS_N<7> S3_N_C<1> @BASEBOARD_FAB2_LIB.BASEBOARD_FAB2(SCH_1):M_D_CS_N(7)
 238    GND  SA<2> @BASEBOARD_FAB2_LIB.BASEBOARD_FAB2(SCH_1):GND
 140    GND  SA<1> @BASEBOARD_FAB2_LIB.BASEBOARD_FAB2(SCH_1):GND
 139 PVPP_DEF  SA<0> @BASEBOARD_FAB2_LIB.BASEBOARD_FAB2(SCH_1):PVPP_DEF
 230 FM_ADR_COMPLETE_DEF_N SAVE_N_NC @BASEBOARD_FAB2_LIB.BASEBOARD_FAB2(SCH_1):FM_ADR_COMPLETE_DEF_N
 141 SMB_DDR_DEF_VPP_SCL    SCL @BASEBOARD_FAB2_LIB.BASEBOARD_FAB2(SCH_1):SMB_DDR_DEF_VPP_SCL
 285 SMB_DDR_DEF_VPP_SDA    SDA @BASEBOARD_FAB2_LIB.BASEBOARD_FAB2(SCH_1):SMB_DDR_DEF_VPP_SDA
 284 PVPP_DEF VDDSPD @BASEBOARD_FAB2_LIB.BASEBOARD_FAB2(SCH_1):PVPP_DEF
 146 M_D_VREF VREFCA @BASEBOARD_FAB2_LIB.BASEBOARD_FAB2(SCH_1):M_D_VREF

CAP_A_0402V-0.01UF,25V,10%,X7RA  I177  C6M1
   1 M_D_VREF      A @BASEBOARD_FAB2_LIB.BASEBOARD_FAB2(SCH_1):M_D_VREF
   2    GND      B @BASEBOARD_FAB2_LIB.BASEBOARD_FAB2(SCH_1):GND


DRAWING: @BASEBOARD_FAB2_LIB.BASEBOARD_FAB2(SCH_1):PAGE51 

SCONN288_H44441004_PIP-SCONN,HA  I43  J4A2
   2    GND VSS<93> @BASEBOARD_FAB2_LIB.BASEBOARD_FAB2(SCH_1):GND
   4    GND VSS<92> @BASEBOARD_FAB2_LIB.BASEBOARD_FAB2(SCH_1):GND
   6    GND VSS<91> @BASEBOARD_FAB2_LIB.BASEBOARD_FAB2(SCH_1):GND
   9    GND VSS<90> @BASEBOARD_FAB2_LIB.BASEBOARD_FAB2(SCH_1):GND
  11    GND VSS<89> @BASEBOARD_FAB2_LIB.BASEBOARD_FAB2(SCH_1):GND
  13    GND VSS<88> @BASEBOARD_FAB2_LIB.BASEBOARD_FAB2(SCH_1):GND
  15    GND VSS<87> @BASEBOARD_FAB2_LIB.BASEBOARD_FAB2(SCH_1):GND
  17    GND VSS<86> @BASEBOARD_FAB2_LIB.BASEBOARD_FAB2(SCH_1):GND
  20    GND VSS<85> @BASEBOARD_FAB2_LIB.BASEBOARD_FAB2(SCH_1):GND
  22    GND VSS<84> @BASEBOARD_FAB2_LIB.BASEBOARD_FAB2(SCH_1):GND
  24    GND VSS<83> @BASEBOARD_FAB2_LIB.BASEBOARD_FAB2(SCH_1):GND
  26    GND VSS<82> @BASEBOARD_FAB2_LIB.BASEBOARD_FAB2(SCH_1):GND
  28    GND VSS<81> @BASEBOARD_FAB2_LIB.BASEBOARD_FAB2(SCH_1):GND
  31    GND VSS<80> @BASEBOARD_FAB2_LIB.BASEBOARD_FAB2(SCH_1):GND
  33    GND VSS<79> @BASEBOARD_FAB2_LIB.BASEBOARD_FAB2(SCH_1):GND
  35    GND VSS<78> @BASEBOARD_FAB2_LIB.BASEBOARD_FAB2(SCH_1):GND
  37    GND VSS<77> @BASEBOARD_FAB2_LIB.BASEBOARD_FAB2(SCH_1):GND
  39    GND VSS<76> @BASEBOARD_FAB2_LIB.BASEBOARD_FAB2(SCH_1):GND
  42    GND VSS<75> @BASEBOARD_FAB2_LIB.BASEBOARD_FAB2(SCH_1):GND
  44    GND VSS<74> @BASEBOARD_FAB2_LIB.BASEBOARD_FAB2(SCH_1):GND
  46    GND VSS<73> @BASEBOARD_FAB2_LIB.BASEBOARD_FAB2(SCH_1):GND
  48    GND VSS<72> @BASEBOARD_FAB2_LIB.BASEBOARD_FAB2(SCH_1):GND
  50    GND VSS<71> @BASEBOARD_FAB2_LIB.BASEBOARD_FAB2(SCH_1):GND
  53    GND VSS<70> @BASEBOARD_FAB2_LIB.BASEBOARD_FAB2(SCH_1):GND
  55    GND VSS<69> @BASEBOARD_FAB2_LIB.BASEBOARD_FAB2(SCH_1):GND
  57    GND VSS<68> @BASEBOARD_FAB2_LIB.BASEBOARD_FAB2(SCH_1):GND
  94    GND VSS<67> @BASEBOARD_FAB2_LIB.BASEBOARD_FAB2(SCH_1):GND
  96    GND VSS<66> @BASEBOARD_FAB2_LIB.BASEBOARD_FAB2(SCH_1):GND
  98    GND VSS<65> @BASEBOARD_FAB2_LIB.BASEBOARD_FAB2(SCH_1):GND
 101    GND VSS<64> @BASEBOARD_FAB2_LIB.BASEBOARD_FAB2(SCH_1):GND
 103    GND VSS<63> @BASEBOARD_FAB2_LIB.BASEBOARD_FAB2(SCH_1):GND
 105    GND VSS<62> @BASEBOARD_FAB2_LIB.BASEBOARD_FAB2(SCH_1):GND
 107    GND VSS<61> @BASEBOARD_FAB2_LIB.BASEBOARD_FAB2(SCH_1):GND
 109    GND VSS<60> @BASEBOARD_FAB2_LIB.BASEBOARD_FAB2(SCH_1):GND
 112    GND VSS<59> @BASEBOARD_FAB2_LIB.BASEBOARD_FAB2(SCH_1):GND
 114    GND VSS<58> @BASEBOARD_FAB2_LIB.BASEBOARD_FAB2(SCH_1):GND
 116    GND VSS<57> @BASEBOARD_FAB2_LIB.BASEBOARD_FAB2(SCH_1):GND
 118    GND VSS<56> @BASEBOARD_FAB2_LIB.BASEBOARD_FAB2(SCH_1):GND
 120    GND VSS<55> @BASEBOARD_FAB2_LIB.BASEBOARD_FAB2(SCH_1):GND
 123    GND VSS<54> @BASEBOARD_FAB2_LIB.BASEBOARD_FAB2(SCH_1):GND
 125    GND VSS<53> @BASEBOARD_FAB2_LIB.BASEBOARD_FAB2(SCH_1):GND
 127    GND VSS<52> @BASEBOARD_FAB2_LIB.BASEBOARD_FAB2(SCH_1):GND
 129    GND VSS<51> @BASEBOARD_FAB2_LIB.BASEBOARD_FAB2(SCH_1):GND
 131    GND VSS<50> @BASEBOARD_FAB2_LIB.BASEBOARD_FAB2(SCH_1):GND
 134    GND VSS<49> @BASEBOARD_FAB2_LIB.BASEBOARD_FAB2(SCH_1):GND
 136    GND VSS<48> @BASEBOARD_FAB2_LIB.BASEBOARD_FAB2(SCH_1):GND
 138    GND VSS<47> @BASEBOARD_FAB2_LIB.BASEBOARD_FAB2(SCH_1):GND
 147    GND VSS<46> @BASEBOARD_FAB2_LIB.BASEBOARD_FAB2(SCH_1):GND
 149    GND VSS<45> @BASEBOARD_FAB2_LIB.BASEBOARD_FAB2(SCH_1):GND
 151    GND VSS<44> @BASEBOARD_FAB2_LIB.BASEBOARD_FAB2(SCH_1):GND
 154    GND VSS<43> @BASEBOARD_FAB2_LIB.BASEBOARD_FAB2(SCH_1):GND
 156    GND VSS<42> @BASEBOARD_FAB2_LIB.BASEBOARD_FAB2(SCH_1):GND
 158    GND VSS<41> @BASEBOARD_FAB2_LIB.BASEBOARD_FAB2(SCH_1):GND
 160    GND VSS<40> @BASEBOARD_FAB2_LIB.BASEBOARD_FAB2(SCH_1):GND
 162    GND VSS<39> @BASEBOARD_FAB2_LIB.BASEBOARD_FAB2(SCH_1):GND
 165    GND VSS<38> @BASEBOARD_FAB2_LIB.BASEBOARD_FAB2(SCH_1):GND
 167    GND VSS<37> @BASEBOARD_FAB2_LIB.BASEBOARD_FAB2(SCH_1):GND
 169    GND VSS<36> @BASEBOARD_FAB2_LIB.BASEBOARD_FAB2(SCH_1):GND
 171    GND VSS<35> @BASEBOARD_FAB2_LIB.BASEBOARD_FAB2(SCH_1):GND
 173    GND VSS<34> @BASEBOARD_FAB2_LIB.BASEBOARD_FAB2(SCH_1):GND
 176    GND VSS<33> @BASEBOARD_FAB2_LIB.BASEBOARD_FAB2(SCH_1):GND
 178    GND VSS<32> @BASEBOARD_FAB2_LIB.BASEBOARD_FAB2(SCH_1):GND
 180    GND VSS<31> @BASEBOARD_FAB2_LIB.BASEBOARD_FAB2(SCH_1):GND
 182    GND VSS<30> @BASEBOARD_FAB2_LIB.BASEBOARD_FAB2(SCH_1):GND
 184    GND VSS<29> @BASEBOARD_FAB2_LIB.BASEBOARD_FAB2(SCH_1):GND
 187    GND VSS<28> @BASEBOARD_FAB2_LIB.BASEBOARD_FAB2(SCH_1):GND
 189    GND VSS<27> @BASEBOARD_FAB2_LIB.BASEBOARD_FAB2(SCH_1):GND
 191    GND VSS<26> @BASEBOARD_FAB2_LIB.BASEBOARD_FAB2(SCH_1):GND
 193    GND VSS<25> @BASEBOARD_FAB2_LIB.BASEBOARD_FAB2(SCH_1):GND
 195    GND VSS<24> @BASEBOARD_FAB2_LIB.BASEBOARD_FAB2(SCH_1):GND
 198    GND VSS<23> @BASEBOARD_FAB2_LIB.BASEBOARD_FAB2(SCH_1):GND
 200    GND VSS<22> @BASEBOARD_FAB2_LIB.BASEBOARD_FAB2(SCH_1):GND
 202    GND VSS<21> @BASEBOARD_FAB2_LIB.BASEBOARD_FAB2(SCH_1):GND
 239    GND VSS<20> @BASEBOARD_FAB2_LIB.BASEBOARD_FAB2(SCH_1):GND
 241    GND VSS<19> @BASEBOARD_FAB2_LIB.BASEBOARD_FAB2(SCH_1):GND
 243    GND VSS<18> @BASEBOARD_FAB2_LIB.BASEBOARD_FAB2(SCH_1):GND
 246    GND VSS<17> @BASEBOARD_FAB2_LIB.BASEBOARD_FAB2(SCH_1):GND
 248    GND VSS<16> @BASEBOARD_FAB2_LIB.BASEBOARD_FAB2(SCH_1):GND
 250    GND VSS<15> @BASEBOARD_FAB2_LIB.BASEBOARD_FAB2(SCH_1):GND
 252    GND VSS<14> @BASEBOARD_FAB2_LIB.BASEBOARD_FAB2(SCH_1):GND
 254    GND VSS<13> @BASEBOARD_FAB2_LIB.BASEBOARD_FAB2(SCH_1):GND
 257    GND VSS<12> @BASEBOARD_FAB2_LIB.BASEBOARD_FAB2(SCH_1):GND
 259    GND VSS<11> @BASEBOARD_FAB2_LIB.BASEBOARD_FAB2(SCH_1):GND
 261    GND VSS<10> @BASEBOARD_FAB2_LIB.BASEBOARD_FAB2(SCH_1):GND
 263    GND VSS<9> @BASEBOARD_FAB2_LIB.BASEBOARD_FAB2(SCH_1):GND
 265    GND VSS<8> @BASEBOARD_FAB2_LIB.BASEBOARD_FAB2(SCH_1):GND
 268    GND VSS<7> @BASEBOARD_FAB2_LIB.BASEBOARD_FAB2(SCH_1):GND
 270    GND VSS<6> @BASEBOARD_FAB2_LIB.BASEBOARD_FAB2(SCH_1):GND
 272    GND VSS<5> @BASEBOARD_FAB2_LIB.BASEBOARD_FAB2(SCH_1):GND
 274    GND VSS<4> @BASEBOARD_FAB2_LIB.BASEBOARD_FAB2(SCH_1):GND
 276    GND VSS<3> @BASEBOARD_FAB2_LIB.BASEBOARD_FAB2(SCH_1):GND
 279    GND VSS<2> @BASEBOARD_FAB2_LIB.BASEBOARD_FAB2(SCH_1):GND
 281    GND VSS<1> @BASEBOARD_FAB2_LIB.BASEBOARD_FAB2(SCH_1):GND
 283    GND VSS<0> @BASEBOARD_FAB2_LIB.BASEBOARD_FAB2(SCH_1):GND

SCONN288_H44441004_PIP-SCONN,HA  I66  J4A2
 152 M_E_DQS_DN<0>  DQS0N @BASEBOARD_FAB2_LIB.BASEBOARD_FAB2(SCH_1):M_E_DQS_DN(0)
 153 M_E_DQS_DP<0>  DQS0P @BASEBOARD_FAB2_LIB.BASEBOARD_FAB2(SCH_1):M_E_DQS_DP(0)
  19 M_E_DQS_DN<10> DQS10N @BASEBOARD_FAB2_LIB.BASEBOARD_FAB2(SCH_1):M_E_DQS_DN(10)
  18 M_E_DQS_DP<10> DQS10P @BASEBOARD_FAB2_LIB.BASEBOARD_FAB2(SCH_1):M_E_DQS_DP(10)
  30 M_E_DQS_DN<11> DQS11N @BASEBOARD_FAB2_LIB.BASEBOARD_FAB2(SCH_1):M_E_DQS_DN(11)
  29 M_E_DQS_DP<11> DQS11P @BASEBOARD_FAB2_LIB.BASEBOARD_FAB2(SCH_1):M_E_DQS_DP(11)
  41 M_E_DQS_DN<12> DQS12N @BASEBOARD_FAB2_LIB.BASEBOARD_FAB2(SCH_1):M_E_DQS_DN(12)
  40 M_E_DQS_DP<12> DQS12P @BASEBOARD_FAB2_LIB.BASEBOARD_FAB2(SCH_1):M_E_DQS_DP(12)
 100 M_E_DQS_DN<13> DQS13N @BASEBOARD_FAB2_LIB.BASEBOARD_FAB2(SCH_1):M_E_DQS_DN(13)
  99 M_E_DQS_DP<13> DQS13P @BASEBOARD_FAB2_LIB.BASEBOARD_FAB2(SCH_1):M_E_DQS_DP(13)
 111 M_E_DQS_DN<14> DQS14N @BASEBOARD_FAB2_LIB.BASEBOARD_FAB2(SCH_1):M_E_DQS_DN(14)
 110 M_E_DQS_DP<14> DQS14P @BASEBOARD_FAB2_LIB.BASEBOARD_FAB2(SCH_1):M_E_DQS_DP(14)
 122 M_E_DQS_DN<15> DQS15N @BASEBOARD_FAB2_LIB.BASEBOARD_FAB2(SCH_1):M_E_DQS_DN(15)
 121 M_E_DQS_DP<15> DQS15P @BASEBOARD_FAB2_LIB.BASEBOARD_FAB2(SCH_1):M_E_DQS_DP(15)
 133 M_E_DQS_DN<16> DQS16N @BASEBOARD_FAB2_LIB.BASEBOARD_FAB2(SCH_1):M_E_DQS_DN(16)
 132 M_E_DQS_DP<16> DQS16P @BASEBOARD_FAB2_LIB.BASEBOARD_FAB2(SCH_1):M_E_DQS_DP(16)
  52 M_E_DQS_DN<17> DQS17N @BASEBOARD_FAB2_LIB.BASEBOARD_FAB2(SCH_1):M_E_DQS_DN(17)
  51 M_E_DQS_DP<17> DQS17P @BASEBOARD_FAB2_LIB.BASEBOARD_FAB2(SCH_1):M_E_DQS_DP(17)
 163 M_E_DQS_DN<1>  DQS1N @BASEBOARD_FAB2_LIB.BASEBOARD_FAB2(SCH_1):M_E_DQS_DN(1)
 164 M_E_DQS_DP<1>  DQS1P @BASEBOARD_FAB2_LIB.BASEBOARD_FAB2(SCH_1):M_E_DQS_DP(1)
 174 M_E_DQS_DN<2>  DQS2N @BASEBOARD_FAB2_LIB.BASEBOARD_FAB2(SCH_1):M_E_DQS_DN(2)
 175 M_E_DQS_DP<2>  DQS2P @BASEBOARD_FAB2_LIB.BASEBOARD_FAB2(SCH_1):M_E_DQS_DP(2)
 185 M_E_DQS_DN<3>  DQS3N @BASEBOARD_FAB2_LIB.BASEBOARD_FAB2(SCH_1):M_E_DQS_DN(3)
 186 M_E_DQS_DP<3>  DQS3P @BASEBOARD_FAB2_LIB.BASEBOARD_FAB2(SCH_1):M_E_DQS_DP(3)
 244 M_E_DQS_DN<4>  DQS4N @BASEBOARD_FAB2_LIB.BASEBOARD_FAB2(SCH_1):M_E_DQS_DN(4)
 245 M_E_DQS_DP<4>  DQS4P @BASEBOARD_FAB2_LIB.BASEBOARD_FAB2(SCH_1):M_E_DQS_DP(4)
 255 M_E_DQS_DN<5>  DQS5N @BASEBOARD_FAB2_LIB.BASEBOARD_FAB2(SCH_1):M_E_DQS_DN(5)
 256 M_E_DQS_DP<5>  DQS5P @BASEBOARD_FAB2_LIB.BASEBOARD_FAB2(SCH_1):M_E_DQS_DP(5)
 266 M_E_DQS_DN<6>  DQS6N @BASEBOARD_FAB2_LIB.BASEBOARD_FAB2(SCH_1):M_E_DQS_DN(6)
 267 M_E_DQS_DP<6>  DQS6P @BASEBOARD_FAB2_LIB.BASEBOARD_FAB2(SCH_1):M_E_DQS_DP(6)
 277 M_E_DQS_DN<7>  DQS7N @BASEBOARD_FAB2_LIB.BASEBOARD_FAB2(SCH_1):M_E_DQS_DN(7)
 278 M_E_DQS_DP<7>  DQS7P @BASEBOARD_FAB2_LIB.BASEBOARD_FAB2(SCH_1):M_E_DQS_DP(7)
 196 M_E_DQS_DN<8>  DQS8N @BASEBOARD_FAB2_LIB.BASEBOARD_FAB2(SCH_1):M_E_DQS_DN(8)
 197 M_E_DQS_DP<8>  DQS8P @BASEBOARD_FAB2_LIB.BASEBOARD_FAB2(SCH_1):M_E_DQS_DP(8)
   8 M_E_DQS_DN<9>  DQS9N @BASEBOARD_FAB2_LIB.BASEBOARD_FAB2(SCH_1):M_E_DQS_DN(9)
   7 M_E_DQS_DP<9>  DQS9P @BASEBOARD_FAB2_LIB.BASEBOARD_FAB2(SCH_1):M_E_DQS_DP(9)

SCONN288_H44441004_PIP-SCONN,HA  I111  J4A2
  79 M_E_MA<0>     A0 @BASEBOARD_FAB2_LIB.BASEBOARD_FAB2(SCH_1):M_E_MA(0)
  72 M_E_MA<1>     A1 @BASEBOARD_FAB2_LIB.BASEBOARD_FAB2(SCH_1):M_E_MA(1)
 225 M_E_MA<10>    A10 @BASEBOARD_FAB2_LIB.BASEBOARD_FAB2(SCH_1):M_E_MA(10)
 210 M_E_MA<11>    A11 @BASEBOARD_FAB2_LIB.BASEBOARD_FAB2(SCH_1):M_E_MA(11)
  65 M_E_MA<12>    A12 @BASEBOARD_FAB2_LIB.BASEBOARD_FAB2(SCH_1):M_E_MA(12)
 232 M_E_MA<13>    A13 @BASEBOARD_FAB2_LIB.BASEBOARD_FAB2(SCH_1):M_E_MA(13)
 228 M_E_MA<14> A14_WE_N @BASEBOARD_FAB2_LIB.BASEBOARD_FAB2(SCH_1):M_E_MA(14)
  86 M_E_MA<15> A15_CAS_N @BASEBOARD_FAB2_LIB.BASEBOARD_FAB2(SCH_1):M_E_MA(15)
  82 M_E_MA<16> A16_RAS_N @BASEBOARD_FAB2_LIB.BASEBOARD_FAB2(SCH_1):M_E_MA(16)
 234 M_E_MA<17>    A17 @BASEBOARD_FAB2_LIB.BASEBOARD_FAB2(SCH_1):M_E_MA(17)
 216 M_E_MA<2>     A2 @BASEBOARD_FAB2_LIB.BASEBOARD_FAB2(SCH_1):M_E_MA(2)
  71 M_E_MA<3>     A3 @BASEBOARD_FAB2_LIB.BASEBOARD_FAB2(SCH_1):M_E_MA(3)
 214 M_E_MA<4>     A4 @BASEBOARD_FAB2_LIB.BASEBOARD_FAB2(SCH_1):M_E_MA(4)
 213 M_E_MA<5>     A5 @BASEBOARD_FAB2_LIB.BASEBOARD_FAB2(SCH_1):M_E_MA(5)
  69 M_E_MA<6>     A6 @BASEBOARD_FAB2_LIB.BASEBOARD_FAB2(SCH_1):M_E_MA(6)
 211 M_E_MA<7>     A7 @BASEBOARD_FAB2_LIB.BASEBOARD_FAB2(SCH_1):M_E_MA(7)
  68 M_E_MA<8>     A8 @BASEBOARD_FAB2_LIB.BASEBOARD_FAB2(SCH_1):M_E_MA(8)
  66 M_E_MA<9>     A9 @BASEBOARD_FAB2_LIB.BASEBOARD_FAB2(SCH_1):M_E_MA(9)
  62 M_E_ACT_N  ACT_N @BASEBOARD_FAB2_LIB.BASEBOARD_FAB2(SCH_1):M_E_ACT_N
 208 M_E_ALERT_N ALERT_N @BASEBOARD_FAB2_LIB.BASEBOARD_FAB2(SCH_1):M_E_ALERT_N
 224 M_E_BA<1>  BA<1> @BASEBOARD_FAB2_LIB.BASEBOARD_FAB2(SCH_1):M_E_BA(1)
  81 M_E_BA<0>  BA<0> @BASEBOARD_FAB2_LIB.BASEBOARD_FAB2(SCH_1):M_E_BA(0)
 207 M_E_BG<1>  BG<1> @BASEBOARD_FAB2_LIB.BASEBOARD_FAB2(SCH_1):M_E_BG(1)
  63 M_E_BG<0>  BG<0> @BASEBOARD_FAB2_LIB.BASEBOARD_FAB2(SCH_1):M_E_BG(0)
 235 M_E_C<2>   C<2> @BASEBOARD_FAB2_LIB.BASEBOARD_FAB2(SCH_1):M_E_C(2)
 199 M_E_ECC<6>  CB<7> @BASEBOARD_FAB2_LIB.BASEBOARD_FAB2(SCH_1):M_E_ECC(6)
  54 M_E_ECC<7>  CB<6> @BASEBOARD_FAB2_LIB.BASEBOARD_FAB2(SCH_1):M_E_ECC(7)
 192 M_E_ECC<4>  CB<5> @BASEBOARD_FAB2_LIB.BASEBOARD_FAB2(SCH_1):M_E_ECC(4)
  47 M_E_ECC<5>  CB<4> @BASEBOARD_FAB2_LIB.BASEBOARD_FAB2(SCH_1):M_E_ECC(5)
 201 M_E_ECC<2>  CB<3> @BASEBOARD_FAB2_LIB.BASEBOARD_FAB2(SCH_1):M_E_ECC(2)
  56 M_E_ECC<3>  CB<2> @BASEBOARD_FAB2_LIB.BASEBOARD_FAB2(SCH_1):M_E_ECC(3)
 194 M_E_ECC<0>  CB<1> @BASEBOARD_FAB2_LIB.BASEBOARD_FAB2(SCH_1):M_E_ECC(0)
  49 M_E_ECC<1>  CB<0> @BASEBOARD_FAB2_LIB.BASEBOARD_FAB2(SCH_1):M_E_ECC(1)
  75 M_E_CLK_DN<0>   CK0N @BASEBOARD_FAB2_LIB.BASEBOARD_FAB2(SCH_1):M_E_CLK_DN(0)
  74 M_E_CLK_DP<0>   CK0P @BASEBOARD_FAB2_LIB.BASEBOARD_FAB2(SCH_1):M_E_CLK_DP(0)
 219 M_E_CLK_DN<1>   CK1N @BASEBOARD_FAB2_LIB.BASEBOARD_FAB2(SCH_1):M_E_CLK_DN(1)
 218 M_E_CLK_DP<1>   CK1P @BASEBOARD_FAB2_LIB.BASEBOARD_FAB2(SCH_1):M_E_CLK_DP(1)
 203 M_E_CKE<1> CKE<1> @BASEBOARD_FAB2_LIB.BASEBOARD_FAB2(SCH_1):M_E_CKE(1)
  60 M_E_CKE<0> CKE<0> @BASEBOARD_FAB2_LIB.BASEBOARD_FAB2(SCH_1):M_E_CKE(0)
 280 M_E_DQ<62> DQ<63> @BASEBOARD_FAB2_LIB.BASEBOARD_FAB2(SCH_1):M_E_DQ(62)
 135 M_E_DQ<63> DQ<62> @BASEBOARD_FAB2_LIB.BASEBOARD_FAB2(SCH_1):M_E_DQ(63)
 273 M_E_DQ<60> DQ<61> @BASEBOARD_FAB2_LIB.BASEBOARD_FAB2(SCH_1):M_E_DQ(60)
 128 M_E_DQ<61> DQ<60> @BASEBOARD_FAB2_LIB.BASEBOARD_FAB2(SCH_1):M_E_DQ(61)
 282 M_E_DQ<58> DQ<59> @BASEBOARD_FAB2_LIB.BASEBOARD_FAB2(SCH_1):M_E_DQ(58)
 137 M_E_DQ<59> DQ<58> @BASEBOARD_FAB2_LIB.BASEBOARD_FAB2(SCH_1):M_E_DQ(59)
 275 M_E_DQ<56> DQ<57> @BASEBOARD_FAB2_LIB.BASEBOARD_FAB2(SCH_1):M_E_DQ(56)
 130 M_E_DQ<57> DQ<56> @BASEBOARD_FAB2_LIB.BASEBOARD_FAB2(SCH_1):M_E_DQ(57)
 269 M_E_DQ<54> DQ<55> @BASEBOARD_FAB2_LIB.BASEBOARD_FAB2(SCH_1):M_E_DQ(54)
 124 M_E_DQ<55> DQ<54> @BASEBOARD_FAB2_LIB.BASEBOARD_FAB2(SCH_1):M_E_DQ(55)
 262 M_E_DQ<52> DQ<53> @BASEBOARD_FAB2_LIB.BASEBOARD_FAB2(SCH_1):M_E_DQ(52)
 117 M_E_DQ<53> DQ<52> @BASEBOARD_FAB2_LIB.BASEBOARD_FAB2(SCH_1):M_E_DQ(53)
 271 M_E_DQ<50> DQ<51> @BASEBOARD_FAB2_LIB.BASEBOARD_FAB2(SCH_1):M_E_DQ(50)
 126 M_E_DQ<51> DQ<50> @BASEBOARD_FAB2_LIB.BASEBOARD_FAB2(SCH_1):M_E_DQ(51)
 264 M_E_DQ<48> DQ<49> @BASEBOARD_FAB2_LIB.BASEBOARD_FAB2(SCH_1):M_E_DQ(48)
 119 M_E_DQ<49> DQ<48> @BASEBOARD_FAB2_LIB.BASEBOARD_FAB2(SCH_1):M_E_DQ(49)
 258 M_E_DQ<46> DQ<47> @BASEBOARD_FAB2_LIB.BASEBOARD_FAB2(SCH_1):M_E_DQ(46)
 113 M_E_DQ<47> DQ<46> @BASEBOARD_FAB2_LIB.BASEBOARD_FAB2(SCH_1):M_E_DQ(47)
 251 M_E_DQ<44> DQ<45> @BASEBOARD_FAB2_LIB.BASEBOARD_FAB2(SCH_1):M_E_DQ(44)
 106 M_E_DQ<45> DQ<44> @BASEBOARD_FAB2_LIB.BASEBOARD_FAB2(SCH_1):M_E_DQ(45)
 260 M_E_DQ<42> DQ<43> @BASEBOARD_FAB2_LIB.BASEBOARD_FAB2(SCH_1):M_E_DQ(42)
 115 M_E_DQ<43> DQ<42> @BASEBOARD_FAB2_LIB.BASEBOARD_FAB2(SCH_1):M_E_DQ(43)
 253 M_E_DQ<40> DQ<41> @BASEBOARD_FAB2_LIB.BASEBOARD_FAB2(SCH_1):M_E_DQ(40)
 108 M_E_DQ<41> DQ<40> @BASEBOARD_FAB2_LIB.BASEBOARD_FAB2(SCH_1):M_E_DQ(41)
 247 M_E_DQ<38> DQ<39> @BASEBOARD_FAB2_LIB.BASEBOARD_FAB2(SCH_1):M_E_DQ(38)
 102 M_E_DQ<39> DQ<38> @BASEBOARD_FAB2_LIB.BASEBOARD_FAB2(SCH_1):M_E_DQ(39)
 240 M_E_DQ<36> DQ<37> @BASEBOARD_FAB2_LIB.BASEBOARD_FAB2(SCH_1):M_E_DQ(36)
  95 M_E_DQ<37> DQ<36> @BASEBOARD_FAB2_LIB.BASEBOARD_FAB2(SCH_1):M_E_DQ(37)
 249 M_E_DQ<34> DQ<35> @BASEBOARD_FAB2_LIB.BASEBOARD_FAB2(SCH_1):M_E_DQ(34)
 104 M_E_DQ<35> DQ<34> @BASEBOARD_FAB2_LIB.BASEBOARD_FAB2(SCH_1):M_E_DQ(35)
 242 M_E_DQ<32> DQ<33> @BASEBOARD_FAB2_LIB.BASEBOARD_FAB2(SCH_1):M_E_DQ(32)
  97 M_E_DQ<33> DQ<32> @BASEBOARD_FAB2_LIB.BASEBOARD_FAB2(SCH_1):M_E_DQ(33)
 188 M_E_DQ<30> DQ<31> @BASEBOARD_FAB2_LIB.BASEBOARD_FAB2(SCH_1):M_E_DQ(30)
  43 M_E_DQ<31> DQ<30> @BASEBOARD_FAB2_LIB.BASEBOARD_FAB2(SCH_1):M_E_DQ(31)
 181 M_E_DQ<28> DQ<29> @BASEBOARD_FAB2_LIB.BASEBOARD_FAB2(SCH_1):M_E_DQ(28)
  36 M_E_DQ<29> DQ<28> @BASEBOARD_FAB2_LIB.BASEBOARD_FAB2(SCH_1):M_E_DQ(29)
 190 M_E_DQ<26> DQ<27> @BASEBOARD_FAB2_LIB.BASEBOARD_FAB2(SCH_1):M_E_DQ(26)
  45 M_E_DQ<27> DQ<26> @BASEBOARD_FAB2_LIB.BASEBOARD_FAB2(SCH_1):M_E_DQ(27)
 183 M_E_DQ<24> DQ<25> @BASEBOARD_FAB2_LIB.BASEBOARD_FAB2(SCH_1):M_E_DQ(24)
  38 M_E_DQ<25> DQ<24> @BASEBOARD_FAB2_LIB.BASEBOARD_FAB2(SCH_1):M_E_DQ(25)
 177 M_E_DQ<22> DQ<23> @BASEBOARD_FAB2_LIB.BASEBOARD_FAB2(SCH_1):M_E_DQ(22)
  32 M_E_DQ<23> DQ<22> @BASEBOARD_FAB2_LIB.BASEBOARD_FAB2(SCH_1):M_E_DQ(23)
 170 M_E_DQ<20> DQ<21> @BASEBOARD_FAB2_LIB.BASEBOARD_FAB2(SCH_1):M_E_DQ(20)
  25 M_E_DQ<21> DQ<20> @BASEBOARD_FAB2_LIB.BASEBOARD_FAB2(SCH_1):M_E_DQ(21)
 179 M_E_DQ<18> DQ<19> @BASEBOARD_FAB2_LIB.BASEBOARD_FAB2(SCH_1):M_E_DQ(18)
  34 M_E_DQ<19> DQ<18> @BASEBOARD_FAB2_LIB.BASEBOARD_FAB2(SCH_1):M_E_DQ(19)
 172 M_E_DQ<16> DQ<17> @BASEBOARD_FAB2_LIB.BASEBOARD_FAB2(SCH_1):M_E_DQ(16)
  27 M_E_DQ<17> DQ<16> @BASEBOARD_FAB2_LIB.BASEBOARD_FAB2(SCH_1):M_E_DQ(17)
 166 M_E_DQ<14> DQ<15> @BASEBOARD_FAB2_LIB.BASEBOARD_FAB2(SCH_1):M_E_DQ(14)
  21 M_E_DQ<15> DQ<14> @BASEBOARD_FAB2_LIB.BASEBOARD_FAB2(SCH_1):M_E_DQ(15)
 159 M_E_DQ<12> DQ<13> @BASEBOARD_FAB2_LIB.BASEBOARD_FAB2(SCH_1):M_E_DQ(12)
  14 M_E_DQ<13> DQ<12> @BASEBOARD_FAB2_LIB.BASEBOARD_FAB2(SCH_1):M_E_DQ(13)
 168 M_E_DQ<10> DQ<11> @BASEBOARD_FAB2_LIB.BASEBOARD_FAB2(SCH_1):M_E_DQ(10)
  23 M_E_DQ<11> DQ<10> @BASEBOARD_FAB2_LIB.BASEBOARD_FAB2(SCH_1):M_E_DQ(11)
 161 M_E_DQ<8>  DQ<9> @BASEBOARD_FAB2_LIB.BASEBOARD_FAB2(SCH_1):M_E_DQ(8)
  16 M_E_DQ<9>  DQ<8> @BASEBOARD_FAB2_LIB.BASEBOARD_FAB2(SCH_1):M_E_DQ(9)
 155 M_E_DQ<6>  DQ<7> @BASEBOARD_FAB2_LIB.BASEBOARD_FAB2(SCH_1):M_E_DQ(6)
  10 M_E_DQ<7>  DQ<6> @BASEBOARD_FAB2_LIB.BASEBOARD_FAB2(SCH_1):M_E_DQ(7)
 148 M_E_DQ<4>  DQ<5> @BASEBOARD_FAB2_LIB.BASEBOARD_FAB2(SCH_1):M_E_DQ(4)
   3 M_E_DQ<5>  DQ<4> @BASEBOARD_FAB2_LIB.BASEBOARD_FAB2(SCH_1):M_E_DQ(5)
 157 M_E_DQ<2>  DQ<3> @BASEBOARD_FAB2_LIB.BASEBOARD_FAB2(SCH_1):M_E_DQ(2)
  12 M_E_DQ<3>  DQ<2> @BASEBOARD_FAB2_LIB.BASEBOARD_FAB2(SCH_1):M_E_DQ(3)
 150 M_E_DQ<0>  DQ<1> @BASEBOARD_FAB2_LIB.BASEBOARD_FAB2(SCH_1):M_E_DQ(0)
   5 M_E_DQ<1>  DQ<0> @BASEBOARD_FAB2_LIB.BASEBOARD_FAB2(SCH_1):M_E_DQ(1)
  78 FM_DIMM_EVENT_COD_N EVENT_N @BASEBOARD_FAB2_LIB.BASEBOARD_FAB2(SCH_1):FM_DIMM_EVENT_COD_N
  91 M_E_ODT<1> ODT<1> @BASEBOARD_FAB2_LIB.BASEBOARD_FAB2(SCH_1):M_E_ODT(1)
  87 M_E_ODT<0> ODT<0> @BASEBOARD_FAB2_LIB.BASEBOARD_FAB2(SCH_1):M_E_ODT(0)
 222 M_E_PAR    PAR @BASEBOARD_FAB2_LIB.BASEBOARD_FAB2(SCH_1):M_E_PAR
  58 M_DEF_RST_N RESET_N @BASEBOARD_FAB2_LIB.BASEBOARD_FAB2(SCH_1):M_DEF_RST_N
 144 TP_CH_E_DIMM_E0_RFU_2 RFU<2> @BASEBOARD_FAB2_LIB.BASEBOARD_FAB2(SCH_1):TP_CH_E_DIMM_E0_RFU_2
 227 TP_CH_E_DIMM_E0_RFU_1 RFU<1> @BASEBOARD_FAB2_LIB.BASEBOARD_FAB2(SCH_1):TP_CH_E_DIMM_E0_RFU_1
 205 TP_CH_E_DIMM_E0_RFU_0 RFU<0> @BASEBOARD_FAB2_LIB.BASEBOARD_FAB2(SCH_1):TP_CH_E_DIMM_E0_RFU_0
  84 M_E_CS_N<0>   S0_N @BASEBOARD_FAB2_LIB.BASEBOARD_FAB2(SCH_1):M_E_CS_N(0)
  89 M_E_CS_N<1>   S1_N @BASEBOARD_FAB2_LIB.BASEBOARD_FAB2(SCH_1):M_E_CS_N(1)
  93 M_E_CS_N<2> S2_N_C<0> @BASEBOARD_FAB2_LIB.BASEBOARD_FAB2(SCH_1):M_E_CS_N(2)
 237 M_E_CS_N<3> S3_N_C<1> @BASEBOARD_FAB2_LIB.BASEBOARD_FAB2(SCH_1):M_E_CS_N(3)
 238    GND  SA<2> @BASEBOARD_FAB2_LIB.BASEBOARD_FAB2(SCH_1):GND
 140 PVPP_DEF  SA<1> @BASEBOARD_FAB2_LIB.BASEBOARD_FAB2(SCH_1):PVPP_DEF
 139    GND  SA<0> @BASEBOARD_FAB2_LIB.BASEBOARD_FAB2(SCH_1):GND
 230 FM_ADR_COMPLETE_DEF_N SAVE_N_NC @BASEBOARD_FAB2_LIB.BASEBOARD_FAB2(SCH_1):FM_ADR_COMPLETE_DEF_N
 141 SMB_DDR_DEF_VPP_SCL    SCL @BASEBOARD_FAB2_LIB.BASEBOARD_FAB2(SCH_1):SMB_DDR_DEF_VPP_SCL
 285 SMB_DDR_DEF_VPP_SDA    SDA @BASEBOARD_FAB2_LIB.BASEBOARD_FAB2(SCH_1):SMB_DDR_DEF_VPP_SDA
 284 PVPP_DEF VDDSPD @BASEBOARD_FAB2_LIB.BASEBOARD_FAB2(SCH_1):PVPP_DEF
 146 M_E_VREF VREFCA @BASEBOARD_FAB2_LIB.BASEBOARD_FAB2(SCH_1):M_E_VREF

SCONN288_H44441004_PIP-SCONN,HA  I167  J4A2
   1 P12V_NVDIMM_DEF 12V<1> @BASEBOARD_FAB2_LIB.BASEBOARD_FAB2(SCH_1):P12V_NVDIMM_DEF
 145 P12V_NVDIMM_DEF 12V<0> @BASEBOARD_FAB2_LIB.BASEBOARD_FAB2(SCH_1):P12V_NVDIMM_DEF
  59 PVDDQ_DEF VDD<25> @BASEBOARD_FAB2_LIB.BASEBOARD_FAB2(SCH_1):PVDDQ_DEF
  61 PVDDQ_DEF VDD<24> @BASEBOARD_FAB2_LIB.BASEBOARD_FAB2(SCH_1):PVDDQ_DEF
  64 PVDDQ_DEF VDD<23> @BASEBOARD_FAB2_LIB.BASEBOARD_FAB2(SCH_1):PVDDQ_DEF
  67 PVDDQ_DEF VDD<22> @BASEBOARD_FAB2_LIB.BASEBOARD_FAB2(SCH_1):PVDDQ_DEF
  70 PVDDQ_DEF VDD<21> @BASEBOARD_FAB2_LIB.BASEBOARD_FAB2(SCH_1):PVDDQ_DEF
  73 PVDDQ_DEF VDD<20> @BASEBOARD_FAB2_LIB.BASEBOARD_FAB2(SCH_1):PVDDQ_DEF
  76 PVDDQ_DEF VDD<19> @BASEBOARD_FAB2_LIB.BASEBOARD_FAB2(SCH_1):PVDDQ_DEF
  80 PVDDQ_DEF VDD<18> @BASEBOARD_FAB2_LIB.BASEBOARD_FAB2(SCH_1):PVDDQ_DEF
  83 PVDDQ_DEF VDD<17> @BASEBOARD_FAB2_LIB.BASEBOARD_FAB2(SCH_1):PVDDQ_DEF
  85 PVDDQ_DEF VDD<16> @BASEBOARD_FAB2_LIB.BASEBOARD_FAB2(SCH_1):PVDDQ_DEF
  88 PVDDQ_DEF VDD<15> @BASEBOARD_FAB2_LIB.BASEBOARD_FAB2(SCH_1):PVDDQ_DEF
  90 PVDDQ_DEF VDD<14> @BASEBOARD_FAB2_LIB.BASEBOARD_FAB2(SCH_1):PVDDQ_DEF
  92 PVDDQ_DEF VDD<13> @BASEBOARD_FAB2_LIB.BASEBOARD_FAB2(SCH_1):PVDDQ_DEF
 204 PVDDQ_DEF VDD<12> @BASEBOARD_FAB2_LIB.BASEBOARD_FAB2(SCH_1):PVDDQ_DEF
 206 PVDDQ_DEF VDD<11> @BASEBOARD_FAB2_LIB.BASEBOARD_FAB2(SCH_1):PVDDQ_DEF
 209 PVDDQ_DEF VDD<10> @BASEBOARD_FAB2_LIB.BASEBOARD_FAB2(SCH_1):PVDDQ_DEF
 212 PVDDQ_DEF VDD<9> @BASEBOARD_FAB2_LIB.BASEBOARD_FAB2(SCH_1):PVDDQ_DEF
 215 PVDDQ_DEF VDD<8> @BASEBOARD_FAB2_LIB.BASEBOARD_FAB2(SCH_1):PVDDQ_DEF
 217 PVDDQ_DEF VDD<7> @BASEBOARD_FAB2_LIB.BASEBOARD_FAB2(SCH_1):PVDDQ_DEF
 220 PVDDQ_DEF VDD<6> @BASEBOARD_FAB2_LIB.BASEBOARD_FAB2(SCH_1):PVDDQ_DEF
 223 PVDDQ_DEF VDD<5> @BASEBOARD_FAB2_LIB.BASEBOARD_FAB2(SCH_1):PVDDQ_DEF
 226 PVDDQ_DEF VDD<4> @BASEBOARD_FAB2_LIB.BASEBOARD_FAB2(SCH_1):PVDDQ_DEF
 229 PVDDQ_DEF VDD<3> @BASEBOARD_FAB2_LIB.BASEBOARD_FAB2(SCH_1):PVDDQ_DEF
 231 PVDDQ_DEF VDD<2> @BASEBOARD_FAB2_LIB.BASEBOARD_FAB2(SCH_1):PVDDQ_DEF
 233 PVDDQ_DEF VDD<1> @BASEBOARD_FAB2_LIB.BASEBOARD_FAB2(SCH_1):PVDDQ_DEF
 236 PVDDQ_DEF VDD<0> @BASEBOARD_FAB2_LIB.BASEBOARD_FAB2(SCH_1):PVDDQ_DEF
 142 PVPP_DEF VPP<4> @BASEBOARD_FAB2_LIB.BASEBOARD_FAB2(SCH_1):PVPP_DEF
 143 PVPP_DEF VPP<3> @BASEBOARD_FAB2_LIB.BASEBOARD_FAB2(SCH_1):PVPP_DEF
 288 PVPP_DEF VPP<2> @BASEBOARD_FAB2_LIB.BASEBOARD_FAB2(SCH_1):PVPP_DEF
 286 PVPP_DEF VPP<1> @BASEBOARD_FAB2_LIB.BASEBOARD_FAB2(SCH_1):PVPP_DEF
 287 PVPP_DEF VPP<0> @BASEBOARD_FAB2_LIB.BASEBOARD_FAB2(SCH_1):PVPP_DEF
  77 PVTT_DEF VTT<1> @BASEBOARD_FAB2_LIB.BASEBOARD_FAB2(SCH_1):PVTT_DEF
 221 PVTT_DEF VTT<0> @BASEBOARD_FAB2_LIB.BASEBOARD_FAB2(SCH_1):PVTT_DEF

CAP_A_0402V-0.01UF,25V,10%,X7RA  I175  C6L6
   1 M_E_VREF      A @BASEBOARD_FAB2_LIB.BASEBOARD_FAB2(SCH_1):M_E_VREF
   2    GND      B @BASEBOARD_FAB2_LIB.BASEBOARD_FAB2(SCH_1):GND


DRAWING: @BASEBOARD_FAB2_LIB.BASEBOARD_FAB2(SCH_1):PAGE52 

CAP_A_0402V-0.01UF,25V,10%,X7RA  I3  C4A18
   1 M_E_VREF      A @BASEBOARD_FAB2_LIB.BASEBOARD_FAB2(SCH_1):M_E_VREF
   2    GND      B @BASEBOARD_FAB2_LIB.BASEBOARD_FAB2(SCH_1):GND

SCONN288_H44441003_PIP-SCONN,HA  I12  J6L2
  79 M_E_MA<0>     A0 @BASEBOARD_FAB2_LIB.BASEBOARD_FAB2(SCH_1):M_E_MA(0)
  72 M_E_MA<1>     A1 @BASEBOARD_FAB2_LIB.BASEBOARD_FAB2(SCH_1):M_E_MA(1)
 225 M_E_MA<10>    A10 @BASEBOARD_FAB2_LIB.BASEBOARD_FAB2(SCH_1):M_E_MA(10)
 210 M_E_MA<11>    A11 @BASEBOARD_FAB2_LIB.BASEBOARD_FAB2(SCH_1):M_E_MA(11)
  65 M_E_MA<12>    A12 @BASEBOARD_FAB2_LIB.BASEBOARD_FAB2(SCH_1):M_E_MA(12)
 232 M_E_MA<13>    A13 @BASEBOARD_FAB2_LIB.BASEBOARD_FAB2(SCH_1):M_E_MA(13)
 228 M_E_MA<14> A14_WE_N @BASEBOARD_FAB2_LIB.BASEBOARD_FAB2(SCH_1):M_E_MA(14)
  86 M_E_MA<15> A15_CAS_N @BASEBOARD_FAB2_LIB.BASEBOARD_FAB2(SCH_1):M_E_MA(15)
  82 M_E_MA<16> A16_RAS_N @BASEBOARD_FAB2_LIB.BASEBOARD_FAB2(SCH_1):M_E_MA(16)
 234 M_E_MA<17>    A17 @BASEBOARD_FAB2_LIB.BASEBOARD_FAB2(SCH_1):M_E_MA(17)
 216 M_E_MA<2>     A2 @BASEBOARD_FAB2_LIB.BASEBOARD_FAB2(SCH_1):M_E_MA(2)
  71 M_E_MA<3>     A3 @BASEBOARD_FAB2_LIB.BASEBOARD_FAB2(SCH_1):M_E_MA(3)
 214 M_E_MA<4>     A4 @BASEBOARD_FAB2_LIB.BASEBOARD_FAB2(SCH_1):M_E_MA(4)
 213 M_E_MA<5>     A5 @BASEBOARD_FAB2_LIB.BASEBOARD_FAB2(SCH_1):M_E_MA(5)
  69 M_E_MA<6>     A6 @BASEBOARD_FAB2_LIB.BASEBOARD_FAB2(SCH_1):M_E_MA(6)
 211 M_E_MA<7>     A7 @BASEBOARD_FAB2_LIB.BASEBOARD_FAB2(SCH_1):M_E_MA(7)
  68 M_E_MA<8>     A8 @BASEBOARD_FAB2_LIB.BASEBOARD_FAB2(SCH_1):M_E_MA(8)
  66 M_E_MA<9>     A9 @BASEBOARD_FAB2_LIB.BASEBOARD_FAB2(SCH_1):M_E_MA(9)
  62 M_E_ACT_N  ACT_N @BASEBOARD_FAB2_LIB.BASEBOARD_FAB2(SCH_1):M_E_ACT_N
 208 M_E_ALERT_N ALERT_N @BASEBOARD_FAB2_LIB.BASEBOARD_FAB2(SCH_1):M_E_ALERT_N
 224 M_E_BA<1>  BA<1> @BASEBOARD_FAB2_LIB.BASEBOARD_FAB2(SCH_1):M_E_BA(1)
  81 M_E_BA<0>  BA<0> @BASEBOARD_FAB2_LIB.BASEBOARD_FAB2(SCH_1):M_E_BA(0)
 207 M_E_BG<1>  BG<1> @BASEBOARD_FAB2_LIB.BASEBOARD_FAB2(SCH_1):M_E_BG(1)
  63 M_E_BG<0>  BG<0> @BASEBOARD_FAB2_LIB.BASEBOARD_FAB2(SCH_1):M_E_BG(0)
 235 M_E_C<2>   C<2> @BASEBOARD_FAB2_LIB.BASEBOARD_FAB2(SCH_1):M_E_C(2)
 199 M_E_ECC<7>  CB<7> @BASEBOARD_FAB2_LIB.BASEBOARD_FAB2(SCH_1):M_E_ECC(7)
  54 M_E_ECC<6>  CB<6> @BASEBOARD_FAB2_LIB.BASEBOARD_FAB2(SCH_1):M_E_ECC(6)
 192 M_E_ECC<5>  CB<5> @BASEBOARD_FAB2_LIB.BASEBOARD_FAB2(SCH_1):M_E_ECC(5)
  47 M_E_ECC<4>  CB<4> @BASEBOARD_FAB2_LIB.BASEBOARD_FAB2(SCH_1):M_E_ECC(4)
 201 M_E_ECC<3>  CB<3> @BASEBOARD_FAB2_LIB.BASEBOARD_FAB2(SCH_1):M_E_ECC(3)
  56 M_E_ECC<2>  CB<2> @BASEBOARD_FAB2_LIB.BASEBOARD_FAB2(SCH_1):M_E_ECC(2)
 194 M_E_ECC<1>  CB<1> @BASEBOARD_FAB2_LIB.BASEBOARD_FAB2(SCH_1):M_E_ECC(1)
  49 M_E_ECC<0>  CB<0> @BASEBOARD_FAB2_LIB.BASEBOARD_FAB2(SCH_1):M_E_ECC(0)
  75 M_E_CLK_DN<2>   CK0N @BASEBOARD_FAB2_LIB.BASEBOARD_FAB2(SCH_1):M_E_CLK_DN(2)
  74 M_E_CLK_DP<2>   CK0P @BASEBOARD_FAB2_LIB.BASEBOARD_FAB2(SCH_1):M_E_CLK_DP(2)
 219 M_E_CLK_DN<3>   CK1N @BASEBOARD_FAB2_LIB.BASEBOARD_FAB2(SCH_1):M_E_CLK_DN(3)
 218 M_E_CLK_DP<3>   CK1P @BASEBOARD_FAB2_LIB.BASEBOARD_FAB2(SCH_1):M_E_CLK_DP(3)
 203 M_E_CKE<3> CKE<1> @BASEBOARD_FAB2_LIB.BASEBOARD_FAB2(SCH_1):M_E_CKE(3)
  60 M_E_CKE<2> CKE<0> @BASEBOARD_FAB2_LIB.BASEBOARD_FAB2(SCH_1):M_E_CKE(2)
 280 M_E_DQ<63> DQ<63> @BASEBOARD_FAB2_LIB.BASEBOARD_FAB2(SCH_1):M_E_DQ(63)
 135 M_E_DQ<62> DQ<62> @BASEBOARD_FAB2_LIB.BASEBOARD_FAB2(SCH_1):M_E_DQ(62)
 273 M_E_DQ<61> DQ<61> @BASEBOARD_FAB2_LIB.BASEBOARD_FAB2(SCH_1):M_E_DQ(61)
 128 M_E_DQ<60> DQ<60> @BASEBOARD_FAB2_LIB.BASEBOARD_FAB2(SCH_1):M_E_DQ(60)
 282 M_E_DQ<59> DQ<59> @BASEBOARD_FAB2_LIB.BASEBOARD_FAB2(SCH_1):M_E_DQ(59)
 137 M_E_DQ<58> DQ<58> @BASEBOARD_FAB2_LIB.BASEBOARD_FAB2(SCH_1):M_E_DQ(58)
 275 M_E_DQ<57> DQ<57> @BASEBOARD_FAB2_LIB.BASEBOARD_FAB2(SCH_1):M_E_DQ(57)
 130 M_E_DQ<56> DQ<56> @BASEBOARD_FAB2_LIB.BASEBOARD_FAB2(SCH_1):M_E_DQ(56)
 269 M_E_DQ<55> DQ<55> @BASEBOARD_FAB2_LIB.BASEBOARD_FAB2(SCH_1):M_E_DQ(55)
 124 M_E_DQ<54> DQ<54> @BASEBOARD_FAB2_LIB.BASEBOARD_FAB2(SCH_1):M_E_DQ(54)
 262 M_E_DQ<53> DQ<53> @BASEBOARD_FAB2_LIB.BASEBOARD_FAB2(SCH_1):M_E_DQ(53)
 117 M_E_DQ<52> DQ<52> @BASEBOARD_FAB2_LIB.BASEBOARD_FAB2(SCH_1):M_E_DQ(52)
 271 M_E_DQ<51> DQ<51> @BASEBOARD_FAB2_LIB.BASEBOARD_FAB2(SCH_1):M_E_DQ(51)
 126 M_E_DQ<50> DQ<50> @BASEBOARD_FAB2_LIB.BASEBOARD_FAB2(SCH_1):M_E_DQ(50)
 264 M_E_DQ<49> DQ<49> @BASEBOARD_FAB2_LIB.BASEBOARD_FAB2(SCH_1):M_E_DQ(49)
 119 M_E_DQ<48> DQ<48> @BASEBOARD_FAB2_LIB.BASEBOARD_FAB2(SCH_1):M_E_DQ(48)
 258 M_E_DQ<47> DQ<47> @BASEBOARD_FAB2_LIB.BASEBOARD_FAB2(SCH_1):M_E_DQ(47)
 113 M_E_DQ<46> DQ<46> @BASEBOARD_FAB2_LIB.BASEBOARD_FAB2(SCH_1):M_E_DQ(46)
 251 M_E_DQ<45> DQ<45> @BASEBOARD_FAB2_LIB.BASEBOARD_FAB2(SCH_1):M_E_DQ(45)
 106 M_E_DQ<44> DQ<44> @BASEBOARD_FAB2_LIB.BASEBOARD_FAB2(SCH_1):M_E_DQ(44)
 260 M_E_DQ<43> DQ<43> @BASEBOARD_FAB2_LIB.BASEBOARD_FAB2(SCH_1):M_E_DQ(43)
 115 M_E_DQ<42> DQ<42> @BASEBOARD_FAB2_LIB.BASEBOARD_FAB2(SCH_1):M_E_DQ(42)
 253 M_E_DQ<41> DQ<41> @BASEBOARD_FAB2_LIB.BASEBOARD_FAB2(SCH_1):M_E_DQ(41)
 108 M_E_DQ<40> DQ<40> @BASEBOARD_FAB2_LIB.BASEBOARD_FAB2(SCH_1):M_E_DQ(40)
 247 M_E_DQ<39> DQ<39> @BASEBOARD_FAB2_LIB.BASEBOARD_FAB2(SCH_1):M_E_DQ(39)
 102 M_E_DQ<38> DQ<38> @BASEBOARD_FAB2_LIB.BASEBOARD_FAB2(SCH_1):M_E_DQ(38)
 240 M_E_DQ<37> DQ<37> @BASEBOARD_FAB2_LIB.BASEBOARD_FAB2(SCH_1):M_E_DQ(37)
  95 M_E_DQ<36> DQ<36> @BASEBOARD_FAB2_LIB.BASEBOARD_FAB2(SCH_1):M_E_DQ(36)
 249 M_E_DQ<35> DQ<35> @BASEBOARD_FAB2_LIB.BASEBOARD_FAB2(SCH_1):M_E_DQ(35)
 104 M_E_DQ<34> DQ<34> @BASEBOARD_FAB2_LIB.BASEBOARD_FAB2(SCH_1):M_E_DQ(34)
 242 M_E_DQ<33> DQ<33> @BASEBOARD_FAB2_LIB.BASEBOARD_FAB2(SCH_1):M_E_DQ(33)
  97 M_E_DQ<32> DQ<32> @BASEBOARD_FAB2_LIB.BASEBOARD_FAB2(SCH_1):M_E_DQ(32)
 188 M_E_DQ<31> DQ<31> @BASEBOARD_FAB2_LIB.BASEBOARD_FAB2(SCH_1):M_E_DQ(31)
  43 M_E_DQ<30> DQ<30> @BASEBOARD_FAB2_LIB.BASEBOARD_FAB2(SCH_1):M_E_DQ(30)
 181 M_E_DQ<29> DQ<29> @BASEBOARD_FAB2_LIB.BASEBOARD_FAB2(SCH_1):M_E_DQ(29)
  36 M_E_DQ<28> DQ<28> @BASEBOARD_FAB2_LIB.BASEBOARD_FAB2(SCH_1):M_E_DQ(28)
 190 M_E_DQ<27> DQ<27> @BASEBOARD_FAB2_LIB.BASEBOARD_FAB2(SCH_1):M_E_DQ(27)
  45 M_E_DQ<26> DQ<26> @BASEBOARD_FAB2_LIB.BASEBOARD_FAB2(SCH_1):M_E_DQ(26)
 183 M_E_DQ<25> DQ<25> @BASEBOARD_FAB2_LIB.BASEBOARD_FAB2(SCH_1):M_E_DQ(25)
  38 M_E_DQ<24> DQ<24> @BASEBOARD_FAB2_LIB.BASEBOARD_FAB2(SCH_1):M_E_DQ(24)
 177 M_E_DQ<23> DQ<23> @BASEBOARD_FAB2_LIB.BASEBOARD_FAB2(SCH_1):M_E_DQ(23)
  32 M_E_DQ<22> DQ<22> @BASEBOARD_FAB2_LIB.BASEBOARD_FAB2(SCH_1):M_E_DQ(22)
 170 M_E_DQ<21> DQ<21> @BASEBOARD_FAB2_LIB.BASEBOARD_FAB2(SCH_1):M_E_DQ(21)
  25 M_E_DQ<20> DQ<20> @BASEBOARD_FAB2_LIB.BASEBOARD_FAB2(SCH_1):M_E_DQ(20)
 179 M_E_DQ<19> DQ<19> @BASEBOARD_FAB2_LIB.BASEBOARD_FAB2(SCH_1):M_E_DQ(19)
  34 M_E_DQ<18> DQ<18> @BASEBOARD_FAB2_LIB.BASEBOARD_FAB2(SCH_1):M_E_DQ(18)
 172 M_E_DQ<17> DQ<17> @BASEBOARD_FAB2_LIB.BASEBOARD_FAB2(SCH_1):M_E_DQ(17)
  27 M_E_DQ<16> DQ<16> @BASEBOARD_FAB2_LIB.BASEBOARD_FAB2(SCH_1):M_E_DQ(16)
 166 M_E_DQ<15> DQ<15> @BASEBOARD_FAB2_LIB.BASEBOARD_FAB2(SCH_1):M_E_DQ(15)
  21 M_E_DQ<14> DQ<14> @BASEBOARD_FAB2_LIB.BASEBOARD_FAB2(SCH_1):M_E_DQ(14)
 159 M_E_DQ<13> DQ<13> @BASEBOARD_FAB2_LIB.BASEBOARD_FAB2(SCH_1):M_E_DQ(13)
  14 M_E_DQ<12> DQ<12> @BASEBOARD_FAB2_LIB.BASEBOARD_FAB2(SCH_1):M_E_DQ(12)
 168 M_E_DQ<11> DQ<11> @BASEBOARD_FAB2_LIB.BASEBOARD_FAB2(SCH_1):M_E_DQ(11)
  23 M_E_DQ<10> DQ<10> @BASEBOARD_FAB2_LIB.BASEBOARD_FAB2(SCH_1):M_E_DQ(10)
 161 M_E_DQ<9>  DQ<9> @BASEBOARD_FAB2_LIB.BASEBOARD_FAB2(SCH_1):M_E_DQ(9)
  16 M_E_DQ<8>  DQ<8> @BASEBOARD_FAB2_LIB.BASEBOARD_FAB2(SCH_1):M_E_DQ(8)
 155 M_E_DQ<7>  DQ<7> @BASEBOARD_FAB2_LIB.BASEBOARD_FAB2(SCH_1):M_E_DQ(7)
  10 M_E_DQ<6>  DQ<6> @BASEBOARD_FAB2_LIB.BASEBOARD_FAB2(SCH_1):M_E_DQ(6)
 148 M_E_DQ<5>  DQ<5> @BASEBOARD_FAB2_LIB.BASEBOARD_FAB2(SCH_1):M_E_DQ(5)
   3 M_E_DQ<4>  DQ<4> @BASEBOARD_FAB2_LIB.BASEBOARD_FAB2(SCH_1):M_E_DQ(4)
 157 M_E_DQ<3>  DQ<3> @BASEBOARD_FAB2_LIB.BASEBOARD_FAB2(SCH_1):M_E_DQ(3)
  12 M_E_DQ<2>  DQ<2> @BASEBOARD_FAB2_LIB.BASEBOARD_FAB2(SCH_1):M_E_DQ(2)
 150 M_E_DQ<1>  DQ<1> @BASEBOARD_FAB2_LIB.BASEBOARD_FAB2(SCH_1):M_E_DQ(1)
   5 M_E_DQ<0>  DQ<0> @BASEBOARD_FAB2_LIB.BASEBOARD_FAB2(SCH_1):M_E_DQ(0)
  78 FM_DIMM_EVENT_COD_N EVENT_N @BASEBOARD_FAB2_LIB.BASEBOARD_FAB2(SCH_1):FM_DIMM_EVENT_COD_N
  91 M_E_ODT<3> ODT<1> @BASEBOARD_FAB2_LIB.BASEBOARD_FAB2(SCH_1):M_E_ODT(3)
  87 M_E_ODT<2> ODT<0> @BASEBOARD_FAB2_LIB.BASEBOARD_FAB2(SCH_1):M_E_ODT(2)
 222 M_E_PAR    PAR @BASEBOARD_FAB2_LIB.BASEBOARD_FAB2(SCH_1):M_E_PAR
  58 M_DEF_RST_N RESET_N @BASEBOARD_FAB2_LIB.BASEBOARD_FAB2(SCH_1):M_DEF_RST_N
 144 TP_CH_E_DIMM_E1_RFU_2 RFU<2> @BASEBOARD_FAB2_LIB.BASEBOARD_FAB2(SCH_1):TP_CH_E_DIMM_E1_RFU_2
 227 TP_CH_E_DIMM_E1_RFU_1 RFU<1> @BASEBOARD_FAB2_LIB.BASEBOARD_FAB2(SCH_1):TP_CH_E_DIMM_E1_RFU_1
 205 TP_CH_E_DIMM_E1_RFU_0 RFU<0> @BASEBOARD_FAB2_LIB.BASEBOARD_FAB2(SCH_1):TP_CH_E_DIMM_E1_RFU_0
  84 M_E_CS_N<4>   S0_N @BASEBOARD_FAB2_LIB.BASEBOARD_FAB2(SCH_1):M_E_CS_N(4)
  89 M_E_CS_N<5>   S1_N @BASEBOARD_FAB2_LIB.BASEBOARD_FAB2(SCH_1):M_E_CS_N(5)
  93 M_E_CS_N<6> S2_N_C<0> @BASEBOARD_FAB2_LIB.BASEBOARD_FAB2(SCH_1):M_E_CS_N(6)
 237 M_E_CS_N<7> S3_N_C<1> @BASEBOARD_FAB2_LIB.BASEBOARD_FAB2(SCH_1):M_E_CS_N(7)
 238    GND  SA<2> @BASEBOARD_FAB2_LIB.BASEBOARD_FAB2(SCH_1):GND
 140 PVPP_DEF  SA<1> @BASEBOARD_FAB2_LIB.BASEBOARD_FAB2(SCH_1):PVPP_DEF
 139 PVPP_DEF  SA<0> @BASEBOARD_FAB2_LIB.BASEBOARD_FAB2(SCH_1):PVPP_DEF
 230 FM_ADR_COMPLETE_DEF_N SAVE_N_NC @BASEBOARD_FAB2_LIB.BASEBOARD_FAB2(SCH_1):FM_ADR_COMPLETE_DEF_N
 141 SMB_DDR_DEF_VPP_SCL    SCL @BASEBOARD_FAB2_LIB.BASEBOARD_FAB2(SCH_1):SMB_DDR_DEF_VPP_SCL
 285 SMB_DDR_DEF_VPP_SDA    SDA @BASEBOARD_FAB2_LIB.BASEBOARD_FAB2(SCH_1):SMB_DDR_DEF_VPP_SDA
 284 PVPP_DEF VDDSPD @BASEBOARD_FAB2_LIB.BASEBOARD_FAB2(SCH_1):PVPP_DEF
 146 M_E_VREF VREFCA @BASEBOARD_FAB2_LIB.BASEBOARD_FAB2(SCH_1):M_E_VREF

SCONN288_H44441003_PIP-SCONN,HA  I55  J6L2
   1 P12V_NVDIMM_DEF 12V<1> @BASEBOARD_FAB2_LIB.BASEBOARD_FAB2(SCH_1):P12V_NVDIMM_DEF
 145 P12V_NVDIMM_DEF 12V<0> @BASEBOARD_FAB2_LIB.BASEBOARD_FAB2(SCH_1):P12V_NVDIMM_DEF
  59 PVDDQ_DEF VDD<25> @BASEBOARD_FAB2_LIB.BASEBOARD_FAB2(SCH_1):PVDDQ_DEF
  61 PVDDQ_DEF VDD<24> @BASEBOARD_FAB2_LIB.BASEBOARD_FAB2(SCH_1):PVDDQ_DEF
  64 PVDDQ_DEF VDD<23> @BASEBOARD_FAB2_LIB.BASEBOARD_FAB2(SCH_1):PVDDQ_DEF
  67 PVDDQ_DEF VDD<22> @BASEBOARD_FAB2_LIB.BASEBOARD_FAB2(SCH_1):PVDDQ_DEF
  70 PVDDQ_DEF VDD<21> @BASEBOARD_FAB2_LIB.BASEBOARD_FAB2(SCH_1):PVDDQ_DEF
  73 PVDDQ_DEF VDD<20> @BASEBOARD_FAB2_LIB.BASEBOARD_FAB2(SCH_1):PVDDQ_DEF
  76 PVDDQ_DEF VDD<19> @BASEBOARD_FAB2_LIB.BASEBOARD_FAB2(SCH_1):PVDDQ_DEF
  80 PVDDQ_DEF VDD<18> @BASEBOARD_FAB2_LIB.BASEBOARD_FAB2(SCH_1):PVDDQ_DEF
  83 PVDDQ_DEF VDD<17> @BASEBOARD_FAB2_LIB.BASEBOARD_FAB2(SCH_1):PVDDQ_DEF
  85 PVDDQ_DEF VDD<16> @BASEBOARD_FAB2_LIB.BASEBOARD_FAB2(SCH_1):PVDDQ_DEF
  88 PVDDQ_DEF VDD<15> @BASEBOARD_FAB2_LIB.BASEBOARD_FAB2(SCH_1):PVDDQ_DEF
  90 PVDDQ_DEF VDD<14> @BASEBOARD_FAB2_LIB.BASEBOARD_FAB2(SCH_1):PVDDQ_DEF
  92 PVDDQ_DEF VDD<13> @BASEBOARD_FAB2_LIB.BASEBOARD_FAB2(SCH_1):PVDDQ_DEF
 204 PVDDQ_DEF VDD<12> @BASEBOARD_FAB2_LIB.BASEBOARD_FAB2(SCH_1):PVDDQ_DEF
 206 PVDDQ_DEF VDD<11> @BASEBOARD_FAB2_LIB.BASEBOARD_FAB2(SCH_1):PVDDQ_DEF
 209 PVDDQ_DEF VDD<10> @BASEBOARD_FAB2_LIB.BASEBOARD_FAB2(SCH_1):PVDDQ_DEF
 212 PVDDQ_DEF VDD<9> @BASEBOARD_FAB2_LIB.BASEBOARD_FAB2(SCH_1):PVDDQ_DEF
 215 PVDDQ_DEF VDD<8> @BASEBOARD_FAB2_LIB.BASEBOARD_FAB2(SCH_1):PVDDQ_DEF
 217 PVDDQ_DEF VDD<7> @BASEBOARD_FAB2_LIB.BASEBOARD_FAB2(SCH_1):PVDDQ_DEF
 220 PVDDQ_DEF VDD<6> @BASEBOARD_FAB2_LIB.BASEBOARD_FAB2(SCH_1):PVDDQ_DEF
 223 PVDDQ_DEF VDD<5> @BASEBOARD_FAB2_LIB.BASEBOARD_FAB2(SCH_1):PVDDQ_DEF
 226 PVDDQ_DEF VDD<4> @BASEBOARD_FAB2_LIB.BASEBOARD_FAB2(SCH_1):PVDDQ_DEF
 229 PVDDQ_DEF VDD<3> @BASEBOARD_FAB2_LIB.BASEBOARD_FAB2(SCH_1):PVDDQ_DEF
 231 PVDDQ_DEF VDD<2> @BASEBOARD_FAB2_LIB.BASEBOARD_FAB2(SCH_1):PVDDQ_DEF
 233 PVDDQ_DEF VDD<1> @BASEBOARD_FAB2_LIB.BASEBOARD_FAB2(SCH_1):PVDDQ_DEF
 236 PVDDQ_DEF VDD<0> @BASEBOARD_FAB2_LIB.BASEBOARD_FAB2(SCH_1):PVDDQ_DEF
 142 PVPP_DEF VPP<4> @BASEBOARD_FAB2_LIB.BASEBOARD_FAB2(SCH_1):PVPP_DEF
 143 PVPP_DEF VPP<3> @BASEBOARD_FAB2_LIB.BASEBOARD_FAB2(SCH_1):PVPP_DEF
 288 PVPP_DEF VPP<2> @BASEBOARD_FAB2_LIB.BASEBOARD_FAB2(SCH_1):PVPP_DEF
 286 PVPP_DEF VPP<1> @BASEBOARD_FAB2_LIB.BASEBOARD_FAB2(SCH_1):PVPP_DEF
 287 PVPP_DEF VPP<0> @BASEBOARD_FAB2_LIB.BASEBOARD_FAB2(SCH_1):PVPP_DEF
  77 PVTT_DEF VTT<1> @BASEBOARD_FAB2_LIB.BASEBOARD_FAB2(SCH_1):PVTT_DEF
 221 PVTT_DEF VTT<0> @BASEBOARD_FAB2_LIB.BASEBOARD_FAB2(SCH_1):PVTT_DEF

SCONN288_H44441003_PIP-SCONN,HA  I100  J6L2
 152 M_E_DQS_DN<0>  DQS0N @BASEBOARD_FAB2_LIB.BASEBOARD_FAB2(SCH_1):M_E_DQS_DN(0)
 153 M_E_DQS_DP<0>  DQS0P @BASEBOARD_FAB2_LIB.BASEBOARD_FAB2(SCH_1):M_E_DQS_DP(0)
  19 M_E_DQS_DN<10> DQS10N @BASEBOARD_FAB2_LIB.BASEBOARD_FAB2(SCH_1):M_E_DQS_DN(10)
  18 M_E_DQS_DP<10> DQS10P @BASEBOARD_FAB2_LIB.BASEBOARD_FAB2(SCH_1):M_E_DQS_DP(10)
  30 M_E_DQS_DN<11> DQS11N @BASEBOARD_FAB2_LIB.BASEBOARD_FAB2(SCH_1):M_E_DQS_DN(11)
  29 M_E_DQS_DP<11> DQS11P @BASEBOARD_FAB2_LIB.BASEBOARD_FAB2(SCH_1):M_E_DQS_DP(11)
  41 M_E_DQS_DN<12> DQS12N @BASEBOARD_FAB2_LIB.BASEBOARD_FAB2(SCH_1):M_E_DQS_DN(12)
  40 M_E_DQS_DP<12> DQS12P @BASEBOARD_FAB2_LIB.BASEBOARD_FAB2(SCH_1):M_E_DQS_DP(12)
 100 M_E_DQS_DN<13> DQS13N @BASEBOARD_FAB2_LIB.BASEBOARD_FAB2(SCH_1):M_E_DQS_DN(13)
  99 M_E_DQS_DP<13> DQS13P @BASEBOARD_FAB2_LIB.BASEBOARD_FAB2(SCH_1):M_E_DQS_DP(13)
 111 M_E_DQS_DN<14> DQS14N @BASEBOARD_FAB2_LIB.BASEBOARD_FAB2(SCH_1):M_E_DQS_DN(14)
 110 M_E_DQS_DP<14> DQS14P @BASEBOARD_FAB2_LIB.BASEBOARD_FAB2(SCH_1):M_E_DQS_DP(14)
 122 M_E_DQS_DN<15> DQS15N @BASEBOARD_FAB2_LIB.BASEBOARD_FAB2(SCH_1):M_E_DQS_DN(15)
 121 M_E_DQS_DP<15> DQS15P @BASEBOARD_FAB2_LIB.BASEBOARD_FAB2(SCH_1):M_E_DQS_DP(15)
 133 M_E_DQS_DN<16> DQS16N @BASEBOARD_FAB2_LIB.BASEBOARD_FAB2(SCH_1):M_E_DQS_DN(16)
 132 M_E_DQS_DP<16> DQS16P @BASEBOARD_FAB2_LIB.BASEBOARD_FAB2(SCH_1):M_E_DQS_DP(16)
  52 M_E_DQS_DN<17> DQS17N @BASEBOARD_FAB2_LIB.BASEBOARD_FAB2(SCH_1):M_E_DQS_DN(17)
  51 M_E_DQS_DP<17> DQS17P @BASEBOARD_FAB2_LIB.BASEBOARD_FAB2(SCH_1):M_E_DQS_DP(17)
 163 M_E_DQS_DN<1>  DQS1N @BASEBOARD_FAB2_LIB.BASEBOARD_FAB2(SCH_1):M_E_DQS_DN(1)
 164 M_E_DQS_DP<1>  DQS1P @BASEBOARD_FAB2_LIB.BASEBOARD_FAB2(SCH_1):M_E_DQS_DP(1)
 174 M_E_DQS_DN<2>  DQS2N @BASEBOARD_FAB2_LIB.BASEBOARD_FAB2(SCH_1):M_E_DQS_DN(2)
 175 M_E_DQS_DP<2>  DQS2P @BASEBOARD_FAB2_LIB.BASEBOARD_FAB2(SCH_1):M_E_DQS_DP(2)
 185 M_E_DQS_DN<3>  DQS3N @BASEBOARD_FAB2_LIB.BASEBOARD_FAB2(SCH_1):M_E_DQS_DN(3)
 186 M_E_DQS_DP<3>  DQS3P @BASEBOARD_FAB2_LIB.BASEBOARD_FAB2(SCH_1):M_E_DQS_DP(3)
 244 M_E_DQS_DN<4>  DQS4N @BASEBOARD_FAB2_LIB.BASEBOARD_FAB2(SCH_1):M_E_DQS_DN(4)
 245 M_E_DQS_DP<4>  DQS4P @BASEBOARD_FAB2_LIB.BASEBOARD_FAB2(SCH_1):M_E_DQS_DP(4)
 255 M_E_DQS_DN<5>  DQS5N @BASEBOARD_FAB2_LIB.BASEBOARD_FAB2(SCH_1):M_E_DQS_DN(5)
 256 M_E_DQS_DP<5>  DQS5P @BASEBOARD_FAB2_LIB.BASEBOARD_FAB2(SCH_1):M_E_DQS_DP(5)
 266 M_E_DQS_DN<6>  DQS6N @BASEBOARD_FAB2_LIB.BASEBOARD_FAB2(SCH_1):M_E_DQS_DN(6)
 267 M_E_DQS_DP<6>  DQS6P @BASEBOARD_FAB2_LIB.BASEBOARD_FAB2(SCH_1):M_E_DQS_DP(6)
 277 M_E_DQS_DN<7>  DQS7N @BASEBOARD_FAB2_LIB.BASEBOARD_FAB2(SCH_1):M_E_DQS_DN(7)
 278 M_E_DQS_DP<7>  DQS7P @BASEBOARD_FAB2_LIB.BASEBOARD_FAB2(SCH_1):M_E_DQS_DP(7)
 196 M_E_DQS_DN<8>  DQS8N @BASEBOARD_FAB2_LIB.BASEBOARD_FAB2(SCH_1):M_E_DQS_DN(8)
 197 M_E_DQS_DP<8>  DQS8P @BASEBOARD_FAB2_LIB.BASEBOARD_FAB2(SCH_1):M_E_DQS_DP(8)
   8 M_E_DQS_DN<9>  DQS9N @BASEBOARD_FAB2_LIB.BASEBOARD_FAB2(SCH_1):M_E_DQS_DN(9)
   7 M_E_DQS_DP<9>  DQS9P @BASEBOARD_FAB2_LIB.BASEBOARD_FAB2(SCH_1):M_E_DQS_DP(9)

SCONN288_H44441003_PIP-SCONN,HA  I138  J6L2
   2    GND VSS<93> @BASEBOARD_FAB2_LIB.BASEBOARD_FAB2(SCH_1):GND
   4    GND VSS<92> @BASEBOARD_FAB2_LIB.BASEBOARD_FAB2(SCH_1):GND
   6    GND VSS<91> @BASEBOARD_FAB2_LIB.BASEBOARD_FAB2(SCH_1):GND
   9    GND VSS<90> @BASEBOARD_FAB2_LIB.BASEBOARD_FAB2(SCH_1):GND
  11    GND VSS<89> @BASEBOARD_FAB2_LIB.BASEBOARD_FAB2(SCH_1):GND
  13    GND VSS<88> @BASEBOARD_FAB2_LIB.BASEBOARD_FAB2(SCH_1):GND
  15    GND VSS<87> @BASEBOARD_FAB2_LIB.BASEBOARD_FAB2(SCH_1):GND
  17    GND VSS<86> @BASEBOARD_FAB2_LIB.BASEBOARD_FAB2(SCH_1):GND
  20    GND VSS<85> @BASEBOARD_FAB2_LIB.BASEBOARD_FAB2(SCH_1):GND
  22    GND VSS<84> @BASEBOARD_FAB2_LIB.BASEBOARD_FAB2(SCH_1):GND
  24    GND VSS<83> @BASEBOARD_FAB2_LIB.BASEBOARD_FAB2(SCH_1):GND
  26    GND VSS<82> @BASEBOARD_FAB2_LIB.BASEBOARD_FAB2(SCH_1):GND
  28    GND VSS<81> @BASEBOARD_FAB2_LIB.BASEBOARD_FAB2(SCH_1):GND
  31    GND VSS<80> @BASEBOARD_FAB2_LIB.BASEBOARD_FAB2(SCH_1):GND
  33    GND VSS<79> @BASEBOARD_FAB2_LIB.BASEBOARD_FAB2(SCH_1):GND
  35    GND VSS<78> @BASEBOARD_FAB2_LIB.BASEBOARD_FAB2(SCH_1):GND
  37    GND VSS<77> @BASEBOARD_FAB2_LIB.BASEBOARD_FAB2(SCH_1):GND
  39    GND VSS<76> @BASEBOARD_FAB2_LIB.BASEBOARD_FAB2(SCH_1):GND
  42    GND VSS<75> @BASEBOARD_FAB2_LIB.BASEBOARD_FAB2(SCH_1):GND
  44    GND VSS<74> @BASEBOARD_FAB2_LIB.BASEBOARD_FAB2(SCH_1):GND
  46    GND VSS<73> @BASEBOARD_FAB2_LIB.BASEBOARD_FAB2(SCH_1):GND
  48    GND VSS<72> @BASEBOARD_FAB2_LIB.BASEBOARD_FAB2(SCH_1):GND
  50    GND VSS<71> @BASEBOARD_FAB2_LIB.BASEBOARD_FAB2(SCH_1):GND
  53    GND VSS<70> @BASEBOARD_FAB2_LIB.BASEBOARD_FAB2(SCH_1):GND
  55    GND VSS<69> @BASEBOARD_FAB2_LIB.BASEBOARD_FAB2(SCH_1):GND
  57    GND VSS<68> @BASEBOARD_FAB2_LIB.BASEBOARD_FAB2(SCH_1):GND
  94    GND VSS<67> @BASEBOARD_FAB2_LIB.BASEBOARD_FAB2(SCH_1):GND
  96    GND VSS<66> @BASEBOARD_FAB2_LIB.BASEBOARD_FAB2(SCH_1):GND
  98    GND VSS<65> @BASEBOARD_FAB2_LIB.BASEBOARD_FAB2(SCH_1):GND
 101    GND VSS<64> @BASEBOARD_FAB2_LIB.BASEBOARD_FAB2(SCH_1):GND
 103    GND VSS<63> @BASEBOARD_FAB2_LIB.BASEBOARD_FAB2(SCH_1):GND
 105    GND VSS<62> @BASEBOARD_FAB2_LIB.BASEBOARD_FAB2(SCH_1):GND
 107    GND VSS<61> @BASEBOARD_FAB2_LIB.BASEBOARD_FAB2(SCH_1):GND
 109    GND VSS<60> @BASEBOARD_FAB2_LIB.BASEBOARD_FAB2(SCH_1):GND
 112    GND VSS<59> @BASEBOARD_FAB2_LIB.BASEBOARD_FAB2(SCH_1):GND
 114    GND VSS<58> @BASEBOARD_FAB2_LIB.BASEBOARD_FAB2(SCH_1):GND
 116    GND VSS<57> @BASEBOARD_FAB2_LIB.BASEBOARD_FAB2(SCH_1):GND
 118    GND VSS<56> @BASEBOARD_FAB2_LIB.BASEBOARD_FAB2(SCH_1):GND
 120    GND VSS<55> @BASEBOARD_FAB2_LIB.BASEBOARD_FAB2(SCH_1):GND
 123    GND VSS<54> @BASEBOARD_FAB2_LIB.BASEBOARD_FAB2(SCH_1):GND
 125    GND VSS<53> @BASEBOARD_FAB2_LIB.BASEBOARD_FAB2(SCH_1):GND
 127    GND VSS<52> @BASEBOARD_FAB2_LIB.BASEBOARD_FAB2(SCH_1):GND
 129    GND VSS<51> @BASEBOARD_FAB2_LIB.BASEBOARD_FAB2(SCH_1):GND
 131    GND VSS<50> @BASEBOARD_FAB2_LIB.BASEBOARD_FAB2(SCH_1):GND
 134    GND VSS<49> @BASEBOARD_FAB2_LIB.BASEBOARD_FAB2(SCH_1):GND
 136    GND VSS<48> @BASEBOARD_FAB2_LIB.BASEBOARD_FAB2(SCH_1):GND
 138    GND VSS<47> @BASEBOARD_FAB2_LIB.BASEBOARD_FAB2(SCH_1):GND
 147    GND VSS<46> @BASEBOARD_FAB2_LIB.BASEBOARD_FAB2(SCH_1):GND
 149    GND VSS<45> @BASEBOARD_FAB2_LIB.BASEBOARD_FAB2(SCH_1):GND
 151    GND VSS<44> @BASEBOARD_FAB2_LIB.BASEBOARD_FAB2(SCH_1):GND
 154    GND VSS<43> @BASEBOARD_FAB2_LIB.BASEBOARD_FAB2(SCH_1):GND
 156    GND VSS<42> @BASEBOARD_FAB2_LIB.BASEBOARD_FAB2(SCH_1):GND
 158    GND VSS<41> @BASEBOARD_FAB2_LIB.BASEBOARD_FAB2(SCH_1):GND
 160    GND VSS<40> @BASEBOARD_FAB2_LIB.BASEBOARD_FAB2(SCH_1):GND
 162    GND VSS<39> @BASEBOARD_FAB2_LIB.BASEBOARD_FAB2(SCH_1):GND
 165    GND VSS<38> @BASEBOARD_FAB2_LIB.BASEBOARD_FAB2(SCH_1):GND
 167    GND VSS<37> @BASEBOARD_FAB2_LIB.BASEBOARD_FAB2(SCH_1):GND
 169    GND VSS<36> @BASEBOARD_FAB2_LIB.BASEBOARD_FAB2(SCH_1):GND
 171    GND VSS<35> @BASEBOARD_FAB2_LIB.BASEBOARD_FAB2(SCH_1):GND
 173    GND VSS<34> @BASEBOARD_FAB2_LIB.BASEBOARD_FAB2(SCH_1):GND
 176    GND VSS<33> @BASEBOARD_FAB2_LIB.BASEBOARD_FAB2(SCH_1):GND
 178    GND VSS<32> @BASEBOARD_FAB2_LIB.BASEBOARD_FAB2(SCH_1):GND
 180    GND VSS<31> @BASEBOARD_FAB2_LIB.BASEBOARD_FAB2(SCH_1):GND
 182    GND VSS<30> @BASEBOARD_FAB2_LIB.BASEBOARD_FAB2(SCH_1):GND
 184    GND VSS<29> @BASEBOARD_FAB2_LIB.BASEBOARD_FAB2(SCH_1):GND
 187    GND VSS<28> @BASEBOARD_FAB2_LIB.BASEBOARD_FAB2(SCH_1):GND
 189    GND VSS<27> @BASEBOARD_FAB2_LIB.BASEBOARD_FAB2(SCH_1):GND
 191    GND VSS<26> @BASEBOARD_FAB2_LIB.BASEBOARD_FAB2(SCH_1):GND
 193    GND VSS<25> @BASEBOARD_FAB2_LIB.BASEBOARD_FAB2(SCH_1):GND
 195    GND VSS<24> @BASEBOARD_FAB2_LIB.BASEBOARD_FAB2(SCH_1):GND
 198    GND VSS<23> @BASEBOARD_FAB2_LIB.BASEBOARD_FAB2(SCH_1):GND
 200    GND VSS<22> @BASEBOARD_FAB2_LIB.BASEBOARD_FAB2(SCH_1):GND
 202    GND VSS<21> @BASEBOARD_FAB2_LIB.BASEBOARD_FAB2(SCH_1):GND
 239    GND VSS<20> @BASEBOARD_FAB2_LIB.BASEBOARD_FAB2(SCH_1):GND
 241    GND VSS<19> @BASEBOARD_FAB2_LIB.BASEBOARD_FAB2(SCH_1):GND
 243    GND VSS<18> @BASEBOARD_FAB2_LIB.BASEBOARD_FAB2(SCH_1):GND
 246    GND VSS<17> @BASEBOARD_FAB2_LIB.BASEBOARD_FAB2(SCH_1):GND
 248    GND VSS<16> @BASEBOARD_FAB2_LIB.BASEBOARD_FAB2(SCH_1):GND
 250    GND VSS<15> @BASEBOARD_FAB2_LIB.BASEBOARD_FAB2(SCH_1):GND
 252    GND VSS<14> @BASEBOARD_FAB2_LIB.BASEBOARD_FAB2(SCH_1):GND
 254    GND VSS<13> @BASEBOARD_FAB2_LIB.BASEBOARD_FAB2(SCH_1):GND
 257    GND VSS<12> @BASEBOARD_FAB2_LIB.BASEBOARD_FAB2(SCH_1):GND
 259    GND VSS<11> @BASEBOARD_FAB2_LIB.BASEBOARD_FAB2(SCH_1):GND
 261    GND VSS<10> @BASEBOARD_FAB2_LIB.BASEBOARD_FAB2(SCH_1):GND
 263    GND VSS<9> @BASEBOARD_FAB2_LIB.BASEBOARD_FAB2(SCH_1):GND
 265    GND VSS<8> @BASEBOARD_FAB2_LIB.BASEBOARD_FAB2(SCH_1):GND
 268    GND VSS<7> @BASEBOARD_FAB2_LIB.BASEBOARD_FAB2(SCH_1):GND
 270    GND VSS<6> @BASEBOARD_FAB2_LIB.BASEBOARD_FAB2(SCH_1):GND
 272    GND VSS<5> @BASEBOARD_FAB2_LIB.BASEBOARD_FAB2(SCH_1):GND
 274    GND VSS<4> @BASEBOARD_FAB2_LIB.BASEBOARD_FAB2(SCH_1):GND
 276    GND VSS<3> @BASEBOARD_FAB2_LIB.BASEBOARD_FAB2(SCH_1):GND
 279    GND VSS<2> @BASEBOARD_FAB2_LIB.BASEBOARD_FAB2(SCH_1):GND
 281    GND VSS<1> @BASEBOARD_FAB2_LIB.BASEBOARD_FAB2(SCH_1):GND
 283    GND VSS<0> @BASEBOARD_FAB2_LIB.BASEBOARD_FAB2(SCH_1):GND


DRAWING: @BASEBOARD_FAB2_LIB.BASEBOARD_FAB2(SCH_1):PAGE53 

SCONN288_H44441004_PIP-SCONN,HA  I43  J4A1
   2    GND VSS<93> @BASEBOARD_FAB2_LIB.BASEBOARD_FAB2(SCH_1):GND
   4    GND VSS<92> @BASEBOARD_FAB2_LIB.BASEBOARD_FAB2(SCH_1):GND
   6    GND VSS<91> @BASEBOARD_FAB2_LIB.BASEBOARD_FAB2(SCH_1):GND
   9    GND VSS<90> @BASEBOARD_FAB2_LIB.BASEBOARD_FAB2(SCH_1):GND
  11    GND VSS<89> @BASEBOARD_FAB2_LIB.BASEBOARD_FAB2(SCH_1):GND
  13    GND VSS<88> @BASEBOARD_FAB2_LIB.BASEBOARD_FAB2(SCH_1):GND
  15    GND VSS<87> @BASEBOARD_FAB2_LIB.BASEBOARD_FAB2(SCH_1):GND
  17    GND VSS<86> @BASEBOARD_FAB2_LIB.BASEBOARD_FAB2(SCH_1):GND
  20    GND VSS<85> @BASEBOARD_FAB2_LIB.BASEBOARD_FAB2(SCH_1):GND
  22    GND VSS<84> @BASEBOARD_FAB2_LIB.BASEBOARD_FAB2(SCH_1):GND
  24    GND VSS<83> @BASEBOARD_FAB2_LIB.BASEBOARD_FAB2(SCH_1):GND
  26    GND VSS<82> @BASEBOARD_FAB2_LIB.BASEBOARD_FAB2(SCH_1):GND
  28    GND VSS<81> @BASEBOARD_FAB2_LIB.BASEBOARD_FAB2(SCH_1):GND
  31    GND VSS<80> @BASEBOARD_FAB2_LIB.BASEBOARD_FAB2(SCH_1):GND
  33    GND VSS<79> @BASEBOARD_FAB2_LIB.BASEBOARD_FAB2(SCH_1):GND
  35    GND VSS<78> @BASEBOARD_FAB2_LIB.BASEBOARD_FAB2(SCH_1):GND
  37    GND VSS<77> @BASEBOARD_FAB2_LIB.BASEBOARD_FAB2(SCH_1):GND
  39    GND VSS<76> @BASEBOARD_FAB2_LIB.BASEBOARD_FAB2(SCH_1):GND
  42    GND VSS<75> @BASEBOARD_FAB2_LIB.BASEBOARD_FAB2(SCH_1):GND
  44    GND VSS<74> @BASEBOARD_FAB2_LIB.BASEBOARD_FAB2(SCH_1):GND
  46    GND VSS<73> @BASEBOARD_FAB2_LIB.BASEBOARD_FAB2(SCH_1):GND
  48    GND VSS<72> @BASEBOARD_FAB2_LIB.BASEBOARD_FAB2(SCH_1):GND
  50    GND VSS<71> @BASEBOARD_FAB2_LIB.BASEBOARD_FAB2(SCH_1):GND
  53    GND VSS<70> @BASEBOARD_FAB2_LIB.BASEBOARD_FAB2(SCH_1):GND
  55    GND VSS<69> @BASEBOARD_FAB2_LIB.BASEBOARD_FAB2(SCH_1):GND
  57    GND VSS<68> @BASEBOARD_FAB2_LIB.BASEBOARD_FAB2(SCH_1):GND
  94    GND VSS<67> @BASEBOARD_FAB2_LIB.BASEBOARD_FAB2(SCH_1):GND
  96    GND VSS<66> @BASEBOARD_FAB2_LIB.BASEBOARD_FAB2(SCH_1):GND
  98    GND VSS<65> @BASEBOARD_FAB2_LIB.BASEBOARD_FAB2(SCH_1):GND
 101    GND VSS<64> @BASEBOARD_FAB2_LIB.BASEBOARD_FAB2(SCH_1):GND
 103    GND VSS<63> @BASEBOARD_FAB2_LIB.BASEBOARD_FAB2(SCH_1):GND
 105    GND VSS<62> @BASEBOARD_FAB2_LIB.BASEBOARD_FAB2(SCH_1):GND
 107    GND VSS<61> @BASEBOARD_FAB2_LIB.BASEBOARD_FAB2(SCH_1):GND
 109    GND VSS<60> @BASEBOARD_FAB2_LIB.BASEBOARD_FAB2(SCH_1):GND
 112    GND VSS<59> @BASEBOARD_FAB2_LIB.BASEBOARD_FAB2(SCH_1):GND
 114    GND VSS<58> @BASEBOARD_FAB2_LIB.BASEBOARD_FAB2(SCH_1):GND
 116    GND VSS<57> @BASEBOARD_FAB2_LIB.BASEBOARD_FAB2(SCH_1):GND
 118    GND VSS<56> @BASEBOARD_FAB2_LIB.BASEBOARD_FAB2(SCH_1):GND
 120    GND VSS<55> @BASEBOARD_FAB2_LIB.BASEBOARD_FAB2(SCH_1):GND
 123    GND VSS<54> @BASEBOARD_FAB2_LIB.BASEBOARD_FAB2(SCH_1):GND
 125    GND VSS<53> @BASEBOARD_FAB2_LIB.BASEBOARD_FAB2(SCH_1):GND
 127    GND VSS<52> @BASEBOARD_FAB2_LIB.BASEBOARD_FAB2(SCH_1):GND
 129    GND VSS<51> @BASEBOARD_FAB2_LIB.BASEBOARD_FAB2(SCH_1):GND
 131    GND VSS<50> @BASEBOARD_FAB2_LIB.BASEBOARD_FAB2(SCH_1):GND
 134    GND VSS<49> @BASEBOARD_FAB2_LIB.BASEBOARD_FAB2(SCH_1):GND
 136    GND VSS<48> @BASEBOARD_FAB2_LIB.BASEBOARD_FAB2(SCH_1):GND
 138    GND VSS<47> @BASEBOARD_FAB2_LIB.BASEBOARD_FAB2(SCH_1):GND
 147    GND VSS<46> @BASEBOARD_FAB2_LIB.BASEBOARD_FAB2(SCH_1):GND
 149    GND VSS<45> @BASEBOARD_FAB2_LIB.BASEBOARD_FAB2(SCH_1):GND
 151    GND VSS<44> @BASEBOARD_FAB2_LIB.BASEBOARD_FAB2(SCH_1):GND
 154    GND VSS<43> @BASEBOARD_FAB2_LIB.BASEBOARD_FAB2(SCH_1):GND
 156    GND VSS<42> @BASEBOARD_FAB2_LIB.BASEBOARD_FAB2(SCH_1):GND
 158    GND VSS<41> @BASEBOARD_FAB2_LIB.BASEBOARD_FAB2(SCH_1):GND
 160    GND VSS<40> @BASEBOARD_FAB2_LIB.BASEBOARD_FAB2(SCH_1):GND
 162    GND VSS<39> @BASEBOARD_FAB2_LIB.BASEBOARD_FAB2(SCH_1):GND
 165    GND VSS<38> @BASEBOARD_FAB2_LIB.BASEBOARD_FAB2(SCH_1):GND
 167    GND VSS<37> @BASEBOARD_FAB2_LIB.BASEBOARD_FAB2(SCH_1):GND
 169    GND VSS<36> @BASEBOARD_FAB2_LIB.BASEBOARD_FAB2(SCH_1):GND
 171    GND VSS<35> @BASEBOARD_FAB2_LIB.BASEBOARD_FAB2(SCH_1):GND
 173    GND VSS<34> @BASEBOARD_FAB2_LIB.BASEBOARD_FAB2(SCH_1):GND
 176    GND VSS<33> @BASEBOARD_FAB2_LIB.BASEBOARD_FAB2(SCH_1):GND
 178    GND VSS<32> @BASEBOARD_FAB2_LIB.BASEBOARD_FAB2(SCH_1):GND
 180    GND VSS<31> @BASEBOARD_FAB2_LIB.BASEBOARD_FAB2(SCH_1):GND
 182    GND VSS<30> @BASEBOARD_FAB2_LIB.BASEBOARD_FAB2(SCH_1):GND
 184    GND VSS<29> @BASEBOARD_FAB2_LIB.BASEBOARD_FAB2(SCH_1):GND
 187    GND VSS<28> @BASEBOARD_FAB2_LIB.BASEBOARD_FAB2(SCH_1):GND
 189    GND VSS<27> @BASEBOARD_FAB2_LIB.BASEBOARD_FAB2(SCH_1):GND
 191    GND VSS<26> @BASEBOARD_FAB2_LIB.BASEBOARD_FAB2(SCH_1):GND
 193    GND VSS<25> @BASEBOARD_FAB2_LIB.BASEBOARD_FAB2(SCH_1):GND
 195    GND VSS<24> @BASEBOARD_FAB2_LIB.BASEBOARD_FAB2(SCH_1):GND
 198    GND VSS<23> @BASEBOARD_FAB2_LIB.BASEBOARD_FAB2(SCH_1):GND
 200    GND VSS<22> @BASEBOARD_FAB2_LIB.BASEBOARD_FAB2(SCH_1):GND
 202    GND VSS<21> @BASEBOARD_FAB2_LIB.BASEBOARD_FAB2(SCH_1):GND
 239    GND VSS<20> @BASEBOARD_FAB2_LIB.BASEBOARD_FAB2(SCH_1):GND
 241    GND VSS<19> @BASEBOARD_FAB2_LIB.BASEBOARD_FAB2(SCH_1):GND
 243    GND VSS<18> @BASEBOARD_FAB2_LIB.BASEBOARD_FAB2(SCH_1):GND
 246    GND VSS<17> @BASEBOARD_FAB2_LIB.BASEBOARD_FAB2(SCH_1):GND
 248    GND VSS<16> @BASEBOARD_FAB2_LIB.BASEBOARD_FAB2(SCH_1):GND
 250    GND VSS<15> @BASEBOARD_FAB2_LIB.BASEBOARD_FAB2(SCH_1):GND
 252    GND VSS<14> @BASEBOARD_FAB2_LIB.BASEBOARD_FAB2(SCH_1):GND
 254    GND VSS<13> @BASEBOARD_FAB2_LIB.BASEBOARD_FAB2(SCH_1):GND
 257    GND VSS<12> @BASEBOARD_FAB2_LIB.BASEBOARD_FAB2(SCH_1):GND
 259    GND VSS<11> @BASEBOARD_FAB2_LIB.BASEBOARD_FAB2(SCH_1):GND
 261    GND VSS<10> @BASEBOARD_FAB2_LIB.BASEBOARD_FAB2(SCH_1):GND
 263    GND VSS<9> @BASEBOARD_FAB2_LIB.BASEBOARD_FAB2(SCH_1):GND
 265    GND VSS<8> @BASEBOARD_FAB2_LIB.BASEBOARD_FAB2(SCH_1):GND
 268    GND VSS<7> @BASEBOARD_FAB2_LIB.BASEBOARD_FAB2(SCH_1):GND
 270    GND VSS<6> @BASEBOARD_FAB2_LIB.BASEBOARD_FAB2(SCH_1):GND
 272    GND VSS<5> @BASEBOARD_FAB2_LIB.BASEBOARD_FAB2(SCH_1):GND
 274    GND VSS<4> @BASEBOARD_FAB2_LIB.BASEBOARD_FAB2(SCH_1):GND
 276    GND VSS<3> @BASEBOARD_FAB2_LIB.BASEBOARD_FAB2(SCH_1):GND
 279    GND VSS<2> @BASEBOARD_FAB2_LIB.BASEBOARD_FAB2(SCH_1):GND
 281    GND VSS<1> @BASEBOARD_FAB2_LIB.BASEBOARD_FAB2(SCH_1):GND
 283    GND VSS<0> @BASEBOARD_FAB2_LIB.BASEBOARD_FAB2(SCH_1):GND

SCONN288_H44441004_PIP-SCONN,HA  I66  J4A1
 152 M_F_DQS_DN<0>  DQS0N @BASEBOARD_FAB2_LIB.BASEBOARD_FAB2(SCH_1):M_F_DQS_DN(0)
 153 M_F_DQS_DP<0>  DQS0P @BASEBOARD_FAB2_LIB.BASEBOARD_FAB2(SCH_1):M_F_DQS_DP(0)
  19 M_F_DQS_DN<10> DQS10N @BASEBOARD_FAB2_LIB.BASEBOARD_FAB2(SCH_1):M_F_DQS_DN(10)
  18 M_F_DQS_DP<10> DQS10P @BASEBOARD_FAB2_LIB.BASEBOARD_FAB2(SCH_1):M_F_DQS_DP(10)
  30 M_F_DQS_DN<11> DQS11N @BASEBOARD_FAB2_LIB.BASEBOARD_FAB2(SCH_1):M_F_DQS_DN(11)
  29 M_F_DQS_DP<11> DQS11P @BASEBOARD_FAB2_LIB.BASEBOARD_FAB2(SCH_1):M_F_DQS_DP(11)
  41 M_F_DQS_DN<12> DQS12N @BASEBOARD_FAB2_LIB.BASEBOARD_FAB2(SCH_1):M_F_DQS_DN(12)
  40 M_F_DQS_DP<12> DQS12P @BASEBOARD_FAB2_LIB.BASEBOARD_FAB2(SCH_1):M_F_DQS_DP(12)
 100 M_F_DQS_DN<13> DQS13N @BASEBOARD_FAB2_LIB.BASEBOARD_FAB2(SCH_1):M_F_DQS_DN(13)
  99 M_F_DQS_DP<13> DQS13P @BASEBOARD_FAB2_LIB.BASEBOARD_FAB2(SCH_1):M_F_DQS_DP(13)
 111 M_F_DQS_DN<14> DQS14N @BASEBOARD_FAB2_LIB.BASEBOARD_FAB2(SCH_1):M_F_DQS_DN(14)
 110 M_F_DQS_DP<14> DQS14P @BASEBOARD_FAB2_LIB.BASEBOARD_FAB2(SCH_1):M_F_DQS_DP(14)
 122 M_F_DQS_DN<15> DQS15N @BASEBOARD_FAB2_LIB.BASEBOARD_FAB2(SCH_1):M_F_DQS_DN(15)
 121 M_F_DQS_DP<15> DQS15P @BASEBOARD_FAB2_LIB.BASEBOARD_FAB2(SCH_1):M_F_DQS_DP(15)
 133 M_F_DQS_DN<16> DQS16N @BASEBOARD_FAB2_LIB.BASEBOARD_FAB2(SCH_1):M_F_DQS_DN(16)
 132 M_F_DQS_DP<16> DQS16P @BASEBOARD_FAB2_LIB.BASEBOARD_FAB2(SCH_1):M_F_DQS_DP(16)
  52 M_F_DQS_DN<17> DQS17N @BASEBOARD_FAB2_LIB.BASEBOARD_FAB2(SCH_1):M_F_DQS_DN(17)
  51 M_F_DQS_DP<17> DQS17P @BASEBOARD_FAB2_LIB.BASEBOARD_FAB2(SCH_1):M_F_DQS_DP(17)
 163 M_F_DQS_DN<1>  DQS1N @BASEBOARD_FAB2_LIB.BASEBOARD_FAB2(SCH_1):M_F_DQS_DN(1)
 164 M_F_DQS_DP<1>  DQS1P @BASEBOARD_FAB2_LIB.BASEBOARD_FAB2(SCH_1):M_F_DQS_DP(1)
 174 M_F_DQS_DN<2>  DQS2N @BASEBOARD_FAB2_LIB.BASEBOARD_FAB2(SCH_1):M_F_DQS_DN(2)
 175 M_F_DQS_DP<2>  DQS2P @BASEBOARD_FAB2_LIB.BASEBOARD_FAB2(SCH_1):M_F_DQS_DP(2)
 185 M_F_DQS_DN<3>  DQS3N @BASEBOARD_FAB2_LIB.BASEBOARD_FAB2(SCH_1):M_F_DQS_DN(3)
 186 M_F_DQS_DP<3>  DQS3P @BASEBOARD_FAB2_LIB.BASEBOARD_FAB2(SCH_1):M_F_DQS_DP(3)
 244 M_F_DQS_DN<4>  DQS4N @BASEBOARD_FAB2_LIB.BASEBOARD_FAB2(SCH_1):M_F_DQS_DN(4)
 245 M_F_DQS_DP<4>  DQS4P @BASEBOARD_FAB2_LIB.BASEBOARD_FAB2(SCH_1):M_F_DQS_DP(4)
 255 M_F_DQS_DN<5>  DQS5N @BASEBOARD_FAB2_LIB.BASEBOARD_FAB2(SCH_1):M_F_DQS_DN(5)
 256 M_F_DQS_DP<5>  DQS5P @BASEBOARD_FAB2_LIB.BASEBOARD_FAB2(SCH_1):M_F_DQS_DP(5)
 266 M_F_DQS_DN<6>  DQS6N @BASEBOARD_FAB2_LIB.BASEBOARD_FAB2(SCH_1):M_F_DQS_DN(6)
 267 M_F_DQS_DP<6>  DQS6P @BASEBOARD_FAB2_LIB.BASEBOARD_FAB2(SCH_1):M_F_DQS_DP(6)
 277 M_F_DQS_DN<7>  DQS7N @BASEBOARD_FAB2_LIB.BASEBOARD_FAB2(SCH_1):M_F_DQS_DN(7)
 278 M_F_DQS_DP<7>  DQS7P @BASEBOARD_FAB2_LIB.BASEBOARD_FAB2(SCH_1):M_F_DQS_DP(7)
 196 M_F_DQS_DN<8>  DQS8N @BASEBOARD_FAB2_LIB.BASEBOARD_FAB2(SCH_1):M_F_DQS_DN(8)
 197 M_F_DQS_DP<8>  DQS8P @BASEBOARD_FAB2_LIB.BASEBOARD_FAB2(SCH_1):M_F_DQS_DP(8)
   8 M_F_DQS_DN<9>  DQS9N @BASEBOARD_FAB2_LIB.BASEBOARD_FAB2(SCH_1):M_F_DQS_DN(9)
   7 M_F_DQS_DP<9>  DQS9P @BASEBOARD_FAB2_LIB.BASEBOARD_FAB2(SCH_1):M_F_DQS_DP(9)

SCONN288_H44441004_PIP-SCONN,HA  I111  J4A1
  79 M_F_MA<0>     A0 @BASEBOARD_FAB2_LIB.BASEBOARD_FAB2(SCH_1):M_F_MA(0)
  72 M_F_MA<1>     A1 @BASEBOARD_FAB2_LIB.BASEBOARD_FAB2(SCH_1):M_F_MA(1)
 225 M_F_MA<10>    A10 @BASEBOARD_FAB2_LIB.BASEBOARD_FAB2(SCH_1):M_F_MA(10)
 210 M_F_MA<11>    A11 @BASEBOARD_FAB2_LIB.BASEBOARD_FAB2(SCH_1):M_F_MA(11)
  65 M_F_MA<12>    A12 @BASEBOARD_FAB2_LIB.BASEBOARD_FAB2(SCH_1):M_F_MA(12)
 232 M_F_MA<13>    A13 @BASEBOARD_FAB2_LIB.BASEBOARD_FAB2(SCH_1):M_F_MA(13)
 228 M_F_MA<14> A14_WE_N @BASEBOARD_FAB2_LIB.BASEBOARD_FAB2(SCH_1):M_F_MA(14)
  86 M_F_MA<15> A15_CAS_N @BASEBOARD_FAB2_LIB.BASEBOARD_FAB2(SCH_1):M_F_MA(15)
  82 M_F_MA<16> A16_RAS_N @BASEBOARD_FAB2_LIB.BASEBOARD_FAB2(SCH_1):M_F_MA(16)
 234 M_F_MA<17>    A17 @BASEBOARD_FAB2_LIB.BASEBOARD_FAB2(SCH_1):M_F_MA(17)
 216 M_F_MA<2>     A2 @BASEBOARD_FAB2_LIB.BASEBOARD_FAB2(SCH_1):M_F_MA(2)
  71 M_F_MA<3>     A3 @BASEBOARD_FAB2_LIB.BASEBOARD_FAB2(SCH_1):M_F_MA(3)
 214 M_F_MA<4>     A4 @BASEBOARD_FAB2_LIB.BASEBOARD_FAB2(SCH_1):M_F_MA(4)
 213 M_F_MA<5>     A5 @BASEBOARD_FAB2_LIB.BASEBOARD_FAB2(SCH_1):M_F_MA(5)
  69 M_F_MA<6>     A6 @BASEBOARD_FAB2_LIB.BASEBOARD_FAB2(SCH_1):M_F_MA(6)
 211 M_F_MA<7>     A7 @BASEBOARD_FAB2_LIB.BASEBOARD_FAB2(SCH_1):M_F_MA(7)
  68 M_F_MA<8>     A8 @BASEBOARD_FAB2_LIB.BASEBOARD_FAB2(SCH_1):M_F_MA(8)
  66 M_F_MA<9>     A9 @BASEBOARD_FAB2_LIB.BASEBOARD_FAB2(SCH_1):M_F_MA(9)
  62 M_F_ACT_N  ACT_N @BASEBOARD_FAB2_LIB.BASEBOARD_FAB2(SCH_1):M_F_ACT_N
 208 M_F_ALERT_N ALERT_N @BASEBOARD_FAB2_LIB.BASEBOARD_FAB2(SCH_1):M_F_ALERT_N
 224 M_F_BA<1>  BA<1> @BASEBOARD_FAB2_LIB.BASEBOARD_FAB2(SCH_1):M_F_BA(1)
  81 M_F_BA<0>  BA<0> @BASEBOARD_FAB2_LIB.BASEBOARD_FAB2(SCH_1):M_F_BA(0)
 207 M_F_BG<1>  BG<1> @BASEBOARD_FAB2_LIB.BASEBOARD_FAB2(SCH_1):M_F_BG(1)
  63 M_F_BG<0>  BG<0> @BASEBOARD_FAB2_LIB.BASEBOARD_FAB2(SCH_1):M_F_BG(0)
 235 M_F_C<2>   C<2> @BASEBOARD_FAB2_LIB.BASEBOARD_FAB2(SCH_1):M_F_C(2)
 199 M_F_ECC<6>  CB<7> @BASEBOARD_FAB2_LIB.BASEBOARD_FAB2(SCH_1):M_F_ECC(6)
  54 M_F_ECC<7>  CB<6> @BASEBOARD_FAB2_LIB.BASEBOARD_FAB2(SCH_1):M_F_ECC(7)
 192 M_F_ECC<4>  CB<5> @BASEBOARD_FAB2_LIB.BASEBOARD_FAB2(SCH_1):M_F_ECC(4)
  47 M_F_ECC<5>  CB<4> @BASEBOARD_FAB2_LIB.BASEBOARD_FAB2(SCH_1):M_F_ECC(5)
 201 M_F_ECC<2>  CB<3> @BASEBOARD_FAB2_LIB.BASEBOARD_FAB2(SCH_1):M_F_ECC(2)
  56 M_F_ECC<3>  CB<2> @BASEBOARD_FAB2_LIB.BASEBOARD_FAB2(SCH_1):M_F_ECC(3)
 194 M_F_ECC<0>  CB<1> @BASEBOARD_FAB2_LIB.BASEBOARD_FAB2(SCH_1):M_F_ECC(0)
  49 M_F_ECC<1>  CB<0> @BASEBOARD_FAB2_LIB.BASEBOARD_FAB2(SCH_1):M_F_ECC(1)
  75 M_F_CLK_DN<0>   CK0N @BASEBOARD_FAB2_LIB.BASEBOARD_FAB2(SCH_1):M_F_CLK_DN(0)
  74 M_F_CLK_DP<0>   CK0P @BASEBOARD_FAB2_LIB.BASEBOARD_FAB2(SCH_1):M_F_CLK_DP(0)
 219 M_F_CLK_DN<1>   CK1N @BASEBOARD_FAB2_LIB.BASEBOARD_FAB2(SCH_1):M_F_CLK_DN(1)
 218 M_F_CLK_DP<1>   CK1P @BASEBOARD_FAB2_LIB.BASEBOARD_FAB2(SCH_1):M_F_CLK_DP(1)
 203 M_F_CKE<1> CKE<1> @BASEBOARD_FAB2_LIB.BASEBOARD_FAB2(SCH_1):M_F_CKE(1)
  60 M_F_CKE<0> CKE<0> @BASEBOARD_FAB2_LIB.BASEBOARD_FAB2(SCH_1):M_F_CKE(0)
 280 M_F_DQ<62> DQ<63> @BASEBOARD_FAB2_LIB.BASEBOARD_FAB2(SCH_1):M_F_DQ(62)
 135 M_F_DQ<63> DQ<62> @BASEBOARD_FAB2_LIB.BASEBOARD_FAB2(SCH_1):M_F_DQ(63)
 273 M_F_DQ<60> DQ<61> @BASEBOARD_FAB2_LIB.BASEBOARD_FAB2(SCH_1):M_F_DQ(60)
 128 M_F_DQ<61> DQ<60> @BASEBOARD_FAB2_LIB.BASEBOARD_FAB2(SCH_1):M_F_DQ(61)
 282 M_F_DQ<58> DQ<59> @BASEBOARD_FAB2_LIB.BASEBOARD_FAB2(SCH_1):M_F_DQ(58)
 137 M_F_DQ<59> DQ<58> @BASEBOARD_FAB2_LIB.BASEBOARD_FAB2(SCH_1):M_F_DQ(59)
 275 M_F_DQ<56> DQ<57> @BASEBOARD_FAB2_LIB.BASEBOARD_FAB2(SCH_1):M_F_DQ(56)
 130 M_F_DQ<57> DQ<56> @BASEBOARD_FAB2_LIB.BASEBOARD_FAB2(SCH_1):M_F_DQ(57)
 269 M_F_DQ<54> DQ<55> @BASEBOARD_FAB2_LIB.BASEBOARD_FAB2(SCH_1):M_F_DQ(54)
 124 M_F_DQ<55> DQ<54> @BASEBOARD_FAB2_LIB.BASEBOARD_FAB2(SCH_1):M_F_DQ(55)
 262 M_F_DQ<52> DQ<53> @BASEBOARD_FAB2_LIB.BASEBOARD_FAB2(SCH_1):M_F_DQ(52)
 117 M_F_DQ<53> DQ<52> @BASEBOARD_FAB2_LIB.BASEBOARD_FAB2(SCH_1):M_F_DQ(53)
 271 M_F_DQ<50> DQ<51> @BASEBOARD_FAB2_LIB.BASEBOARD_FAB2(SCH_1):M_F_DQ(50)
 126 M_F_DQ<51> DQ<50> @BASEBOARD_FAB2_LIB.BASEBOARD_FAB2(SCH_1):M_F_DQ(51)
 264 M_F_DQ<48> DQ<49> @BASEBOARD_FAB2_LIB.BASEBOARD_FAB2(SCH_1):M_F_DQ(48)
 119 M_F_DQ<49> DQ<48> @BASEBOARD_FAB2_LIB.BASEBOARD_FAB2(SCH_1):M_F_DQ(49)
 258 M_F_DQ<46> DQ<47> @BASEBOARD_FAB2_LIB.BASEBOARD_FAB2(SCH_1):M_F_DQ(46)
 113 M_F_DQ<47> DQ<46> @BASEBOARD_FAB2_LIB.BASEBOARD_FAB2(SCH_1):M_F_DQ(47)
 251 M_F_DQ<44> DQ<45> @BASEBOARD_FAB2_LIB.BASEBOARD_FAB2(SCH_1):M_F_DQ(44)
 106 M_F_DQ<45> DQ<44> @BASEBOARD_FAB2_LIB.BASEBOARD_FAB2(SCH_1):M_F_DQ(45)
 260 M_F_DQ<42> DQ<43> @BASEBOARD_FAB2_LIB.BASEBOARD_FAB2(SCH_1):M_F_DQ(42)
 115 M_F_DQ<43> DQ<42> @BASEBOARD_FAB2_LIB.BASEBOARD_FAB2(SCH_1):M_F_DQ(43)
 253 M_F_DQ<40> DQ<41> @BASEBOARD_FAB2_LIB.BASEBOARD_FAB2(SCH_1):M_F_DQ(40)
 108 M_F_DQ<41> DQ<40> @BASEBOARD_FAB2_LIB.BASEBOARD_FAB2(SCH_1):M_F_DQ(41)
 247 M_F_DQ<38> DQ<39> @BASEBOARD_FAB2_LIB.BASEBOARD_FAB2(SCH_1):M_F_DQ(38)
 102 M_F_DQ<39> DQ<38> @BASEBOARD_FAB2_LIB.BASEBOARD_FAB2(SCH_1):M_F_DQ(39)
 240 M_F_DQ<36> DQ<37> @BASEBOARD_FAB2_LIB.BASEBOARD_FAB2(SCH_1):M_F_DQ(36)
  95 M_F_DQ<37> DQ<36> @BASEBOARD_FAB2_LIB.BASEBOARD_FAB2(SCH_1):M_F_DQ(37)
 249 M_F_DQ<34> DQ<35> @BASEBOARD_FAB2_LIB.BASEBOARD_FAB2(SCH_1):M_F_DQ(34)
 104 M_F_DQ<35> DQ<34> @BASEBOARD_FAB2_LIB.BASEBOARD_FAB2(SCH_1):M_F_DQ(35)
 242 M_F_DQ<32> DQ<33> @BASEBOARD_FAB2_LIB.BASEBOARD_FAB2(SCH_1):M_F_DQ(32)
  97 M_F_DQ<33> DQ<32> @BASEBOARD_FAB2_LIB.BASEBOARD_FAB2(SCH_1):M_F_DQ(33)
 188 M_F_DQ<30> DQ<31> @BASEBOARD_FAB2_LIB.BASEBOARD_FAB2(SCH_1):M_F_DQ(30)
  43 M_F_DQ<31> DQ<30> @BASEBOARD_FAB2_LIB.BASEBOARD_FAB2(SCH_1):M_F_DQ(31)
 181 M_F_DQ<28> DQ<29> @BASEBOARD_FAB2_LIB.BASEBOARD_FAB2(SCH_1):M_F_DQ(28)
  36 M_F_DQ<29> DQ<28> @BASEBOARD_FAB2_LIB.BASEBOARD_FAB2(SCH_1):M_F_DQ(29)
 190 M_F_DQ<26> DQ<27> @BASEBOARD_FAB2_LIB.BASEBOARD_FAB2(SCH_1):M_F_DQ(26)
  45 M_F_DQ<27> DQ<26> @BASEBOARD_FAB2_LIB.BASEBOARD_FAB2(SCH_1):M_F_DQ(27)
 183 M_F_DQ<24> DQ<25> @BASEBOARD_FAB2_LIB.BASEBOARD_FAB2(SCH_1):M_F_DQ(24)
  38 M_F_DQ<25> DQ<24> @BASEBOARD_FAB2_LIB.BASEBOARD_FAB2(SCH_1):M_F_DQ(25)
 177 M_F_DQ<22> DQ<23> @BASEBOARD_FAB2_LIB.BASEBOARD_FAB2(SCH_1):M_F_DQ(22)
  32 M_F_DQ<23> DQ<22> @BASEBOARD_FAB2_LIB.BASEBOARD_FAB2(SCH_1):M_F_DQ(23)
 170 M_F_DQ<20> DQ<21> @BASEBOARD_FAB2_LIB.BASEBOARD_FAB2(SCH_1):M_F_DQ(20)
  25 M_F_DQ<21> DQ<20> @BASEBOARD_FAB2_LIB.BASEBOARD_FAB2(SCH_1):M_F_DQ(21)
 179 M_F_DQ<18> DQ<19> @BASEBOARD_FAB2_LIB.BASEBOARD_FAB2(SCH_1):M_F_DQ(18)
  34 M_F_DQ<19> DQ<18> @BASEBOARD_FAB2_LIB.BASEBOARD_FAB2(SCH_1):M_F_DQ(19)
 172 M_F_DQ<16> DQ<17> @BASEBOARD_FAB2_LIB.BASEBOARD_FAB2(SCH_1):M_F_DQ(16)
  27 M_F_DQ<17> DQ<16> @BASEBOARD_FAB2_LIB.BASEBOARD_FAB2(SCH_1):M_F_DQ(17)
 166 M_F_DQ<14> DQ<15> @BASEBOARD_FAB2_LIB.BASEBOARD_FAB2(SCH_1):M_F_DQ(14)
  21 M_F_DQ<15> DQ<14> @BASEBOARD_FAB2_LIB.BASEBOARD_FAB2(SCH_1):M_F_DQ(15)
 159 M_F_DQ<12> DQ<13> @BASEBOARD_FAB2_LIB.BASEBOARD_FAB2(SCH_1):M_F_DQ(12)
  14 M_F_DQ<13> DQ<12> @BASEBOARD_FAB2_LIB.BASEBOARD_FAB2(SCH_1):M_F_DQ(13)
 168 M_F_DQ<10> DQ<11> @BASEBOARD_FAB2_LIB.BASEBOARD_FAB2(SCH_1):M_F_DQ(10)
  23 M_F_DQ<11> DQ<10> @BASEBOARD_FAB2_LIB.BASEBOARD_FAB2(SCH_1):M_F_DQ(11)
 161 M_F_DQ<8>  DQ<9> @BASEBOARD_FAB2_LIB.BASEBOARD_FAB2(SCH_1):M_F_DQ(8)
  16 M_F_DQ<9>  DQ<8> @BASEBOARD_FAB2_LIB.BASEBOARD_FAB2(SCH_1):M_F_DQ(9)
 155 M_F_DQ<6>  DQ<7> @BASEBOARD_FAB2_LIB.BASEBOARD_FAB2(SCH_1):M_F_DQ(6)
  10 M_F_DQ<7>  DQ<6> @BASEBOARD_FAB2_LIB.BASEBOARD_FAB2(SCH_1):M_F_DQ(7)
 148 M_F_DQ<4>  DQ<5> @BASEBOARD_FAB2_LIB.BASEBOARD_FAB2(SCH_1):M_F_DQ(4)
   3 M_F_DQ<5>  DQ<4> @BASEBOARD_FAB2_LIB.BASEBOARD_FAB2(SCH_1):M_F_DQ(5)
 157 M_F_DQ<2>  DQ<3> @BASEBOARD_FAB2_LIB.BASEBOARD_FAB2(SCH_1):M_F_DQ(2)
  12 M_F_DQ<3>  DQ<2> @BASEBOARD_FAB2_LIB.BASEBOARD_FAB2(SCH_1):M_F_DQ(3)
 150 M_F_DQ<0>  DQ<1> @BASEBOARD_FAB2_LIB.BASEBOARD_FAB2(SCH_1):M_F_DQ(0)
   5 M_F_DQ<1>  DQ<0> @BASEBOARD_FAB2_LIB.BASEBOARD_FAB2(SCH_1):M_F_DQ(1)
  78 FM_DIMM_EVENT_COD_N EVENT_N @BASEBOARD_FAB2_LIB.BASEBOARD_FAB2(SCH_1):FM_DIMM_EVENT_COD_N
  91 M_F_ODT<1> ODT<1> @BASEBOARD_FAB2_LIB.BASEBOARD_FAB2(SCH_1):M_F_ODT(1)
  87 M_F_ODT<0> ODT<0> @BASEBOARD_FAB2_LIB.BASEBOARD_FAB2(SCH_1):M_F_ODT(0)
 222 M_F_PAR    PAR @BASEBOARD_FAB2_LIB.BASEBOARD_FAB2(SCH_1):M_F_PAR
  58 M_DEF_RST_N RESET_N @BASEBOARD_FAB2_LIB.BASEBOARD_FAB2(SCH_1):M_DEF_RST_N
 144 TP_CH_F_DIMM_F0_RFU_2 RFU<2> @BASEBOARD_FAB2_LIB.BASEBOARD_FAB2(SCH_1):TP_CH_F_DIMM_F0_RFU_2
 227 TP_CH_F_DIMM_F0_RFU_1 RFU<1> @BASEBOARD_FAB2_LIB.BASEBOARD_FAB2(SCH_1):TP_CH_F_DIMM_F0_RFU_1
 205 TP_CH_F_DIMM_F0_RFU_0 RFU<0> @BASEBOARD_FAB2_LIB.BASEBOARD_FAB2(SCH_1):TP_CH_F_DIMM_F0_RFU_0
  84 M_F_CS_N<0>   S0_N @BASEBOARD_FAB2_LIB.BASEBOARD_FAB2(SCH_1):M_F_CS_N(0)
  89 M_F_CS_N<1>   S1_N @BASEBOARD_FAB2_LIB.BASEBOARD_FAB2(SCH_1):M_F_CS_N(1)
  93 M_F_CS_N<2> S2_N_C<0> @BASEBOARD_FAB2_LIB.BASEBOARD_FAB2(SCH_1):M_F_CS_N(2)
 237 M_F_CS_N<3> S3_N_C<1> @BASEBOARD_FAB2_LIB.BASEBOARD_FAB2(SCH_1):M_F_CS_N(3)
 238 PVPP_DEF  SA<2> @BASEBOARD_FAB2_LIB.BASEBOARD_FAB2(SCH_1):PVPP_DEF
 140    GND  SA<1> @BASEBOARD_FAB2_LIB.BASEBOARD_FAB2(SCH_1):GND
 139    GND  SA<0> @BASEBOARD_FAB2_LIB.BASEBOARD_FAB2(SCH_1):GND
 230 FM_ADR_COMPLETE_DEF_N SAVE_N_NC @BASEBOARD_FAB2_LIB.BASEBOARD_FAB2(SCH_1):FM_ADR_COMPLETE_DEF_N
 141 SMB_DDR_DEF_VPP_SCL    SCL @BASEBOARD_FAB2_LIB.BASEBOARD_FAB2(SCH_1):SMB_DDR_DEF_VPP_SCL
 285 SMB_DDR_DEF_VPP_SDA    SDA @BASEBOARD_FAB2_LIB.BASEBOARD_FAB2(SCH_1):SMB_DDR_DEF_VPP_SDA
 284 PVPP_DEF VDDSPD @BASEBOARD_FAB2_LIB.BASEBOARD_FAB2(SCH_1):PVPP_DEF
 146 M_F_VREF VREFCA @BASEBOARD_FAB2_LIB.BASEBOARD_FAB2(SCH_1):M_F_VREF

SCONN288_H44441004_PIP-SCONN,HA  I171  J4A1
   1 P12V_NVDIMM_DEF 12V<1> @BASEBOARD_FAB2_LIB.BASEBOARD_FAB2(SCH_1):P12V_NVDIMM_DEF
 145 P12V_NVDIMM_DEF 12V<0> @BASEBOARD_FAB2_LIB.BASEBOARD_FAB2(SCH_1):P12V_NVDIMM_DEF
  59 PVDDQ_DEF VDD<25> @BASEBOARD_FAB2_LIB.BASEBOARD_FAB2(SCH_1):PVDDQ_DEF
  61 PVDDQ_DEF VDD<24> @BASEBOARD_FAB2_LIB.BASEBOARD_FAB2(SCH_1):PVDDQ_DEF
  64 PVDDQ_DEF VDD<23> @BASEBOARD_FAB2_LIB.BASEBOARD_FAB2(SCH_1):PVDDQ_DEF
  67 PVDDQ_DEF VDD<22> @BASEBOARD_FAB2_LIB.BASEBOARD_FAB2(SCH_1):PVDDQ_DEF
  70 PVDDQ_DEF VDD<21> @BASEBOARD_FAB2_LIB.BASEBOARD_FAB2(SCH_1):PVDDQ_DEF
  73 PVDDQ_DEF VDD<20> @BASEBOARD_FAB2_LIB.BASEBOARD_FAB2(SCH_1):PVDDQ_DEF
  76 PVDDQ_DEF VDD<19> @BASEBOARD_FAB2_LIB.BASEBOARD_FAB2(SCH_1):PVDDQ_DEF
  80 PVDDQ_DEF VDD<18> @BASEBOARD_FAB2_LIB.BASEBOARD_FAB2(SCH_1):PVDDQ_DEF
  83 PVDDQ_DEF VDD<17> @BASEBOARD_FAB2_LIB.BASEBOARD_FAB2(SCH_1):PVDDQ_DEF
  85 PVDDQ_DEF VDD<16> @BASEBOARD_FAB2_LIB.BASEBOARD_FAB2(SCH_1):PVDDQ_DEF
  88 PVDDQ_DEF VDD<15> @BASEBOARD_FAB2_LIB.BASEBOARD_FAB2(SCH_1):PVDDQ_DEF
  90 PVDDQ_DEF VDD<14> @BASEBOARD_FAB2_LIB.BASEBOARD_FAB2(SCH_1):PVDDQ_DEF
  92 PVDDQ_DEF VDD<13> @BASEBOARD_FAB2_LIB.BASEBOARD_FAB2(SCH_1):PVDDQ_DEF
 204 PVDDQ_DEF VDD<12> @BASEBOARD_FAB2_LIB.BASEBOARD_FAB2(SCH_1):PVDDQ_DEF
 206 PVDDQ_DEF VDD<11> @BASEBOARD_FAB2_LIB.BASEBOARD_FAB2(SCH_1):PVDDQ_DEF
 209 PVDDQ_DEF VDD<10> @BASEBOARD_FAB2_LIB.BASEBOARD_FAB2(SCH_1):PVDDQ_DEF
 212 PVDDQ_DEF VDD<9> @BASEBOARD_FAB2_LIB.BASEBOARD_FAB2(SCH_1):PVDDQ_DEF
 215 PVDDQ_DEF VDD<8> @BASEBOARD_FAB2_LIB.BASEBOARD_FAB2(SCH_1):PVDDQ_DEF
 217 PVDDQ_DEF VDD<7> @BASEBOARD_FAB2_LIB.BASEBOARD_FAB2(SCH_1):PVDDQ_DEF
 220 PVDDQ_DEF VDD<6> @BASEBOARD_FAB2_LIB.BASEBOARD_FAB2(SCH_1):PVDDQ_DEF
 223 PVDDQ_DEF VDD<5> @BASEBOARD_FAB2_LIB.BASEBOARD_FAB2(SCH_1):PVDDQ_DEF
 226 PVDDQ_DEF VDD<4> @BASEBOARD_FAB2_LIB.BASEBOARD_FAB2(SCH_1):PVDDQ_DEF
 229 PVDDQ_DEF VDD<3> @BASEBOARD_FAB2_LIB.BASEBOARD_FAB2(SCH_1):PVDDQ_DEF
 231 PVDDQ_DEF VDD<2> @BASEBOARD_FAB2_LIB.BASEBOARD_FAB2(SCH_1):PVDDQ_DEF
 233 PVDDQ_DEF VDD<1> @BASEBOARD_FAB2_LIB.BASEBOARD_FAB2(SCH_1):PVDDQ_DEF
 236 PVDDQ_DEF VDD<0> @BASEBOARD_FAB2_LIB.BASEBOARD_FAB2(SCH_1):PVDDQ_DEF
 142 PVPP_DEF VPP<4> @BASEBOARD_FAB2_LIB.BASEBOARD_FAB2(SCH_1):PVPP_DEF
 143 PVPP_DEF VPP<3> @BASEBOARD_FAB2_LIB.BASEBOARD_FAB2(SCH_1):PVPP_DEF
 288 PVPP_DEF VPP<2> @BASEBOARD_FAB2_LIB.BASEBOARD_FAB2(SCH_1):PVPP_DEF
 286 PVPP_DEF VPP<1> @BASEBOARD_FAB2_LIB.BASEBOARD_FAB2(SCH_1):PVPP_DEF
 287 PVPP_DEF VPP<0> @BASEBOARD_FAB2_LIB.BASEBOARD_FAB2(SCH_1):PVPP_DEF
  77 PVTT_DEF VTT<1> @BASEBOARD_FAB2_LIB.BASEBOARD_FAB2(SCH_1):PVTT_DEF
 221 PVTT_DEF VTT<0> @BASEBOARD_FAB2_LIB.BASEBOARD_FAB2(SCH_1):PVTT_DEF

CAP_A_0402V-0.01UF,25V,10%,X7RA  I178  C6L1
   1 M_F_VREF      A @BASEBOARD_FAB2_LIB.BASEBOARD_FAB2(SCH_1):M_F_VREF
   2    GND      B @BASEBOARD_FAB2_LIB.BASEBOARD_FAB2(SCH_1):GND


DRAWING: @BASEBOARD_FAB2_LIB.BASEBOARD_FAB2(SCH_1):PAGE54 

SCONN288_H44441003_PIP-SCONN,HA  I43  J6L1
   2    GND VSS<93> @BASEBOARD_FAB2_LIB.BASEBOARD_FAB2(SCH_1):GND
   4    GND VSS<92> @BASEBOARD_FAB2_LIB.BASEBOARD_FAB2(SCH_1):GND
   6    GND VSS<91> @BASEBOARD_FAB2_LIB.BASEBOARD_FAB2(SCH_1):GND
   9    GND VSS<90> @BASEBOARD_FAB2_LIB.BASEBOARD_FAB2(SCH_1):GND
  11    GND VSS<89> @BASEBOARD_FAB2_LIB.BASEBOARD_FAB2(SCH_1):GND
  13    GND VSS<88> @BASEBOARD_FAB2_LIB.BASEBOARD_FAB2(SCH_1):GND
  15    GND VSS<87> @BASEBOARD_FAB2_LIB.BASEBOARD_FAB2(SCH_1):GND
  17    GND VSS<86> @BASEBOARD_FAB2_LIB.BASEBOARD_FAB2(SCH_1):GND
  20    GND VSS<85> @BASEBOARD_FAB2_LIB.BASEBOARD_FAB2(SCH_1):GND
  22    GND VSS<84> @BASEBOARD_FAB2_LIB.BASEBOARD_FAB2(SCH_1):GND
  24    GND VSS<83> @BASEBOARD_FAB2_LIB.BASEBOARD_FAB2(SCH_1):GND
  26    GND VSS<82> @BASEBOARD_FAB2_LIB.BASEBOARD_FAB2(SCH_1):GND
  28    GND VSS<81> @BASEBOARD_FAB2_LIB.BASEBOARD_FAB2(SCH_1):GND
  31    GND VSS<80> @BASEBOARD_FAB2_LIB.BASEBOARD_FAB2(SCH_1):GND
  33    GND VSS<79> @BASEBOARD_FAB2_LIB.BASEBOARD_FAB2(SCH_1):GND
  35    GND VSS<78> @BASEBOARD_FAB2_LIB.BASEBOARD_FAB2(SCH_1):GND
  37    GND VSS<77> @BASEBOARD_FAB2_LIB.BASEBOARD_FAB2(SCH_1):GND
  39    GND VSS<76> @BASEBOARD_FAB2_LIB.BASEBOARD_FAB2(SCH_1):GND
  42    GND VSS<75> @BASEBOARD_FAB2_LIB.BASEBOARD_FAB2(SCH_1):GND
  44    GND VSS<74> @BASEBOARD_FAB2_LIB.BASEBOARD_FAB2(SCH_1):GND
  46    GND VSS<73> @BASEBOARD_FAB2_LIB.BASEBOARD_FAB2(SCH_1):GND
  48    GND VSS<72> @BASEBOARD_FAB2_LIB.BASEBOARD_FAB2(SCH_1):GND
  50    GND VSS<71> @BASEBOARD_FAB2_LIB.BASEBOARD_FAB2(SCH_1):GND
  53    GND VSS<70> @BASEBOARD_FAB2_LIB.BASEBOARD_FAB2(SCH_1):GND
  55    GND VSS<69> @BASEBOARD_FAB2_LIB.BASEBOARD_FAB2(SCH_1):GND
  57    GND VSS<68> @BASEBOARD_FAB2_LIB.BASEBOARD_FAB2(SCH_1):GND
  94    GND VSS<67> @BASEBOARD_FAB2_LIB.BASEBOARD_FAB2(SCH_1):GND
  96    GND VSS<66> @BASEBOARD_FAB2_LIB.BASEBOARD_FAB2(SCH_1):GND
  98    GND VSS<65> @BASEBOARD_FAB2_LIB.BASEBOARD_FAB2(SCH_1):GND
 101    GND VSS<64> @BASEBOARD_FAB2_LIB.BASEBOARD_FAB2(SCH_1):GND
 103    GND VSS<63> @BASEBOARD_FAB2_LIB.BASEBOARD_FAB2(SCH_1):GND
 105    GND VSS<62> @BASEBOARD_FAB2_LIB.BASEBOARD_FAB2(SCH_1):GND
 107    GND VSS<61> @BASEBOARD_FAB2_LIB.BASEBOARD_FAB2(SCH_1):GND
 109    GND VSS<60> @BASEBOARD_FAB2_LIB.BASEBOARD_FAB2(SCH_1):GND
 112    GND VSS<59> @BASEBOARD_FAB2_LIB.BASEBOARD_FAB2(SCH_1):GND
 114    GND VSS<58> @BASEBOARD_FAB2_LIB.BASEBOARD_FAB2(SCH_1):GND
 116    GND VSS<57> @BASEBOARD_FAB2_LIB.BASEBOARD_FAB2(SCH_1):GND
 118    GND VSS<56> @BASEBOARD_FAB2_LIB.BASEBOARD_FAB2(SCH_1):GND
 120    GND VSS<55> @BASEBOARD_FAB2_LIB.BASEBOARD_FAB2(SCH_1):GND
 123    GND VSS<54> @BASEBOARD_FAB2_LIB.BASEBOARD_FAB2(SCH_1):GND
 125    GND VSS<53> @BASEBOARD_FAB2_LIB.BASEBOARD_FAB2(SCH_1):GND
 127    GND VSS<52> @BASEBOARD_FAB2_LIB.BASEBOARD_FAB2(SCH_1):GND
 129    GND VSS<51> @BASEBOARD_FAB2_LIB.BASEBOARD_FAB2(SCH_1):GND
 131    GND VSS<50> @BASEBOARD_FAB2_LIB.BASEBOARD_FAB2(SCH_1):GND
 134    GND VSS<49> @BASEBOARD_FAB2_LIB.BASEBOARD_FAB2(SCH_1):GND
 136    GND VSS<48> @BASEBOARD_FAB2_LIB.BASEBOARD_FAB2(SCH_1):GND
 138    GND VSS<47> @BASEBOARD_FAB2_LIB.BASEBOARD_FAB2(SCH_1):GND
 147    GND VSS<46> @BASEBOARD_FAB2_LIB.BASEBOARD_FAB2(SCH_1):GND
 149    GND VSS<45> @BASEBOARD_FAB2_LIB.BASEBOARD_FAB2(SCH_1):GND
 151    GND VSS<44> @BASEBOARD_FAB2_LIB.BASEBOARD_FAB2(SCH_1):GND
 154    GND VSS<43> @BASEBOARD_FAB2_LIB.BASEBOARD_FAB2(SCH_1):GND
 156    GND VSS<42> @BASEBOARD_FAB2_LIB.BASEBOARD_FAB2(SCH_1):GND
 158    GND VSS<41> @BASEBOARD_FAB2_LIB.BASEBOARD_FAB2(SCH_1):GND
 160    GND VSS<40> @BASEBOARD_FAB2_LIB.BASEBOARD_FAB2(SCH_1):GND
 162    GND VSS<39> @BASEBOARD_FAB2_LIB.BASEBOARD_FAB2(SCH_1):GND
 165    GND VSS<38> @BASEBOARD_FAB2_LIB.BASEBOARD_FAB2(SCH_1):GND
 167    GND VSS<37> @BASEBOARD_FAB2_LIB.BASEBOARD_FAB2(SCH_1):GND
 169    GND VSS<36> @BASEBOARD_FAB2_LIB.BASEBOARD_FAB2(SCH_1):GND
 171    GND VSS<35> @BASEBOARD_FAB2_LIB.BASEBOARD_FAB2(SCH_1):GND
 173    GND VSS<34> @BASEBOARD_FAB2_LIB.BASEBOARD_FAB2(SCH_1):GND
 176    GND VSS<33> @BASEBOARD_FAB2_LIB.BASEBOARD_FAB2(SCH_1):GND
 178    GND VSS<32> @BASEBOARD_FAB2_LIB.BASEBOARD_FAB2(SCH_1):GND
 180    GND VSS<31> @BASEBOARD_FAB2_LIB.BASEBOARD_FAB2(SCH_1):GND
 182    GND VSS<30> @BASEBOARD_FAB2_LIB.BASEBOARD_FAB2(SCH_1):GND
 184    GND VSS<29> @BASEBOARD_FAB2_LIB.BASEBOARD_FAB2(SCH_1):GND
 187    GND VSS<28> @BASEBOARD_FAB2_LIB.BASEBOARD_FAB2(SCH_1):GND
 189    GND VSS<27> @BASEBOARD_FAB2_LIB.BASEBOARD_FAB2(SCH_1):GND
 191    GND VSS<26> @BASEBOARD_FAB2_LIB.BASEBOARD_FAB2(SCH_1):GND
 193    GND VSS<25> @BASEBOARD_FAB2_LIB.BASEBOARD_FAB2(SCH_1):GND
 195    GND VSS<24> @BASEBOARD_FAB2_LIB.BASEBOARD_FAB2(SCH_1):GND
 198    GND VSS<23> @BASEBOARD_FAB2_LIB.BASEBOARD_FAB2(SCH_1):GND
 200    GND VSS<22> @BASEBOARD_FAB2_LIB.BASEBOARD_FAB2(SCH_1):GND
 202    GND VSS<21> @BASEBOARD_FAB2_LIB.BASEBOARD_FAB2(SCH_1):GND
 239    GND VSS<20> @BASEBOARD_FAB2_LIB.BASEBOARD_FAB2(SCH_1):GND
 241    GND VSS<19> @BASEBOARD_FAB2_LIB.BASEBOARD_FAB2(SCH_1):GND
 243    GND VSS<18> @BASEBOARD_FAB2_LIB.BASEBOARD_FAB2(SCH_1):GND
 246    GND VSS<17> @BASEBOARD_FAB2_LIB.BASEBOARD_FAB2(SCH_1):GND
 248    GND VSS<16> @BASEBOARD_FAB2_LIB.BASEBOARD_FAB2(SCH_1):GND
 250    GND VSS<15> @BASEBOARD_FAB2_LIB.BASEBOARD_FAB2(SCH_1):GND
 252    GND VSS<14> @BASEBOARD_FAB2_LIB.BASEBOARD_FAB2(SCH_1):GND
 254    GND VSS<13> @BASEBOARD_FAB2_LIB.BASEBOARD_FAB2(SCH_1):GND
 257    GND VSS<12> @BASEBOARD_FAB2_LIB.BASEBOARD_FAB2(SCH_1):GND
 259    GND VSS<11> @BASEBOARD_FAB2_LIB.BASEBOARD_FAB2(SCH_1):GND
 261    GND VSS<10> @BASEBOARD_FAB2_LIB.BASEBOARD_FAB2(SCH_1):GND
 263    GND VSS<9> @BASEBOARD_FAB2_LIB.BASEBOARD_FAB2(SCH_1):GND
 265    GND VSS<8> @BASEBOARD_FAB2_LIB.BASEBOARD_FAB2(SCH_1):GND
 268    GND VSS<7> @BASEBOARD_FAB2_LIB.BASEBOARD_FAB2(SCH_1):GND
 270    GND VSS<6> @BASEBOARD_FAB2_LIB.BASEBOARD_FAB2(SCH_1):GND
 272    GND VSS<5> @BASEBOARD_FAB2_LIB.BASEBOARD_FAB2(SCH_1):GND
 274    GND VSS<4> @BASEBOARD_FAB2_LIB.BASEBOARD_FAB2(SCH_1):GND
 276    GND VSS<3> @BASEBOARD_FAB2_LIB.BASEBOARD_FAB2(SCH_1):GND
 279    GND VSS<2> @BASEBOARD_FAB2_LIB.BASEBOARD_FAB2(SCH_1):GND
 281    GND VSS<1> @BASEBOARD_FAB2_LIB.BASEBOARD_FAB2(SCH_1):GND
 283    GND VSS<0> @BASEBOARD_FAB2_LIB.BASEBOARD_FAB2(SCH_1):GND

SCONN288_H44441003_PIP-SCONN,HA  I66  J6L1
 152 M_F_DQS_DN<0>  DQS0N @BASEBOARD_FAB2_LIB.BASEBOARD_FAB2(SCH_1):M_F_DQS_DN(0)
 153 M_F_DQS_DP<0>  DQS0P @BASEBOARD_FAB2_LIB.BASEBOARD_FAB2(SCH_1):M_F_DQS_DP(0)
  19 M_F_DQS_DN<10> DQS10N @BASEBOARD_FAB2_LIB.BASEBOARD_FAB2(SCH_1):M_F_DQS_DN(10)
  18 M_F_DQS_DP<10> DQS10P @BASEBOARD_FAB2_LIB.BASEBOARD_FAB2(SCH_1):M_F_DQS_DP(10)
  30 M_F_DQS_DN<11> DQS11N @BASEBOARD_FAB2_LIB.BASEBOARD_FAB2(SCH_1):M_F_DQS_DN(11)
  29 M_F_DQS_DP<11> DQS11P @BASEBOARD_FAB2_LIB.BASEBOARD_FAB2(SCH_1):M_F_DQS_DP(11)
  41 M_F_DQS_DN<12> DQS12N @BASEBOARD_FAB2_LIB.BASEBOARD_FAB2(SCH_1):M_F_DQS_DN(12)
  40 M_F_DQS_DP<12> DQS12P @BASEBOARD_FAB2_LIB.BASEBOARD_FAB2(SCH_1):M_F_DQS_DP(12)
 100 M_F_DQS_DN<13> DQS13N @BASEBOARD_FAB2_LIB.BASEBOARD_FAB2(SCH_1):M_F_DQS_DN(13)
  99 M_F_DQS_DP<13> DQS13P @BASEBOARD_FAB2_LIB.BASEBOARD_FAB2(SCH_1):M_F_DQS_DP(13)
 111 M_F_DQS_DN<14> DQS14N @BASEBOARD_FAB2_LIB.BASEBOARD_FAB2(SCH_1):M_F_DQS_DN(14)
 110 M_F_DQS_DP<14> DQS14P @BASEBOARD_FAB2_LIB.BASEBOARD_FAB2(SCH_1):M_F_DQS_DP(14)
 122 M_F_DQS_DN<15> DQS15N @BASEBOARD_FAB2_LIB.BASEBOARD_FAB2(SCH_1):M_F_DQS_DN(15)
 121 M_F_DQS_DP<15> DQS15P @BASEBOARD_FAB2_LIB.BASEBOARD_FAB2(SCH_1):M_F_DQS_DP(15)
 133 M_F_DQS_DN<16> DQS16N @BASEBOARD_FAB2_LIB.BASEBOARD_FAB2(SCH_1):M_F_DQS_DN(16)
 132 M_F_DQS_DP<16> DQS16P @BASEBOARD_FAB2_LIB.BASEBOARD_FAB2(SCH_1):M_F_DQS_DP(16)
  52 M_F_DQS_DN<17> DQS17N @BASEBOARD_FAB2_LIB.BASEBOARD_FAB2(SCH_1):M_F_DQS_DN(17)
  51 M_F_DQS_DP<17> DQS17P @BASEBOARD_FAB2_LIB.BASEBOARD_FAB2(SCH_1):M_F_DQS_DP(17)
 163 M_F_DQS_DN<1>  DQS1N @BASEBOARD_FAB2_LIB.BASEBOARD_FAB2(SCH_1):M_F_DQS_DN(1)
 164 M_F_DQS_DP<1>  DQS1P @BASEBOARD_FAB2_LIB.BASEBOARD_FAB2(SCH_1):M_F_DQS_DP(1)
 174 M_F_DQS_DN<2>  DQS2N @BASEBOARD_FAB2_LIB.BASEBOARD_FAB2(SCH_1):M_F_DQS_DN(2)
 175 M_F_DQS_DP<2>  DQS2P @BASEBOARD_FAB2_LIB.BASEBOARD_FAB2(SCH_1):M_F_DQS_DP(2)
 185 M_F_DQS_DN<3>  DQS3N @BASEBOARD_FAB2_LIB.BASEBOARD_FAB2(SCH_1):M_F_DQS_DN(3)
 186 M_F_DQS_DP<3>  DQS3P @BASEBOARD_FAB2_LIB.BASEBOARD_FAB2(SCH_1):M_F_DQS_DP(3)
 244 M_F_DQS_DN<4>  DQS4N @BASEBOARD_FAB2_LIB.BASEBOARD_FAB2(SCH_1):M_F_DQS_DN(4)
 245 M_F_DQS_DP<4>  DQS4P @BASEBOARD_FAB2_LIB.BASEBOARD_FAB2(SCH_1):M_F_DQS_DP(4)
 255 M_F_DQS_DN<5>  DQS5N @BASEBOARD_FAB2_LIB.BASEBOARD_FAB2(SCH_1):M_F_DQS_DN(5)
 256 M_F_DQS_DP<5>  DQS5P @BASEBOARD_FAB2_LIB.BASEBOARD_FAB2(SCH_1):M_F_DQS_DP(5)
 266 M_F_DQS_DN<6>  DQS6N @BASEBOARD_FAB2_LIB.BASEBOARD_FAB2(SCH_1):M_F_DQS_DN(6)
 267 M_F_DQS_DP<6>  DQS6P @BASEBOARD_FAB2_LIB.BASEBOARD_FAB2(SCH_1):M_F_DQS_DP(6)
 277 M_F_DQS_DN<7>  DQS7N @BASEBOARD_FAB2_LIB.BASEBOARD_FAB2(SCH_1):M_F_DQS_DN(7)
 278 M_F_DQS_DP<7>  DQS7P @BASEBOARD_FAB2_LIB.BASEBOARD_FAB2(SCH_1):M_F_DQS_DP(7)
 196 M_F_DQS_DN<8>  DQS8N @BASEBOARD_FAB2_LIB.BASEBOARD_FAB2(SCH_1):M_F_DQS_DN(8)
 197 M_F_DQS_DP<8>  DQS8P @BASEBOARD_FAB2_LIB.BASEBOARD_FAB2(SCH_1):M_F_DQS_DP(8)
   8 M_F_DQS_DN<9>  DQS9N @BASEBOARD_FAB2_LIB.BASEBOARD_FAB2(SCH_1):M_F_DQS_DN(9)
   7 M_F_DQS_DP<9>  DQS9P @BASEBOARD_FAB2_LIB.BASEBOARD_FAB2(SCH_1):M_F_DQS_DP(9)

SCONN288_H44441003_PIP-SCONN,HA  I111  J6L1
  79 M_F_MA<0>     A0 @BASEBOARD_FAB2_LIB.BASEBOARD_FAB2(SCH_1):M_F_MA(0)
  72 M_F_MA<1>     A1 @BASEBOARD_FAB2_LIB.BASEBOARD_FAB2(SCH_1):M_F_MA(1)
 225 M_F_MA<10>    A10 @BASEBOARD_FAB2_LIB.BASEBOARD_FAB2(SCH_1):M_F_MA(10)
 210 M_F_MA<11>    A11 @BASEBOARD_FAB2_LIB.BASEBOARD_FAB2(SCH_1):M_F_MA(11)
  65 M_F_MA<12>    A12 @BASEBOARD_FAB2_LIB.BASEBOARD_FAB2(SCH_1):M_F_MA(12)
 232 M_F_MA<13>    A13 @BASEBOARD_FAB2_LIB.BASEBOARD_FAB2(SCH_1):M_F_MA(13)
 228 M_F_MA<14> A14_WE_N @BASEBOARD_FAB2_LIB.BASEBOARD_FAB2(SCH_1):M_F_MA(14)
  86 M_F_MA<15> A15_CAS_N @BASEBOARD_FAB2_LIB.BASEBOARD_FAB2(SCH_1):M_F_MA(15)
  82 M_F_MA<16> A16_RAS_N @BASEBOARD_FAB2_LIB.BASEBOARD_FAB2(SCH_1):M_F_MA(16)
 234 M_F_MA<17>    A17 @BASEBOARD_FAB2_LIB.BASEBOARD_FAB2(SCH_1):M_F_MA(17)
 216 M_F_MA<2>     A2 @BASEBOARD_FAB2_LIB.BASEBOARD_FAB2(SCH_1):M_F_MA(2)
  71 M_F_MA<3>     A3 @BASEBOARD_FAB2_LIB.BASEBOARD_FAB2(SCH_1):M_F_MA(3)
 214 M_F_MA<4>     A4 @BASEBOARD_FAB2_LIB.BASEBOARD_FAB2(SCH_1):M_F_MA(4)
 213 M_F_MA<5>     A5 @BASEBOARD_FAB2_LIB.BASEBOARD_FAB2(SCH_1):M_F_MA(5)
  69 M_F_MA<6>     A6 @BASEBOARD_FAB2_LIB.BASEBOARD_FAB2(SCH_1):M_F_MA(6)
 211 M_F_MA<7>     A7 @BASEBOARD_FAB2_LIB.BASEBOARD_FAB2(SCH_1):M_F_MA(7)
  68 M_F_MA<8>     A8 @BASEBOARD_FAB2_LIB.BASEBOARD_FAB2(SCH_1):M_F_MA(8)
  66 M_F_MA<9>     A9 @BASEBOARD_FAB2_LIB.BASEBOARD_FAB2(SCH_1):M_F_MA(9)
  62 M_F_ACT_N  ACT_N @BASEBOARD_FAB2_LIB.BASEBOARD_FAB2(SCH_1):M_F_ACT_N
 208 M_F_ALERT_N ALERT_N @BASEBOARD_FAB2_LIB.BASEBOARD_FAB2(SCH_1):M_F_ALERT_N
 224 M_F_BA<1>  BA<1> @BASEBOARD_FAB2_LIB.BASEBOARD_FAB2(SCH_1):M_F_BA(1)
  81 M_F_BA<0>  BA<0> @BASEBOARD_FAB2_LIB.BASEBOARD_FAB2(SCH_1):M_F_BA(0)
 207 M_F_BG<1>  BG<1> @BASEBOARD_FAB2_LIB.BASEBOARD_FAB2(SCH_1):M_F_BG(1)
  63 M_F_BG<0>  BG<0> @BASEBOARD_FAB2_LIB.BASEBOARD_FAB2(SCH_1):M_F_BG(0)
 235 M_F_C<2>   C<2> @BASEBOARD_FAB2_LIB.BASEBOARD_FAB2(SCH_1):M_F_C(2)
 199 M_F_ECC<7>  CB<7> @BASEBOARD_FAB2_LIB.BASEBOARD_FAB2(SCH_1):M_F_ECC(7)
  54 M_F_ECC<6>  CB<6> @BASEBOARD_FAB2_LIB.BASEBOARD_FAB2(SCH_1):M_F_ECC(6)
 192 M_F_ECC<5>  CB<5> @BASEBOARD_FAB2_LIB.BASEBOARD_FAB2(SCH_1):M_F_ECC(5)
  47 M_F_ECC<4>  CB<4> @BASEBOARD_FAB2_LIB.BASEBOARD_FAB2(SCH_1):M_F_ECC(4)
 201 M_F_ECC<3>  CB<3> @BASEBOARD_FAB2_LIB.BASEBOARD_FAB2(SCH_1):M_F_ECC(3)
  56 M_F_ECC<2>  CB<2> @BASEBOARD_FAB2_LIB.BASEBOARD_FAB2(SCH_1):M_F_ECC(2)
 194 M_F_ECC<1>  CB<1> @BASEBOARD_FAB2_LIB.BASEBOARD_FAB2(SCH_1):M_F_ECC(1)
  49 M_F_ECC<0>  CB<0> @BASEBOARD_FAB2_LIB.BASEBOARD_FAB2(SCH_1):M_F_ECC(0)
  75 M_F_CLK_DN<2>   CK0N @BASEBOARD_FAB2_LIB.BASEBOARD_FAB2(SCH_1):M_F_CLK_DN(2)
  74 M_F_CLK_DP<2>   CK0P @BASEBOARD_FAB2_LIB.BASEBOARD_FAB2(SCH_1):M_F_CLK_DP(2)
 219 M_F_CLK_DN<3>   CK1N @BASEBOARD_FAB2_LIB.BASEBOARD_FAB2(SCH_1):M_F_CLK_DN(3)
 218 M_F_CLK_DP<3>   CK1P @BASEBOARD_FAB2_LIB.BASEBOARD_FAB2(SCH_1):M_F_CLK_DP(3)
 203 M_F_CKE<3> CKE<1> @BASEBOARD_FAB2_LIB.BASEBOARD_FAB2(SCH_1):M_F_CKE(3)
  60 M_F_CKE<2> CKE<0> @BASEBOARD_FAB2_LIB.BASEBOARD_FAB2(SCH_1):M_F_CKE(2)
 280 M_F_DQ<63> DQ<63> @BASEBOARD_FAB2_LIB.BASEBOARD_FAB2(SCH_1):M_F_DQ(63)
 135 M_F_DQ<62> DQ<62> @BASEBOARD_FAB2_LIB.BASEBOARD_FAB2(SCH_1):M_F_DQ(62)
 273 M_F_DQ<61> DQ<61> @BASEBOARD_FAB2_LIB.BASEBOARD_FAB2(SCH_1):M_F_DQ(61)
 128 M_F_DQ<60> DQ<60> @BASEBOARD_FAB2_LIB.BASEBOARD_FAB2(SCH_1):M_F_DQ(60)
 282 M_F_DQ<59> DQ<59> @BASEBOARD_FAB2_LIB.BASEBOARD_FAB2(SCH_1):M_F_DQ(59)
 137 M_F_DQ<58> DQ<58> @BASEBOARD_FAB2_LIB.BASEBOARD_FAB2(SCH_1):M_F_DQ(58)
 275 M_F_DQ<57> DQ<57> @BASEBOARD_FAB2_LIB.BASEBOARD_FAB2(SCH_1):M_F_DQ(57)
 130 M_F_DQ<56> DQ<56> @BASEBOARD_FAB2_LIB.BASEBOARD_FAB2(SCH_1):M_F_DQ(56)
 269 M_F_DQ<55> DQ<55> @BASEBOARD_FAB2_LIB.BASEBOARD_FAB2(SCH_1):M_F_DQ(55)
 124 M_F_DQ<54> DQ<54> @BASEBOARD_FAB2_LIB.BASEBOARD_FAB2(SCH_1):M_F_DQ(54)
 262 M_F_DQ<53> DQ<53> @BASEBOARD_FAB2_LIB.BASEBOARD_FAB2(SCH_1):M_F_DQ(53)
 117 M_F_DQ<52> DQ<52> @BASEBOARD_FAB2_LIB.BASEBOARD_FAB2(SCH_1):M_F_DQ(52)
 271 M_F_DQ<51> DQ<51> @BASEBOARD_FAB2_LIB.BASEBOARD_FAB2(SCH_1):M_F_DQ(51)
 126 M_F_DQ<50> DQ<50> @BASEBOARD_FAB2_LIB.BASEBOARD_FAB2(SCH_1):M_F_DQ(50)
 264 M_F_DQ<49> DQ<49> @BASEBOARD_FAB2_LIB.BASEBOARD_FAB2(SCH_1):M_F_DQ(49)
 119 M_F_DQ<48> DQ<48> @BASEBOARD_FAB2_LIB.BASEBOARD_FAB2(SCH_1):M_F_DQ(48)
 258 M_F_DQ<47> DQ<47> @BASEBOARD_FAB2_LIB.BASEBOARD_FAB2(SCH_1):M_F_DQ(47)
 113 M_F_DQ<46> DQ<46> @BASEBOARD_FAB2_LIB.BASEBOARD_FAB2(SCH_1):M_F_DQ(46)
 251 M_F_DQ<45> DQ<45> @BASEBOARD_FAB2_LIB.BASEBOARD_FAB2(SCH_1):M_F_DQ(45)
 106 M_F_DQ<44> DQ<44> @BASEBOARD_FAB2_LIB.BASEBOARD_FAB2(SCH_1):M_F_DQ(44)
 260 M_F_DQ<43> DQ<43> @BASEBOARD_FAB2_LIB.BASEBOARD_FAB2(SCH_1):M_F_DQ(43)
 115 M_F_DQ<42> DQ<42> @BASEBOARD_FAB2_LIB.BASEBOARD_FAB2(SCH_1):M_F_DQ(42)
 253 M_F_DQ<41> DQ<41> @BASEBOARD_FAB2_LIB.BASEBOARD_FAB2(SCH_1):M_F_DQ(41)
 108 M_F_DQ<40> DQ<40> @BASEBOARD_FAB2_LIB.BASEBOARD_FAB2(SCH_1):M_F_DQ(40)
 247 M_F_DQ<39> DQ<39> @BASEBOARD_FAB2_LIB.BASEBOARD_FAB2(SCH_1):M_F_DQ(39)
 102 M_F_DQ<38> DQ<38> @BASEBOARD_FAB2_LIB.BASEBOARD_FAB2(SCH_1):M_F_DQ(38)
 240 M_F_DQ<37> DQ<37> @BASEBOARD_FAB2_LIB.BASEBOARD_FAB2(SCH_1):M_F_DQ(37)
  95 M_F_DQ<36> DQ<36> @BASEBOARD_FAB2_LIB.BASEBOARD_FAB2(SCH_1):M_F_DQ(36)
 249 M_F_DQ<35> DQ<35> @BASEBOARD_FAB2_LIB.BASEBOARD_FAB2(SCH_1):M_F_DQ(35)
 104 M_F_DQ<34> DQ<34> @BASEBOARD_FAB2_LIB.BASEBOARD_FAB2(SCH_1):M_F_DQ(34)
 242 M_F_DQ<33> DQ<33> @BASEBOARD_FAB2_LIB.BASEBOARD_FAB2(SCH_1):M_F_DQ(33)
  97 M_F_DQ<32> DQ<32> @BASEBOARD_FAB2_LIB.BASEBOARD_FAB2(SCH_1):M_F_DQ(32)
 188 M_F_DQ<31> DQ<31> @BASEBOARD_FAB2_LIB.BASEBOARD_FAB2(SCH_1):M_F_DQ(31)
  43 M_F_DQ<30> DQ<30> @BASEBOARD_FAB2_LIB.BASEBOARD_FAB2(SCH_1):M_F_DQ(30)
 181 M_F_DQ<29> DQ<29> @BASEBOARD_FAB2_LIB.BASEBOARD_FAB2(SCH_1):M_F_DQ(29)
  36 M_F_DQ<28> DQ<28> @BASEBOARD_FAB2_LIB.BASEBOARD_FAB2(SCH_1):M_F_DQ(28)
 190 M_F_DQ<27> DQ<27> @BASEBOARD_FAB2_LIB.BASEBOARD_FAB2(SCH_1):M_F_DQ(27)
  45 M_F_DQ<26> DQ<26> @BASEBOARD_FAB2_LIB.BASEBOARD_FAB2(SCH_1):M_F_DQ(26)
 183 M_F_DQ<25> DQ<25> @BASEBOARD_FAB2_LIB.BASEBOARD_FAB2(SCH_1):M_F_DQ(25)
  38 M_F_DQ<24> DQ<24> @BASEBOARD_FAB2_LIB.BASEBOARD_FAB2(SCH_1):M_F_DQ(24)
 177 M_F_DQ<23> DQ<23> @BASEBOARD_FAB2_LIB.BASEBOARD_FAB2(SCH_1):M_F_DQ(23)
  32 M_F_DQ<22> DQ<22> @BASEBOARD_FAB2_LIB.BASEBOARD_FAB2(SCH_1):M_F_DQ(22)
 170 M_F_DQ<21> DQ<21> @BASEBOARD_FAB2_LIB.BASEBOARD_FAB2(SCH_1):M_F_DQ(21)
  25 M_F_DQ<20> DQ<20> @BASEBOARD_FAB2_LIB.BASEBOARD_FAB2(SCH_1):M_F_DQ(20)
 179 M_F_DQ<19> DQ<19> @BASEBOARD_FAB2_LIB.BASEBOARD_FAB2(SCH_1):M_F_DQ(19)
  34 M_F_DQ<18> DQ<18> @BASEBOARD_FAB2_LIB.BASEBOARD_FAB2(SCH_1):M_F_DQ(18)
 172 M_F_DQ<17> DQ<17> @BASEBOARD_FAB2_LIB.BASEBOARD_FAB2(SCH_1):M_F_DQ(17)
  27 M_F_DQ<16> DQ<16> @BASEBOARD_FAB2_LIB.BASEBOARD_FAB2(SCH_1):M_F_DQ(16)
 166 M_F_DQ<15> DQ<15> @BASEBOARD_FAB2_LIB.BASEBOARD_FAB2(SCH_1):M_F_DQ(15)
  21 M_F_DQ<14> DQ<14> @BASEBOARD_FAB2_LIB.BASEBOARD_FAB2(SCH_1):M_F_DQ(14)
 159 M_F_DQ<13> DQ<13> @BASEBOARD_FAB2_LIB.BASEBOARD_FAB2(SCH_1):M_F_DQ(13)
  14 M_F_DQ<12> DQ<12> @BASEBOARD_FAB2_LIB.BASEBOARD_FAB2(SCH_1):M_F_DQ(12)
 168 M_F_DQ<11> DQ<11> @BASEBOARD_FAB2_LIB.BASEBOARD_FAB2(SCH_1):M_F_DQ(11)
  23 M_F_DQ<10> DQ<10> @BASEBOARD_FAB2_LIB.BASEBOARD_FAB2(SCH_1):M_F_DQ(10)
 161 M_F_DQ<9>  DQ<9> @BASEBOARD_FAB2_LIB.BASEBOARD_FAB2(SCH_1):M_F_DQ(9)
  16 M_F_DQ<8>  DQ<8> @BASEBOARD_FAB2_LIB.BASEBOARD_FAB2(SCH_1):M_F_DQ(8)
 155 M_F_DQ<7>  DQ<7> @BASEBOARD_FAB2_LIB.BASEBOARD_FAB2(SCH_1):M_F_DQ(7)
  10 M_F_DQ<6>  DQ<6> @BASEBOARD_FAB2_LIB.BASEBOARD_FAB2(SCH_1):M_F_DQ(6)
 148 M_F_DQ<5>  DQ<5> @BASEBOARD_FAB2_LIB.BASEBOARD_FAB2(SCH_1):M_F_DQ(5)
   3 M_F_DQ<4>  DQ<4> @BASEBOARD_FAB2_LIB.BASEBOARD_FAB2(SCH_1):M_F_DQ(4)
 157 M_F_DQ<3>  DQ<3> @BASEBOARD_FAB2_LIB.BASEBOARD_FAB2(SCH_1):M_F_DQ(3)
  12 M_F_DQ<2>  DQ<2> @BASEBOARD_FAB2_LIB.BASEBOARD_FAB2(SCH_1):M_F_DQ(2)
 150 M_F_DQ<1>  DQ<1> @BASEBOARD_FAB2_LIB.BASEBOARD_FAB2(SCH_1):M_F_DQ(1)
   5 M_F_DQ<0>  DQ<0> @BASEBOARD_FAB2_LIB.BASEBOARD_FAB2(SCH_1):M_F_DQ(0)
  78 FM_DIMM_EVENT_COD_N EVENT_N @BASEBOARD_FAB2_LIB.BASEBOARD_FAB2(SCH_1):FM_DIMM_EVENT_COD_N
  91 M_F_ODT<3> ODT<1> @BASEBOARD_FAB2_LIB.BASEBOARD_FAB2(SCH_1):M_F_ODT(3)
  87 M_F_ODT<2> ODT<0> @BASEBOARD_FAB2_LIB.BASEBOARD_FAB2(SCH_1):M_F_ODT(2)
 222 M_F_PAR    PAR @BASEBOARD_FAB2_LIB.BASEBOARD_FAB2(SCH_1):M_F_PAR
  58 M_DEF_RST_N RESET_N @BASEBOARD_FAB2_LIB.BASEBOARD_FAB2(SCH_1):M_DEF_RST_N
 144 TP_CH_F_DIMM_F1_RFU_2 RFU<2> @BASEBOARD_FAB2_LIB.BASEBOARD_FAB2(SCH_1):TP_CH_F_DIMM_F1_RFU_2
 227 TP_CH_F_DIMM_F1_RFU_1 RFU<1> @BASEBOARD_FAB2_LIB.BASEBOARD_FAB2(SCH_1):TP_CH_F_DIMM_F1_RFU_1
 205 TP_CH_F_DIMM_F1_RFU_0 RFU<0> @BASEBOARD_FAB2_LIB.BASEBOARD_FAB2(SCH_1):TP_CH_F_DIMM_F1_RFU_0
  84 M_F_CS_N<4>   S0_N @BASEBOARD_FAB2_LIB.BASEBOARD_FAB2(SCH_1):M_F_CS_N(4)
  89 M_F_CS_N<5>   S1_N @BASEBOARD_FAB2_LIB.BASEBOARD_FAB2(SCH_1):M_F_CS_N(5)
  93 M_F_CS_N<6> S2_N_C<0> @BASEBOARD_FAB2_LIB.BASEBOARD_FAB2(SCH_1):M_F_CS_N(6)
 237 M_F_CS_N<7> S3_N_C<1> @BASEBOARD_FAB2_LIB.BASEBOARD_FAB2(SCH_1):M_F_CS_N(7)
 238 PVPP_DEF  SA<2> @BASEBOARD_FAB2_LIB.BASEBOARD_FAB2(SCH_1):PVPP_DEF
 140    GND  SA<1> @BASEBOARD_FAB2_LIB.BASEBOARD_FAB2(SCH_1):GND
 139 PVPP_DEF  SA<0> @BASEBOARD_FAB2_LIB.BASEBOARD_FAB2(SCH_1):PVPP_DEF
 230 FM_ADR_COMPLETE_DEF_N SAVE_N_NC @BASEBOARD_FAB2_LIB.BASEBOARD_FAB2(SCH_1):FM_ADR_COMPLETE_DEF_N
 141 SMB_DDR_DEF_VPP_SCL    SCL @BASEBOARD_FAB2_LIB.BASEBOARD_FAB2(SCH_1):SMB_DDR_DEF_VPP_SCL
 285 SMB_DDR_DEF_VPP_SDA    SDA @BASEBOARD_FAB2_LIB.BASEBOARD_FAB2(SCH_1):SMB_DDR_DEF_VPP_SDA
 284 PVPP_DEF VDDSPD @BASEBOARD_FAB2_LIB.BASEBOARD_FAB2(SCH_1):PVPP_DEF
 146 M_F_VREF VREFCA @BASEBOARD_FAB2_LIB.BASEBOARD_FAB2(SCH_1):M_F_VREF

SCONN288_H44441003_PIP-SCONN,HA  I170  J6L1
   1 P12V_NVDIMM_DEF 12V<1> @BASEBOARD_FAB2_LIB.BASEBOARD_FAB2(SCH_1):P12V_NVDIMM_DEF
 145 P12V_NVDIMM_DEF 12V<0> @BASEBOARD_FAB2_LIB.BASEBOARD_FAB2(SCH_1):P12V_NVDIMM_DEF
  59 PVDDQ_DEF VDD<25> @BASEBOARD_FAB2_LIB.BASEBOARD_FAB2(SCH_1):PVDDQ_DEF
  61 PVDDQ_DEF VDD<24> @BASEBOARD_FAB2_LIB.BASEBOARD_FAB2(SCH_1):PVDDQ_DEF
  64 PVDDQ_DEF VDD<23> @BASEBOARD_FAB2_LIB.BASEBOARD_FAB2(SCH_1):PVDDQ_DEF
  67 PVDDQ_DEF VDD<22> @BASEBOARD_FAB2_LIB.BASEBOARD_FAB2(SCH_1):PVDDQ_DEF
  70 PVDDQ_DEF VDD<21> @BASEBOARD_FAB2_LIB.BASEBOARD_FAB2(SCH_1):PVDDQ_DEF
  73 PVDDQ_DEF VDD<20> @BASEBOARD_FAB2_LIB.BASEBOARD_FAB2(SCH_1):PVDDQ_DEF
  76 PVDDQ_DEF VDD<19> @BASEBOARD_FAB2_LIB.BASEBOARD_FAB2(SCH_1):PVDDQ_DEF
  80 PVDDQ_DEF VDD<18> @BASEBOARD_FAB2_LIB.BASEBOARD_FAB2(SCH_1):PVDDQ_DEF
  83 PVDDQ_DEF VDD<17> @BASEBOARD_FAB2_LIB.BASEBOARD_FAB2(SCH_1):PVDDQ_DEF
  85 PVDDQ_DEF VDD<16> @BASEBOARD_FAB2_LIB.BASEBOARD_FAB2(SCH_1):PVDDQ_DEF
  88 PVDDQ_DEF VDD<15> @BASEBOARD_FAB2_LIB.BASEBOARD_FAB2(SCH_1):PVDDQ_DEF
  90 PVDDQ_DEF VDD<14> @BASEBOARD_FAB2_LIB.BASEBOARD_FAB2(SCH_1):PVDDQ_DEF
  92 PVDDQ_DEF VDD<13> @BASEBOARD_FAB2_LIB.BASEBOARD_FAB2(SCH_1):PVDDQ_DEF
 204 PVDDQ_DEF VDD<12> @BASEBOARD_FAB2_LIB.BASEBOARD_FAB2(SCH_1):PVDDQ_DEF
 206 PVDDQ_DEF VDD<11> @BASEBOARD_FAB2_LIB.BASEBOARD_FAB2(SCH_1):PVDDQ_DEF
 209 PVDDQ_DEF VDD<10> @BASEBOARD_FAB2_LIB.BASEBOARD_FAB2(SCH_1):PVDDQ_DEF
 212 PVDDQ_DEF VDD<9> @BASEBOARD_FAB2_LIB.BASEBOARD_FAB2(SCH_1):PVDDQ_DEF
 215 PVDDQ_DEF VDD<8> @BASEBOARD_FAB2_LIB.BASEBOARD_FAB2(SCH_1):PVDDQ_DEF
 217 PVDDQ_DEF VDD<7> @BASEBOARD_FAB2_LIB.BASEBOARD_FAB2(SCH_1):PVDDQ_DEF
 220 PVDDQ_DEF VDD<6> @BASEBOARD_FAB2_LIB.BASEBOARD_FAB2(SCH_1):PVDDQ_DEF
 223 PVDDQ_DEF VDD<5> @BASEBOARD_FAB2_LIB.BASEBOARD_FAB2(SCH_1):PVDDQ_DEF
 226 PVDDQ_DEF VDD<4> @BASEBOARD_FAB2_LIB.BASEBOARD_FAB2(SCH_1):PVDDQ_DEF
 229 PVDDQ_DEF VDD<3> @BASEBOARD_FAB2_LIB.BASEBOARD_FAB2(SCH_1):PVDDQ_DEF
 231 PVDDQ_DEF VDD<2> @BASEBOARD_FAB2_LIB.BASEBOARD_FAB2(SCH_1):PVDDQ_DEF
 233 PVDDQ_DEF VDD<1> @BASEBOARD_FAB2_LIB.BASEBOARD_FAB2(SCH_1):PVDDQ_DEF
 236 PVDDQ_DEF VDD<0> @BASEBOARD_FAB2_LIB.BASEBOARD_FAB2(SCH_1):PVDDQ_DEF
 142 PVPP_DEF VPP<4> @BASEBOARD_FAB2_LIB.BASEBOARD_FAB2(SCH_1):PVPP_DEF
 143 PVPP_DEF VPP<3> @BASEBOARD_FAB2_LIB.BASEBOARD_FAB2(SCH_1):PVPP_DEF
 288 PVPP_DEF VPP<2> @BASEBOARD_FAB2_LIB.BASEBOARD_FAB2(SCH_1):PVPP_DEF
 286 PVPP_DEF VPP<1> @BASEBOARD_FAB2_LIB.BASEBOARD_FAB2(SCH_1):PVPP_DEF
 287 PVPP_DEF VPP<0> @BASEBOARD_FAB2_LIB.BASEBOARD_FAB2(SCH_1):PVPP_DEF
  77 PVTT_DEF VTT<1> @BASEBOARD_FAB2_LIB.BASEBOARD_FAB2(SCH_1):PVTT_DEF
 221 PVTT_DEF VTT<0> @BASEBOARD_FAB2_LIB.BASEBOARD_FAB2(SCH_1):PVTT_DEF

CAP_A_0402V-0.01UF,25V,10%,X7RA  I179  C4A5
   1 M_F_VREF      A @BASEBOARD_FAB2_LIB.BASEBOARD_FAB2(SCH_1):M_F_VREF
   2    GND      B @BASEBOARD_FAB2_LIB.BASEBOARD_FAB2(SCH_1):GND


DRAWING: @BASEBOARD_FAB2_LIB.BASEBOARD_FAB2(SCH_1):PAGE55 

RES_0402-49.9,1%,1/16W,CHIP,G2A  I4  R9N1
   1 PVCCIO_CPU1      A @BASEBOARD_FAB2_LIB.BASEBOARD_FAB2(SCH_1):PVCCIO_CPU1
   2 SVID_ALERT1_CPU1_R_N      B @BASEBOARD_FAB2_LIB.BASEBOARD_FAB2(SCH_1):SVID_ALERT1_CPU1_R_N

RES_0402-100.0,1%,1/16W,CHIP,GA  I7  R9N2
   1 PVCCIO_CPU1      A @BASEBOARD_FAB2_LIB.BASEBOARD_FAB2(SCH_1):PVCCIO_CPU1
   2 SVID_DIO1_CPU1_R      B @BASEBOARD_FAB2_LIB.BASEBOARD_FAB2(SCH_1):SVID_DIO1_CPU1_R

RES_0402-49.9,1%,1/16W,CHIP,G2A  I19  R3B2
   1 SVID_ALERT0_CPU1_R_N      A @BASEBOARD_FAB2_LIB.BASEBOARD_FAB2(SCH_1):SVID_ALERT0_CPU1_R_N
   2 PVCCIO_CPU1      B @BASEBOARD_FAB2_LIB.BASEBOARD_FAB2(SCH_1):PVCCIO_CPU1

RES_0402-100.0,1%,1/16W,CHIP,GA  I21  R3B4
   1 SVID_DIO0_CPU1_R      A @BASEBOARD_FAB2_LIB.BASEBOARD_FAB2(SCH_1):SVID_DIO0_CPU1_R
   2 PVCCIO_CPU1      B @BASEBOARD_FAB2_LIB.BASEBOARD_FAB2(SCH_1):PVCCIO_CPU1

RES_0402-0.0,5%,1/16W,CHIP,G21A  I24  R1C2
   1 SVID_DIO1_CPU1      A @BASEBOARD_FAB2_LIB.BASEBOARD_FAB2(SCH_1):SVID_DIO1_CPU1
   2 SVID_DIO1_CPU1_R      B @BASEBOARD_FAB2_LIB.BASEBOARD_FAB2(SCH_1):SVID_DIO1_CPU1_R

RES_0402-0.0,5%,1/16W,CHIP,G21A  I25  R1C3
   1 SVID_CLK1_CPU1      A @BASEBOARD_FAB2_LIB.BASEBOARD_FAB2(SCH_1):SVID_CLK1_CPU1
   2 SVID_CLK1_CPU1_R      B @BASEBOARD_FAB2_LIB.BASEBOARD_FAB2(SCH_1):SVID_CLK1_CPU1_R

RES_0402-221,1.0%,1/16W,CHIP,GA  I26  R1C1
   1 SVID_ALERT1_CPU1_N      A @BASEBOARD_FAB2_LIB.BASEBOARD_FAB2(SCH_1):SVID_ALERT1_CPU1_N
   2 SVID_ALERT1_CPU1_R_N      B @BASEBOARD_FAB2_LIB.BASEBOARD_FAB2(SCH_1):SVID_ALERT1_CPU1_R_N

RES_0402-221,1.0%,1/16W,CHIP,GA  I27  R3B1
   1 SVID_ALERT0_CPU1_N      A @BASEBOARD_FAB2_LIB.BASEBOARD_FAB2(SCH_1):SVID_ALERT0_CPU1_N
   2 SVID_ALERT0_CPU1_R_N      B @BASEBOARD_FAB2_LIB.BASEBOARD_FAB2(SCH_1):SVID_ALERT0_CPU1_R_N

RES_0402-0.0,5%,1/16W,CHIP,G21A  I28  R3B5
   1 SVID_CLK0_CPU1      A @BASEBOARD_FAB2_LIB.BASEBOARD_FAB2(SCH_1):SVID_CLK0_CPU1
   2 SVID_CLK0_CPU1_R      B @BASEBOARD_FAB2_LIB.BASEBOARD_FAB2(SCH_1):SVID_CLK0_CPU1_R

RES_0402-0.0,5%,1/16W,CHIP,G21A  I29  R3B3
   1 SVID_DIO0_CPU1      A @BASEBOARD_FAB2_LIB.BASEBOARD_FAB2(SCH_1):SVID_DIO0_CPU1
   2 SVID_DIO0_CPU1_R      B @BASEBOARD_FAB2_LIB.BASEBOARD_FAB2(SCH_1):SVID_DIO0_CPU1_R

RES_0402-100.0,1%,1/16W,CHIP,GA  I115  R7P19
   1 A_CPU1_GHJ_RCOMP2      A @BASEBOARD_FAB2_LIB.BASEBOARD_FAB2(SCH_1):A_CPU1_GHJ_RCOMP2
   2    GND      B @BASEBOARD_FAB2_LIB.BASEBOARD_FAB2(SCH_1):GND

RES_0402-90.9,1%,1/16W,CHIP,G2A  I116  R3D1
   1 A_CPU1_KLM_RCOMP0      A @BASEBOARD_FAB2_LIB.BASEBOARD_FAB2(SCH_1):A_CPU1_KLM_RCOMP0
   2    GND      B @BASEBOARD_FAB2_LIB.BASEBOARD_FAB2(SCH_1):GND

RES_0402-90.9,1%,1/16W,CHIP,G2A  I117  R3D2
   1 A_CPU1_KLM_RCOMP1      A @BASEBOARD_FAB2_LIB.BASEBOARD_FAB2(SCH_1):A_CPU1_KLM_RCOMP1
   2    GND      B @BASEBOARD_FAB2_LIB.BASEBOARD_FAB2(SCH_1):GND

RES_0402-100.0,1%,1/16W,CHIP,GA  I118  R3D3
   1 A_CPU1_KLM_RCOMP2      A @BASEBOARD_FAB2_LIB.BASEBOARD_FAB2(SCH_1):A_CPU1_KLM_RCOMP2
   2    GND      B @BASEBOARD_FAB2_LIB.BASEBOARD_FAB2(SCH_1):GND

RES_0402-90.9,1%,1/16W,CHIP,G2A  I119  R7P16
   1 A_CPU1_GHJ_RCOMP0      A @BASEBOARD_FAB2_LIB.BASEBOARD_FAB2(SCH_1):A_CPU1_GHJ_RCOMP0
   2    GND      B @BASEBOARD_FAB2_LIB.BASEBOARD_FAB2(SCH_1):GND

RES_0402-49.9,1%,1/16W,CHIP,G2A  I123  R7P8
   1 A_CPU1_PE3_RBIAS      A @BASEBOARD_FAB2_LIB.BASEBOARD_FAB2(SCH_1):A_CPU1_PE3_RBIAS
   2    GND      B @BASEBOARD_FAB2_LIB.BASEBOARD_FAB2(SCH_1):GND

RES_0402-49.9,1%,1/16W,CHIP,G2A  I124  R7P10
   1 A_CPU1_PE012_RBIAS      A @BASEBOARD_FAB2_LIB.BASEBOARD_FAB2(SCH_1):A_CPU1_PE012_RBIAS
   2    GND      B @BASEBOARD_FAB2_LIB.BASEBOARD_FAB2(SCH_1):GND

RES_0402-49.9,1%,1/16W,CHIP,G2A  I125  R3D19
   1 A_CPU1_UPI01_RBIAS      A @BASEBOARD_FAB2_LIB.BASEBOARD_FAB2(SCH_1):A_CPU1_UPI01_RBIAS
   2    GND      B @BASEBOARD_FAB2_LIB.BASEBOARD_FAB2(SCH_1):GND

RES_0402-49.9,1%,1/16W,CHIP,G2A  I126  R7P11
   1 A_CPU1_UPI2_RBIAS      A @BASEBOARD_FAB2_LIB.BASEBOARD_FAB2(SCH_1):A_CPU1_UPI2_RBIAS
   2    GND      B @BASEBOARD_FAB2_LIB.BASEBOARD_FAB2(SCH_1):GND

RES_0402-90.9,1%,1/16W,CHIP,G2A  I140  R7P17
   1 A_CPU1_GHJ_RCOMP1      A @BASEBOARD_FAB2_LIB.BASEBOARD_FAB2(SCH_1):A_CPU1_GHJ_RCOMP1
   2    GND      B @BASEBOARD_FAB2_LIB.BASEBOARD_FAB2(SCH_1):GND

SOCKET_P_MECH_A_RIGHT-P0,PLASTA  I152  XRU2
SOCKET_P_MECH_A_LEFT-P0,PLASTIA  I153  XLU2
RES_0402-49.9,1%,1/16W,CHIP,G2A  I155  R3D4
   1 A_CPU1_MCP01_RBIAS      A @BASEBOARD_FAB2_LIB.BASEBOARD_FAB2(SCH_1):A_CPU1_MCP01_RBIAS
   2    GND      B @BASEBOARD_FAB2_LIB.BASEBOARD_FAB2(SCH_1):GND

RES_0402-49.9,1%,1/16W,CHIP,G2A  I156  R7P26
   1 H_PMSYNC_CLK_24M_CPU1      A @BASEBOARD_FAB2_LIB.BASEBOARD_FAB2(SCH_1):H_PMSYNC_CLK_24M_CPU1
   2 H_PMSYNC_CLK_24M      B @BASEBOARD_FAB2_LIB.BASEBOARD_FAB2(SCH_1):H_PMSYNC_CLK_24M

RES_0402-1.8K,1%,1/16W,CHIP,G2A  I157  R8N1
   1 P3V3_STBY      A @BASEBOARD_FAB2_LIB.BASEBOARD_FAB2(SCH_1):P3V3_STBY
   2 FM_CPU1_PROC_ID1      B @BASEBOARD_FAB2_LIB.BASEBOARD_FAB2(SCH_1):FM_CPU1_PROC_ID1

RES_0402-1.8K,1%,1/16W,CHIP,G2A  I158  R8N4
   1 P3V3_STBY      A @BASEBOARD_FAB2_LIB.BASEBOARD_FAB2(SCH_1):P3V3_STBY
   2 FM_CPU1_PROC_ID0      B @BASEBOARD_FAB2_LIB.BASEBOARD_FAB2(SCH_1):FM_CPU1_PROC_ID0

RES_0402-10.0K,1%,1/16W,CHIP,GA  I159  R8N3
   1 P3V3_STBY      A @BASEBOARD_FAB2_LIB.BASEBOARD_FAB2(SCH_1):P3V3_STBY
   2 FM_CPU1_PKGID2      B @BASEBOARD_FAB2_LIB.BASEBOARD_FAB2(SCH_1):FM_CPU1_PKGID2

RES_0402-10.0K,1%,1/16W,CHIP,GA  I160  R8N5
   1 P3V3_STBY      A @BASEBOARD_FAB2_LIB.BASEBOARD_FAB2(SCH_1):P3V3_STBY
   2 FM_CPU1_PKGID1      B @BASEBOARD_FAB2_LIB.BASEBOARD_FAB2(SCH_1):FM_CPU1_PKGID1

RES_0402-10.0K,1%,1/16W,CHIP,GA  I161  R8N2
   1 P3V3_STBY      A @BASEBOARD_FAB2_LIB.BASEBOARD_FAB2(SCH_1):P3V3_STBY
   2 FM_CPU1_PKGID0      B @BASEBOARD_FAB2_LIB.BASEBOARD_FAB2(SCH_1):FM_CPU1_PKGID0

RES_0402-49.9,1%,1/16W,CHIP,G2A  I170  R7P25
   1 H_PM_SYNC_GTL_R2      A @BASEBOARD_FAB2_LIB.BASEBOARD_FAB2(SCH_1):H_PM_SYNC_GTL_R2
   2 H_PM_SYNC_GTL      B @BASEBOARD_FAB2_LIB.BASEBOARD_FAB2(SCH_1):H_PM_SYNC_GTL

SKX_EXT_B_BGA1-IC,TBD  I172  U2D1
AU24 CLK_100M_CPU1_BCLK0_DN BCLK0_DN @BASEBOARD_FAB2_LIB.BASEBOARD_FAB2(SCH_1):CLK_100M_CPU1_BCLK0_DN
AW24 CLK_100M_CPU1_BCLK0_DP BCLK0_DP @BASEBOARD_FAB2_LIB.BASEBOARD_FAB2(SCH_1):CLK_100M_CPU1_BCLK0_DP
CR26 CLK_100M_CPU1_BCLK1_DN BCLK1_DN @BASEBOARD_FAB2_LIB.BASEBOARD_FAB2(SCH_1):CLK_100M_CPU1_BCLK1_DN
CP27 CLK_100M_CPU1_BCLK1_DP BCLK1_DP @BASEBOARD_FAB2_LIB.BASEBOARD_FAB2(SCH_1):CLK_100M_CPU1_BCLK1_DP
CT25 CLK_100M_CPU1_BCLK2_DN BCLK2_DN @BASEBOARD_FAB2_LIB.BASEBOARD_FAB2(SCH_1):CLK_100M_CPU1_BCLK2_DN
CU26 CLK_100M_CPU1_BCLK2_DP BCLK2_DP @BASEBOARD_FAB2_LIB.BASEBOARD_FAB2(SCH_1):CLK_100M_CPU1_BCLK2_DP
BA20 PD_CPU1_BIST_ENABLE BIST_ENABLE @BASEBOARD_FAB2_LIB.BASEBOARD_FAB2(SCH_1):PD_CPU1_BIST_ENABLE
BD23 H_CPU1_BMCINIT BMCINIT @BASEBOARD_FAB2_LIB.BASEBOARD_FAB2(SCH_1):H_CPU1_BMCINIT
AC12 XDP_CPU_OBSFN_B1_MBP7_N BPM_N<7> @BASEBOARD_FAB2_LIB.BASEBOARD_FAB2(SCH_1):XDP_CPU_OBSFN_B1_MBP7_N
AE12 XDP_CPU_OBSFN_B0_MBP6_N BPM_N<6> @BASEBOARD_FAB2_LIB.BASEBOARD_FAB2(SCH_1):XDP_CPU_OBSFN_B0_MBP6_N
 Y11 TP_XDP_CPU1_OBSDATA_B3_MBP5_N BPM_N<5> @BASEBOARD_FAB2_LIB.BASEBOARD_FAB2(SCH_1):TP_XDP_CPU1_OBSDATA_B3_MBP5_N
AA12 TP_XDP_CPU1_OBSDATA_B2_MBP4_N BPM_N<4> @BASEBOARD_FAB2_LIB.BASEBOARD_FAB2(SCH_1):TP_XDP_CPU1_OBSDATA_B2_MBP4_N
AF11 TP_XDP_CPU1_OBSDATA_B1_MBP3_N BPM_N<3> @BASEBOARD_FAB2_LIB.BASEBOARD_FAB2(SCH_1):TP_XDP_CPU1_OBSDATA_B1_MBP3_N
AG10 TP_XDP_CPU1_OBSDATA_B0_MBP2_N BPM_N<2> @BASEBOARD_FAB2_LIB.BASEBOARD_FAB2(SCH_1):TP_XDP_CPU1_OBSDATA_B0_MBP2_N
AH11 XDP_CPU_MBP1_N BPM_N<1> @BASEBOARD_FAB2_LIB.BASEBOARD_FAB2(SCH_1):XDP_CPU_MBP1_N
AJ10 XDP_CPU_MBP0_N BPM_N<0> @BASEBOARD_FAB2_LIB.BASEBOARD_FAB2(SCH_1):XDP_CPU_MBP0_N
AL14 H_CPU1_CATERR_G_N CATERR_N @BASEBOARD_FAB2_LIB.BASEBOARD_FAB2(SCH_1):H_CPU1_CATERR_G_N
AN30 PWRGD_CPU1_DRAMPWROK_GHJ_G DDR012_DRAM_PWR_OK @BASEBOARD_FAB2_LIB.BASEBOARD_FAB2(SCH_1):PWRGD_CPU1_DRAMPWROK_GHJ_G
AC42 A_CPU1_GHJ_RCOMP2 DDR012_RCOMP<2> @BASEBOARD_FAB2_LIB.BASEBOARD_FAB2(SCH_1):A_CPU1_GHJ_RCOMP2
AB43 A_CPU1_GHJ_RCOMP1 DDR012_RCOMP<1> @BASEBOARD_FAB2_LIB.BASEBOARD_FAB2(SCH_1):A_CPU1_GHJ_RCOMP1
 Y43 A_CPU1_GHJ_RCOMP0 DDR012_RCOMP<0> @BASEBOARD_FAB2_LIB.BASEBOARD_FAB2(SCH_1):A_CPU1_GHJ_RCOMP0
 U64 M_GHJ_RST_N DDR012_RESET_N @BASEBOARD_FAB2_LIB.BASEBOARD_FAB2(SCH_1):M_GHJ_RST_N
AJ18 SMB_DDR_GHJ_SCL_G_R DDR012_SPDSCL @BASEBOARD_FAB2_LIB.BASEBOARD_FAB2(SCH_1):SMB_DDR_GHJ_SCL_G_R
AF17 SMB_DDR_GHJ_SDA_G_R DDR012_SPDSDA @BASEBOARD_FAB2_LIB.BASEBOARD_FAB2(SCH_1):SMB_DDR_GHJ_SDA_G_R
AJ64 M_G_CPU_VREF DDR0_CAVREF @BASEBOARD_FAB2_LIB.BASEBOARD_FAB2(SCH_1):M_G_CPU_VREF
AK63 M_H_CPU_VREF DDR1_CAVREF @BASEBOARD_FAB2_LIB.BASEBOARD_FAB2(SCH_1):M_H_CPU_VREF
AH63 M_J_CPU_VREF DDR2_CAVREF @BASEBOARD_FAB2_LIB.BASEBOARD_FAB2(SCH_1):M_J_CPU_VREF
CR28 PWRGD_CPU1_DRAMPWROK_KLM_G DDR345_DRAM_PWR_OK @BASEBOARD_FAB2_LIB.BASEBOARD_FAB2(SCH_1):PWRGD_CPU1_DRAMPWROK_KLM_G
DD49 A_CPU1_KLM_RCOMP2 DDR345_RCOMP<2> @BASEBOARD_FAB2_LIB.BASEBOARD_FAB2(SCH_1):A_CPU1_KLM_RCOMP2
DD47 A_CPU1_KLM_RCOMP1 DDR345_RCOMP<1> @BASEBOARD_FAB2_LIB.BASEBOARD_FAB2(SCH_1):A_CPU1_KLM_RCOMP1
DC48 A_CPU1_KLM_RCOMP0 DDR345_RCOMP<0> @BASEBOARD_FAB2_LIB.BASEBOARD_FAB2(SCH_1):A_CPU1_KLM_RCOMP0
DV63 M_KLM_RST_N DDR345_RESET_N @BASEBOARD_FAB2_LIB.BASEBOARD_FAB2(SCH_1):M_KLM_RST_N
AE18 SMB_DDR_KLM_SCL_G_R DDR345_SPDSCL @BASEBOARD_FAB2_LIB.BASEBOARD_FAB2(SCH_1):SMB_DDR_KLM_SCL_G_R
AD17 SMB_DDR_KLM_SDA_G_R DDR345_SPDSDA @BASEBOARD_FAB2_LIB.BASEBOARD_FAB2(SCH_1):SMB_DDR_KLM_SDA_G_R
CP61 M_K_CPU_VREF DDR3_CAVREF @BASEBOARD_FAB2_LIB.BASEBOARD_FAB2(SCH_1):M_K_CPU_VREF
CT61 M_L_CPU_VREF DDR4_CAVREF @BASEBOARD_FAB2_LIB.BASEBOARD_FAB2(SCH_1):M_L_CPU_VREF
CV61 M_M_CPU_VREF DDR5_CAVREF @BASEBOARD_FAB2_LIB.BASEBOARD_FAB2(SCH_1):M_M_CPU_VREF
AJ14 PD_CPU1_EAR_N  EAR_N @BASEBOARD_FAB2_LIB.BASEBOARD_FAB2(SCH_1):PD_CPU1_EAR_N
AL12 H_CPU1_ERR2_G_N ERROR_N<2> @BASEBOARD_FAB2_LIB.BASEBOARD_FAB2(SCH_1):H_CPU1_ERR2_G_N
AK11 H_CPU1_ERR1_G_N ERROR_N<1> @BASEBOARD_FAB2_LIB.BASEBOARD_FAB2(SCH_1):H_CPU1_ERR1_G_N
AJ12 H_CPU1_ERR0_G_N ERROR_N<0> @BASEBOARD_FAB2_LIB.BASEBOARD_FAB2(SCH_1):H_CPU1_ERR0_G_N
AV17 PU_CPU1_FRMAGENT FRMAGENT @BASEBOARD_FAB2_LIB.BASEBOARD_FAB2(SCH_1):PU_CPU1_FRMAGENT
AE20 PU_CPU1_LEGACY_SKT LEGACY_SKT @BASEBOARD_FAB2_LIB.BASEBOARD_FAB2(SCH_1):PU_CPU1_LEGACY_SKT
CT31 A_CPU1_MCP01_RBIAS MCP01_RBIAS<1> @BASEBOARD_FAB2_LIB.BASEBOARD_FAB2(SCH_1):A_CPU1_MCP01_RBIAS
CU32 A_CPU1_MCP01_RBIAS MCP01_RBIAS<0> @BASEBOARD_FAB2_LIB.BASEBOARD_FAB2(SCH_1):A_CPU1_MCP01_RBIAS
AH13 H_CPU1_MEMGHJ_MEMHOT_G_N MEM_HOT_C012_N @BASEBOARD_FAB2_LIB.BASEBOARD_FAB2(SCH_1):H_CPU1_MEMGHJ_MEMHOT_G_N
AF13 H_CPU1_MEMKLM_MEMHOT_G_N MEM_HOT_C345_N @BASEBOARD_FAB2_LIB.BASEBOARD_FAB2(SCH_1):H_CPU1_MEMKLM_MEMHOT_G_N
AN20 H_CPU1_MSMI_G_N MSMI_N @BASEBOARD_FAB2_LIB.BASEBOARD_FAB2(SCH_1):H_CPU1_MSMI_G_N
AP11 TP_CPU1_NMI    NMI @BASEBOARD_FAB2_LIB.BASEBOARD_FAB2(SCH_1):TP_CPU1_NMI
CL30 A_CPU1_PE012_RBIAS PE012_RBIAS<1> @BASEBOARD_FAB2_LIB.BASEBOARD_FAB2(SCH_1):A_CPU1_PE012_RBIAS
CN30 A_CPU1_PE012_RBIAS PE012_RBIAS<0> @BASEBOARD_FAB2_LIB.BASEBOARD_FAB2(SCH_1):A_CPU1_PE012_RBIAS
CR30 A_CPU1_PE3_RBIAS PE3_RBIAS<1> @BASEBOARD_FAB2_LIB.BASEBOARD_FAB2(SCH_1):A_CPU1_PE3_RBIAS
CP29 A_CPU1_PE3_RBIAS PE3_RBIAS<0> @BASEBOARD_FAB2_LIB.BASEBOARD_FAB2(SCH_1):A_CPU1_PE3_RBIAS
AU12 PECI_CPU_G   PECI @BASEBOARD_FAB2_LIB.BASEBOARD_FAB2(SCH_1):PECI_CPU_G
AM19 SMB_CPU1_PE_HP_GTL_SCL PE_HP_SCL @BASEBOARD_FAB2_LIB.BASEBOARD_FAB2(SCH_1):SMB_CPU1_PE_HP_GTL_SCL
AL18 SMB_CPU1_PE_HP_GTL_SDA PE_HP_SDA @BASEBOARD_FAB2_LIB.BASEBOARD_FAB2(SCH_1):SMB_CPU1_PE_HP_GTL_SDA
CW56 PD_PIROM_CPU1_ADDR2 PIROM_ADDR<2> @BASEBOARD_FAB2_LIB.BASEBOARD_FAB2(SCH_1):PD_PIROM_CPU1_ADDR2
CV57 PD_PIROM_CPU1_ADDR1 PIROM_ADDR<1> @BASEBOARD_FAB2_LIB.BASEBOARD_FAB2(SCH_1):PD_PIROM_CPU1_ADDR1
CU58 PU_PIROM_CPU1_ADDR0 PIROM_ADDR<0> @BASEBOARD_FAB2_LIB.BASEBOARD_FAB2(SCH_1):PU_PIROM_CPU1_ADDR0
DA72 FM_CPU1_PKGID2 PKGID<2> @BASEBOARD_FAB2_LIB.BASEBOARD_FAB2(SCH_1):FM_CPU1_PKGID2
CW72 FM_CPU1_PKGID1 PKGID<1> @BASEBOARD_FAB2_LIB.BASEBOARD_FAB2(SCH_1):FM_CPU1_PKGID1
DC72 FM_CPU1_PKGID0 PKGID<0> @BASEBOARD_FAB2_LIB.BASEBOARD_FAB2(SCH_1):FM_CPU1_PKGID0
AR14 H_PM_SYNC_GTL_R2 PMSYNC @BASEBOARD_FAB2_LIB.BASEBOARD_FAB2(SCH_1):H_PM_SYNC_GTL_R2
AT19 H_PMSYNC_CLK_24M_CPU1 PMSYNC_CLK @BASEBOARD_FAB2_LIB.BASEBOARD_FAB2(SCH_1):H_PMSYNC_CLK_24M_CPU1
AF15 H_CPU1_FAST_WAKE_N PM_FAST_WAKE_N @BASEBOARD_FAB2_LIB.BASEBOARD_FAB2(SCH_1):H_CPU1_FAST_WAKE_N
AG16 XDP_CPU_PRDY_N PRDY_N @BASEBOARD_FAB2_LIB.BASEBOARD_FAB2(SCH_1):XDP_CPU_PRDY_N
AR12 XDP_CPU_PREQ_N PREQ_N @BASEBOARD_FAB2_LIB.BASEBOARD_FAB2(SCH_1):XDP_CPU_PREQ_N
AB17 TP_CPU1_PROC_DIS_G_N PROCDIS_N @BASEBOARD_FAB2_LIB.BASEBOARD_FAB2(SCH_1):TP_CPU1_PROC_DIS_G_N
AC16 H_CPU1_PROCHOT_G_N PROCHOT_N @BASEBOARD_FAB2_LIB.BASEBOARD_FAB2(SCH_1):H_CPU1_PROCHOT_G_N
DB71 FM_CPU1_PROC_ID1 PROC_ID<1> @BASEBOARD_FAB2_LIB.BASEBOARD_FAB2(SCH_1):FM_CPU1_PROC_ID1
CY71 FM_CPU1_PROC_ID0 PROC_ID<0> @BASEBOARD_FAB2_LIB.BASEBOARD_FAB2(SCH_1):FM_CPU1_PROC_ID0
BC24 PWRGD_CPU1_G PWRGOOD @BASEBOARD_FAB2_LIB.BASEBOARD_FAB2(SCH_1):PWRGD_CPU1_G
AP21 RST_CPU1_G_N RESET_N @BASEBOARD_FAB2_LIB.BASEBOARD_FAB2(SCH_1):RST_CPU1_G_N
AR18 PU_CPU1_SAFE_MODE_BOOT SAFE_MODE_BOOT @BASEBOARD_FAB2_LIB.BASEBOARD_FAB2(SCH_1):PU_CPU1_SAFE_MODE_BOOT
AB13 FM_CPU1_SKTOCC_LVT3_N SKTOCC_N @BASEBOARD_FAB2_LIB.BASEBOARD_FAB2(SCH_1):FM_CPU1_SKTOCC_LVT3_N
CT59 SMB_PIROM_CPU1_SCL SMBCLK @BASEBOARD_FAB2_LIB.BASEBOARD_FAB2(SCH_1):SMB_PIROM_CPU1_SCL
CW58 SMB_PIROM_CPU1_SDA SMBDAT @BASEBOARD_FAB2_LIB.BASEBOARD_FAB2(SCH_1):SMB_PIROM_CPU1_SDA
CV59 FM_CPU1_SM_WP  SM_WP @BASEBOARD_FAB2_LIB.BASEBOARD_FAB2(SCH_1):FM_CPU1_SM_WP
AU20 TP_CPU1_SOCKET_ID_2 SOCKET_ID<2> @BASEBOARD_FAB2_LIB.BASEBOARD_FAB2(SCH_1):TP_CPU1_SOCKET_ID_2
AU16 PU_CPU1_SOCKET_ID_1 SOCKET_ID<1> @BASEBOARD_FAB2_LIB.BASEBOARD_FAB2(SCH_1):PU_CPU1_SOCKET_ID_1
AU22 PU_CPU1_SOCKET_ID_0 SOCKET_ID<0> @BASEBOARD_FAB2_LIB.BASEBOARD_FAB2(SCH_1):PU_CPU1_SOCKET_ID_0
DL44 SVID_ALERT1_CPU1_N SVIDALERT_N<1> @BASEBOARD_FAB2_LIB.BASEBOARD_FAB2(SCH_1):SVID_ALERT1_CPU1_N
DE44 SVID_ALERT0_CPU1_N SVIDALERT_N<0> @BASEBOARD_FAB2_LIB.BASEBOARD_FAB2(SCH_1):SVID_ALERT0_CPU1_N
DG44 SVID_CLK1_CPU1 SVIDCLK<1> @BASEBOARD_FAB2_LIB.BASEBOARD_FAB2(SCH_1):SVID_CLK1_CPU1
DC44 SVID_CLK0_CPU1 SVIDCLK<0> @BASEBOARD_FAB2_LIB.BASEBOARD_FAB2(SCH_1):SVID_CLK0_CPU1
DJ44 SVID_DIO1_CPU1 SVIDDATA<1> @BASEBOARD_FAB2_LIB.BASEBOARD_FAB2(SCH_1):SVID_DIO1_CPU1
DB45 SVID_DIO0_CPU1 SVIDDATA<0> @BASEBOARD_FAB2_LIB.BASEBOARD_FAB2(SCH_1):SVID_DIO0_CPU1
AA14 XDP_CPU_TCK0    TCK @BASEBOARD_FAB2_LIB.BASEBOARD_FAB2(SCH_1):XDP_CPU_TCK0
AC14 XDP_CPU1_TDI    TDI @BASEBOARD_FAB2_LIB.BASEBOARD_FAB2(SCH_1):XDP_CPU1_TDI
AE14 XDP_CPU1_TDO    TDO @BASEBOARD_FAB2_LIB.BASEBOARD_FAB2(SCH_1):XDP_CPU1_TDO
AY19 PD_CPU1_TEST12 TEST_12 @BASEBOARD_FAB2_LIB.BASEBOARD_FAB2(SCH_1):PD_CPU1_TEST12
DB51 PD_CPU1_TEST13 TEST_13 @BASEBOARD_FAB2_LIB.BASEBOARD_FAB2(SCH_1):PD_CPU1_TEST13
DC50 PD_CPU1_TEST14 TEST_14 @BASEBOARD_FAB2_LIB.BASEBOARD_FAB2(SCH_1):PD_CPU1_TEST14
AW14 PD_CPU1_KSFC_DIS TEST_15 @BASEBOARD_FAB2_LIB.BASEBOARD_FAB2(SCH_1):PD_CPU1_KSFC_DIS
AB15 H_CPU1_THERMTRIP_G_N THERMTRIP_N @BASEBOARD_FAB2_LIB.BASEBOARD_FAB2(SCH_1):H_CPU1_THERMTRIP_G_N
 W14 XDP_CPU_TMS    TMS @BASEBOARD_FAB2_LIB.BASEBOARD_FAB2(SCH_1):XDP_CPU_TMS
 Y13 XDP_CPU_TRST_N TRST_N @BASEBOARD_FAB2_LIB.BASEBOARD_FAB2(SCH_1):XDP_CPU_TRST_N
AM11 PU_CPU1_TSC_SYNC TSC_SYNC @BASEBOARD_FAB2_LIB.BASEBOARD_FAB2(SCH_1):PU_CPU1_TSC_SYNC
AW18 PU_CPU1_TXT_AGENT TXT_AGENT @BASEBOARD_FAB2_LIB.BASEBOARD_FAB2(SCH_1):PU_CPU1_TXT_AGENT
AV15 PD_CPU1_TXT_PLTEN TXT_PLTEN @BASEBOARD_FAB2_LIB.BASEBOARD_FAB2(SCH_1):PD_CPU1_TXT_PLTEN
AP29 A_CPU1_UPI01_RBIAS UPI01_RBIAS<1> @BASEBOARD_FAB2_LIB.BASEBOARD_FAB2(SCH_1):A_CPU1_UPI01_RBIAS
AT29 A_CPU1_UPI01_RBIAS UPI01_RBIAS<0> @BASEBOARD_FAB2_LIB.BASEBOARD_FAB2(SCH_1):A_CPU1_UPI01_RBIAS
CK29 A_CPU1_UPI2_RBIAS UPI2_RBIAS<1> @BASEBOARD_FAB2_LIB.BASEBOARD_FAB2(SCH_1):A_CPU1_UPI2_RBIAS
CL28 A_CPU1_UPI2_RBIAS UPI2_RBIAS<0> @BASEBOARD_FAB2_LIB.BASEBOARD_FAB2(SCH_1):A_CPU1_UPI2_RBIAS

RES_0402-4.75K,1%,1/16W,CHIP,GA  I181  R6P39
   1 P3V3_STBY      A @BASEBOARD_FAB2_LIB.BASEBOARD_FAB2(SCH_1):P3V3_STBY
   2 FM_CPU1_SKTOCC_LVT3_N      B @BASEBOARD_FAB2_LIB.BASEBOARD_FAB2(SCH_1):FM_CPU1_SKTOCC_LVT3_N


DRAWING: @BASEBOARD_FAB2_LIB.BASEBOARD_FAB2(SCH_1):PAGE56 

SKX_EXT_B_BGA1-IC,TBD  I169  U2D1
AV21 CPU_XDP_PRESENT_N DEBUG_EN_N @BASEBOARD_FAB2_LIB.BASEBOARD_FAB2(SCH_1):CPU_XDP_PRESENT_N
AW12 PD_CPU1_DMIMODE_OVERRIDE DMIMODE_OVERRIDE @BASEBOARD_FAB2_LIB.BASEBOARD_FAB2(SCH_1):PD_CPU1_DMIMODE_OVERRIDE
AU14 H_CPU1_FIVR_FAULT_G FIVR_FAULT @BASEBOARD_FAB2_LIB.BASEBOARD_FAB2(SCH_1):H_CPU1_FIVR_FAULT_G
AP17 XDP_CPU_PWR_DEBUG_N PWR_DEBUG_N @BASEBOARD_FAB2_LIB.BASEBOARD_FAB2(SCH_1):XDP_CPU_PWR_DEBUG_N
  A4 TP_CPU1_RSVD_304 RSVD<304> @BASEBOARD_FAB2_LIB.BASEBOARD_FAB2(SCH_1):TP_CPU1_RSVD_304
  A6 TP_CPU1_RSVD_303 RSVD<303> @BASEBOARD_FAB2_LIB.BASEBOARD_FAB2(SCH_1):TP_CPU1_RSVD_303
 A14 P1V8_MCP_CPU1 RSVD<302> @BASEBOARD_FAB2_LIB.BASEBOARD_FAB2(SCH_1):P1V8_MCP_CPU1
 A16 P1V8_MCP_CPU1 RSVD<301> @BASEBOARD_FAB2_LIB.BASEBOARD_FAB2(SCH_1):P1V8_MCP_CPU1
 A24 TP_CPU1_RSVD_300 RSVD<300> @BASEBOARD_FAB2_LIB.BASEBOARD_FAB2(SCH_1):TP_CPU1_RSVD_300
  B3 TP_CPU1_RSVD_299 RSVD<299> @BASEBOARD_FAB2_LIB.BASEBOARD_FAB2(SCH_1):TP_CPU1_RSVD_299
  B7 TP_CPU1_RSVD_298 RSVD<298> @BASEBOARD_FAB2_LIB.BASEBOARD_FAB2(SCH_1):TP_CPU1_RSVD_298
 B13 P1V8_MCP_CPU1 RSVD<296> @BASEBOARD_FAB2_LIB.BASEBOARD_FAB2(SCH_1):P1V8_MCP_CPU1
 B15 P1V8_MCP_CPU1 RSVD<295> @BASEBOARD_FAB2_LIB.BASEBOARD_FAB2(SCH_1):P1V8_MCP_CPU1
 B17 P1V8_MCP_CPU1 RSVD<294> @BASEBOARD_FAB2_LIB.BASEBOARD_FAB2(SCH_1):P1V8_MCP_CPU1
 B77 TP_CPU1_RSVD_293 RSVD<293> @BASEBOARD_FAB2_LIB.BASEBOARD_FAB2(SCH_1):TP_CPU1_RSVD_293
 B81 TP_CPU1_RSVD_292 RSVD<292> @BASEBOARD_FAB2_LIB.BASEBOARD_FAB2(SCH_1):TP_CPU1_RSVD_292
  C6 TP_CPU1_RSVD_291 RSVD<291> @BASEBOARD_FAB2_LIB.BASEBOARD_FAB2(SCH_1):TP_CPU1_RSVD_291
 C18 TP_CPU1_RSVD_290 RSVD<290> @BASEBOARD_FAB2_LIB.BASEBOARD_FAB2(SCH_1):TP_CPU1_RSVD_290
 C24 TP_CPU1_RSVD_289 RSVD<289> @BASEBOARD_FAB2_LIB.BASEBOARD_FAB2(SCH_1):TP_CPU1_RSVD_289
 C82 TP_CPU1_RSVD_288 RSVD<288> @BASEBOARD_FAB2_LIB.BASEBOARD_FAB2(SCH_1):TP_CPU1_RSVD_288
  D5 TP_CPU1_RSVD_287 RSVD<287> @BASEBOARD_FAB2_LIB.BASEBOARD_FAB2(SCH_1):TP_CPU1_RSVD_287
 D17 TP_CPU1_RSVD_286 RSVD<286> @BASEBOARD_FAB2_LIB.BASEBOARD_FAB2(SCH_1):TP_CPU1_RSVD_286
 D65 TP_CPU1_RSVD_285 RSVD<285> @BASEBOARD_FAB2_LIB.BASEBOARD_FAB2(SCH_1):TP_CPU1_RSVD_285
 D83 TP_CPU1_RSVD_284 RSVD<284> @BASEBOARD_FAB2_LIB.BASEBOARD_FAB2(SCH_1):TP_CPU1_RSVD_284
  E2 TP_CPU1_RSVD_283 RSVD<283> @BASEBOARD_FAB2_LIB.BASEBOARD_FAB2(SCH_1):TP_CPU1_RSVD_283
  E4 TP_CPU1_RSVD_282 RSVD<282> @BASEBOARD_FAB2_LIB.BASEBOARD_FAB2(SCH_1):TP_CPU1_RSVD_282
 E24 TP_CPU1_RSVD_281 RSVD<281> @BASEBOARD_FAB2_LIB.BASEBOARD_FAB2(SCH_1):TP_CPU1_RSVD_281
 E84 TP_CPU1_RSVD_280 RSVD<280> @BASEBOARD_FAB2_LIB.BASEBOARD_FAB2(SCH_1):TP_CPU1_RSVD_280
  F3 TP_CPU1_RSVD_279 RSVD<279> @BASEBOARD_FAB2_LIB.BASEBOARD_FAB2(SCH_1):TP_CPU1_RSVD_279
 F23 TP_CPU1_RSVD_278 RSVD<278> @BASEBOARD_FAB2_LIB.BASEBOARD_FAB2(SCH_1):TP_CPU1_RSVD_278
 F65 TP_CPU1_RSVD_277 RSVD<277> @BASEBOARD_FAB2_LIB.BASEBOARD_FAB2(SCH_1):TP_CPU1_RSVD_277
 F83 TP_CPU1_RSVD_276 RSVD<276> @BASEBOARD_FAB2_LIB.BASEBOARD_FAB2(SCH_1):TP_CPU1_RSVD_276
  G2 TP_CPU1_RSVD_275 RSVD<275> @BASEBOARD_FAB2_LIB.BASEBOARD_FAB2(SCH_1):TP_CPU1_RSVD_275
 G64 TP_CPU1_RSVD_274 RSVD<274> @BASEBOARD_FAB2_LIB.BASEBOARD_FAB2(SCH_1):TP_CPU1_RSVD_274
 G84 TP_CPU1_RSVD_273 RSVD<273> @BASEBOARD_FAB2_LIB.BASEBOARD_FAB2(SCH_1):TP_CPU1_RSVD_273
  H1 TP_CPU1_RSVD_272 RSVD<272> @BASEBOARD_FAB2_LIB.BASEBOARD_FAB2(SCH_1):TP_CPU1_RSVD_272
 H83 TP_CPU1_RSVD_271 RSVD<271> @BASEBOARD_FAB2_LIB.BASEBOARD_FAB2(SCH_1):TP_CPU1_RSVD_271
 H85 TP_CPU1_RSVD_270 RSVD<270> @BASEBOARD_FAB2_LIB.BASEBOARD_FAB2(SCH_1):TP_CPU1_RSVD_270
 J46 TP_CPU1_RSVD_269 RSVD<269> @BASEBOARD_FAB2_LIB.BASEBOARD_FAB2(SCH_1):TP_CPU1_RSVD_269
 J62 TP_CPU1_RSVD_268 RSVD<268> @BASEBOARD_FAB2_LIB.BASEBOARD_FAB2(SCH_1):TP_CPU1_RSVD_268
 K61 TP_CPU1_RSVD_267 RSVD<267> @BASEBOARD_FAB2_LIB.BASEBOARD_FAB2(SCH_1):TP_CPU1_RSVD_267
 M63 TP_CPU1_RSVD_266 RSVD<266> @BASEBOARD_FAB2_LIB.BASEBOARD_FAB2(SCH_1):TP_CPU1_RSVD_266
 P65 TP_CPU1_RSVD_265 RSVD<265> @BASEBOARD_FAB2_LIB.BASEBOARD_FAB2(SCH_1):TP_CPU1_RSVD_265
 R62 TP_CPU1_RSVD_264 RSVD<264> @BASEBOARD_FAB2_LIB.BASEBOARD_FAB2(SCH_1):TP_CPU1_RSVD_264
 R66 TP_CPU1_RSVD_263 RSVD<263> @BASEBOARD_FAB2_LIB.BASEBOARD_FAB2(SCH_1):TP_CPU1_RSVD_263
 T67 TP_CPU1_RSVD_262 RSVD<262> @BASEBOARD_FAB2_LIB.BASEBOARD_FAB2(SCH_1):TP_CPU1_RSVD_262
 U66 TP_CPU1_RSVD_261 RSVD<261> @BASEBOARD_FAB2_LIB.BASEBOARD_FAB2(SCH_1):TP_CPU1_RSVD_261
 V65 TP_CPU1_RSVD_260 RSVD<260> @BASEBOARD_FAB2_LIB.BASEBOARD_FAB2(SCH_1):TP_CPU1_RSVD_260
 V67 TP_CPU1_RSVD_259 RSVD<259> @BASEBOARD_FAB2_LIB.BASEBOARD_FAB2(SCH_1):TP_CPU1_RSVD_259
 W66 TP_CPU1_RSVD_258 RSVD<258> @BASEBOARD_FAB2_LIB.BASEBOARD_FAB2(SCH_1):TP_CPU1_RSVD_258
 Y23 FM_CPU1_RC_ERROR_N RSVD<257> @BASEBOARD_FAB2_LIB.BASEBOARD_FAB2(SCH_1):FM_CPU1_RC_ERROR_N
 Y65 TP_CPU1_RSVD_256 RSVD<256> @BASEBOARD_FAB2_LIB.BASEBOARD_FAB2(SCH_1):TP_CPU1_RSVD_256
AD47 TP_CPU1_RSVD_254 RSVD<254> @BASEBOARD_FAB2_LIB.BASEBOARD_FAB2(SCH_1):TP_CPU1_RSVD_254
AD49 TP_CPU1_RSVD_253 RSVD<253> @BASEBOARD_FAB2_LIB.BASEBOARD_FAB2(SCH_1):TP_CPU1_RSVD_253
AD51 TP_CPU1_RSVD_252 RSVD<252> @BASEBOARD_FAB2_LIB.BASEBOARD_FAB2(SCH_1):TP_CPU1_RSVD_252
AE46 TP_CPU1_RSVD_251 RSVD<251> @BASEBOARD_FAB2_LIB.BASEBOARD_FAB2(SCH_1):TP_CPU1_RSVD_251
AE48 TP_CPU1_RSVD_250 RSVD<250> @BASEBOARD_FAB2_LIB.BASEBOARD_FAB2(SCH_1):TP_CPU1_RSVD_250
AE50 TP_CPU1_RSVD_249 RSVD<249> @BASEBOARD_FAB2_LIB.BASEBOARD_FAB2(SCH_1):TP_CPU1_RSVD_249
AE52 TP_CPU1_RSVD_248 RSVD<248> @BASEBOARD_FAB2_LIB.BASEBOARD_FAB2(SCH_1):TP_CPU1_RSVD_248
AE72 TP_CPU1_RSVD_247 RSVD<247> @BASEBOARD_FAB2_LIB.BASEBOARD_FAB2(SCH_1):TP_CPU1_RSVD_247
AF19 TP_CPU1_RSVD_246 RSVD<246> @BASEBOARD_FAB2_LIB.BASEBOARD_FAB2(SCH_1):TP_CPU1_RSVD_246
AF47 TP_CPU1_RSVD_245 RSVD<245> @BASEBOARD_FAB2_LIB.BASEBOARD_FAB2(SCH_1):TP_CPU1_RSVD_245
AF49 TP_CPU1_RSVD_244 RSVD<244> @BASEBOARD_FAB2_LIB.BASEBOARD_FAB2(SCH_1):TP_CPU1_RSVD_244
AF51 TP_CPU1_RSVD_243 RSVD<243> @BASEBOARD_FAB2_LIB.BASEBOARD_FAB2(SCH_1):TP_CPU1_RSVD_243
AF53 TP_CPU1_RSVD_242 RSVD<242> @BASEBOARD_FAB2_LIB.BASEBOARD_FAB2(SCH_1):TP_CPU1_RSVD_242
AF71 TP_CPU1_RSVD_241 RSVD<241> @BASEBOARD_FAB2_LIB.BASEBOARD_FAB2(SCH_1):TP_CPU1_RSVD_241
AG20 TP_CPU1_RSVD_240 RSVD<240> @BASEBOARD_FAB2_LIB.BASEBOARD_FAB2(SCH_1):TP_CPU1_RSVD_240
AG48 TP_CPU1_RSVD_239 RSVD<239> @BASEBOARD_FAB2_LIB.BASEBOARD_FAB2(SCH_1):TP_CPU1_RSVD_239
AG50 TP_CPU1_RSVD_238 RSVD<238> @BASEBOARD_FAB2_LIB.BASEBOARD_FAB2(SCH_1):TP_CPU1_RSVD_238
AG52 TP_CPU1_RSVD_237 RSVD<237> @BASEBOARD_FAB2_LIB.BASEBOARD_FAB2(SCH_1):TP_CPU1_RSVD_237
AG54 TP_CPU1_RSVD_236 RSVD<236> @BASEBOARD_FAB2_LIB.BASEBOARD_FAB2(SCH_1):TP_CPU1_RSVD_236
AG56 TP_CPU1_RSVD_235 RSVD<235> @BASEBOARD_FAB2_LIB.BASEBOARD_FAB2(SCH_1):TP_CPU1_RSVD_235
AG72 TP_CPU1_RSVD_234 RSVD<234> @BASEBOARD_FAB2_LIB.BASEBOARD_FAB2(SCH_1):TP_CPU1_RSVD_234
AH15 TP_CPU1_RSVD_233 RSVD<233> @BASEBOARD_FAB2_LIB.BASEBOARD_FAB2(SCH_1):TP_CPU1_RSVD_233
AH19 TP_CPU1_RSVD_232 RSVD<232> @BASEBOARD_FAB2_LIB.BASEBOARD_FAB2(SCH_1):TP_CPU1_RSVD_232
AH55 TP_CPU1_RSVD_231 RSVD<231> @BASEBOARD_FAB2_LIB.BASEBOARD_FAB2(SCH_1):TP_CPU1_RSVD_231
AH57 TP_CPU1_RSVD_230 RSVD<230> @BASEBOARD_FAB2_LIB.BASEBOARD_FAB2(SCH_1):TP_CPU1_RSVD_230
AH71 TP_CPU1_RSVD_229 RSVD<229> @BASEBOARD_FAB2_LIB.BASEBOARD_FAB2(SCH_1):TP_CPU1_RSVD_229
AH73 TP_CPU1_RSVD_228 RSVD<228> @BASEBOARD_FAB2_LIB.BASEBOARD_FAB2(SCH_1):TP_CPU1_RSVD_228
AJ20 TP_CPU1_RSVD_227 RSVD<227> @BASEBOARD_FAB2_LIB.BASEBOARD_FAB2(SCH_1):TP_CPU1_RSVD_227
AJ56 TP_CPU1_RSVD_226 RSVD<226> @BASEBOARD_FAB2_LIB.BASEBOARD_FAB2(SCH_1):TP_CPU1_RSVD_226
AJ58 TP_CPU1_RSVD_225 RSVD<225> @BASEBOARD_FAB2_LIB.BASEBOARD_FAB2(SCH_1):TP_CPU1_RSVD_225
AJ60 TP_CPU1_RSVD_224 RSVD<224> @BASEBOARD_FAB2_LIB.BASEBOARD_FAB2(SCH_1):TP_CPU1_RSVD_224
AJ62 TP_CPU1_RSVD_223 RSVD<223> @BASEBOARD_FAB2_LIB.BASEBOARD_FAB2(SCH_1):TP_CPU1_RSVD_223
AJ70 TP_CPU1_RSVD_222 RSVD<222> @BASEBOARD_FAB2_LIB.BASEBOARD_FAB2(SCH_1):TP_CPU1_RSVD_222
AK21 VSENSE_P1V8MCP_CPU1_SKT_VSEN RSVD<221> @BASEBOARD_FAB2_LIB.BASEBOARD_FAB2(SCH_1):VSENSE_P1V8MCP_CPU1_SKT_VSEN
AK27 CLK_322M_OSC_CPU1_RC_DP RSVD<220> @BASEBOARD_FAB2_LIB.BASEBOARD_FAB2(SCH_1):CLK_322M_OSC_CPU1_RC_DP
AK57 TP_CPU1_RSVD_219 RSVD<219> @BASEBOARD_FAB2_LIB.BASEBOARD_FAB2(SCH_1):TP_CPU1_RSVD_219
AK59 TP_CPU1_RSVD_218 RSVD<218> @BASEBOARD_FAB2_LIB.BASEBOARD_FAB2(SCH_1):TP_CPU1_RSVD_218
AK61 TP_CPU1_RSVD_217 RSVD<217> @BASEBOARD_FAB2_LIB.BASEBOARD_FAB2(SCH_1):TP_CPU1_RSVD_217
AK69 TP_CPU1_RSVD_216 RSVD<216> @BASEBOARD_FAB2_LIB.BASEBOARD_FAB2(SCH_1):TP_CPU1_RSVD_216
AL20 VSENSE_P1V8MCP_CPU1_SKT_VRTN RSVD<215> @BASEBOARD_FAB2_LIB.BASEBOARD_FAB2(SCH_1):VSENSE_P1V8MCP_CPU1_SKT_VRTN
AL22 TP_CPU1_RSVD_214 RSVD<214> @BASEBOARD_FAB2_LIB.BASEBOARD_FAB2(SCH_1):TP_CPU1_RSVD_214
AL26 CLK_322M_OSC_CPU1_RC_DN RSVD<213> @BASEBOARD_FAB2_LIB.BASEBOARD_FAB2(SCH_1):CLK_322M_OSC_CPU1_RC_DN
AL58 TP_CPU1_RSVD_212 RSVD<212> @BASEBOARD_FAB2_LIB.BASEBOARD_FAB2(SCH_1):TP_CPU1_RSVD_212
AL60 TP_CPU1_RSVD_211 RSVD<211> @BASEBOARD_FAB2_LIB.BASEBOARD_FAB2(SCH_1):TP_CPU1_RSVD_211
AL62 TP_CPU1_RSVD_210 RSVD<210> @BASEBOARD_FAB2_LIB.BASEBOARD_FAB2(SCH_1):TP_CPU1_RSVD_210
AM21 PVCCMCP_CPU1 RSVD<209> @BASEBOARD_FAB2_LIB.BASEBOARD_FAB2(SCH_1):PVCCMCP_CPU1
AM23 TP_CPU1_RSVD_208 RSVD<208> @BASEBOARD_FAB2_LIB.BASEBOARD_FAB2(SCH_1):TP_CPU1_RSVD_208
AM25 PVCCMCP_CPU1 RSVD<207> @BASEBOARD_FAB2_LIB.BASEBOARD_FAB2(SCH_1):PVCCMCP_CPU1
AM27 CLK_100M_CPU1_RC_REFCLK0_DP RSVD<206> @BASEBOARD_FAB2_LIB.BASEBOARD_FAB2(SCH_1):CLK_100M_CPU1_RC_REFCLK0_DP
AM59 TP_CPU1_RSVD_205 RSVD<205> @BASEBOARD_FAB2_LIB.BASEBOARD_FAB2(SCH_1):TP_CPU1_RSVD_205
AM61 TP_CPU1_RSVD_204 RSVD<204> @BASEBOARD_FAB2_LIB.BASEBOARD_FAB2(SCH_1):TP_CPU1_RSVD_204
AN18 PVCCMCP_CPU1 RSVD<203> @BASEBOARD_FAB2_LIB.BASEBOARD_FAB2(SCH_1):PVCCMCP_CPU1
AN22 PVCCMCP_CPU1 RSVD<202> @BASEBOARD_FAB2_LIB.BASEBOARD_FAB2(SCH_1):PVCCMCP_CPU1
AN24 PVCCMCP_CPU1 RSVD<201> @BASEBOARD_FAB2_LIB.BASEBOARD_FAB2(SCH_1):PVCCMCP_CPU1
AN26 PVCCMCP_CPU1 RSVD<200> @BASEBOARD_FAB2_LIB.BASEBOARD_FAB2(SCH_1):PVCCMCP_CPU1
AN60 TP_CPU1_RSVD_199 RSVD<199> @BASEBOARD_FAB2_LIB.BASEBOARD_FAB2(SCH_1):TP_CPU1_RSVD_199
AN62 TP_CPU1_RSVD_198 RSVD<198> @BASEBOARD_FAB2_LIB.BASEBOARD_FAB2(SCH_1):TP_CPU1_RSVD_198
AP23 PVCCMCP_CPU1 RSVD<197> @BASEBOARD_FAB2_LIB.BASEBOARD_FAB2(SCH_1):PVCCMCP_CPU1
AP25 PVCCMCP_CPU1 RSVD<196> @BASEBOARD_FAB2_LIB.BASEBOARD_FAB2(SCH_1):PVCCMCP_CPU1
AP27 CLK_100M_CPU1_RC_REFCLK0_DN RSVD<195> @BASEBOARD_FAB2_LIB.BASEBOARD_FAB2(SCH_1):CLK_100M_CPU1_RC_REFCLK0_DN
AP61 TP_CPU1_RSVD_194 RSVD<194> @BASEBOARD_FAB2_LIB.BASEBOARD_FAB2(SCH_1):TP_CPU1_RSVD_194
AF45 PD_CPU1_RSVD_TEST_1 TEST_1 @BASEBOARD_FAB2_LIB.BASEBOARD_FAB2(SCH_1):PD_CPU1_RSVD_TEST_1
AY13 TP_CPU1_RSVD_TEST_11 TEST_11 @BASEBOARD_FAB2_LIB.BASEBOARD_FAB2(SCH_1):TP_CPU1_RSVD_TEST_11
AG46 PD_CPU1_RSVD_TEST_2 TEST_2 @BASEBOARD_FAB2_LIB.BASEBOARD_FAB2(SCH_1):PD_CPU1_RSVD_TEST_2
AM13 TP_CPU1_RSVD_TEST_3 TEST_3 @BASEBOARD_FAB2_LIB.BASEBOARD_FAB2(SCH_1):TP_CPU1_RSVD_TEST_3
AN12 TP_CPU1_RSVD_TEST_4 TEST_4 @BASEBOARD_FAB2_LIB.BASEBOARD_FAB2(SCH_1):TP_CPU1_RSVD_TEST_4
AN14 TP_CPU1_RSVD_TEST_5 TEST_5 @BASEBOARD_FAB2_LIB.BASEBOARD_FAB2(SCH_1):TP_CPU1_RSVD_TEST_5

RES_0402-49.9,1%,1/16W,CHIP,G2A  I173  R8P3
   1 PD_CPU1_RSVD_TEST_2      A @BASEBOARD_FAB2_LIB.BASEBOARD_FAB2(SCH_1):PD_CPU1_RSVD_TEST_2
   2    GND      B @BASEBOARD_FAB2_LIB.BASEBOARD_FAB2(SCH_1):GND

RES_0402-49.9,1%,1/16W,CHIP,G2A  I174  R8R1
   1 PD_CPU1_RSVD_TEST_1      A @BASEBOARD_FAB2_LIB.BASEBOARD_FAB2(SCH_1):PD_CPU1_RSVD_TEST_1
   2    GND      B @BASEBOARD_FAB2_LIB.BASEBOARD_FAB2(SCH_1):GND


DRAWING: @BASEBOARD_FAB2_LIB.BASEBOARD_FAB2(SCH_1):PAGE57 

SKX_EXT_B_BGA1-IC,TBD  I172  U2D1
 J60 M_G_ACT_N DDR0_ACT_N @BASEBOARD_FAB2_LIB.BASEBOARD_FAB2(SCH_1):M_G_ACT_N
 B61 M_G_ALERT_N DDR0_ALERT_N @BASEBOARD_FAB2_LIB.BASEBOARD_FAB2(SCH_1):M_G_ALERT_N
 G54 M_G_BA<1> DDR0_BA<1> @BASEBOARD_FAB2_LIB.BASEBOARD_FAB2(SCH_1):M_G_BA(1)
 C52 M_G_BA<0> DDR0_BA<0> @BASEBOARD_FAB2_LIB.BASEBOARD_FAB2(SCH_1):M_G_BA(0)
 F63 M_G_BG<1> DDR0_BG<1> @BASEBOARD_FAB2_LIB.BASEBOARD_FAB2(SCH_1):M_G_BG(1)
 D61 M_G_BG<0> DDR0_BG<0> @BASEBOARD_FAB2_LIB.BASEBOARD_FAB2(SCH_1):M_G_BG(0)
 G46 M_G_C<2> DDR0_CID<2> @BASEBOARD_FAB2_LIB.BASEBOARD_FAB2(SCH_1):M_G_C(2)
 D63 M_G_CKE<3> DDR0_CKE<3> @BASEBOARD_FAB2_LIB.BASEBOARD_FAB2(SCH_1):M_G_CKE(3)
 B63 M_G_CKE<2> DDR0_CKE<2> @BASEBOARD_FAB2_LIB.BASEBOARD_FAB2(SCH_1):M_G_CKE(2)
 C64 M_G_CKE<1> DDR0_CKE<1> @BASEBOARD_FAB2_LIB.BASEBOARD_FAB2(SCH_1):M_G_CKE(1)
 C62 M_G_CKE<0> DDR0_CKE<0> @BASEBOARD_FAB2_LIB.BASEBOARD_FAB2(SCH_1):M_G_CKE(0)
 C56 M_G_CLK_DN<3> DDR0_CLK_DN<3> @BASEBOARD_FAB2_LIB.BASEBOARD_FAB2(SCH_1):M_G_CLK_DN(3)
 J56 M_G_CLK_DN<2> DDR0_CLK_DN<2> @BASEBOARD_FAB2_LIB.BASEBOARD_FAB2(SCH_1):M_G_CLK_DN(2)
 C54 M_G_CLK_DN<1> DDR0_CLK_DN<1> @BASEBOARD_FAB2_LIB.BASEBOARD_FAB2(SCH_1):M_G_CLK_DN(1)
 F55 M_G_CLK_DN<0> DDR0_CLK_DN<0> @BASEBOARD_FAB2_LIB.BASEBOARD_FAB2(SCH_1):M_G_CLK_DN(0)
 B57 M_G_CLK_DP<3> DDR0_CLK_DP<3> @BASEBOARD_FAB2_LIB.BASEBOARD_FAB2(SCH_1):M_G_CLK_DP(3)
 G56 M_G_CLK_DP<2> DDR0_CLK_DP<2> @BASEBOARD_FAB2_LIB.BASEBOARD_FAB2(SCH_1):M_G_CLK_DP(2)
 B55 M_G_CLK_DP<1> DDR0_CLK_DP<1> @BASEBOARD_FAB2_LIB.BASEBOARD_FAB2(SCH_1):M_G_CLK_DP(1)
 D55 M_G_CLK_DP<0> DDR0_CLK_DP<0> @BASEBOARD_FAB2_LIB.BASEBOARD_FAB2(SCH_1):M_G_CLK_DP(0)
 K45 M_G_CS_N<7> DDR0_CS_N<7> @BASEBOARD_FAB2_LIB.BASEBOARD_FAB2(SCH_1):M_G_CS_N(7)
 F45 M_G_CS_N<6> DDR0_CS_N<6> @BASEBOARD_FAB2_LIB.BASEBOARD_FAB2(SCH_1):M_G_CS_N(6)
 D49 M_G_CS_N<5> DDR0_CS_N<5> @BASEBOARD_FAB2_LIB.BASEBOARD_FAB2(SCH_1):M_G_CS_N(5)
 B51 M_G_CS_N<4> DDR0_CS_N<4> @BASEBOARD_FAB2_LIB.BASEBOARD_FAB2(SCH_1):M_G_CS_N(4)
 F47 M_G_CS_N<3> DDR0_CS_N<3> @BASEBOARD_FAB2_LIB.BASEBOARD_FAB2(SCH_1):M_G_CS_N(3)
 D47 M_G_CS_N<2> DDR0_CS_N<2> @BASEBOARD_FAB2_LIB.BASEBOARD_FAB2(SCH_1):M_G_CS_N(2)
 F49 M_G_CS_N<1> DDR0_CS_N<1> @BASEBOARD_FAB2_LIB.BASEBOARD_FAB2(SCH_1):M_G_CS_N(1)
 G52 M_G_CS_N<0> DDR0_CS_N<0> @BASEBOARD_FAB2_LIB.BASEBOARD_FAB2(SCH_1):M_G_CS_N(0)
 K23 M_G_DQ<63> DDR0_DQ<63> @BASEBOARD_FAB2_LIB.BASEBOARD_FAB2(SCH_1):M_G_DQ(63)
 H23 M_G_DQ<62> DDR0_DQ<62> @BASEBOARD_FAB2_LIB.BASEBOARD_FAB2(SCH_1):M_G_DQ(62)
 N26 M_G_DQ<61> DDR0_DQ<61> @BASEBOARD_FAB2_LIB.BASEBOARD_FAB2(SCH_1):M_G_DQ(61)
 L26 M_G_DQ<60> DDR0_DQ<60> @BASEBOARD_FAB2_LIB.BASEBOARD_FAB2(SCH_1):M_G_DQ(60)
 T23 M_G_DQ<59> DDR0_DQ<59> @BASEBOARD_FAB2_LIB.BASEBOARD_FAB2(SCH_1):M_G_DQ(59)
 P23 M_G_DQ<58> DDR0_DQ<58> @BASEBOARD_FAB2_LIB.BASEBOARD_FAB2(SCH_1):M_G_DQ(58)
 P25 M_G_DQ<57> DDR0_DQ<57> @BASEBOARD_FAB2_LIB.BASEBOARD_FAB2(SCH_1):M_G_DQ(57)
 K25 M_G_DQ<56> DDR0_DQ<56> @BASEBOARD_FAB2_LIB.BASEBOARD_FAB2(SCH_1):M_G_DQ(56)
 P29 M_G_DQ<55> DDR0_DQ<55> @BASEBOARD_FAB2_LIB.BASEBOARD_FAB2(SCH_1):M_G_DQ(55)
 K29 M_G_DQ<54> DDR0_DQ<54> @BASEBOARD_FAB2_LIB.BASEBOARD_FAB2(SCH_1):M_G_DQ(54)
 N32 M_G_DQ<53> DDR0_DQ<53> @BASEBOARD_FAB2_LIB.BASEBOARD_FAB2(SCH_1):M_G_DQ(53)
 L32 M_G_DQ<52> DDR0_DQ<52> @BASEBOARD_FAB2_LIB.BASEBOARD_FAB2(SCH_1):M_G_DQ(52)
 N28 M_G_DQ<51> DDR0_DQ<51> @BASEBOARD_FAB2_LIB.BASEBOARD_FAB2(SCH_1):M_G_DQ(51)
 L28 M_G_DQ<50> DDR0_DQ<50> @BASEBOARD_FAB2_LIB.BASEBOARD_FAB2(SCH_1):M_G_DQ(50)
 P31 M_G_DQ<49> DDR0_DQ<49> @BASEBOARD_FAB2_LIB.BASEBOARD_FAB2(SCH_1):M_G_DQ(49)
 K31 M_G_DQ<48> DDR0_DQ<48> @BASEBOARD_FAB2_LIB.BASEBOARD_FAB2(SCH_1):M_G_DQ(48)
 P35 M_G_DQ<47> DDR0_DQ<47> @BASEBOARD_FAB2_LIB.BASEBOARD_FAB2(SCH_1):M_G_DQ(47)
 K35 M_G_DQ<46> DDR0_DQ<46> @BASEBOARD_FAB2_LIB.BASEBOARD_FAB2(SCH_1):M_G_DQ(46)
 N38 M_G_DQ<45> DDR0_DQ<45> @BASEBOARD_FAB2_LIB.BASEBOARD_FAB2(SCH_1):M_G_DQ(45)
 L38 M_G_DQ<44> DDR0_DQ<44> @BASEBOARD_FAB2_LIB.BASEBOARD_FAB2(SCH_1):M_G_DQ(44)
 N34 M_G_DQ<43> DDR0_DQ<43> @BASEBOARD_FAB2_LIB.BASEBOARD_FAB2(SCH_1):M_G_DQ(43)
 L34 M_G_DQ<42> DDR0_DQ<42> @BASEBOARD_FAB2_LIB.BASEBOARD_FAB2(SCH_1):M_G_DQ(42)
 P37 M_G_DQ<41> DDR0_DQ<41> @BASEBOARD_FAB2_LIB.BASEBOARD_FAB2(SCH_1):M_G_DQ(41)
 K37 M_G_DQ<40> DDR0_DQ<40> @BASEBOARD_FAB2_LIB.BASEBOARD_FAB2(SCH_1):M_G_DQ(40)
 F39 M_G_DQ<39> DDR0_DQ<39> @BASEBOARD_FAB2_LIB.BASEBOARD_FAB2(SCH_1):M_G_DQ(39)
 B39 M_G_DQ<38> DDR0_DQ<38> @BASEBOARD_FAB2_LIB.BASEBOARD_FAB2(SCH_1):M_G_DQ(38)
 F41 M_G_DQ<37> DDR0_DQ<37> @BASEBOARD_FAB2_LIB.BASEBOARD_FAB2(SCH_1):M_G_DQ(37)
 E42 M_G_DQ<36> DDR0_DQ<36> @BASEBOARD_FAB2_LIB.BASEBOARD_FAB2(SCH_1):M_G_DQ(36)
 E38 M_G_DQ<35> DDR0_DQ<35> @BASEBOARD_FAB2_LIB.BASEBOARD_FAB2(SCH_1):M_G_DQ(35)
 C38 M_G_DQ<34> DDR0_DQ<34> @BASEBOARD_FAB2_LIB.BASEBOARD_FAB2(SCH_1):M_G_DQ(34)
 B41 M_G_DQ<33> DDR0_DQ<33> @BASEBOARD_FAB2_LIB.BASEBOARD_FAB2(SCH_1):M_G_DQ(33)
 C42 M_G_DQ<32> DDR0_DQ<32> @BASEBOARD_FAB2_LIB.BASEBOARD_FAB2(SCH_1):M_G_DQ(32)
 R74 M_G_DQ<31> DDR0_DQ<31> @BASEBOARD_FAB2_LIB.BASEBOARD_FAB2(SCH_1):M_G_DQ(31)
 L74 M_G_DQ<30> DDR0_DQ<30> @BASEBOARD_FAB2_LIB.BASEBOARD_FAB2(SCH_1):M_G_DQ(30)
 P77 M_G_DQ<29> DDR0_DQ<29> @BASEBOARD_FAB2_LIB.BASEBOARD_FAB2(SCH_1):M_G_DQ(29)
 M77 M_G_DQ<28> DDR0_DQ<28> @BASEBOARD_FAB2_LIB.BASEBOARD_FAB2(SCH_1):M_G_DQ(28)
 P73 M_G_DQ<27> DDR0_DQ<27> @BASEBOARD_FAB2_LIB.BASEBOARD_FAB2(SCH_1):M_G_DQ(27)
 M73 M_G_DQ<26> DDR0_DQ<26> @BASEBOARD_FAB2_LIB.BASEBOARD_FAB2(SCH_1):M_G_DQ(26)
 R76 M_G_DQ<25> DDR0_DQ<25> @BASEBOARD_FAB2_LIB.BASEBOARD_FAB2(SCH_1):M_G_DQ(25)
 L76 M_G_DQ<24> DDR0_DQ<24> @BASEBOARD_FAB2_LIB.BASEBOARD_FAB2(SCH_1):M_G_DQ(24)
 N80 M_G_DQ<23> DDR0_DQ<23> @BASEBOARD_FAB2_LIB.BASEBOARD_FAB2(SCH_1):M_G_DQ(23)
 R82 M_G_DQ<22> DDR0_DQ<22> @BASEBOARD_FAB2_LIB.BASEBOARD_FAB2(SCH_1):M_G_DQ(22)
 V79 M_G_DQ<21> DDR0_DQ<21> @BASEBOARD_FAB2_LIB.BASEBOARD_FAB2(SCH_1):M_G_DQ(21)
 W80 M_G_DQ<20> DDR0_DQ<20> @BASEBOARD_FAB2_LIB.BASEBOARD_FAB2(SCH_1):M_G_DQ(20)
 M81 M_G_DQ<19> DDR0_DQ<19> @BASEBOARD_FAB2_LIB.BASEBOARD_FAB2(SCH_1):M_G_DQ(19)
 N82 M_G_DQ<18> DDR0_DQ<18> @BASEBOARD_FAB2_LIB.BASEBOARD_FAB2(SCH_1):M_G_DQ(18)
 T79 M_G_DQ<17> DDR0_DQ<17> @BASEBOARD_FAB2_LIB.BASEBOARD_FAB2(SCH_1):M_G_DQ(17)
 V81 M_G_DQ<16> DDR0_DQ<16> @BASEBOARD_FAB2_LIB.BASEBOARD_FAB2(SCH_1):M_G_DQ(16)
 N84 M_G_DQ<15> DDR0_DQ<15> @BASEBOARD_FAB2_LIB.BASEBOARD_FAB2(SCH_1):M_G_DQ(15)
 N86 M_G_DQ<14> DDR0_DQ<14> @BASEBOARD_FAB2_LIB.BASEBOARD_FAB2(SCH_1):M_G_DQ(14)
AA84 M_G_DQ<13> DDR0_DQ<13> @BASEBOARD_FAB2_LIB.BASEBOARD_FAB2(SCH_1):M_G_DQ(13)
AA86 M_G_DQ<12> DDR0_DQ<12> @BASEBOARD_FAB2_LIB.BASEBOARD_FAB2(SCH_1):M_G_DQ(12)
 L84 M_G_DQ<11> DDR0_DQ<11> @BASEBOARD_FAB2_LIB.BASEBOARD_FAB2(SCH_1):M_G_DQ(11)
 L86 M_G_DQ<10> DDR0_DQ<10> @BASEBOARD_FAB2_LIB.BASEBOARD_FAB2(SCH_1):M_G_DQ(10)
 W84 M_G_DQ<9> DDR0_DQ<9> @BASEBOARD_FAB2_LIB.BASEBOARD_FAB2(SCH_1):M_G_DQ(9)
 W86 M_G_DQ<8> DDR0_DQ<8> @BASEBOARD_FAB2_LIB.BASEBOARD_FAB2(SCH_1):M_G_DQ(8)
AG84 M_G_DQ<7> DDR0_DQ<7> @BASEBOARD_FAB2_LIB.BASEBOARD_FAB2(SCH_1):M_G_DQ(7)
AG86 M_G_DQ<6> DDR0_DQ<6> @BASEBOARD_FAB2_LIB.BASEBOARD_FAB2(SCH_1):M_G_DQ(6)
AR84 M_G_DQ<5> DDR0_DQ<5> @BASEBOARD_FAB2_LIB.BASEBOARD_FAB2(SCH_1):M_G_DQ(5)
AR86 M_G_DQ<4> DDR0_DQ<4> @BASEBOARD_FAB2_LIB.BASEBOARD_FAB2(SCH_1):M_G_DQ(4)
AE84 M_G_DQ<3> DDR0_DQ<3> @BASEBOARD_FAB2_LIB.BASEBOARD_FAB2(SCH_1):M_G_DQ(3)
AE86 M_G_DQ<2> DDR0_DQ<2> @BASEBOARD_FAB2_LIB.BASEBOARD_FAB2(SCH_1):M_G_DQ(2)
AN84 M_G_DQ<1> DDR0_DQ<1> @BASEBOARD_FAB2_LIB.BASEBOARD_FAB2(SCH_1):M_G_DQ(1)
AN86 M_G_DQ<0> DDR0_DQ<0> @BASEBOARD_FAB2_LIB.BASEBOARD_FAB2(SCH_1):M_G_DQ(0)
AB67 M_G_DQS_DN<17> DDR0_DQS_DN<17> @BASEBOARD_FAB2_LIB.BASEBOARD_FAB2(SCH_1):M_G_DQS_DN(17)
 J24 M_G_DQS_DN<16> DDR0_DQS_DN<16> @BASEBOARD_FAB2_LIB.BASEBOARD_FAB2(SCH_1):M_G_DQS_DN(16)
 J30 M_G_DQS_DN<15> DDR0_DQS_DN<15> @BASEBOARD_FAB2_LIB.BASEBOARD_FAB2(SCH_1):M_G_DQS_DN(15)
 J36 M_G_DQS_DN<14> DDR0_DQS_DN<14> @BASEBOARD_FAB2_LIB.BASEBOARD_FAB2(SCH_1):M_G_DQS_DN(14)
 A40 M_G_DQS_DN<13> DDR0_DQS_DN<13> @BASEBOARD_FAB2_LIB.BASEBOARD_FAB2(SCH_1):M_G_DQS_DN(13)
 K75 M_G_DQS_DN<12> DDR0_DQS_DN<12> @BASEBOARD_FAB2_LIB.BASEBOARD_FAB2(SCH_1):M_G_DQS_DN(12)
 U82 M_G_DQS_DN<11> DDR0_DQS_DN<11> @BASEBOARD_FAB2_LIB.BASEBOARD_FAB2(SCH_1):M_G_DQS_DN(11)
 U84 M_G_DQS_DN<10> DDR0_DQS_DN<10> @BASEBOARD_FAB2_LIB.BASEBOARD_FAB2(SCH_1):M_G_DQS_DN(10)
AL84 M_G_DQS_DN<9> DDR0_DQS_DN<9> @BASEBOARD_FAB2_LIB.BASEBOARD_FAB2(SCH_1):M_G_DQS_DN(9)
AH67 M_G_DQS_DN<8> DDR0_DQS_DN<8> @BASEBOARD_FAB2_LIB.BASEBOARD_FAB2(SCH_1):M_G_DQS_DN(8)
 N24 M_G_DQS_DN<7> DDR0_DQS_DN<7> @BASEBOARD_FAB2_LIB.BASEBOARD_FAB2(SCH_1):M_G_DQS_DN(7)
 R30 M_G_DQS_DN<6> DDR0_DQS_DN<6> @BASEBOARD_FAB2_LIB.BASEBOARD_FAB2(SCH_1):M_G_DQS_DN(6)
 R36 M_G_DQS_DN<5> DDR0_DQS_DN<5> @BASEBOARD_FAB2_LIB.BASEBOARD_FAB2(SCH_1):M_G_DQS_DN(5)
 G40 M_G_DQS_DN<4> DDR0_DQS_DN<4> @BASEBOARD_FAB2_LIB.BASEBOARD_FAB2(SCH_1):M_G_DQS_DN(4)
 T75 M_G_DQS_DN<3> DDR0_DQS_DN<3> @BASEBOARD_FAB2_LIB.BASEBOARD_FAB2(SCH_1):M_G_DQS_DN(3)
 P79 M_G_DQS_DN<2> DDR0_DQS_DN<2> @BASEBOARD_FAB2_LIB.BASEBOARD_FAB2(SCH_1):M_G_DQS_DN(2)
 R84 M_G_DQS_DN<1> DDR0_DQS_DN<1> @BASEBOARD_FAB2_LIB.BASEBOARD_FAB2(SCH_1):M_G_DQS_DN(1)
AJ84 M_G_DQS_DN<0> DDR0_DQS_DN<0> @BASEBOARD_FAB2_LIB.BASEBOARD_FAB2(SCH_1):M_G_DQS_DN(0)
AD67 M_G_DQS_DP<17> DDR0_DQS_DP<17> @BASEBOARD_FAB2_LIB.BASEBOARD_FAB2(SCH_1):M_G_DQS_DP(17)
 L24 M_G_DQS_DP<16> DDR0_DQS_DP<16> @BASEBOARD_FAB2_LIB.BASEBOARD_FAB2(SCH_1):M_G_DQS_DP(16)
 L30 M_G_DQS_DP<15> DDR0_DQS_DP<15> @BASEBOARD_FAB2_LIB.BASEBOARD_FAB2(SCH_1):M_G_DQS_DP(15)
 L36 M_G_DQS_DP<14> DDR0_DQS_DP<14> @BASEBOARD_FAB2_LIB.BASEBOARD_FAB2(SCH_1):M_G_DQS_DP(14)
 C40 M_G_DQS_DP<13> DDR0_DQS_DP<13> @BASEBOARD_FAB2_LIB.BASEBOARD_FAB2(SCH_1):M_G_DQS_DP(13)
 M75 M_G_DQS_DP<12> DDR0_DQS_DP<12> @BASEBOARD_FAB2_LIB.BASEBOARD_FAB2(SCH_1):M_G_DQS_DP(12)
 T81 M_G_DQS_DP<11> DDR0_DQS_DP<11> @BASEBOARD_FAB2_LIB.BASEBOARD_FAB2(SCH_1):M_G_DQS_DP(11)
 V85 M_G_DQS_DP<10> DDR0_DQS_DP<10> @BASEBOARD_FAB2_LIB.BASEBOARD_FAB2(SCH_1):M_G_DQS_DP(10)
AM85 M_G_DQS_DP<9> DDR0_DQS_DP<9> @BASEBOARD_FAB2_LIB.BASEBOARD_FAB2(SCH_1):M_G_DQS_DP(9)
AF67 M_G_DQS_DP<8> DDR0_DQS_DP<8> @BASEBOARD_FAB2_LIB.BASEBOARD_FAB2(SCH_1):M_G_DQS_DP(8)
 R24 M_G_DQS_DP<7> DDR0_DQS_DP<7> @BASEBOARD_FAB2_LIB.BASEBOARD_FAB2(SCH_1):M_G_DQS_DP(7)
 N30 M_G_DQS_DP<6> DDR0_DQS_DP<6> @BASEBOARD_FAB2_LIB.BASEBOARD_FAB2(SCH_1):M_G_DQS_DP(6)
 N36 M_G_DQS_DP<5> DDR0_DQS_DP<5> @BASEBOARD_FAB2_LIB.BASEBOARD_FAB2(SCH_1):M_G_DQS_DP(5)
 E40 M_G_DQS_DP<4> DDR0_DQS_DP<4> @BASEBOARD_FAB2_LIB.BASEBOARD_FAB2(SCH_1):M_G_DQS_DP(4)
 P75 M_G_DQS_DP<3> DDR0_DQS_DP<3> @BASEBOARD_FAB2_LIB.BASEBOARD_FAB2(SCH_1):M_G_DQS_DP(3)
 R80 M_G_DQS_DP<2> DDR0_DQS_DP<2> @BASEBOARD_FAB2_LIB.BASEBOARD_FAB2(SCH_1):M_G_DQS_DP(2)
 P85 M_G_DQS_DP<1> DDR0_DQS_DP<1> @BASEBOARD_FAB2_LIB.BASEBOARD_FAB2(SCH_1):M_G_DQS_DP(1)
AH85 M_G_DQS_DP<0> DDR0_DQS_DP<0> @BASEBOARD_FAB2_LIB.BASEBOARD_FAB2(SCH_1):M_G_DQS_DP(0)
AG66 M_G_ECC<7> DDR0_ECC<7> @BASEBOARD_FAB2_LIB.BASEBOARD_FAB2(SCH_1):M_G_ECC(7)
AC66 M_G_ECC<6> DDR0_ECC<6> @BASEBOARD_FAB2_LIB.BASEBOARD_FAB2(SCH_1):M_G_ECC(6)
AF69 M_G_ECC<5> DDR0_ECC<5> @BASEBOARD_FAB2_LIB.BASEBOARD_FAB2(SCH_1):M_G_ECC(5)
AD69 M_G_ECC<4> DDR0_ECC<4> @BASEBOARD_FAB2_LIB.BASEBOARD_FAB2(SCH_1):M_G_ECC(4)
AF65 M_G_ECC<3> DDR0_ECC<3> @BASEBOARD_FAB2_LIB.BASEBOARD_FAB2(SCH_1):M_G_ECC(3)
AD65 M_G_ECC<2> DDR0_ECC<2> @BASEBOARD_FAB2_LIB.BASEBOARD_FAB2(SCH_1):M_G_ECC(2)
AG68 M_G_ECC<1> DDR0_ECC<1> @BASEBOARD_FAB2_LIB.BASEBOARD_FAB2(SCH_1):M_G_ECC(1)
AC68 M_G_ECC<0> DDR0_ECC<0> @BASEBOARD_FAB2_LIB.BASEBOARD_FAB2(SCH_1):M_G_ECC(0)
 K47 M_G_MA<17> DDR0_MA<17> @BASEBOARD_FAB2_LIB.BASEBOARD_FAB2(SCH_1):M_G_MA(17)
 D51 M_G_MA<16> DDR0_MA<16> @BASEBOARD_FAB2_LIB.BASEBOARD_FAB2(SCH_1):M_G_MA(16)
 K49 M_G_MA<15> DDR0_MA<15> @BASEBOARD_FAB2_LIB.BASEBOARD_FAB2(SCH_1):M_G_MA(15)
 F51 M_G_MA<14> DDR0_MA<14> @BASEBOARD_FAB2_LIB.BASEBOARD_FAB2(SCH_1):M_G_MA(14)
 J48 M_G_MA<13> DDR0_MA<13> @BASEBOARD_FAB2_LIB.BASEBOARD_FAB2(SCH_1):M_G_MA(13)
 J64 M_G_MA<12> DDR0_MA<12> @BASEBOARD_FAB2_LIB.BASEBOARD_FAB2(SCH_1):M_G_MA(12)
 G62 M_G_MA<11> DDR0_MA<11> @BASEBOARD_FAB2_LIB.BASEBOARD_FAB2(SCH_1):M_G_MA(11)
 J54 M_G_MA<10> DDR0_MA<10> @BASEBOARD_FAB2_LIB.BASEBOARD_FAB2(SCH_1):M_G_MA(10)
 F61 M_G_MA<9> DDR0_MA<9> @BASEBOARD_FAB2_LIB.BASEBOARD_FAB2(SCH_1):M_G_MA(9)
 C60 M_G_MA<8> DDR0_MA<8> @BASEBOARD_FAB2_LIB.BASEBOARD_FAB2(SCH_1):M_G_MA(8)
 G60 M_G_MA<7> DDR0_MA<7> @BASEBOARD_FAB2_LIB.BASEBOARD_FAB2(SCH_1):M_G_MA(7)
 D59 M_G_MA<6> DDR0_MA<6> @BASEBOARD_FAB2_LIB.BASEBOARD_FAB2(SCH_1):M_G_MA(6)
 F59 M_G_MA<5> DDR0_MA<5> @BASEBOARD_FAB2_LIB.BASEBOARD_FAB2(SCH_1):M_G_MA(5)
 G58 M_G_MA<4> DDR0_MA<4> @BASEBOARD_FAB2_LIB.BASEBOARD_FAB2(SCH_1):M_G_MA(4)
 C58 M_G_MA<3> DDR0_MA<3> @BASEBOARD_FAB2_LIB.BASEBOARD_FAB2(SCH_1):M_G_MA(3)
 D57 M_G_MA<2> DDR0_MA<2> @BASEBOARD_FAB2_LIB.BASEBOARD_FAB2(SCH_1):M_G_MA(2)
 F57 M_G_MA<1> DDR0_MA<1> @BASEBOARD_FAB2_LIB.BASEBOARD_FAB2(SCH_1):M_G_MA(1)
 F53 M_G_MA<0> DDR0_MA<0> @BASEBOARD_FAB2_LIB.BASEBOARD_FAB2(SCH_1):M_G_MA(0)
 G48 M_G_ODT<3> DDR0_ODT<3> @BASEBOARD_FAB2_LIB.BASEBOARD_FAB2(SCH_1):M_G_ODT(3)
 G50 M_G_ODT<2> DDR0_ODT<2> @BASEBOARD_FAB2_LIB.BASEBOARD_FAB2(SCH_1):M_G_ODT(2)
 C48 M_G_ODT<1> DDR0_ODT<1> @BASEBOARD_FAB2_LIB.BASEBOARD_FAB2(SCH_1):M_G_ODT(1)
 C50 M_G_ODT<0> DDR0_ODT<0> @BASEBOARD_FAB2_LIB.BASEBOARD_FAB2(SCH_1):M_G_ODT(0)
 D53 M_G_PAR DDR0_PAR @BASEBOARD_FAB2_LIB.BASEBOARD_FAB2(SCH_1):M_G_PAR


DRAWING: @BASEBOARD_FAB2_LIB.BASEBOARD_FAB2(SCH_1):PAGE58 

SKX_EXT_B_BGA1-IC,TBD  I172  U2D1
 T63 M_H_ACT_N DDR1_ACT_N @BASEBOARD_FAB2_LIB.BASEBOARD_FAB2(SCH_1):M_H_ACT_N
 W62 M_H_ALERT_N DDR1_ALERT_N @BASEBOARD_FAB2_LIB.BASEBOARD_FAB2(SCH_1):M_H_ALERT_N
 K55 M_H_BA<1> DDR1_BA<1> @BASEBOARD_FAB2_LIB.BASEBOARD_FAB2(SCH_1):M_H_BA(1)
 T53 M_H_BA<0> DDR1_BA<0> @BASEBOARD_FAB2_LIB.BASEBOARD_FAB2(SCH_1):M_H_BA(0)
 N60 M_H_BG<1> DDR1_BG<1> @BASEBOARD_FAB2_LIB.BASEBOARD_FAB2(SCH_1):M_H_BG(1)
 M61 M_H_BG<0> DDR1_BG<0> @BASEBOARD_FAB2_LIB.BASEBOARD_FAB2(SCH_1):M_H_BG(0)
 M47 M_H_C<2> DDR1_CID<2> @BASEBOARD_FAB2_LIB.BASEBOARD_FAB2(SCH_1):M_H_C(2)
 L64 M_H_CKE<3> DDR1_CKE<3> @BASEBOARD_FAB2_LIB.BASEBOARD_FAB2(SCH_1):M_H_CKE(3)
 K63 M_H_CKE<2> DDR1_CKE<2> @BASEBOARD_FAB2_LIB.BASEBOARD_FAB2(SCH_1):M_H_CKE(2)
 R64 M_H_CKE<1> DDR1_CKE<1> @BASEBOARD_FAB2_LIB.BASEBOARD_FAB2(SCH_1):M_H_CKE(1)
 N62 M_H_CKE<0> DDR1_CKE<0> @BASEBOARD_FAB2_LIB.BASEBOARD_FAB2(SCH_1):M_H_CKE(0)
 R56 M_H_CLK_DN<3> DDR1_CLK_DN<3> @BASEBOARD_FAB2_LIB.BASEBOARD_FAB2(SCH_1):M_H_CLK_DN(3)
 N56 M_H_CLK_DN<2> DDR1_CLK_DN<2> @BASEBOARD_FAB2_LIB.BASEBOARD_FAB2(SCH_1):M_H_CLK_DN(2)
 R54 M_H_CLK_DN<1> DDR1_CLK_DN<1> @BASEBOARD_FAB2_LIB.BASEBOARD_FAB2(SCH_1):M_H_CLK_DN(1)
 M53 M_H_CLK_DN<0> DDR1_CLK_DN<0> @BASEBOARD_FAB2_LIB.BASEBOARD_FAB2(SCH_1):M_H_CLK_DN(0)
 T57 M_H_CLK_DP<3> DDR1_CLK_DP<3> @BASEBOARD_FAB2_LIB.BASEBOARD_FAB2(SCH_1):M_H_CLK_DP(3)
 M57 M_H_CLK_DP<2> DDR1_CLK_DP<2> @BASEBOARD_FAB2_LIB.BASEBOARD_FAB2(SCH_1):M_H_CLK_DP(2)
 T55 M_H_CLK_DP<1> DDR1_CLK_DP<1> @BASEBOARD_FAB2_LIB.BASEBOARD_FAB2(SCH_1):M_H_CLK_DP(1)
 N54 M_H_CLK_DP<0> DDR1_CLK_DP<0> @BASEBOARD_FAB2_LIB.BASEBOARD_FAB2(SCH_1):M_H_CLK_DP(0)
 R46 M_H_CS_N<7> DDR1_CS_N<7> @BASEBOARD_FAB2_LIB.BASEBOARD_FAB2(SCH_1):M_H_CS_N(7)
 M45 M_H_CS_N<6> DDR1_CS_N<6> @BASEBOARD_FAB2_LIB.BASEBOARD_FAB2(SCH_1):M_H_CS_N(6)
 T49 M_H_CS_N<5> DDR1_CS_N<5> @BASEBOARD_FAB2_LIB.BASEBOARD_FAB2(SCH_1):M_H_CS_N(5)
 J50 M_H_CS_N<4> DDR1_CS_N<4> @BASEBOARD_FAB2_LIB.BASEBOARD_FAB2(SCH_1):M_H_CS_N(4)
 V47 M_H_CS_N<3> DDR1_CS_N<3> @BASEBOARD_FAB2_LIB.BASEBOARD_FAB2(SCH_1):M_H_CS_N(3)
 N46 M_H_CS_N<2> DDR1_CS_N<2> @BASEBOARD_FAB2_LIB.BASEBOARD_FAB2(SCH_1):M_H_CS_N(2)
 R50 M_H_CS_N<1> DDR1_CS_N<1> @BASEBOARD_FAB2_LIB.BASEBOARD_FAB2(SCH_1):M_H_CS_N(1)
 K51 M_H_CS_N<0> DDR1_CS_N<0> @BASEBOARD_FAB2_LIB.BASEBOARD_FAB2(SCH_1):M_H_CS_N(0)
AA26 M_H_DQ<63> DDR1_DQ<63> @BASEBOARD_FAB2_LIB.BASEBOARD_FAB2(SCH_1):M_H_DQ(63)
 U26 M_H_DQ<62> DDR1_DQ<62> @BASEBOARD_FAB2_LIB.BASEBOARD_FAB2(SCH_1):M_H_DQ(62)
 Y29 M_H_DQ<61> DDR1_DQ<61> @BASEBOARD_FAB2_LIB.BASEBOARD_FAB2(SCH_1):M_H_DQ(61)
 V29 M_H_DQ<60> DDR1_DQ<60> @BASEBOARD_FAB2_LIB.BASEBOARD_FAB2(SCH_1):M_H_DQ(60)
 Y25 M_H_DQ<59> DDR1_DQ<59> @BASEBOARD_FAB2_LIB.BASEBOARD_FAB2(SCH_1):M_H_DQ(59)
 V25 M_H_DQ<58> DDR1_DQ<58> @BASEBOARD_FAB2_LIB.BASEBOARD_FAB2(SCH_1):M_H_DQ(58)
AA28 M_H_DQ<57> DDR1_DQ<57> @BASEBOARD_FAB2_LIB.BASEBOARD_FAB2(SCH_1):M_H_DQ(57)
 U28 M_H_DQ<56> DDR1_DQ<56> @BASEBOARD_FAB2_LIB.BASEBOARD_FAB2(SCH_1):M_H_DQ(56)
 F27 M_H_DQ<55> DDR1_DQ<55> @BASEBOARD_FAB2_LIB.BASEBOARD_FAB2(SCH_1):M_H_DQ(55)
 B27 M_H_DQ<54> DDR1_DQ<54> @BASEBOARD_FAB2_LIB.BASEBOARD_FAB2(SCH_1):M_H_DQ(54)
 F29 M_H_DQ<53> DDR1_DQ<53> @BASEBOARD_FAB2_LIB.BASEBOARD_FAB2(SCH_1):M_H_DQ(53)
 E30 M_H_DQ<52> DDR1_DQ<52> @BASEBOARD_FAB2_LIB.BASEBOARD_FAB2(SCH_1):M_H_DQ(52)
 E26 M_H_DQ<51> DDR1_DQ<51> @BASEBOARD_FAB2_LIB.BASEBOARD_FAB2(SCH_1):M_H_DQ(51)
 C26 M_H_DQ<50> DDR1_DQ<50> @BASEBOARD_FAB2_LIB.BASEBOARD_FAB2(SCH_1):M_H_DQ(50)
 B29 M_H_DQ<49> DDR1_DQ<49> @BASEBOARD_FAB2_LIB.BASEBOARD_FAB2(SCH_1):M_H_DQ(49)
 C30 M_H_DQ<48> DDR1_DQ<48> @BASEBOARD_FAB2_LIB.BASEBOARD_FAB2(SCH_1):M_H_DQ(48)
 F33 M_H_DQ<47> DDR1_DQ<47> @BASEBOARD_FAB2_LIB.BASEBOARD_FAB2(SCH_1):M_H_DQ(47)
 B33 M_H_DQ<46> DDR1_DQ<46> @BASEBOARD_FAB2_LIB.BASEBOARD_FAB2(SCH_1):M_H_DQ(46)
 F35 M_H_DQ<45> DDR1_DQ<45> @BASEBOARD_FAB2_LIB.BASEBOARD_FAB2(SCH_1):M_H_DQ(45)
 E36 M_H_DQ<44> DDR1_DQ<44> @BASEBOARD_FAB2_LIB.BASEBOARD_FAB2(SCH_1):M_H_DQ(44)
 E32 M_H_DQ<43> DDR1_DQ<43> @BASEBOARD_FAB2_LIB.BASEBOARD_FAB2(SCH_1):M_H_DQ(43)
 C32 M_H_DQ<42> DDR1_DQ<42> @BASEBOARD_FAB2_LIB.BASEBOARD_FAB2(SCH_1):M_H_DQ(42)
 B35 M_H_DQ<41> DDR1_DQ<41> @BASEBOARD_FAB2_LIB.BASEBOARD_FAB2(SCH_1):M_H_DQ(41)
 C36 M_H_DQ<40> DDR1_DQ<40> @BASEBOARD_FAB2_LIB.BASEBOARD_FAB2(SCH_1):M_H_DQ(40)
 P41 M_H_DQ<39> DDR1_DQ<39> @BASEBOARD_FAB2_LIB.BASEBOARD_FAB2(SCH_1):M_H_DQ(39)
 K41 M_H_DQ<38> DDR1_DQ<38> @BASEBOARD_FAB2_LIB.BASEBOARD_FAB2(SCH_1):M_H_DQ(38)
 T43 M_H_DQ<37> DDR1_DQ<37> @BASEBOARD_FAB2_LIB.BASEBOARD_FAB2(SCH_1):M_H_DQ(37)
 P43 M_H_DQ<36> DDR1_DQ<36> @BASEBOARD_FAB2_LIB.BASEBOARD_FAB2(SCH_1):M_H_DQ(36)
 N40 M_H_DQ<35> DDR1_DQ<35> @BASEBOARD_FAB2_LIB.BASEBOARD_FAB2(SCH_1):M_H_DQ(35)
 L40 M_H_DQ<34> DDR1_DQ<34> @BASEBOARD_FAB2_LIB.BASEBOARD_FAB2(SCH_1):M_H_DQ(34)
 H43 M_H_DQ<33> DDR1_DQ<33> @BASEBOARD_FAB2_LIB.BASEBOARD_FAB2(SCH_1):M_H_DQ(33)
 K43 M_H_DQ<32> DDR1_DQ<32> @BASEBOARD_FAB2_LIB.BASEBOARD_FAB2(SCH_1):M_H_DQ(32)
 G72 M_H_DQ<31> DDR1_DQ<31> @BASEBOARD_FAB2_LIB.BASEBOARD_FAB2(SCH_1):M_H_DQ(31)
 C72 M_H_DQ<30> DDR1_DQ<30> @BASEBOARD_FAB2_LIB.BASEBOARD_FAB2(SCH_1):M_H_DQ(30)
 G74 M_H_DQ<29> DDR1_DQ<29> @BASEBOARD_FAB2_LIB.BASEBOARD_FAB2(SCH_1):M_H_DQ(29)
 F75 M_H_DQ<28> DDR1_DQ<28> @BASEBOARD_FAB2_LIB.BASEBOARD_FAB2(SCH_1):M_H_DQ(28)
 F71 M_H_DQ<27> DDR1_DQ<27> @BASEBOARD_FAB2_LIB.BASEBOARD_FAB2(SCH_1):M_H_DQ(27)
 D71 M_H_DQ<26> DDR1_DQ<26> @BASEBOARD_FAB2_LIB.BASEBOARD_FAB2(SCH_1):M_H_DQ(26)
 C74 M_H_DQ<25> DDR1_DQ<25> @BASEBOARD_FAB2_LIB.BASEBOARD_FAB2(SCH_1):M_H_DQ(25)
 D75 M_H_DQ<24> DDR1_DQ<24> @BASEBOARD_FAB2_LIB.BASEBOARD_FAB2(SCH_1):M_H_DQ(24)
 J78 M_H_DQ<23> DDR1_DQ<23> @BASEBOARD_FAB2_LIB.BASEBOARD_FAB2(SCH_1):M_H_DQ(23)
 E78 M_H_DQ<22> DDR1_DQ<22> @BASEBOARD_FAB2_LIB.BASEBOARD_FAB2(SCH_1):M_H_DQ(22)
 H81 M_H_DQ<21> DDR1_DQ<21> @BASEBOARD_FAB2_LIB.BASEBOARD_FAB2(SCH_1):M_H_DQ(21)
 F81 M_H_DQ<20> DDR1_DQ<20> @BASEBOARD_FAB2_LIB.BASEBOARD_FAB2(SCH_1):M_H_DQ(20)
 H77 M_H_DQ<19> DDR1_DQ<19> @BASEBOARD_FAB2_LIB.BASEBOARD_FAB2(SCH_1):M_H_DQ(19)
 F77 M_H_DQ<18> DDR1_DQ<18> @BASEBOARD_FAB2_LIB.BASEBOARD_FAB2(SCH_1):M_H_DQ(18)
 J80 M_H_DQ<17> DDR1_DQ<17> @BASEBOARD_FAB2_LIB.BASEBOARD_FAB2(SCH_1):M_H_DQ(17)
 E80 M_H_DQ<16> DDR1_DQ<16> @BASEBOARD_FAB2_LIB.BASEBOARD_FAB2(SCH_1):M_H_DQ(16)
AC80 M_H_DQ<15> DDR1_DQ<15> @BASEBOARD_FAB2_LIB.BASEBOARD_FAB2(SCH_1):M_H_DQ(15)
AE82 M_H_DQ<14> DDR1_DQ<14> @BASEBOARD_FAB2_LIB.BASEBOARD_FAB2(SCH_1):M_H_DQ(14)
AH79 M_H_DQ<13> DDR1_DQ<13> @BASEBOARD_FAB2_LIB.BASEBOARD_FAB2(SCH_1):M_H_DQ(13)
AJ80 M_H_DQ<12> DDR1_DQ<12> @BASEBOARD_FAB2_LIB.BASEBOARD_FAB2(SCH_1):M_H_DQ(12)
AB81 M_H_DQ<11> DDR1_DQ<11> @BASEBOARD_FAB2_LIB.BASEBOARD_FAB2(SCH_1):M_H_DQ(11)
AC82 M_H_DQ<10> DDR1_DQ<10> @BASEBOARD_FAB2_LIB.BASEBOARD_FAB2(SCH_1):M_H_DQ(10)
AF79 M_H_DQ<9> DDR1_DQ<9> @BASEBOARD_FAB2_LIB.BASEBOARD_FAB2(SCH_1):M_H_DQ(9)
AH81 M_H_DQ<8> DDR1_DQ<8> @BASEBOARD_FAB2_LIB.BASEBOARD_FAB2(SCH_1):M_H_DQ(8)
AN80 M_H_DQ<7> DDR1_DQ<7> @BASEBOARD_FAB2_LIB.BASEBOARD_FAB2(SCH_1):M_H_DQ(7)
AR82 M_H_DQ<6> DDR1_DQ<6> @BASEBOARD_FAB2_LIB.BASEBOARD_FAB2(SCH_1):M_H_DQ(6)
AV79 M_H_DQ<5> DDR1_DQ<5> @BASEBOARD_FAB2_LIB.BASEBOARD_FAB2(SCH_1):M_H_DQ(5)
AW80 M_H_DQ<4> DDR1_DQ<4> @BASEBOARD_FAB2_LIB.BASEBOARD_FAB2(SCH_1):M_H_DQ(4)
AM81 M_H_DQ<3> DDR1_DQ<3> @BASEBOARD_FAB2_LIB.BASEBOARD_FAB2(SCH_1):M_H_DQ(3)
AN82 M_H_DQ<2> DDR1_DQ<2> @BASEBOARD_FAB2_LIB.BASEBOARD_FAB2(SCH_1):M_H_DQ(2)
AT79 M_H_DQ<1> DDR1_DQ<1> @BASEBOARD_FAB2_LIB.BASEBOARD_FAB2(SCH_1):M_H_DQ(1)
AV81 M_H_DQ<0> DDR1_DQ<0> @BASEBOARD_FAB2_LIB.BASEBOARD_FAB2(SCH_1):M_H_DQ(0)
 G68 M_H_DQS_DN<17> DDR1_DQS_DN<17> @BASEBOARD_FAB2_LIB.BASEBOARD_FAB2(SCH_1):M_H_DQS_DN(17)
 T27 M_H_DQS_DN<16> DDR1_DQS_DN<16> @BASEBOARD_FAB2_LIB.BASEBOARD_FAB2(SCH_1):M_H_DQS_DN(16)
 A28 M_H_DQS_DN<15> DDR1_DQS_DN<15> @BASEBOARD_FAB2_LIB.BASEBOARD_FAB2(SCH_1):M_H_DQS_DN(15)
 A34 M_H_DQS_DN<14> DDR1_DQS_DN<14> @BASEBOARD_FAB2_LIB.BASEBOARD_FAB2(SCH_1):M_H_DQS_DN(14)
 J42 M_H_DQS_DN<13> DDR1_DQS_DN<13> @BASEBOARD_FAB2_LIB.BASEBOARD_FAB2(SCH_1):M_H_DQS_DN(13)
 B73 M_H_DQS_DN<12> DDR1_DQS_DN<12> @BASEBOARD_FAB2_LIB.BASEBOARD_FAB2(SCH_1):M_H_DQS_DN(12)
 D79 M_H_DQS_DN<11> DDR1_DQS_DN<11> @BASEBOARD_FAB2_LIB.BASEBOARD_FAB2(SCH_1):M_H_DQS_DN(11)
AG82 M_H_DQS_DN<10> DDR1_DQS_DN<10> @BASEBOARD_FAB2_LIB.BASEBOARD_FAB2(SCH_1):M_H_DQS_DN(10)
AU82 M_H_DQS_DN<9> DDR1_DQS_DN<9> @BASEBOARD_FAB2_LIB.BASEBOARD_FAB2(SCH_1):M_H_DQS_DN(9)
 N68 M_H_DQS_DN<8> DDR1_DQS_DN<8> @BASEBOARD_FAB2_LIB.BASEBOARD_FAB2(SCH_1):M_H_DQS_DN(8)
AB27 M_H_DQS_DN<7> DDR1_DQS_DN<7> @BASEBOARD_FAB2_LIB.BASEBOARD_FAB2(SCH_1):M_H_DQS_DN(7)
 G28 M_H_DQS_DN<6> DDR1_DQS_DN<6> @BASEBOARD_FAB2_LIB.BASEBOARD_FAB2(SCH_1):M_H_DQS_DN(6)
 G34 M_H_DQS_DN<5> DDR1_DQS_DN<5> @BASEBOARD_FAB2_LIB.BASEBOARD_FAB2(SCH_1):M_H_DQS_DN(5)
 N42 M_H_DQS_DN<4> DDR1_DQS_DN<4> @BASEBOARD_FAB2_LIB.BASEBOARD_FAB2(SCH_1):M_H_DQS_DN(4)
 H73 M_H_DQS_DN<3> DDR1_DQS_DN<3> @BASEBOARD_FAB2_LIB.BASEBOARD_FAB2(SCH_1):M_H_DQS_DN(3)
 K79 M_H_DQS_DN<2> DDR1_DQS_DN<2> @BASEBOARD_FAB2_LIB.BASEBOARD_FAB2(SCH_1):M_H_DQS_DN(2)
AD79 M_H_DQS_DN<1> DDR1_DQS_DN<1> @BASEBOARD_FAB2_LIB.BASEBOARD_FAB2(SCH_1):M_H_DQS_DN(1)
AP79 M_H_DQS_DN<0> DDR1_DQS_DN<0> @BASEBOARD_FAB2_LIB.BASEBOARD_FAB2(SCH_1):M_H_DQS_DN(0)
 J68 M_H_DQS_DP<17> DDR1_DQS_DP<17> @BASEBOARD_FAB2_LIB.BASEBOARD_FAB2(SCH_1):M_H_DQS_DP(17)
 V27 M_H_DQS_DP<16> DDR1_DQS_DP<16> @BASEBOARD_FAB2_LIB.BASEBOARD_FAB2(SCH_1):M_H_DQS_DP(16)
 C28 M_H_DQS_DP<15> DDR1_DQS_DP<15> @BASEBOARD_FAB2_LIB.BASEBOARD_FAB2(SCH_1):M_H_DQS_DP(15)
 C34 M_H_DQS_DP<14> DDR1_DQS_DP<14> @BASEBOARD_FAB2_LIB.BASEBOARD_FAB2(SCH_1):M_H_DQS_DP(14)
 L42 M_H_DQS_DP<13> DDR1_DQS_DP<13> @BASEBOARD_FAB2_LIB.BASEBOARD_FAB2(SCH_1):M_H_DQS_DP(13)
 D73 M_H_DQS_DP<12> DDR1_DQS_DP<12> @BASEBOARD_FAB2_LIB.BASEBOARD_FAB2(SCH_1):M_H_DQS_DP(12)
 F79 M_H_DQS_DP<11> DDR1_DQS_DP<11> @BASEBOARD_FAB2_LIB.BASEBOARD_FAB2(SCH_1):M_H_DQS_DP(11)
AF81 M_H_DQS_DP<10> DDR1_DQS_DP<10> @BASEBOARD_FAB2_LIB.BASEBOARD_FAB2(SCH_1):M_H_DQS_DP(10)
AT81 M_H_DQS_DP<9> DDR1_DQS_DP<9> @BASEBOARD_FAB2_LIB.BASEBOARD_FAB2(SCH_1):M_H_DQS_DP(9)
 L68 M_H_DQS_DP<8> DDR1_DQS_DP<8> @BASEBOARD_FAB2_LIB.BASEBOARD_FAB2(SCH_1):M_H_DQS_DP(8)
 Y27 M_H_DQS_DP<7> DDR1_DQS_DP<7> @BASEBOARD_FAB2_LIB.BASEBOARD_FAB2(SCH_1):M_H_DQS_DP(7)
 E28 M_H_DQS_DP<6> DDR1_DQS_DP<6> @BASEBOARD_FAB2_LIB.BASEBOARD_FAB2(SCH_1):M_H_DQS_DP(6)
 E34 M_H_DQS_DP<5> DDR1_DQS_DP<5> @BASEBOARD_FAB2_LIB.BASEBOARD_FAB2(SCH_1):M_H_DQS_DP(5)
 R42 M_H_DQS_DP<4> DDR1_DQS_DP<4> @BASEBOARD_FAB2_LIB.BASEBOARD_FAB2(SCH_1):M_H_DQS_DP(4)
 F73 M_H_DQS_DP<3> DDR1_DQS_DP<3> @BASEBOARD_FAB2_LIB.BASEBOARD_FAB2(SCH_1):M_H_DQS_DP(3)
 H79 M_H_DQS_DP<2> DDR1_DQS_DP<2> @BASEBOARD_FAB2_LIB.BASEBOARD_FAB2(SCH_1):M_H_DQS_DP(2)
AE80 M_H_DQS_DP<1> DDR1_DQS_DP<1> @BASEBOARD_FAB2_LIB.BASEBOARD_FAB2(SCH_1):M_H_DQS_DP(1)
AR80 M_H_DQS_DP<0> DDR1_DQS_DP<0> @BASEBOARD_FAB2_LIB.BASEBOARD_FAB2(SCH_1):M_H_DQS_DP(0)
 M67 M_H_ECC<7> DDR1_ECC<7> @BASEBOARD_FAB2_LIB.BASEBOARD_FAB2(SCH_1):M_H_ECC(7)
 H67 M_H_ECC<6> DDR1_ECC<6> @BASEBOARD_FAB2_LIB.BASEBOARD_FAB2(SCH_1):M_H_ECC(6)
 M69 M_H_ECC<5> DDR1_ECC<5> @BASEBOARD_FAB2_LIB.BASEBOARD_FAB2(SCH_1):M_H_ECC(5)
 L70 M_H_ECC<4> DDR1_ECC<4> @BASEBOARD_FAB2_LIB.BASEBOARD_FAB2(SCH_1):M_H_ECC(4)
 L66 M_H_ECC<3> DDR1_ECC<3> @BASEBOARD_FAB2_LIB.BASEBOARD_FAB2(SCH_1):M_H_ECC(3)
 J66 M_H_ECC<2> DDR1_ECC<2> @BASEBOARD_FAB2_LIB.BASEBOARD_FAB2(SCH_1):M_H_ECC(2)
 H69 M_H_ECC<1> DDR1_ECC<1> @BASEBOARD_FAB2_LIB.BASEBOARD_FAB2(SCH_1):M_H_ECC(1)
 J70 M_H_ECC<0> DDR1_ECC<0> @BASEBOARD_FAB2_LIB.BASEBOARD_FAB2(SCH_1):M_H_ECC(0)
 N48 M_H_MA<17> DDR1_MA<17> @BASEBOARD_FAB2_LIB.BASEBOARD_FAB2(SCH_1):M_H_MA(17)
 R52 M_H_MA<16> DDR1_MA<16> @BASEBOARD_FAB2_LIB.BASEBOARD_FAB2(SCH_1):M_H_MA(16)
 N52 M_H_MA<15> DDR1_MA<15> @BASEBOARD_FAB2_LIB.BASEBOARD_FAB2(SCH_1):M_H_MA(15)
 T51 M_H_MA<14> DDR1_MA<14> @BASEBOARD_FAB2_LIB.BASEBOARD_FAB2(SCH_1):M_H_MA(14)
 M51 M_H_MA<13> DDR1_MA<13> @BASEBOARD_FAB2_LIB.BASEBOARD_FAB2(SCH_1):M_H_MA(13)
 T61 M_H_MA<12> DDR1_MA<12> @BASEBOARD_FAB2_LIB.BASEBOARD_FAB2(SCH_1):M_H_MA(12)
 R60 M_H_MA<11> DDR1_MA<11> @BASEBOARD_FAB2_LIB.BASEBOARD_FAB2(SCH_1):M_H_MA(11)
 M55 M_H_MA<10> DDR1_MA<10> @BASEBOARD_FAB2_LIB.BASEBOARD_FAB2(SCH_1):M_H_MA(10)
 K59 M_H_MA<9> DDR1_MA<9> @BASEBOARD_FAB2_LIB.BASEBOARD_FAB2(SCH_1):M_H_MA(9)
 W60 M_H_MA<8> DDR1_MA<8> @BASEBOARD_FAB2_LIB.BASEBOARD_FAB2(SCH_1):M_H_MA(8)
 V61 M_H_MA<7> DDR1_MA<7> @BASEBOARD_FAB2_LIB.BASEBOARD_FAB2(SCH_1):M_H_MA(7)
 T59 M_H_MA<6> DDR1_MA<6> @BASEBOARD_FAB2_LIB.BASEBOARD_FAB2(SCH_1):M_H_MA(6)
 R58 M_H_MA<5> DDR1_MA<5> @BASEBOARD_FAB2_LIB.BASEBOARD_FAB2(SCH_1):M_H_MA(5)
 M59 M_H_MA<4> DDR1_MA<4> @BASEBOARD_FAB2_LIB.BASEBOARD_FAB2(SCH_1):M_H_MA(4)
 N58 M_H_MA<3> DDR1_MA<3> @BASEBOARD_FAB2_LIB.BASEBOARD_FAB2(SCH_1):M_H_MA(3)
 K57 M_H_MA<2> DDR1_MA<2> @BASEBOARD_FAB2_LIB.BASEBOARD_FAB2(SCH_1):M_H_MA(2)
 J58 M_H_MA<1> DDR1_MA<1> @BASEBOARD_FAB2_LIB.BASEBOARD_FAB2(SCH_1):M_H_MA(1)
 J52 M_H_MA<0> DDR1_MA<0> @BASEBOARD_FAB2_LIB.BASEBOARD_FAB2(SCH_1):M_H_MA(0)
 T47 M_H_ODT<3> DDR1_ODT<3> @BASEBOARD_FAB2_LIB.BASEBOARD_FAB2(SCH_1):M_H_ODT(3)
 M49 M_H_ODT<2> DDR1_ODT<2> @BASEBOARD_FAB2_LIB.BASEBOARD_FAB2(SCH_1):M_H_ODT(2)
 R48 M_H_ODT<1> DDR1_ODT<1> @BASEBOARD_FAB2_LIB.BASEBOARD_FAB2(SCH_1):M_H_ODT(1)
 N50 M_H_ODT<0> DDR1_ODT<0> @BASEBOARD_FAB2_LIB.BASEBOARD_FAB2(SCH_1):M_H_ODT(0)
 K53 M_H_PAR DDR1_PAR @BASEBOARD_FAB2_LIB.BASEBOARD_FAB2(SCH_1):M_H_PAR


DRAWING: @BASEBOARD_FAB2_LIB.BASEBOARD_FAB2(SCH_1):PAGE59 

SKX_EXT_B_BGA1-IC,TBD  I172  U2D1
AB61 M_J_ACT_N DDR2_ACT_N @BASEBOARD_FAB2_LIB.BASEBOARD_FAB2(SCH_1):M_J_ACT_N
AD61 M_J_ALERT_N DDR2_ALERT_N @BASEBOARD_FAB2_LIB.BASEBOARD_FAB2(SCH_1):M_J_ALERT_N
AE56 M_J_BA<1> DDR2_BA<1> @BASEBOARD_FAB2_LIB.BASEBOARD_FAB2(SCH_1):M_J_BA(1)
 W52 M_J_BA<0> DDR2_BA<0> @BASEBOARD_FAB2_LIB.BASEBOARD_FAB2(SCH_1):M_J_BA(0)
AE62 M_J_BG<1> DDR2_BG<1> @BASEBOARD_FAB2_LIB.BASEBOARD_FAB2(SCH_1):M_J_BG(1)
AA60 M_J_BG<0> DDR2_BG<0> @BASEBOARD_FAB2_LIB.BASEBOARD_FAB2(SCH_1):M_J_BG(0)
AB45 M_J_C<2> DDR2_CID<2> @BASEBOARD_FAB2_LIB.BASEBOARD_FAB2(SCH_1):M_J_C(2)
AB63 M_J_CKE<3> DDR2_CKE<3> @BASEBOARD_FAB2_LIB.BASEBOARD_FAB2(SCH_1):M_J_CKE(3)
 V63 M_J_CKE<2> DDR2_CKE<2> @BASEBOARD_FAB2_LIB.BASEBOARD_FAB2(SCH_1):M_J_CKE(2)
AD63 M_J_CKE<1> DDR2_CKE<1> @BASEBOARD_FAB2_LIB.BASEBOARD_FAB2(SCH_1):M_J_CKE(1)
AA62 M_J_CKE<0> DDR2_CKE<0> @BASEBOARD_FAB2_LIB.BASEBOARD_FAB2(SCH_1):M_J_CKE(0)
 W56 M_J_CLK_DN<3> DDR2_CLK_DN<3> @BASEBOARD_FAB2_LIB.BASEBOARD_FAB2(SCH_1):M_J_CLK_DN(3)
AA56 M_J_CLK_DN<2> DDR2_CLK_DN<2> @BASEBOARD_FAB2_LIB.BASEBOARD_FAB2(SCH_1):M_J_CLK_DN(2)
 W54 M_J_CLK_DN<1> DDR2_CLK_DN<1> @BASEBOARD_FAB2_LIB.BASEBOARD_FAB2(SCH_1):M_J_CLK_DN(1)
AA54 M_J_CLK_DN<0> DDR2_CLK_DN<0> @BASEBOARD_FAB2_LIB.BASEBOARD_FAB2(SCH_1):M_J_CLK_DN(0)
 V57 M_J_CLK_DP<3> DDR2_CLK_DP<3> @BASEBOARD_FAB2_LIB.BASEBOARD_FAB2(SCH_1):M_J_CLK_DP(3)
AB57 M_J_CLK_DP<2> DDR2_CLK_DP<2> @BASEBOARD_FAB2_LIB.BASEBOARD_FAB2(SCH_1):M_J_CLK_DP(2)
 V55 M_J_CLK_DP<1> DDR2_CLK_DP<1> @BASEBOARD_FAB2_LIB.BASEBOARD_FAB2(SCH_1):M_J_CLK_DP(1)
AB55 M_J_CLK_DP<0> DDR2_CLK_DP<0> @BASEBOARD_FAB2_LIB.BASEBOARD_FAB2(SCH_1):M_J_CLK_DP(0)
 V45 M_J_CS_N<7> DDR2_CS_N<7> @BASEBOARD_FAB2_LIB.BASEBOARD_FAB2(SCH_1):M_J_CS_N(7)
 T45 M_J_CS_N<6> DDR2_CS_N<6> @BASEBOARD_FAB2_LIB.BASEBOARD_FAB2(SCH_1):M_J_CS_N(6)
 W48 M_J_CS_N<5> DDR2_CS_N<5> @BASEBOARD_FAB2_LIB.BASEBOARD_FAB2(SCH_1):M_J_CS_N(5)
AB51 M_J_CS_N<4> DDR2_CS_N<4> @BASEBOARD_FAB2_LIB.BASEBOARD_FAB2(SCH_1):M_J_CS_N(4)
AA46 M_J_CS_N<3> DDR2_CS_N<3> @BASEBOARD_FAB2_LIB.BASEBOARD_FAB2(SCH_1):M_J_CS_N(3)
 W46 M_J_CS_N<2> DDR2_CS_N<2> @BASEBOARD_FAB2_LIB.BASEBOARD_FAB2(SCH_1):M_J_CS_N(2)
AB49 M_J_CS_N<1> DDR2_CS_N<1> @BASEBOARD_FAB2_LIB.BASEBOARD_FAB2(SCH_1):M_J_CS_N(1)
 V51 M_J_CS_N<0> DDR2_CS_N<0> @BASEBOARD_FAB2_LIB.BASEBOARD_FAB2(SCH_1):M_J_CS_N(0)
AH23 M_J_DQ<63> DDR2_DQ<63> @BASEBOARD_FAB2_LIB.BASEBOARD_FAB2(SCH_1):M_J_DQ(63)
AD23 M_J_DQ<62> DDR2_DQ<62> @BASEBOARD_FAB2_LIB.BASEBOARD_FAB2(SCH_1):M_J_DQ(62)
AG26 M_J_DQ<61> DDR2_DQ<61> @BASEBOARD_FAB2_LIB.BASEBOARD_FAB2(SCH_1):M_J_DQ(61)
AE26 M_J_DQ<60> DDR2_DQ<60> @BASEBOARD_FAB2_LIB.BASEBOARD_FAB2(SCH_1):M_J_DQ(60)
AG22 M_J_DQ<59> DDR2_DQ<59> @BASEBOARD_FAB2_LIB.BASEBOARD_FAB2(SCH_1):M_J_DQ(59)
AE22 M_J_DQ<58> DDR2_DQ<58> @BASEBOARD_FAB2_LIB.BASEBOARD_FAB2(SCH_1):M_J_DQ(58)
AH25 M_J_DQ<57> DDR2_DQ<57> @BASEBOARD_FAB2_LIB.BASEBOARD_FAB2(SCH_1):M_J_DQ(57)
AD25 M_J_DQ<56> DDR2_DQ<56> @BASEBOARD_FAB2_LIB.BASEBOARD_FAB2(SCH_1):M_J_DQ(56)
AH29 M_J_DQ<55> DDR2_DQ<55> @BASEBOARD_FAB2_LIB.BASEBOARD_FAB2(SCH_1):M_J_DQ(55)
AD29 M_J_DQ<54> DDR2_DQ<54> @BASEBOARD_FAB2_LIB.BASEBOARD_FAB2(SCH_1):M_J_DQ(54)
AG32 M_J_DQ<53> DDR2_DQ<53> @BASEBOARD_FAB2_LIB.BASEBOARD_FAB2(SCH_1):M_J_DQ(53)
AE32 M_J_DQ<52> DDR2_DQ<52> @BASEBOARD_FAB2_LIB.BASEBOARD_FAB2(SCH_1):M_J_DQ(52)
AG28 M_J_DQ<51> DDR2_DQ<51> @BASEBOARD_FAB2_LIB.BASEBOARD_FAB2(SCH_1):M_J_DQ(51)
AE28 M_J_DQ<50> DDR2_DQ<50> @BASEBOARD_FAB2_LIB.BASEBOARD_FAB2(SCH_1):M_J_DQ(50)
AH31 M_J_DQ<49> DDR2_DQ<49> @BASEBOARD_FAB2_LIB.BASEBOARD_FAB2(SCH_1):M_J_DQ(49)
AD31 M_J_DQ<48> DDR2_DQ<48> @BASEBOARD_FAB2_LIB.BASEBOARD_FAB2(SCH_1):M_J_DQ(48)
AA32 M_J_DQ<47> DDR2_DQ<47> @BASEBOARD_FAB2_LIB.BASEBOARD_FAB2(SCH_1):M_J_DQ(47)
 U32 M_J_DQ<46> DDR2_DQ<46> @BASEBOARD_FAB2_LIB.BASEBOARD_FAB2(SCH_1):M_J_DQ(46)
 Y35 M_J_DQ<45> DDR2_DQ<45> @BASEBOARD_FAB2_LIB.BASEBOARD_FAB2(SCH_1):M_J_DQ(45)
 V35 M_J_DQ<44> DDR2_DQ<44> @BASEBOARD_FAB2_LIB.BASEBOARD_FAB2(SCH_1):M_J_DQ(44)
 Y31 M_J_DQ<43> DDR2_DQ<43> @BASEBOARD_FAB2_LIB.BASEBOARD_FAB2(SCH_1):M_J_DQ(43)
 V31 M_J_DQ<42> DDR2_DQ<42> @BASEBOARD_FAB2_LIB.BASEBOARD_FAB2(SCH_1):M_J_DQ(42)
AA34 M_J_DQ<41> DDR2_DQ<41> @BASEBOARD_FAB2_LIB.BASEBOARD_FAB2(SCH_1):M_J_DQ(41)
 U34 M_J_DQ<40> DDR2_DQ<40> @BASEBOARD_FAB2_LIB.BASEBOARD_FAB2(SCH_1):M_J_DQ(40)
AA38 M_J_DQ<39> DDR2_DQ<39> @BASEBOARD_FAB2_LIB.BASEBOARD_FAB2(SCH_1):M_J_DQ(39)
 U38 M_J_DQ<38> DDR2_DQ<38> @BASEBOARD_FAB2_LIB.BASEBOARD_FAB2(SCH_1):M_J_DQ(38)
 Y41 M_J_DQ<37> DDR2_DQ<37> @BASEBOARD_FAB2_LIB.BASEBOARD_FAB2(SCH_1):M_J_DQ(37)
 V41 M_J_DQ<36> DDR2_DQ<36> @BASEBOARD_FAB2_LIB.BASEBOARD_FAB2(SCH_1):M_J_DQ(36)
 Y37 M_J_DQ<35> DDR2_DQ<35> @BASEBOARD_FAB2_LIB.BASEBOARD_FAB2(SCH_1):M_J_DQ(35)
 V37 M_J_DQ<34> DDR2_DQ<34> @BASEBOARD_FAB2_LIB.BASEBOARD_FAB2(SCH_1):M_J_DQ(34)
AA40 M_J_DQ<33> DDR2_DQ<33> @BASEBOARD_FAB2_LIB.BASEBOARD_FAB2(SCH_1):M_J_DQ(33)
 U40 M_J_DQ<32> DDR2_DQ<32> @BASEBOARD_FAB2_LIB.BASEBOARD_FAB2(SCH_1):M_J_DQ(32)
AT65 M_J_DQ<31> DDR2_DQ<31> @BASEBOARD_FAB2_LIB.BASEBOARD_FAB2(SCH_1):M_J_DQ(31)
AM65 M_J_DQ<30> DDR2_DQ<30> @BASEBOARD_FAB2_LIB.BASEBOARD_FAB2(SCH_1):M_J_DQ(30)
AR68 M_J_DQ<29> DDR2_DQ<29> @BASEBOARD_FAB2_LIB.BASEBOARD_FAB2(SCH_1):M_J_DQ(29)
AN68 M_J_DQ<28> DDR2_DQ<28> @BASEBOARD_FAB2_LIB.BASEBOARD_FAB2(SCH_1):M_J_DQ(28)
AR64 M_J_DQ<27> DDR2_DQ<27> @BASEBOARD_FAB2_LIB.BASEBOARD_FAB2(SCH_1):M_J_DQ(27)
AN64 M_J_DQ<26> DDR2_DQ<26> @BASEBOARD_FAB2_LIB.BASEBOARD_FAB2(SCH_1):M_J_DQ(26)
AT67 M_J_DQ<25> DDR2_DQ<25> @BASEBOARD_FAB2_LIB.BASEBOARD_FAB2(SCH_1):M_J_DQ(25)
AM67 M_J_DQ<24> DDR2_DQ<24> @BASEBOARD_FAB2_LIB.BASEBOARD_FAB2(SCH_1):M_J_DQ(24)
 V69 M_J_DQ<23> DDR2_DQ<23> @BASEBOARD_FAB2_LIB.BASEBOARD_FAB2(SCH_1):M_J_DQ(23)
 T71 M_J_DQ<22> DDR2_DQ<22> @BASEBOARD_FAB2_LIB.BASEBOARD_FAB2(SCH_1):M_J_DQ(22)
AB71 M_J_DQ<21> DDR2_DQ<21> @BASEBOARD_FAB2_LIB.BASEBOARD_FAB2(SCH_1):M_J_DQ(21)
AA72 M_J_DQ<20> DDR2_DQ<20> @BASEBOARD_FAB2_LIB.BASEBOARD_FAB2(SCH_1):M_J_DQ(20)
 T69 M_J_DQ<19> DDR2_DQ<19> @BASEBOARD_FAB2_LIB.BASEBOARD_FAB2(SCH_1):M_J_DQ(19)
 R70 M_J_DQ<18> DDR2_DQ<18> @BASEBOARD_FAB2_LIB.BASEBOARD_FAB2(SCH_1):M_J_DQ(18)
AA70 M_J_DQ<17> DDR2_DQ<17> @BASEBOARD_FAB2_LIB.BASEBOARD_FAB2(SCH_1):M_J_DQ(17)
 W72 M_J_DQ<16> DDR2_DQ<16> @BASEBOARD_FAB2_LIB.BASEBOARD_FAB2(SCH_1):M_J_DQ(16)
 Y75 M_J_DQ<15> DDR2_DQ<15> @BASEBOARD_FAB2_LIB.BASEBOARD_FAB2(SCH_1):M_J_DQ(15)
AB77 M_J_DQ<14> DDR2_DQ<14> @BASEBOARD_FAB2_LIB.BASEBOARD_FAB2(SCH_1):M_J_DQ(14)
AE74 M_J_DQ<13> DDR2_DQ<13> @BASEBOARD_FAB2_LIB.BASEBOARD_FAB2(SCH_1):M_J_DQ(13)
AF75 M_J_DQ<12> DDR2_DQ<12> @BASEBOARD_FAB2_LIB.BASEBOARD_FAB2(SCH_1):M_J_DQ(12)
 W76 M_J_DQ<11> DDR2_DQ<11> @BASEBOARD_FAB2_LIB.BASEBOARD_FAB2(SCH_1):M_J_DQ(11)
 Y77 M_J_DQ<10> DDR2_DQ<10> @BASEBOARD_FAB2_LIB.BASEBOARD_FAB2(SCH_1):M_J_DQ(10)
AC74 M_J_DQ<9> DDR2_DQ<9> @BASEBOARD_FAB2_LIB.BASEBOARD_FAB2(SCH_1):M_J_DQ(9)
AE76 M_J_DQ<8> DDR2_DQ<8> @BASEBOARD_FAB2_LIB.BASEBOARD_FAB2(SCH_1):M_J_DQ(8)
AK75 M_J_DQ<7> DDR2_DQ<7> @BASEBOARD_FAB2_LIB.BASEBOARD_FAB2(SCH_1):M_J_DQ(7)
AM77 M_J_DQ<6> DDR2_DQ<6> @BASEBOARD_FAB2_LIB.BASEBOARD_FAB2(SCH_1):M_J_DQ(6)
AR74 M_J_DQ<5> DDR2_DQ<5> @BASEBOARD_FAB2_LIB.BASEBOARD_FAB2(SCH_1):M_J_DQ(5)
AT75 M_J_DQ<4> DDR2_DQ<4> @BASEBOARD_FAB2_LIB.BASEBOARD_FAB2(SCH_1):M_J_DQ(4)
AJ76 M_J_DQ<3> DDR2_DQ<3> @BASEBOARD_FAB2_LIB.BASEBOARD_FAB2(SCH_1):M_J_DQ(3)
AK77 M_J_DQ<2> DDR2_DQ<2> @BASEBOARD_FAB2_LIB.BASEBOARD_FAB2(SCH_1):M_J_DQ(2)
AN74 M_J_DQ<1> DDR2_DQ<1> @BASEBOARD_FAB2_LIB.BASEBOARD_FAB2(SCH_1):M_J_DQ(1)
AR76 M_J_DQ<0> DDR2_DQ<0> @BASEBOARD_FAB2_LIB.BASEBOARD_FAB2(SCH_1):M_J_DQ(0)
AT71 M_J_DQS_DN<17> DDR2_DQS_DN<17> @BASEBOARD_FAB2_LIB.BASEBOARD_FAB2(SCH_1):M_J_DQS_DN(17)
AC24 M_J_DQS_DN<16> DDR2_DQS_DN<16> @BASEBOARD_FAB2_LIB.BASEBOARD_FAB2(SCH_1):M_J_DQS_DN(16)
AC30 M_J_DQS_DN<15> DDR2_DQS_DN<15> @BASEBOARD_FAB2_LIB.BASEBOARD_FAB2(SCH_1):M_J_DQS_DN(15)
 T33 M_J_DQS_DN<14> DDR2_DQS_DN<14> @BASEBOARD_FAB2_LIB.BASEBOARD_FAB2(SCH_1):M_J_DQS_DN(14)
 T39 M_J_DQS_DN<13> DDR2_DQS_DN<13> @BASEBOARD_FAB2_LIB.BASEBOARD_FAB2(SCH_1):M_J_DQS_DN(13)
AL66 M_J_DQS_DN<12> DDR2_DQS_DN<12> @BASEBOARD_FAB2_LIB.BASEBOARD_FAB2(SCH_1):M_J_DQS_DN(12)
 U72 M_J_DQS_DN<11> DDR2_DQS_DN<11> @BASEBOARD_FAB2_LIB.BASEBOARD_FAB2(SCH_1):M_J_DQS_DN(11)
AD77 M_J_DQS_DN<10> DDR2_DQS_DN<10> @BASEBOARD_FAB2_LIB.BASEBOARD_FAB2(SCH_1):M_J_DQS_DN(10)
AP77 M_J_DQS_DN<9> DDR2_DQS_DN<9> @BASEBOARD_FAB2_LIB.BASEBOARD_FAB2(SCH_1):M_J_DQS_DN(9)
BB71 M_J_DQS_DN<8> DDR2_DQS_DN<8> @BASEBOARD_FAB2_LIB.BASEBOARD_FAB2(SCH_1):M_J_DQS_DN(8)
AJ24 M_J_DQS_DN<7> DDR2_DQS_DN<7> @BASEBOARD_FAB2_LIB.BASEBOARD_FAB2(SCH_1):M_J_DQS_DN(7)
AJ30 M_J_DQS_DN<6> DDR2_DQS_DN<6> @BASEBOARD_FAB2_LIB.BASEBOARD_FAB2(SCH_1):M_J_DQS_DN(6)
AB33 M_J_DQS_DN<5> DDR2_DQS_DN<5> @BASEBOARD_FAB2_LIB.BASEBOARD_FAB2(SCH_1):M_J_DQS_DN(5)
AB39 M_J_DQS_DN<4> DDR2_DQS_DN<4> @BASEBOARD_FAB2_LIB.BASEBOARD_FAB2(SCH_1):M_J_DQS_DN(4)
AU66 M_J_DQS_DN<3> DDR2_DQS_DN<3> @BASEBOARD_FAB2_LIB.BASEBOARD_FAB2(SCH_1):M_J_DQS_DN(3)
 Y69 M_J_DQS_DN<2> DDR2_DQS_DN<2> @BASEBOARD_FAB2_LIB.BASEBOARD_FAB2(SCH_1):M_J_DQS_DN(2)
AA74 M_J_DQS_DN<1> DDR2_DQS_DN<1> @BASEBOARD_FAB2_LIB.BASEBOARD_FAB2(SCH_1):M_J_DQS_DN(1)
AL74 M_J_DQS_DN<0> DDR2_DQS_DN<0> @BASEBOARD_FAB2_LIB.BASEBOARD_FAB2(SCH_1):M_J_DQS_DN(0)
AV71 M_J_DQS_DP<17> DDR2_DQS_DP<17> @BASEBOARD_FAB2_LIB.BASEBOARD_FAB2(SCH_1):M_J_DQS_DP(17)
AE24 M_J_DQS_DP<16> DDR2_DQS_DP<16> @BASEBOARD_FAB2_LIB.BASEBOARD_FAB2(SCH_1):M_J_DQS_DP(16)
AE30 M_J_DQS_DP<15> DDR2_DQS_DP<15> @BASEBOARD_FAB2_LIB.BASEBOARD_FAB2(SCH_1):M_J_DQS_DP(15)
 V33 M_J_DQS_DP<14> DDR2_DQS_DP<14> @BASEBOARD_FAB2_LIB.BASEBOARD_FAB2(SCH_1):M_J_DQS_DP(14)
 V39 M_J_DQS_DP<13> DDR2_DQS_DP<13> @BASEBOARD_FAB2_LIB.BASEBOARD_FAB2(SCH_1):M_J_DQS_DP(13)
AN66 M_J_DQS_DP<12> DDR2_DQS_DP<12> @BASEBOARD_FAB2_LIB.BASEBOARD_FAB2(SCH_1):M_J_DQS_DP(12)
 V71 M_J_DQS_DP<11> DDR2_DQS_DP<11> @BASEBOARD_FAB2_LIB.BASEBOARD_FAB2(SCH_1):M_J_DQS_DP(11)
AC76 M_J_DQS_DP<10> DDR2_DQS_DP<10> @BASEBOARD_FAB2_LIB.BASEBOARD_FAB2(SCH_1):M_J_DQS_DP(10)
AN76 M_J_DQS_DP<9> DDR2_DQS_DP<9> @BASEBOARD_FAB2_LIB.BASEBOARD_FAB2(SCH_1):M_J_DQS_DP(9)
AY71 M_J_DQS_DP<8> DDR2_DQS_DP<8> @BASEBOARD_FAB2_LIB.BASEBOARD_FAB2(SCH_1):M_J_DQS_DP(8)
AG24 M_J_DQS_DP<7> DDR2_DQS_DP<7> @BASEBOARD_FAB2_LIB.BASEBOARD_FAB2(SCH_1):M_J_DQS_DP(7)
AG30 M_J_DQS_DP<6> DDR2_DQS_DP<6> @BASEBOARD_FAB2_LIB.BASEBOARD_FAB2(SCH_1):M_J_DQS_DP(6)
 Y33 M_J_DQS_DP<5> DDR2_DQS_DP<5> @BASEBOARD_FAB2_LIB.BASEBOARD_FAB2(SCH_1):M_J_DQS_DP(5)
 Y39 M_J_DQS_DP<4> DDR2_DQS_DP<4> @BASEBOARD_FAB2_LIB.BASEBOARD_FAB2(SCH_1):M_J_DQS_DP(4)
AR66 M_J_DQS_DP<3> DDR2_DQS_DP<3> @BASEBOARD_FAB2_LIB.BASEBOARD_FAB2(SCH_1):M_J_DQS_DP(3)
 W70 M_J_DQS_DP<2> DDR2_DQS_DP<2> @BASEBOARD_FAB2_LIB.BASEBOARD_FAB2(SCH_1):M_J_DQS_DP(2)
AB75 M_J_DQS_DP<1> DDR2_DQS_DP<1> @BASEBOARD_FAB2_LIB.BASEBOARD_FAB2(SCH_1):M_J_DQS_DP(1)
AM75 M_J_DQS_DP<0> DDR2_DQS_DP<0> @BASEBOARD_FAB2_LIB.BASEBOARD_FAB2(SCH_1):M_J_DQS_DP(0)
BA70 M_J_ECC<7> DDR2_ECC<7> @BASEBOARD_FAB2_LIB.BASEBOARD_FAB2(SCH_1):M_J_ECC(7)
AU70 M_J_ECC<6> DDR2_ECC<6> @BASEBOARD_FAB2_LIB.BASEBOARD_FAB2(SCH_1):M_J_ECC(6)
AY73 M_J_ECC<5> DDR2_ECC<5> @BASEBOARD_FAB2_LIB.BASEBOARD_FAB2(SCH_1):M_J_ECC(5)
AV73 M_J_ECC<4> DDR2_ECC<4> @BASEBOARD_FAB2_LIB.BASEBOARD_FAB2(SCH_1):M_J_ECC(4)
AY69 M_J_ECC<3> DDR2_ECC<3> @BASEBOARD_FAB2_LIB.BASEBOARD_FAB2(SCH_1):M_J_ECC(3)
AV69 M_J_ECC<2> DDR2_ECC<2> @BASEBOARD_FAB2_LIB.BASEBOARD_FAB2(SCH_1):M_J_ECC(2)
BA72 M_J_ECC<1> DDR2_ECC<1> @BASEBOARD_FAB2_LIB.BASEBOARD_FAB2(SCH_1):M_J_ECC(1)
AU72 M_J_ECC<0> DDR2_ECC<0> @BASEBOARD_FAB2_LIB.BASEBOARD_FAB2(SCH_1):M_J_ECC(0)
AC46 M_J_MA<17> DDR2_MA<17> @BASEBOARD_FAB2_LIB.BASEBOARD_FAB2(SCH_1):M_J_MA(17)
AA52 M_J_MA<16> DDR2_MA<16> @BASEBOARD_FAB2_LIB.BASEBOARD_FAB2(SCH_1):M_J_MA(16)
AE54 M_J_MA<15> DDR2_MA<15> @BASEBOARD_FAB2_LIB.BASEBOARD_FAB2(SCH_1):M_J_MA(15)
 W50 M_J_MA<14> DDR2_MA<14> @BASEBOARD_FAB2_LIB.BASEBOARD_FAB2(SCH_1):M_J_MA(14)
AD53 M_J_MA<13> DDR2_MA<13> @BASEBOARD_FAB2_LIB.BASEBOARD_FAB2(SCH_1):M_J_MA(13)
AG62 M_J_MA<12> DDR2_MA<12> @BASEBOARD_FAB2_LIB.BASEBOARD_FAB2(SCH_1):M_J_MA(12)
AG60 M_J_MA<11> DDR2_MA<11> @BASEBOARD_FAB2_LIB.BASEBOARD_FAB2(SCH_1):M_J_MA(11)
AD55 M_J_MA<10> DDR2_MA<10> @BASEBOARD_FAB2_LIB.BASEBOARD_FAB2(SCH_1):M_J_MA(10)
AG58 M_J_MA<9> DDR2_MA<9> @BASEBOARD_FAB2_LIB.BASEBOARD_FAB2(SCH_1):M_J_MA(9)
AD59 M_J_MA<8> DDR2_MA<8> @BASEBOARD_FAB2_LIB.BASEBOARD_FAB2(SCH_1):M_J_MA(8)
AE60 M_J_MA<7> DDR2_MA<7> @BASEBOARD_FAB2_LIB.BASEBOARD_FAB2(SCH_1):M_J_MA(7)
AB59 M_J_MA<6> DDR2_MA<6> @BASEBOARD_FAB2_LIB.BASEBOARD_FAB2(SCH_1):M_J_MA(6)
 V59 M_J_MA<5> DDR2_MA<5> @BASEBOARD_FAB2_LIB.BASEBOARD_FAB2(SCH_1):M_J_MA(5)
AA58 M_J_MA<4> DDR2_MA<4> @BASEBOARD_FAB2_LIB.BASEBOARD_FAB2(SCH_1):M_J_MA(4)
 W58 M_J_MA<3> DDR2_MA<3> @BASEBOARD_FAB2_LIB.BASEBOARD_FAB2(SCH_1):M_J_MA(3)
AD57 M_J_MA<2> DDR2_MA<2> @BASEBOARD_FAB2_LIB.BASEBOARD_FAB2(SCH_1):M_J_MA(2)
AE58 M_J_MA<1> DDR2_MA<1> @BASEBOARD_FAB2_LIB.BASEBOARD_FAB2(SCH_1):M_J_MA(1)
AB53 M_J_MA<0> DDR2_MA<0> @BASEBOARD_FAB2_LIB.BASEBOARD_FAB2(SCH_1):M_J_MA(0)
AB47 M_J_ODT<3> DDR2_ODT<3> @BASEBOARD_FAB2_LIB.BASEBOARD_FAB2(SCH_1):M_J_ODT(3)
 V49 M_J_ODT<2> DDR2_ODT<2> @BASEBOARD_FAB2_LIB.BASEBOARD_FAB2(SCH_1):M_J_ODT(2)
AA48 M_J_ODT<1> DDR2_ODT<1> @BASEBOARD_FAB2_LIB.BASEBOARD_FAB2(SCH_1):M_J_ODT(1)
AA50 M_J_ODT<0> DDR2_ODT<0> @BASEBOARD_FAB2_LIB.BASEBOARD_FAB2(SCH_1):M_J_ODT(0)
 V53 M_J_PAR DDR2_PAR @BASEBOARD_FAB2_LIB.BASEBOARD_FAB2(SCH_1):M_J_PAR


DRAWING: @BASEBOARD_FAB2_LIB.BASEBOARD_FAB2(SCH_1):PAGE60 

SKX_EXT_B_BGA1-IC,TBD  I172  U2D1
DW60 M_K_ACT_N DDR3_ACT_N @BASEBOARD_FAB2_LIB.BASEBOARD_FAB2(SCH_1):M_K_ACT_N
ED63 M_K_ALERT_N DDR3_ALERT_N @BASEBOARD_FAB2_LIB.BASEBOARD_FAB2(SCH_1):M_K_ALERT_N
EA54 M_K_BA<1> DDR3_BA<1> @BASEBOARD_FAB2_LIB.BASEBOARD_FAB2(SCH_1):M_K_BA(1)
EE52 M_K_BA<0> DDR3_BA<0> @BASEBOARD_FAB2_LIB.BASEBOARD_FAB2(SCH_1):M_K_BA(0)
DW62 M_K_BG<1> DDR3_BG<1> @BASEBOARD_FAB2_LIB.BASEBOARD_FAB2(SCH_1):M_K_BG(1)
ED61 M_K_BG<0> DDR3_BG<0> @BASEBOARD_FAB2_LIB.BASEBOARD_FAB2(SCH_1):M_K_BG(0)
DV47 M_K_C<2> DDR3_CID<2> @BASEBOARD_FAB2_LIB.BASEBOARD_FAB2(SCH_1):M_K_C(2)
EB63 M_K_CKE<3> DDR3_CKE<3> @BASEBOARD_FAB2_LIB.BASEBOARD_FAB2(SCH_1):M_K_CKE(3)
EA62 M_K_CKE<2> DDR3_CKE<2> @BASEBOARD_FAB2_LIB.BASEBOARD_FAB2(SCH_1):M_K_CKE(2)
EF63 M_K_CKE<1> DDR3_CKE<1> @BASEBOARD_FAB2_LIB.BASEBOARD_FAB2(SCH_1):M_K_CKE(1)
EE62 M_K_CKE<0> DDR3_CKE<0> @BASEBOARD_FAB2_LIB.BASEBOARD_FAB2(SCH_1):M_K_CKE(0)
EF57 M_K_CLK_DN<3> DDR3_CLK_DN<3> @BASEBOARD_FAB2_LIB.BASEBOARD_FAB2(SCH_1):M_K_CLK_DN(3)
DW56 M_K_CLK_DN<2> DDR3_CLK_DN<2> @BASEBOARD_FAB2_LIB.BASEBOARD_FAB2(SCH_1):M_K_CLK_DN(2)
EF55 M_K_CLK_DN<1> DDR3_CLK_DN<1> @BASEBOARD_FAB2_LIB.BASEBOARD_FAB2(SCH_1):M_K_CLK_DN(1)
ED55 M_K_CLK_DN<0> DDR3_CLK_DN<0> @BASEBOARD_FAB2_LIB.BASEBOARD_FAB2(SCH_1):M_K_CLK_DN(0)
EE56 M_K_CLK_DP<3> DDR3_CLK_DP<3> @BASEBOARD_FAB2_LIB.BASEBOARD_FAB2(SCH_1):M_K_CLK_DP(3)
EA56 M_K_CLK_DP<2> DDR3_CLK_DP<2> @BASEBOARD_FAB2_LIB.BASEBOARD_FAB2(SCH_1):M_K_CLK_DP(2)
EE54 M_K_CLK_DP<1> DDR3_CLK_DP<1> @BASEBOARD_FAB2_LIB.BASEBOARD_FAB2(SCH_1):M_K_CLK_DP(1)
EB55 M_K_CLK_DP<0> DDR3_CLK_DP<0> @BASEBOARD_FAB2_LIB.BASEBOARD_FAB2(SCH_1):M_K_CLK_DP(0)
EB45 M_K_CS_N<7> DDR3_CS_N<7> @BASEBOARD_FAB2_LIB.BASEBOARD_FAB2(SCH_1):M_K_CS_N(7)
DV45 M_K_CS_N<6> DDR3_CS_N<6> @BASEBOARD_FAB2_LIB.BASEBOARD_FAB2(SCH_1):M_K_CS_N(6)
EB49 M_K_CS_N<5> DDR3_CS_N<5> @BASEBOARD_FAB2_LIB.BASEBOARD_FAB2(SCH_1):M_K_CS_N(5)
EB51 M_K_CS_N<4> DDR3_CS_N<4> @BASEBOARD_FAB2_LIB.BASEBOARD_FAB2(SCH_1):M_K_CS_N(4)
EB47 M_K_CS_N<3> DDR3_CS_N<3> @BASEBOARD_FAB2_LIB.BASEBOARD_FAB2(SCH_1):M_K_CS_N(3)
ED47 M_K_CS_N<2> DDR3_CS_N<2> @BASEBOARD_FAB2_LIB.BASEBOARD_FAB2(SCH_1):M_K_CS_N(2)
ED49 M_K_CS_N<1> DDR3_CS_N<1> @BASEBOARD_FAB2_LIB.BASEBOARD_FAB2(SCH_1):M_K_CS_N(1)
EF51 M_K_CS_N<0> DDR3_CS_N<0> @BASEBOARD_FAB2_LIB.BASEBOARD_FAB2(SCH_1):M_K_CS_N(0)
DW22 M_K_DQ<63> DDR3_DQ<63> @BASEBOARD_FAB2_LIB.BASEBOARD_FAB2(SCH_1):M_K_DQ(63)
EC22 M_K_DQ<62> DDR3_DQ<62> @BASEBOARD_FAB2_LIB.BASEBOARD_FAB2(SCH_1):M_K_DQ(62)
DT25 M_K_DQ<61> DDR3_DQ<61> @BASEBOARD_FAB2_LIB.BASEBOARD_FAB2(SCH_1):M_K_DQ(61)
DP25 M_K_DQ<60> DDR3_DQ<60> @BASEBOARD_FAB2_LIB.BASEBOARD_FAB2(SCH_1):M_K_DQ(60)
EB21 M_K_DQ<59> DDR3_DQ<59> @BASEBOARD_FAB2_LIB.BASEBOARD_FAB2(SCH_1):M_K_DQ(59)
DY21 M_K_DQ<58> DDR3_DQ<58> @BASEBOARD_FAB2_LIB.BASEBOARD_FAB2(SCH_1):M_K_DQ(58)
DU24 M_K_DQ<57> DDR3_DQ<57> @BASEBOARD_FAB2_LIB.BASEBOARD_FAB2(SCH_1):M_K_DQ(57)
DN24 M_K_DQ<56> DDR3_DQ<56> @BASEBOARD_FAB2_LIB.BASEBOARD_FAB2(SCH_1):M_K_DQ(56)
DU28 M_K_DQ<55> DDR3_DQ<55> @BASEBOARD_FAB2_LIB.BASEBOARD_FAB2(SCH_1):M_K_DQ(55)
DN28 M_K_DQ<54> DDR3_DQ<54> @BASEBOARD_FAB2_LIB.BASEBOARD_FAB2(SCH_1):M_K_DQ(54)
DT31 M_K_DQ<53> DDR3_DQ<53> @BASEBOARD_FAB2_LIB.BASEBOARD_FAB2(SCH_1):M_K_DQ(53)
DP31 M_K_DQ<52> DDR3_DQ<52> @BASEBOARD_FAB2_LIB.BASEBOARD_FAB2(SCH_1):M_K_DQ(52)
DT27 M_K_DQ<51> DDR3_DQ<51> @BASEBOARD_FAB2_LIB.BASEBOARD_FAB2(SCH_1):M_K_DQ(51)
DP27 M_K_DQ<50> DDR3_DQ<50> @BASEBOARD_FAB2_LIB.BASEBOARD_FAB2(SCH_1):M_K_DQ(50)
DU30 M_K_DQ<49> DDR3_DQ<49> @BASEBOARD_FAB2_LIB.BASEBOARD_FAB2(SCH_1):M_K_DQ(49)
DN30 M_K_DQ<48> DDR3_DQ<48> @BASEBOARD_FAB2_LIB.BASEBOARD_FAB2(SCH_1):M_K_DQ(48)
DU34 M_K_DQ<47> DDR3_DQ<47> @BASEBOARD_FAB2_LIB.BASEBOARD_FAB2(SCH_1):M_K_DQ(47)
DN34 M_K_DQ<46> DDR3_DQ<46> @BASEBOARD_FAB2_LIB.BASEBOARD_FAB2(SCH_1):M_K_DQ(46)
DT37 M_K_DQ<45> DDR3_DQ<45> @BASEBOARD_FAB2_LIB.BASEBOARD_FAB2(SCH_1):M_K_DQ(45)
DP37 M_K_DQ<44> DDR3_DQ<44> @BASEBOARD_FAB2_LIB.BASEBOARD_FAB2(SCH_1):M_K_DQ(44)
DT33 M_K_DQ<43> DDR3_DQ<43> @BASEBOARD_FAB2_LIB.BASEBOARD_FAB2(SCH_1):M_K_DQ(43)
DP33 M_K_DQ<42> DDR3_DQ<42> @BASEBOARD_FAB2_LIB.BASEBOARD_FAB2(SCH_1):M_K_DQ(42)
DU36 M_K_DQ<41> DDR3_DQ<41> @BASEBOARD_FAB2_LIB.BASEBOARD_FAB2(SCH_1):M_K_DQ(41)
DN36 M_K_DQ<40> DDR3_DQ<40> @BASEBOARD_FAB2_LIB.BASEBOARD_FAB2(SCH_1):M_K_DQ(40)
ED37 M_K_DQ<39> DDR3_DQ<39> @BASEBOARD_FAB2_LIB.BASEBOARD_FAB2(SCH_1):M_K_DQ(39)
DY37 M_K_DQ<38> DDR3_DQ<38> @BASEBOARD_FAB2_LIB.BASEBOARD_FAB2(SCH_1):M_K_DQ(38)
EA40 M_K_DQ<37> DDR3_DQ<37> @BASEBOARD_FAB2_LIB.BASEBOARD_FAB2(SCH_1):M_K_DQ(37)
DY39 M_K_DQ<36> DDR3_DQ<36> @BASEBOARD_FAB2_LIB.BASEBOARD_FAB2(SCH_1):M_K_DQ(36)
EC36 M_K_DQ<35> DDR3_DQ<35> @BASEBOARD_FAB2_LIB.BASEBOARD_FAB2(SCH_1):M_K_DQ(35)
EA36 M_K_DQ<34> DDR3_DQ<34> @BASEBOARD_FAB2_LIB.BASEBOARD_FAB2(SCH_1):M_K_DQ(34)
ED39 M_K_DQ<33> DDR3_DQ<33> @BASEBOARD_FAB2_LIB.BASEBOARD_FAB2(SCH_1):M_K_DQ(33)
EC40 M_K_DQ<32> DDR3_DQ<32> @BASEBOARD_FAB2_LIB.BASEBOARD_FAB2(SCH_1):M_K_DQ(32)
DU74 M_K_DQ<31> DDR3_DQ<31> @BASEBOARD_FAB2_LIB.BASEBOARD_FAB2(SCH_1):M_K_DQ(31)
DN74 M_K_DQ<30> DDR3_DQ<30> @BASEBOARD_FAB2_LIB.BASEBOARD_FAB2(SCH_1):M_K_DQ(30)
DT77 M_K_DQ<29> DDR3_DQ<29> @BASEBOARD_FAB2_LIB.BASEBOARD_FAB2(SCH_1):M_K_DQ(29)
DP77 M_K_DQ<28> DDR3_DQ<28> @BASEBOARD_FAB2_LIB.BASEBOARD_FAB2(SCH_1):M_K_DQ(28)
DT73 M_K_DQ<27> DDR3_DQ<27> @BASEBOARD_FAB2_LIB.BASEBOARD_FAB2(SCH_1):M_K_DQ(27)
DP73 M_K_DQ<26> DDR3_DQ<26> @BASEBOARD_FAB2_LIB.BASEBOARD_FAB2(SCH_1):M_K_DQ(26)
DU76 M_K_DQ<25> DDR3_DQ<25> @BASEBOARD_FAB2_LIB.BASEBOARD_FAB2(SCH_1):M_K_DQ(25)
DN76 M_K_DQ<24> DDR3_DQ<24> @BASEBOARD_FAB2_LIB.BASEBOARD_FAB2(SCH_1):M_K_DQ(24)
DN82 M_K_DQ<23> DDR3_DQ<23> @BASEBOARD_FAB2_LIB.BASEBOARD_FAB2(SCH_1):M_K_DQ(23)
DR80 M_K_DQ<22> DDR3_DQ<22> @BASEBOARD_FAB2_LIB.BASEBOARD_FAB2(SCH_1):M_K_DQ(22)
DJ80 M_K_DQ<21> DDR3_DQ<21> @BASEBOARD_FAB2_LIB.BASEBOARD_FAB2(SCH_1):M_K_DQ(21)
DK79 M_K_DQ<20> DDR3_DQ<20> @BASEBOARD_FAB2_LIB.BASEBOARD_FAB2(SCH_1):M_K_DQ(20)
DR82 M_K_DQ<19> DDR3_DQ<19> @BASEBOARD_FAB2_LIB.BASEBOARD_FAB2(SCH_1):M_K_DQ(19)
DT81 M_K_DQ<18> DDR3_DQ<18> @BASEBOARD_FAB2_LIB.BASEBOARD_FAB2(SCH_1):M_K_DQ(18)
DK81 M_K_DQ<17> DDR3_DQ<17> @BASEBOARD_FAB2_LIB.BASEBOARD_FAB2(SCH_1):M_K_DQ(17)
DM79 M_K_DQ<16> DDR3_DQ<16> @BASEBOARD_FAB2_LIB.BASEBOARD_FAB2(SCH_1):M_K_DQ(16)
DV85 M_K_DQ<15> DDR3_DQ<15> @BASEBOARD_FAB2_LIB.BASEBOARD_FAB2(SCH_1):M_K_DQ(15)
DR84 M_K_DQ<14> DDR3_DQ<14> @BASEBOARD_FAB2_LIB.BASEBOARD_FAB2(SCH_1):M_K_DQ(14)
DE84 M_K_DQ<13> DDR3_DQ<13> @BASEBOARD_FAB2_LIB.BASEBOARD_FAB2(SCH_1):M_K_DQ(13)
DD85 M_K_DQ<12> DDR3_DQ<12> @BASEBOARD_FAB2_LIB.BASEBOARD_FAB2(SCH_1):M_K_DQ(12)
DY83 M_K_DQ<11> DDR3_DQ<11> @BASEBOARD_FAB2_LIB.BASEBOARD_FAB2(SCH_1):M_K_DQ(11)
DV83 M_K_DQ<10> DDR3_DQ<10> @BASEBOARD_FAB2_LIB.BASEBOARD_FAB2(SCH_1):M_K_DQ(10)
DH85 M_K_DQ<9> DDR3_DQ<9> @BASEBOARD_FAB2_LIB.BASEBOARD_FAB2(SCH_1):M_K_DQ(9)
DG84 M_K_DQ<8> DDR3_DQ<8> @BASEBOARD_FAB2_LIB.BASEBOARD_FAB2(SCH_1):M_K_DQ(8)
CW84 M_K_DQ<7> DDR3_DQ<7> @BASEBOARD_FAB2_LIB.BASEBOARD_FAB2(SCH_1):M_K_DQ(7)
CW86 M_K_DQ<6> DDR3_DQ<6> @BASEBOARD_FAB2_LIB.BASEBOARD_FAB2(SCH_1):M_K_DQ(6)
CL86 M_K_DQ<5> DDR3_DQ<5> @BASEBOARD_FAB2_LIB.BASEBOARD_FAB2(SCH_1):M_K_DQ(5)
CL84 M_K_DQ<4> DDR3_DQ<4> @BASEBOARD_FAB2_LIB.BASEBOARD_FAB2(SCH_1):M_K_DQ(4)
DA84 M_K_DQ<3> DDR3_DQ<3> @BASEBOARD_FAB2_LIB.BASEBOARD_FAB2(SCH_1):M_K_DQ(3)
DA86 M_K_DQ<2> DDR3_DQ<2> @BASEBOARD_FAB2_LIB.BASEBOARD_FAB2(SCH_1):M_K_DQ(2)
CN86 M_K_DQ<1> DDR3_DQ<1> @BASEBOARD_FAB2_LIB.BASEBOARD_FAB2(SCH_1):M_K_DQ(1)
CN84 M_K_DQ<0> DDR3_DQ<0> @BASEBOARD_FAB2_LIB.BASEBOARD_FAB2(SCH_1):M_K_DQ(0)
DB67 M_K_DQS_DN<17> DDR3_DQS_DN<17> @BASEBOARD_FAB2_LIB.BASEBOARD_FAB2(SCH_1):M_K_DQS_DN(17)
DM23 M_K_DQS_DN<16> DDR3_DQS_DN<16> @BASEBOARD_FAB2_LIB.BASEBOARD_FAB2(SCH_1):M_K_DQS_DN(16)
DM29 M_K_DQS_DN<15> DDR3_DQS_DN<15> @BASEBOARD_FAB2_LIB.BASEBOARD_FAB2(SCH_1):M_K_DQS_DN(15)
DP35 M_K_DQS_DN<14> DDR3_DQS_DN<14> @BASEBOARD_FAB2_LIB.BASEBOARD_FAB2(SCH_1):M_K_DQS_DN(14)
EA38 M_K_DQS_DN<13> DDR3_DQS_DN<13> @BASEBOARD_FAB2_LIB.BASEBOARD_FAB2(SCH_1):M_K_DQS_DN(13)
DP75 M_K_DQS_DN<12> DDR3_DQS_DN<12> @BASEBOARD_FAB2_LIB.BASEBOARD_FAB2(SCH_1):M_K_DQS_DN(12)
DN80 M_K_DQS_DN<11> DDR3_DQS_DN<11> @BASEBOARD_FAB2_LIB.BASEBOARD_FAB2(SCH_1):M_K_DQS_DN(11)
DM85 M_K_DQS_DN<10> DDR3_DQS_DN<10> @BASEBOARD_FAB2_LIB.BASEBOARD_FAB2(SCH_1):M_K_DQS_DN(10)
CR84 M_K_DQS_DN<9> DDR3_DQS_DN<9> @BASEBOARD_FAB2_LIB.BASEBOARD_FAB2(SCH_1):M_K_DQS_DN(9)
DF67 M_K_DQS_DN<8> DDR3_DQS_DN<8> @BASEBOARD_FAB2_LIB.BASEBOARD_FAB2(SCH_1):M_K_DQS_DN(8)
DV23 M_K_DQS_DN<7> DDR3_DQS_DN<7> @BASEBOARD_FAB2_LIB.BASEBOARD_FAB2(SCH_1):M_K_DQS_DN(7)
DV29 M_K_DQS_DN<6> DDR3_DQS_DN<6> @BASEBOARD_FAB2_LIB.BASEBOARD_FAB2(SCH_1):M_K_DQS_DN(6)
DV35 M_K_DQS_DN<5> DDR3_DQS_DN<5> @BASEBOARD_FAB2_LIB.BASEBOARD_FAB2(SCH_1):M_K_DQS_DN(5)
EE38 M_K_DQS_DN<4> DDR3_DQS_DN<4> @BASEBOARD_FAB2_LIB.BASEBOARD_FAB2(SCH_1):M_K_DQS_DN(4)
DV75 M_K_DQS_DN<3> DDR3_DQS_DN<3> @BASEBOARD_FAB2_LIB.BASEBOARD_FAB2(SCH_1):M_K_DQS_DN(3)
DL82 M_K_DQS_DN<2> DDR3_DQS_DN<2> @BASEBOARD_FAB2_LIB.BASEBOARD_FAB2(SCH_1):M_K_DQS_DN(2)
DN84 M_K_DQS_DN<1> DDR3_DQS_DN<1> @BASEBOARD_FAB2_LIB.BASEBOARD_FAB2(SCH_1):M_K_DQS_DN(1)
CU84 M_K_DQS_DN<0> DDR3_DQS_DN<0> @BASEBOARD_FAB2_LIB.BASEBOARD_FAB2(SCH_1):M_K_DQS_DN(0)
CY67 M_K_DQS_DP<17> DDR3_DQS_DP<17> @BASEBOARD_FAB2_LIB.BASEBOARD_FAB2(SCH_1):M_K_DQS_DP(17)
DP23 M_K_DQS_DP<16> DDR3_DQS_DP<16> @BASEBOARD_FAB2_LIB.BASEBOARD_FAB2(SCH_1):M_K_DQS_DP(16)
DP29 M_K_DQS_DP<15> DDR3_DQS_DP<15> @BASEBOARD_FAB2_LIB.BASEBOARD_FAB2(SCH_1):M_K_DQS_DP(15)
DM35 M_K_DQS_DP<14> DDR3_DQS_DP<14> @BASEBOARD_FAB2_LIB.BASEBOARD_FAB2(SCH_1):M_K_DQS_DP(14)
DW38 M_K_DQS_DP<13> DDR3_DQS_DP<13> @BASEBOARD_FAB2_LIB.BASEBOARD_FAB2(SCH_1):M_K_DQS_DP(13)
DM75 M_K_DQS_DP<12> DDR3_DQS_DP<12> @BASEBOARD_FAB2_LIB.BASEBOARD_FAB2(SCH_1):M_K_DQS_DP(12)
DP79 M_K_DQS_DP<11> DDR3_DQS_DP<11> @BASEBOARD_FAB2_LIB.BASEBOARD_FAB2(SCH_1):M_K_DQS_DP(11)
DL84 M_K_DQS_DP<10> DDR3_DQS_DP<10> @BASEBOARD_FAB2_LIB.BASEBOARD_FAB2(SCH_1):M_K_DQS_DP(10)
CP85 M_K_DQS_DP<9> DDR3_DQS_DP<9> @BASEBOARD_FAB2_LIB.BASEBOARD_FAB2(SCH_1):M_K_DQS_DP(9)
DD67 M_K_DQS_DP<8> DDR3_DQS_DP<8> @BASEBOARD_FAB2_LIB.BASEBOARD_FAB2(SCH_1):M_K_DQS_DP(8)
DT23 M_K_DQS_DP<7> DDR3_DQS_DP<7> @BASEBOARD_FAB2_LIB.BASEBOARD_FAB2(SCH_1):M_K_DQS_DP(7)
DT29 M_K_DQS_DP<6> DDR3_DQS_DP<6> @BASEBOARD_FAB2_LIB.BASEBOARD_FAB2(SCH_1):M_K_DQS_DP(6)
DT35 M_K_DQS_DP<5> DDR3_DQS_DP<5> @BASEBOARD_FAB2_LIB.BASEBOARD_FAB2(SCH_1):M_K_DQS_DP(5)
EC38 M_K_DQS_DP<4> DDR3_DQS_DP<4> @BASEBOARD_FAB2_LIB.BASEBOARD_FAB2(SCH_1):M_K_DQS_DP(4)
DT75 M_K_DQS_DP<3> DDR3_DQS_DP<3> @BASEBOARD_FAB2_LIB.BASEBOARD_FAB2(SCH_1):M_K_DQS_DP(3)
DM81 M_K_DQS_DP<2> DDR3_DQS_DP<2> @BASEBOARD_FAB2_LIB.BASEBOARD_FAB2(SCH_1):M_K_DQS_DP(2)
DP85 M_K_DQS_DP<1> DDR3_DQS_DP<1> @BASEBOARD_FAB2_LIB.BASEBOARD_FAB2(SCH_1):M_K_DQS_DP(1)
CV85 M_K_DQS_DP<0> DDR3_DQS_DP<0> @BASEBOARD_FAB2_LIB.BASEBOARD_FAB2(SCH_1):M_K_DQS_DP(0)
DE66 M_K_ECC<7> DDR3_ECC<7> @BASEBOARD_FAB2_LIB.BASEBOARD_FAB2(SCH_1):M_K_ECC(7)
DA66 M_K_ECC<6> DDR3_ECC<6> @BASEBOARD_FAB2_LIB.BASEBOARD_FAB2(SCH_1):M_K_ECC(6)
DD69 M_K_ECC<5> DDR3_ECC<5> @BASEBOARD_FAB2_LIB.BASEBOARD_FAB2(SCH_1):M_K_ECC(5)
DB69 M_K_ECC<4> DDR3_ECC<4> @BASEBOARD_FAB2_LIB.BASEBOARD_FAB2(SCH_1):M_K_ECC(4)
DD65 M_K_ECC<3> DDR3_ECC<3> @BASEBOARD_FAB2_LIB.BASEBOARD_FAB2(SCH_1):M_K_ECC(3)
DB65 M_K_ECC<2> DDR3_ECC<2> @BASEBOARD_FAB2_LIB.BASEBOARD_FAB2(SCH_1):M_K_ECC(2)
DE68 M_K_ECC<1> DDR3_ECC<1> @BASEBOARD_FAB2_LIB.BASEBOARD_FAB2(SCH_1):M_K_ECC(1)
DA68 M_K_ECC<0> DDR3_ECC<0> @BASEBOARD_FAB2_LIB.BASEBOARD_FAB2(SCH_1):M_K_ECC(0)
EA46 M_K_MA<17> DDR3_MA<17> @BASEBOARD_FAB2_LIB.BASEBOARD_FAB2(SCH_1):M_K_MA(17)
EA52 M_K_MA<16> DDR3_MA<16> @BASEBOARD_FAB2_LIB.BASEBOARD_FAB2(SCH_1):M_K_MA(16)
DV49 M_K_MA<15> DDR3_MA<15> @BASEBOARD_FAB2_LIB.BASEBOARD_FAB2(SCH_1):M_K_MA(15)
ED51 M_K_MA<14> DDR3_MA<14> @BASEBOARD_FAB2_LIB.BASEBOARD_FAB2(SCH_1):M_K_MA(14)
DW48 M_K_MA<13> DDR3_MA<13> @BASEBOARD_FAB2_LIB.BASEBOARD_FAB2(SCH_1):M_K_MA(13)
DT63 M_K_MA<12> DDR3_MA<12> @BASEBOARD_FAB2_LIB.BASEBOARD_FAB2(SCH_1):M_K_MA(12)
EB61 M_K_MA<11> DDR3_MA<11> @BASEBOARD_FAB2_LIB.BASEBOARD_FAB2(SCH_1):M_K_MA(11)
DW54 M_K_MA<10> DDR3_MA<10> @BASEBOARD_FAB2_LIB.BASEBOARD_FAB2(SCH_1):M_K_MA(10)
EF61 M_K_MA<9> DDR3_MA<9> @BASEBOARD_FAB2_LIB.BASEBOARD_FAB2(SCH_1):M_K_MA(9)
EB59 M_K_MA<8> DDR3_MA<8> @BASEBOARD_FAB2_LIB.BASEBOARD_FAB2(SCH_1):M_K_MA(8)
EA60 M_K_MA<7> DDR3_MA<7> @BASEBOARD_FAB2_LIB.BASEBOARD_FAB2(SCH_1):M_K_MA(7)
EE60 M_K_MA<6> DDR3_MA<6> @BASEBOARD_FAB2_LIB.BASEBOARD_FAB2(SCH_1):M_K_MA(6)
EA58 M_K_MA<5> DDR3_MA<5> @BASEBOARD_FAB2_LIB.BASEBOARD_FAB2(SCH_1):M_K_MA(5)
ED59 M_K_MA<4> DDR3_MA<4> @BASEBOARD_FAB2_LIB.BASEBOARD_FAB2(SCH_1):M_K_MA(4)
EB57 M_K_MA<3> DDR3_MA<3> @BASEBOARD_FAB2_LIB.BASEBOARD_FAB2(SCH_1):M_K_MA(3)
EE58 M_K_MA<2> DDR3_MA<2> @BASEBOARD_FAB2_LIB.BASEBOARD_FAB2(SCH_1):M_K_MA(2)
ED57 M_K_MA<1> DDR3_MA<1> @BASEBOARD_FAB2_LIB.BASEBOARD_FAB2(SCH_1):M_K_MA(1)
EB53 M_K_MA<0> DDR3_MA<0> @BASEBOARD_FAB2_LIB.BASEBOARD_FAB2(SCH_1):M_K_MA(0)
EA48 M_K_ODT<3> DDR3_ODT<3> @BASEBOARD_FAB2_LIB.BASEBOARD_FAB2(SCH_1):M_K_ODT(3)
EA50 M_K_ODT<2> DDR3_ODT<2> @BASEBOARD_FAB2_LIB.BASEBOARD_FAB2(SCH_1):M_K_ODT(2)
EE48 M_K_ODT<1> DDR3_ODT<1> @BASEBOARD_FAB2_LIB.BASEBOARD_FAB2(SCH_1):M_K_ODT(1)
EE50 M_K_ODT<0> DDR3_ODT<0> @BASEBOARD_FAB2_LIB.BASEBOARD_FAB2(SCH_1):M_K_ODT(0)
ED53 M_K_PAR DDR3_PAR @BASEBOARD_FAB2_LIB.BASEBOARD_FAB2(SCH_1):M_K_PAR


DRAWING: @BASEBOARD_FAB2_LIB.BASEBOARD_FAB2(SCH_1):PAGE61 

SKX_EXT_B_BGA1-IC,TBD  I172  U2D1
DR62 M_L_ACT_N DDR4_ACT_N @BASEBOARD_FAB2_LIB.BASEBOARD_FAB2(SCH_1):M_L_ACT_N
DT61 M_L_ALERT_N DDR4_ALERT_N @BASEBOARD_FAB2_LIB.BASEBOARD_FAB2(SCH_1):M_L_ALERT_N
DV55 M_L_BA<1> DDR4_BA<1> @BASEBOARD_FAB2_LIB.BASEBOARD_FAB2(SCH_1):M_L_BA(1)
DM53 M_L_BA<0> DDR4_BA<0> @BASEBOARD_FAB2_LIB.BASEBOARD_FAB2(SCH_1):M_L_BA(0)
DM61 M_L_BG<1> DDR4_BG<1> @BASEBOARD_FAB2_LIB.BASEBOARD_FAB2(SCH_1):M_L_BG(1)
DJ62 M_L_BG<0> DDR4_BG<0> @BASEBOARD_FAB2_LIB.BASEBOARD_FAB2(SCH_1):M_L_BG(0)
DT47 M_L_C<2> DDR4_CID<2> @BASEBOARD_FAB2_LIB.BASEBOARD_FAB2(SCH_1):M_L_C(2)
DR64 M_L_CKE<3> DDR4_CKE<3> @BASEBOARD_FAB2_LIB.BASEBOARD_FAB2(SCH_1):M_L_CKE(3)
DL64 M_L_CKE<2> DDR4_CKE<2> @BASEBOARD_FAB2_LIB.BASEBOARD_FAB2(SCH_1):M_L_CKE(2)
DN64 M_L_CKE<1> DDR4_CKE<1> @BASEBOARD_FAB2_LIB.BASEBOARD_FAB2(SCH_1):M_L_CKE(1)
DM63 M_L_CKE<0> DDR4_CKE<0> @BASEBOARD_FAB2_LIB.BASEBOARD_FAB2(SCH_1):M_L_CKE(0)
DT57 M_L_CLK_DN<3> DDR4_CLK_DN<3> @BASEBOARD_FAB2_LIB.BASEBOARD_FAB2(SCH_1):M_L_CLK_DN(3)
DM57 M_L_CLK_DN<2> DDR4_CLK_DN<2> @BASEBOARD_FAB2_LIB.BASEBOARD_FAB2(SCH_1):M_L_CLK_DN(2)
DR54 M_L_CLK_DN<1> DDR4_CLK_DN<1> @BASEBOARD_FAB2_LIB.BASEBOARD_FAB2(SCH_1):M_L_CLK_DN(1)
DM55 M_L_CLK_DN<0> DDR4_CLK_DN<0> @BASEBOARD_FAB2_LIB.BASEBOARD_FAB2(SCH_1):M_L_CLK_DN(0)
DR56 M_L_CLK_DP<3> DDR4_CLK_DP<3> @BASEBOARD_FAB2_LIB.BASEBOARD_FAB2(SCH_1):M_L_CLK_DP(3)
DN56 M_L_CLK_DP<2> DDR4_CLK_DP<2> @BASEBOARD_FAB2_LIB.BASEBOARD_FAB2(SCH_1):M_L_CLK_DP(2)
DT53 M_L_CLK_DP<1> DDR4_CLK_DP<1> @BASEBOARD_FAB2_LIB.BASEBOARD_FAB2(SCH_1):M_L_CLK_DP(1)
DN54 M_L_CLK_DP<0> DDR4_CLK_DP<0> @BASEBOARD_FAB2_LIB.BASEBOARD_FAB2(SCH_1):M_L_CLK_DP(0)
DN46 M_L_CS_N<7> DDR4_CS_N<7> @BASEBOARD_FAB2_LIB.BASEBOARD_FAB2(SCH_1):M_L_CS_N(7)
DT45 M_L_CS_N<6> DDR4_CS_N<6> @BASEBOARD_FAB2_LIB.BASEBOARD_FAB2(SCH_1):M_L_CS_N(6)
DM49 M_L_CS_N<5> DDR4_CS_N<5> @BASEBOARD_FAB2_LIB.BASEBOARD_FAB2(SCH_1):M_L_CS_N(5)
DW50 M_L_CS_N<4> DDR4_CS_N<4> @BASEBOARD_FAB2_LIB.BASEBOARD_FAB2(SCH_1):M_L_CS_N(4)
DK47 M_L_CS_N<3> DDR4_CS_N<3> @BASEBOARD_FAB2_LIB.BASEBOARD_FAB2(SCH_1):M_L_CS_N(3)
DR46 M_L_CS_N<2> DDR4_CS_N<2> @BASEBOARD_FAB2_LIB.BASEBOARD_FAB2(SCH_1):M_L_CS_N(2)
DN50 M_L_CS_N<1> DDR4_CS_N<1> @BASEBOARD_FAB2_LIB.BASEBOARD_FAB2(SCH_1):M_L_CS_N(1)
DV51 M_L_CS_N<0> DDR4_CS_N<0> @BASEBOARD_FAB2_LIB.BASEBOARD_FAB2(SCH_1):M_L_CS_N(0)
DK25 M_L_DQ<63> DDR4_DQ<63> @BASEBOARD_FAB2_LIB.BASEBOARD_FAB2(SCH_1):M_L_DQ(63)
DF25 M_L_DQ<62> DDR4_DQ<62> @BASEBOARD_FAB2_LIB.BASEBOARD_FAB2(SCH_1):M_L_DQ(62)
DJ28 M_L_DQ<61> DDR4_DQ<61> @BASEBOARD_FAB2_LIB.BASEBOARD_FAB2(SCH_1):M_L_DQ(61)
DG28 M_L_DQ<60> DDR4_DQ<60> @BASEBOARD_FAB2_LIB.BASEBOARD_FAB2(SCH_1):M_L_DQ(60)
DJ24 M_L_DQ<59> DDR4_DQ<59> @BASEBOARD_FAB2_LIB.BASEBOARD_FAB2(SCH_1):M_L_DQ(59)
DD25 M_L_DQ<58> DDR4_DQ<58> @BASEBOARD_FAB2_LIB.BASEBOARD_FAB2(SCH_1):M_L_DQ(58)
DK27 M_L_DQ<57> DDR4_DQ<57> @BASEBOARD_FAB2_LIB.BASEBOARD_FAB2(SCH_1):M_L_DQ(57)
DF27 M_L_DQ<56> DDR4_DQ<56> @BASEBOARD_FAB2_LIB.BASEBOARD_FAB2(SCH_1):M_L_DQ(56)
ED25 M_L_DQ<55> DDR4_DQ<55> @BASEBOARD_FAB2_LIB.BASEBOARD_FAB2(SCH_1):M_L_DQ(55)
DY25 M_L_DQ<54> DDR4_DQ<54> @BASEBOARD_FAB2_LIB.BASEBOARD_FAB2(SCH_1):M_L_DQ(54)
EA28 M_L_DQ<53> DDR4_DQ<53> @BASEBOARD_FAB2_LIB.BASEBOARD_FAB2(SCH_1):M_L_DQ(53)
DY27 M_L_DQ<52> DDR4_DQ<52> @BASEBOARD_FAB2_LIB.BASEBOARD_FAB2(SCH_1):M_L_DQ(52)
EC24 M_L_DQ<51> DDR4_DQ<51> @BASEBOARD_FAB2_LIB.BASEBOARD_FAB2(SCH_1):M_L_DQ(51)
EA24 M_L_DQ<50> DDR4_DQ<50> @BASEBOARD_FAB2_LIB.BASEBOARD_FAB2(SCH_1):M_L_DQ(50)
ED27 M_L_DQ<49> DDR4_DQ<49> @BASEBOARD_FAB2_LIB.BASEBOARD_FAB2(SCH_1):M_L_DQ(49)
EC28 M_L_DQ<48> DDR4_DQ<48> @BASEBOARD_FAB2_LIB.BASEBOARD_FAB2(SCH_1):M_L_DQ(48)
ED31 M_L_DQ<47> DDR4_DQ<47> @BASEBOARD_FAB2_LIB.BASEBOARD_FAB2(SCH_1):M_L_DQ(47)
DY31 M_L_DQ<46> DDR4_DQ<46> @BASEBOARD_FAB2_LIB.BASEBOARD_FAB2(SCH_1):M_L_DQ(46)
EA34 M_L_DQ<45> DDR4_DQ<45> @BASEBOARD_FAB2_LIB.BASEBOARD_FAB2(SCH_1):M_L_DQ(45)
DY33 M_L_DQ<44> DDR4_DQ<44> @BASEBOARD_FAB2_LIB.BASEBOARD_FAB2(SCH_1):M_L_DQ(44)
EC30 M_L_DQ<43> DDR4_DQ<43> @BASEBOARD_FAB2_LIB.BASEBOARD_FAB2(SCH_1):M_L_DQ(43)
EA30 M_L_DQ<42> DDR4_DQ<42> @BASEBOARD_FAB2_LIB.BASEBOARD_FAB2(SCH_1):M_L_DQ(42)
ED33 M_L_DQ<41> DDR4_DQ<41> @BASEBOARD_FAB2_LIB.BASEBOARD_FAB2(SCH_1):M_L_DQ(41)
EC34 M_L_DQ<40> DDR4_DQ<40> @BASEBOARD_FAB2_LIB.BASEBOARD_FAB2(SCH_1):M_L_DQ(40)
DU40 M_L_DQ<39> DDR4_DQ<39> @BASEBOARD_FAB2_LIB.BASEBOARD_FAB2(SCH_1):M_L_DQ(39)
DN40 M_L_DQ<38> DDR4_DQ<38> @BASEBOARD_FAB2_LIB.BASEBOARD_FAB2(SCH_1):M_L_DQ(38)
DN42 M_L_DQ<37> DDR4_DQ<37> @BASEBOARD_FAB2_LIB.BASEBOARD_FAB2(SCH_1):M_L_DQ(37)
DL42 M_L_DQ<36> DDR4_DQ<36> @BASEBOARD_FAB2_LIB.BASEBOARD_FAB2(SCH_1):M_L_DQ(36)
DT39 M_L_DQ<35> DDR4_DQ<35> @BASEBOARD_FAB2_LIB.BASEBOARD_FAB2(SCH_1):M_L_DQ(35)
DP39 M_L_DQ<34> DDR4_DQ<34> @BASEBOARD_FAB2_LIB.BASEBOARD_FAB2(SCH_1):M_L_DQ(34)
DW42 M_L_DQ<33> DDR4_DQ<33> @BASEBOARD_FAB2_LIB.BASEBOARD_FAB2(SCH_1):M_L_DQ(33)
DU42 M_L_DQ<32> DDR4_DQ<32> @BASEBOARD_FAB2_LIB.BASEBOARD_FAB2(SCH_1):M_L_DQ(32)
EE72 M_L_DQ<31> DDR4_DQ<31> @BASEBOARD_FAB2_LIB.BASEBOARD_FAB2(SCH_1):M_L_DQ(31)
EA72 M_L_DQ<30> DDR4_DQ<30> @BASEBOARD_FAB2_LIB.BASEBOARD_FAB2(SCH_1):M_L_DQ(30)
EB75 M_L_DQ<29> DDR4_DQ<29> @BASEBOARD_FAB2_LIB.BASEBOARD_FAB2(SCH_1):M_L_DQ(29)
EA74 M_L_DQ<28> DDR4_DQ<28> @BASEBOARD_FAB2_LIB.BASEBOARD_FAB2(SCH_1):M_L_DQ(28)
ED71 M_L_DQ<27> DDR4_DQ<27> @BASEBOARD_FAB2_LIB.BASEBOARD_FAB2(SCH_1):M_L_DQ(27)
EB71 M_L_DQ<26> DDR4_DQ<26> @BASEBOARD_FAB2_LIB.BASEBOARD_FAB2(SCH_1):M_L_DQ(26)
EE74 M_L_DQ<25> DDR4_DQ<25> @BASEBOARD_FAB2_LIB.BASEBOARD_FAB2(SCH_1):M_L_DQ(25)
ED75 M_L_DQ<24> DDR4_DQ<24> @BASEBOARD_FAB2_LIB.BASEBOARD_FAB2(SCH_1):M_L_DQ(24)
EC78 M_L_DQ<23> DDR4_DQ<23> @BASEBOARD_FAB2_LIB.BASEBOARD_FAB2(SCH_1):M_L_DQ(23)
DW78 M_L_DQ<22> DDR4_DQ<22> @BASEBOARD_FAB2_LIB.BASEBOARD_FAB2(SCH_1):M_L_DQ(22)
EB81 M_L_DQ<21> DDR4_DQ<21> @BASEBOARD_FAB2_LIB.BASEBOARD_FAB2(SCH_1):M_L_DQ(21)
DY81 M_L_DQ<20> DDR4_DQ<20> @BASEBOARD_FAB2_LIB.BASEBOARD_FAB2(SCH_1):M_L_DQ(20)
EB77 M_L_DQ<19> DDR4_DQ<19> @BASEBOARD_FAB2_LIB.BASEBOARD_FAB2(SCH_1):M_L_DQ(19)
DY77 M_L_DQ<18> DDR4_DQ<18> @BASEBOARD_FAB2_LIB.BASEBOARD_FAB2(SCH_1):M_L_DQ(18)
EC80 M_L_DQ<17> DDR4_DQ<17> @BASEBOARD_FAB2_LIB.BASEBOARD_FAB2(SCH_1):M_L_DQ(17)
DW80 M_L_DQ<16> DDR4_DQ<16> @BASEBOARD_FAB2_LIB.BASEBOARD_FAB2(SCH_1):M_L_DQ(16)
DE82 M_L_DQ<15> DDR4_DQ<15> @BASEBOARD_FAB2_LIB.BASEBOARD_FAB2(SCH_1):M_L_DQ(15)
DC82 M_L_DQ<14> DDR4_DQ<14> @BASEBOARD_FAB2_LIB.BASEBOARD_FAB2(SCH_1):M_L_DQ(14)
CW80 M_L_DQ<13> DDR4_DQ<13> @BASEBOARD_FAB2_LIB.BASEBOARD_FAB2(SCH_1):M_L_DQ(13)
CY79 M_L_DQ<12> DDR4_DQ<12> @BASEBOARD_FAB2_LIB.BASEBOARD_FAB2(SCH_1):M_L_DQ(12)
DF81 M_L_DQ<11> DDR4_DQ<11> @BASEBOARD_FAB2_LIB.BASEBOARD_FAB2(SCH_1):M_L_DQ(11)
DE80 M_L_DQ<10> DDR4_DQ<10> @BASEBOARD_FAB2_LIB.BASEBOARD_FAB2(SCH_1):M_L_DQ(10)
CY81 M_L_DQ<9> DDR4_DQ<9> @BASEBOARD_FAB2_LIB.BASEBOARD_FAB2(SCH_1):M_L_DQ(9)
DB79 M_L_DQ<8> DDR4_DQ<8> @BASEBOARD_FAB2_LIB.BASEBOARD_FAB2(SCH_1):M_L_DQ(8)
CN82 M_L_DQ<7> DDR4_DQ<7> @BASEBOARD_FAB2_LIB.BASEBOARD_FAB2(SCH_1):M_L_DQ(7)
CR80 M_L_DQ<6> DDR4_DQ<6> @BASEBOARD_FAB2_LIB.BASEBOARD_FAB2(SCH_1):M_L_DQ(6)
CJ80 M_L_DQ<5> DDR4_DQ<5> @BASEBOARD_FAB2_LIB.BASEBOARD_FAB2(SCH_1):M_L_DQ(5)
CK79 M_L_DQ<4> DDR4_DQ<4> @BASEBOARD_FAB2_LIB.BASEBOARD_FAB2(SCH_1):M_L_DQ(4)
CR82 M_L_DQ<3> DDR4_DQ<3> @BASEBOARD_FAB2_LIB.BASEBOARD_FAB2(SCH_1):M_L_DQ(3)
CT81 M_L_DQ<2> DDR4_DQ<2> @BASEBOARD_FAB2_LIB.BASEBOARD_FAB2(SCH_1):M_L_DQ(2)
CK81 M_L_DQ<1> DDR4_DQ<1> @BASEBOARD_FAB2_LIB.BASEBOARD_FAB2(SCH_1):M_L_DQ(1)
CM79 M_L_DQ<0> DDR4_DQ<0> @BASEBOARD_FAB2_LIB.BASEBOARD_FAB2(SCH_1):M_L_DQ(0)
DV67 M_L_DQS_DN<17> DDR4_DQS_DN<17> @BASEBOARD_FAB2_LIB.BASEBOARD_FAB2(SCH_1):M_L_DQS_DN(17)
DG26 M_L_DQS_DN<16> DDR4_DQS_DN<16> @BASEBOARD_FAB2_LIB.BASEBOARD_FAB2(SCH_1):M_L_DQS_DN(16)
EA26 M_L_DQS_DN<15> DDR4_DQS_DN<15> @BASEBOARD_FAB2_LIB.BASEBOARD_FAB2(SCH_1):M_L_DQS_DN(15)
EA32 M_L_DQS_DN<14> DDR4_DQS_DN<14> @BASEBOARD_FAB2_LIB.BASEBOARD_FAB2(SCH_1):M_L_DQS_DN(14)
DP41 M_L_DQS_DN<13> DDR4_DQS_DN<13> @BASEBOARD_FAB2_LIB.BASEBOARD_FAB2(SCH_1):M_L_DQS_DN(13)
EB73 M_L_DQS_DN<12> DDR4_DQS_DN<12> @BASEBOARD_FAB2_LIB.BASEBOARD_FAB2(SCH_1):M_L_DQS_DN(12)
DY79 M_L_DQS_DN<11> DDR4_DQS_DN<11> @BASEBOARD_FAB2_LIB.BASEBOARD_FAB2(SCH_1):M_L_DQS_DN(11)
DC80 M_L_DQS_DN<10> DDR4_DQS_DN<10> @BASEBOARD_FAB2_LIB.BASEBOARD_FAB2(SCH_1):M_L_DQS_DN(10)
CN80 M_L_DQS_DN<9> DDR4_DQS_DN<9> @BASEBOARD_FAB2_LIB.BASEBOARD_FAB2(SCH_1):M_L_DQS_DN(9)
EB67 M_L_DQS_DN<8> DDR4_DQS_DN<8> @BASEBOARD_FAB2_LIB.BASEBOARD_FAB2(SCH_1):M_L_DQS_DN(8)
DL26 M_L_DQS_DN<7> DDR4_DQS_DN<7> @BASEBOARD_FAB2_LIB.BASEBOARD_FAB2(SCH_1):M_L_DQS_DN(7)
EE26 M_L_DQS_DN<6> DDR4_DQS_DN<6> @BASEBOARD_FAB2_LIB.BASEBOARD_FAB2(SCH_1):M_L_DQS_DN(6)
EE32 M_L_DQS_DN<5> DDR4_DQS_DN<5> @BASEBOARD_FAB2_LIB.BASEBOARD_FAB2(SCH_1):M_L_DQS_DN(5)
DV41 M_L_DQS_DN<4> DDR4_DQS_DN<4> @BASEBOARD_FAB2_LIB.BASEBOARD_FAB2(SCH_1):M_L_DQS_DN(4)
EF73 M_L_DQS_DN<3> DDR4_DQS_DN<3> @BASEBOARD_FAB2_LIB.BASEBOARD_FAB2(SCH_1):M_L_DQS_DN(3)
ED79 M_L_DQS_DN<2> DDR4_DQS_DN<2> @BASEBOARD_FAB2_LIB.BASEBOARD_FAB2(SCH_1):M_L_DQS_DN(2)
DA82 M_L_DQS_DN<1> DDR4_DQS_DN<1> @BASEBOARD_FAB2_LIB.BASEBOARD_FAB2(SCH_1):M_L_DQS_DN(1)
CL82 M_L_DQS_DN<0> DDR4_DQS_DN<0> @BASEBOARD_FAB2_LIB.BASEBOARD_FAB2(SCH_1):M_L_DQS_DN(0)
DT67 M_L_DQS_DP<17> DDR4_DQS_DP<17> @BASEBOARD_FAB2_LIB.BASEBOARD_FAB2(SCH_1):M_L_DQS_DP(17)
DE26 M_L_DQS_DP<16> DDR4_DQS_DP<16> @BASEBOARD_FAB2_LIB.BASEBOARD_FAB2(SCH_1):M_L_DQS_DP(16)
DW26 M_L_DQS_DP<15> DDR4_DQS_DP<15> @BASEBOARD_FAB2_LIB.BASEBOARD_FAB2(SCH_1):M_L_DQS_DP(15)
DW32 M_L_DQS_DP<14> DDR4_DQS_DP<14> @BASEBOARD_FAB2_LIB.BASEBOARD_FAB2(SCH_1):M_L_DQS_DP(14)
DM41 M_L_DQS_DP<13> DDR4_DQS_DP<13> @BASEBOARD_FAB2_LIB.BASEBOARD_FAB2(SCH_1):M_L_DQS_DP(13)
DY73 M_L_DQS_DP<12> DDR4_DQS_DP<12> @BASEBOARD_FAB2_LIB.BASEBOARD_FAB2(SCH_1):M_L_DQS_DP(12)
DV79 M_L_DQS_DP<11> DDR4_DQS_DP<11> @BASEBOARD_FAB2_LIB.BASEBOARD_FAB2(SCH_1):M_L_DQS_DP(11)
DD79 M_L_DQS_DP<10> DDR4_DQS_DP<10> @BASEBOARD_FAB2_LIB.BASEBOARD_FAB2(SCH_1):M_L_DQS_DP(10)
CP79 M_L_DQS_DP<9> DDR4_DQS_DP<9> @BASEBOARD_FAB2_LIB.BASEBOARD_FAB2(SCH_1):M_L_DQS_DP(9)
DY67 M_L_DQS_DP<8> DDR4_DQS_DP<8> @BASEBOARD_FAB2_LIB.BASEBOARD_FAB2(SCH_1):M_L_DQS_DP(8)
DJ26 M_L_DQS_DP<7> DDR4_DQS_DP<7> @BASEBOARD_FAB2_LIB.BASEBOARD_FAB2(SCH_1):M_L_DQS_DP(7)
EC26 M_L_DQS_DP<6> DDR4_DQS_DP<6> @BASEBOARD_FAB2_LIB.BASEBOARD_FAB2(SCH_1):M_L_DQS_DP(6)
EC32 M_L_DQS_DP<5> DDR4_DQS_DP<5> @BASEBOARD_FAB2_LIB.BASEBOARD_FAB2(SCH_1):M_L_DQS_DP(5)
DT41 M_L_DQS_DP<4> DDR4_DQS_DP<4> @BASEBOARD_FAB2_LIB.BASEBOARD_FAB2(SCH_1):M_L_DQS_DP(4)
ED73 M_L_DQS_DP<3> DDR4_DQS_DP<3> @BASEBOARD_FAB2_LIB.BASEBOARD_FAB2(SCH_1):M_L_DQS_DP(3)
EB79 M_L_DQS_DP<2> DDR4_DQS_DP<2> @BASEBOARD_FAB2_LIB.BASEBOARD_FAB2(SCH_1):M_L_DQS_DP(2)
DB81 M_L_DQS_DP<1> DDR4_DQS_DP<1> @BASEBOARD_FAB2_LIB.BASEBOARD_FAB2(SCH_1):M_L_DQS_DP(1)
CM81 M_L_DQS_DP<0> DDR4_DQS_DP<0> @BASEBOARD_FAB2_LIB.BASEBOARD_FAB2(SCH_1):M_L_DQS_DP(0)
EA66 M_L_ECC<7> DDR4_ECC<7> @BASEBOARD_FAB2_LIB.BASEBOARD_FAB2(SCH_1):M_L_ECC(7)
DU66 M_L_ECC<6> DDR4_ECC<6> @BASEBOARD_FAB2_LIB.BASEBOARD_FAB2(SCH_1):M_L_ECC(6)
DV69 M_L_ECC<5> DDR4_ECC<5> @BASEBOARD_FAB2_LIB.BASEBOARD_FAB2(SCH_1):M_L_ECC(5)
DU68 M_L_ECC<4> DDR4_ECC<4> @BASEBOARD_FAB2_LIB.BASEBOARD_FAB2(SCH_1):M_L_ECC(4)
DY65 M_L_ECC<3> DDR4_ECC<3> @BASEBOARD_FAB2_LIB.BASEBOARD_FAB2(SCH_1):M_L_ECC(3)
DV65 M_L_ECC<2> DDR4_ECC<2> @BASEBOARD_FAB2_LIB.BASEBOARD_FAB2(SCH_1):M_L_ECC(2)
EA68 M_L_ECC<1> DDR4_ECC<1> @BASEBOARD_FAB2_LIB.BASEBOARD_FAB2(SCH_1):M_L_ECC(1)
DY69 M_L_ECC<0> DDR4_ECC<0> @BASEBOARD_FAB2_LIB.BASEBOARD_FAB2(SCH_1):M_L_ECC(0)
DR48 M_L_MA<17> DDR4_MA<17> @BASEBOARD_FAB2_LIB.BASEBOARD_FAB2(SCH_1):M_L_MA(17)
DN52 M_L_MA<16> DDR4_MA<16> @BASEBOARD_FAB2_LIB.BASEBOARD_FAB2(SCH_1):M_L_MA(16)
DR52 M_L_MA<15> DDR4_MA<15> @BASEBOARD_FAB2_LIB.BASEBOARD_FAB2(SCH_1):M_L_MA(15)
DM51 M_L_MA<14> DDR4_MA<14> @BASEBOARD_FAB2_LIB.BASEBOARD_FAB2(SCH_1):M_L_MA(14)
DT51 M_L_MA<13> DDR4_MA<13> @BASEBOARD_FAB2_LIB.BASEBOARD_FAB2(SCH_1):M_L_MA(13)
DN60 M_L_MA<12> DDR4_MA<12> @BASEBOARD_FAB2_LIB.BASEBOARD_FAB2(SCH_1):M_L_MA(12)
DR60 M_L_MA<11> DDR4_MA<11> @BASEBOARD_FAB2_LIB.BASEBOARD_FAB2(SCH_1):M_L_MA(11)
DT55 M_L_MA<10> DDR4_MA<10> @BASEBOARD_FAB2_LIB.BASEBOARD_FAB2(SCH_1):M_L_MA(10)
DV59 M_L_MA<9> DDR4_MA<9> @BASEBOARD_FAB2_LIB.BASEBOARD_FAB2(SCH_1):M_L_MA(9)
DJ60 M_L_MA<8> DDR4_MA<8> @BASEBOARD_FAB2_LIB.BASEBOARD_FAB2(SCH_1):M_L_MA(8)
DK61 M_L_MA<7> DDR4_MA<7> @BASEBOARD_FAB2_LIB.BASEBOARD_FAB2(SCH_1):M_L_MA(7)
DM59 M_L_MA<6> DDR4_MA<6> @BASEBOARD_FAB2_LIB.BASEBOARD_FAB2(SCH_1):M_L_MA(6)
DN58 M_L_MA<5> DDR4_MA<5> @BASEBOARD_FAB2_LIB.BASEBOARD_FAB2(SCH_1):M_L_MA(5)
DT59 M_L_MA<4> DDR4_MA<4> @BASEBOARD_FAB2_LIB.BASEBOARD_FAB2(SCH_1):M_L_MA(4)
DR58 M_L_MA<3> DDR4_MA<3> @BASEBOARD_FAB2_LIB.BASEBOARD_FAB2(SCH_1):M_L_MA(3)
DV57 M_L_MA<2> DDR4_MA<2> @BASEBOARD_FAB2_LIB.BASEBOARD_FAB2(SCH_1):M_L_MA(2)
DW58 M_L_MA<1> DDR4_MA<1> @BASEBOARD_FAB2_LIB.BASEBOARD_FAB2(SCH_1):M_L_MA(1)
DW52 M_L_MA<0> DDR4_MA<0> @BASEBOARD_FAB2_LIB.BASEBOARD_FAB2(SCH_1):M_L_MA(0)
DM47 M_L_ODT<3> DDR4_ODT<3> @BASEBOARD_FAB2_LIB.BASEBOARD_FAB2(SCH_1):M_L_ODT(3)
DT49 M_L_ODT<2> DDR4_ODT<2> @BASEBOARD_FAB2_LIB.BASEBOARD_FAB2(SCH_1):M_L_ODT(2)
DN48 M_L_ODT<1> DDR4_ODT<1> @BASEBOARD_FAB2_LIB.BASEBOARD_FAB2(SCH_1):M_L_ODT(1)
DR50 M_L_ODT<0> DDR4_ODT<0> @BASEBOARD_FAB2_LIB.BASEBOARD_FAB2(SCH_1):M_L_ODT(0)
DV53 M_L_PAR DDR4_PAR @BASEBOARD_FAB2_LIB.BASEBOARD_FAB2(SCH_1):M_L_PAR


DRAWING: @BASEBOARD_FAB2_LIB.BASEBOARD_FAB2(SCH_1):PAGE62 

SKX_EXT_B_BGA1-IC,TBD  I172  U2D1
DC62 M_M_ACT_N DDR5_ACT_N @BASEBOARD_FAB2_LIB.BASEBOARD_FAB2(SCH_1):M_M_ACT_N
DD61 M_M_ALERT_N DDR5_ALERT_N @BASEBOARD_FAB2_LIB.BASEBOARD_FAB2(SCH_1):M_M_ALERT_N
DC56 M_M_BA<1> DDR5_BA<1> @BASEBOARD_FAB2_LIB.BASEBOARD_FAB2(SCH_1):M_M_BA(1)
DJ52 M_M_BA<0> DDR5_BA<0> @BASEBOARD_FAB2_LIB.BASEBOARD_FAB2(SCH_1):M_M_BA(0)
DF61 M_M_BG<1> DDR5_BG<1> @BASEBOARD_FAB2_LIB.BASEBOARD_FAB2(SCH_1):M_M_BG(1)
DA62 M_M_BG<0> DDR5_BG<0> @BASEBOARD_FAB2_LIB.BASEBOARD_FAB2(SCH_1):M_M_BG(0)
DF45 M_M_C<2> DDR5_CID<2> @BASEBOARD_FAB2_LIB.BASEBOARD_FAB2(SCH_1):M_M_C(2)
DF63 M_M_CKE<3> DDR5_CKE<3> @BASEBOARD_FAB2_LIB.BASEBOARD_FAB2(SCH_1):M_M_CKE(3)
DK63 M_M_CKE<2> DDR5_CKE<2> @BASEBOARD_FAB2_LIB.BASEBOARD_FAB2(SCH_1):M_M_CKE(2)
DD63 M_M_CKE<1> DDR5_CKE<1> @BASEBOARD_FAB2_LIB.BASEBOARD_FAB2(SCH_1):M_M_CKE(1)
DG62 M_M_CKE<0> DDR5_CKE<0> @BASEBOARD_FAB2_LIB.BASEBOARD_FAB2(SCH_1):M_M_CKE(0)
DF57 M_M_CLK_DN<3> DDR5_CLK_DN<3> @BASEBOARD_FAB2_LIB.BASEBOARD_FAB2(SCH_1):M_M_CLK_DN(3)
DK57 M_M_CLK_DN<2> DDR5_CLK_DN<2> @BASEBOARD_FAB2_LIB.BASEBOARD_FAB2(SCH_1):M_M_CLK_DN(2)
DF55 M_M_CLK_DN<1> DDR5_CLK_DN<1> @BASEBOARD_FAB2_LIB.BASEBOARD_FAB2(SCH_1):M_M_CLK_DN(1)
DK55 M_M_CLK_DN<0> DDR5_CLK_DN<0> @BASEBOARD_FAB2_LIB.BASEBOARD_FAB2(SCH_1):M_M_CLK_DN(0)
DG56 M_M_CLK_DP<3> DDR5_CLK_DP<3> @BASEBOARD_FAB2_LIB.BASEBOARD_FAB2(SCH_1):M_M_CLK_DP(3)
DJ56 M_M_CLK_DP<2> DDR5_CLK_DP<2> @BASEBOARD_FAB2_LIB.BASEBOARD_FAB2(SCH_1):M_M_CLK_DP(2)
DG54 M_M_CLK_DP<1> DDR5_CLK_DP<1> @BASEBOARD_FAB2_LIB.BASEBOARD_FAB2(SCH_1):M_M_CLK_DP(1)
DJ54 M_M_CLK_DP<0> DDR5_CLK_DP<0> @BASEBOARD_FAB2_LIB.BASEBOARD_FAB2(SCH_1):M_M_CLK_DP(0)
DK45 M_M_CS_N<7> DDR5_CS_N<7> @BASEBOARD_FAB2_LIB.BASEBOARD_FAB2(SCH_1):M_M_CS_N(7)
DM45 M_M_CS_N<6> DDR5_CS_N<6> @BASEBOARD_FAB2_LIB.BASEBOARD_FAB2(SCH_1):M_M_CS_N(6)
DJ48 M_M_CS_N<5> DDR5_CS_N<5> @BASEBOARD_FAB2_LIB.BASEBOARD_FAB2(SCH_1):M_M_CS_N(5)
DF51 M_M_CS_N<4> DDR5_CS_N<4> @BASEBOARD_FAB2_LIB.BASEBOARD_FAB2(SCH_1):M_M_CS_N(4)
DG46 M_M_CS_N<3> DDR5_CS_N<3> @BASEBOARD_FAB2_LIB.BASEBOARD_FAB2(SCH_1):M_M_CS_N(3)
DJ46 M_M_CS_N<2> DDR5_CS_N<2> @BASEBOARD_FAB2_LIB.BASEBOARD_FAB2(SCH_1):M_M_CS_N(2)
DF49 M_M_CS_N<1> DDR5_CS_N<1> @BASEBOARD_FAB2_LIB.BASEBOARD_FAB2(SCH_1):M_M_CS_N(1)
DK51 M_M_CS_N<0> DDR5_CS_N<0> @BASEBOARD_FAB2_LIB.BASEBOARD_FAB2(SCH_1):M_M_CS_N(0)
DC28 M_M_DQ<63> DDR5_DQ<63> @BASEBOARD_FAB2_LIB.BASEBOARD_FAB2(SCH_1):M_M_DQ(63)
CW28 M_M_DQ<62> DDR5_DQ<62> @BASEBOARD_FAB2_LIB.BASEBOARD_FAB2(SCH_1):M_M_DQ(62)
DB31 M_M_DQ<61> DDR5_DQ<61> @BASEBOARD_FAB2_LIB.BASEBOARD_FAB2(SCH_1):M_M_DQ(61)
CY31 M_M_DQ<60> DDR5_DQ<60> @BASEBOARD_FAB2_LIB.BASEBOARD_FAB2(SCH_1):M_M_DQ(60)
DB27 M_M_DQ<59> DDR5_DQ<59> @BASEBOARD_FAB2_LIB.BASEBOARD_FAB2(SCH_1):M_M_DQ(59)
CY27 M_M_DQ<58> DDR5_DQ<58> @BASEBOARD_FAB2_LIB.BASEBOARD_FAB2(SCH_1):M_M_DQ(58)
DC30 M_M_DQ<57> DDR5_DQ<57> @BASEBOARD_FAB2_LIB.BASEBOARD_FAB2(SCH_1):M_M_DQ(57)
CW30 M_M_DQ<56> DDR5_DQ<56> @BASEBOARD_FAB2_LIB.BASEBOARD_FAB2(SCH_1):M_M_DQ(56)
DC34 M_M_DQ<55> DDR5_DQ<55> @BASEBOARD_FAB2_LIB.BASEBOARD_FAB2(SCH_1):M_M_DQ(55)
CW34 M_M_DQ<54> DDR5_DQ<54> @BASEBOARD_FAB2_LIB.BASEBOARD_FAB2(SCH_1):M_M_DQ(54)
DB37 M_M_DQ<53> DDR5_DQ<53> @BASEBOARD_FAB2_LIB.BASEBOARD_FAB2(SCH_1):M_M_DQ(53)
CY37 M_M_DQ<52> DDR5_DQ<52> @BASEBOARD_FAB2_LIB.BASEBOARD_FAB2(SCH_1):M_M_DQ(52)
DB33 M_M_DQ<51> DDR5_DQ<51> @BASEBOARD_FAB2_LIB.BASEBOARD_FAB2(SCH_1):M_M_DQ(51)
CY33 M_M_DQ<50> DDR5_DQ<50> @BASEBOARD_FAB2_LIB.BASEBOARD_FAB2(SCH_1):M_M_DQ(50)
DC36 M_M_DQ<49> DDR5_DQ<49> @BASEBOARD_FAB2_LIB.BASEBOARD_FAB2(SCH_1):M_M_DQ(49)
CW36 M_M_DQ<48> DDR5_DQ<48> @BASEBOARD_FAB2_LIB.BASEBOARD_FAB2(SCH_1):M_M_DQ(48)
DK31 M_M_DQ<47> DDR5_DQ<47> @BASEBOARD_FAB2_LIB.BASEBOARD_FAB2(SCH_1):M_M_DQ(47)
DF31 M_M_DQ<46> DDR5_DQ<46> @BASEBOARD_FAB2_LIB.BASEBOARD_FAB2(SCH_1):M_M_DQ(46)
DJ34 M_M_DQ<45> DDR5_DQ<45> @BASEBOARD_FAB2_LIB.BASEBOARD_FAB2(SCH_1):M_M_DQ(45)
DG34 M_M_DQ<44> DDR5_DQ<44> @BASEBOARD_FAB2_LIB.BASEBOARD_FAB2(SCH_1):M_M_DQ(44)
DJ30 M_M_DQ<43> DDR5_DQ<43> @BASEBOARD_FAB2_LIB.BASEBOARD_FAB2(SCH_1):M_M_DQ(43)
DG30 M_M_DQ<42> DDR5_DQ<42> @BASEBOARD_FAB2_LIB.BASEBOARD_FAB2(SCH_1):M_M_DQ(42)
DK33 M_M_DQ<41> DDR5_DQ<41> @BASEBOARD_FAB2_LIB.BASEBOARD_FAB2(SCH_1):M_M_DQ(41)
DF33 M_M_DQ<40> DDR5_DQ<40> @BASEBOARD_FAB2_LIB.BASEBOARD_FAB2(SCH_1):M_M_DQ(40)
DH39 M_M_DQ<39> DDR5_DQ<39> @BASEBOARD_FAB2_LIB.BASEBOARD_FAB2(SCH_1):M_M_DQ(39)
DD39 M_M_DQ<38> DDR5_DQ<38> @BASEBOARD_FAB2_LIB.BASEBOARD_FAB2(SCH_1):M_M_DQ(38)
DE42 M_M_DQ<37> DDR5_DQ<37> @BASEBOARD_FAB2_LIB.BASEBOARD_FAB2(SCH_1):M_M_DQ(37)
DA42 M_M_DQ<36> DDR5_DQ<36> @BASEBOARD_FAB2_LIB.BASEBOARD_FAB2(SCH_1):M_M_DQ(36)
DG38 M_M_DQ<35> DDR5_DQ<35> @BASEBOARD_FAB2_LIB.BASEBOARD_FAB2(SCH_1):M_M_DQ(35)
DE38 M_M_DQ<34> DDR5_DQ<34> @BASEBOARD_FAB2_LIB.BASEBOARD_FAB2(SCH_1):M_M_DQ(34)
DG42 M_M_DQ<33> DDR5_DQ<33> @BASEBOARD_FAB2_LIB.BASEBOARD_FAB2(SCH_1):M_M_DQ(33)
DD41 M_M_DQ<32> DDR5_DQ<32> @BASEBOARD_FAB2_LIB.BASEBOARD_FAB2(SCH_1):M_M_DQ(32)
CU64 M_M_DQ<31> DDR5_DQ<31> @BASEBOARD_FAB2_LIB.BASEBOARD_FAB2(SCH_1):M_M_DQ(31)
CN64 M_M_DQ<30> DDR5_DQ<30> @BASEBOARD_FAB2_LIB.BASEBOARD_FAB2(SCH_1):M_M_DQ(30)
CT67 M_M_DQ<29> DDR5_DQ<29> @BASEBOARD_FAB2_LIB.BASEBOARD_FAB2(SCH_1):M_M_DQ(29)
CP67 M_M_DQ<28> DDR5_DQ<28> @BASEBOARD_FAB2_LIB.BASEBOARD_FAB2(SCH_1):M_M_DQ(28)
CT63 M_M_DQ<27> DDR5_DQ<27> @BASEBOARD_FAB2_LIB.BASEBOARD_FAB2(SCH_1):M_M_DQ(27)
CP63 M_M_DQ<26> DDR5_DQ<26> @BASEBOARD_FAB2_LIB.BASEBOARD_FAB2(SCH_1):M_M_DQ(26)
CU66 M_M_DQ<25> DDR5_DQ<25> @BASEBOARD_FAB2_LIB.BASEBOARD_FAB2(SCH_1):M_M_DQ(25)
CN66 M_M_DQ<24> DDR5_DQ<24> @BASEBOARD_FAB2_LIB.BASEBOARD_FAB2(SCH_1):M_M_DQ(24)
DM71 M_M_DQ<23> DDR5_DQ<23> @BASEBOARD_FAB2_LIB.BASEBOARD_FAB2(SCH_1):M_M_DQ(23)
DK69 M_M_DQ<22> DDR5_DQ<22> @BASEBOARD_FAB2_LIB.BASEBOARD_FAB2(SCH_1):M_M_DQ(22)
DG72 M_M_DQ<21> DDR5_DQ<21> @BASEBOARD_FAB2_LIB.BASEBOARD_FAB2(SCH_1):M_M_DQ(21)
DF71 M_M_DQ<20> DDR5_DQ<20> @BASEBOARD_FAB2_LIB.BASEBOARD_FAB2(SCH_1):M_M_DQ(20)
DN70 M_M_DQ<19> DDR5_DQ<19> @BASEBOARD_FAB2_LIB.BASEBOARD_FAB2(SCH_1):M_M_DQ(19)
DM69 M_M_DQ<18> DDR5_DQ<18> @BASEBOARD_FAB2_LIB.BASEBOARD_FAB2(SCH_1):M_M_DQ(18)
DJ72 M_M_DQ<17> DDR5_DQ<17> @BASEBOARD_FAB2_LIB.BASEBOARD_FAB2(SCH_1):M_M_DQ(17)
DG70 M_M_DQ<16> DDR5_DQ<16> @BASEBOARD_FAB2_LIB.BASEBOARD_FAB2(SCH_1):M_M_DQ(16)
DH77 M_M_DQ<15> DDR5_DQ<15> @BASEBOARD_FAB2_LIB.BASEBOARD_FAB2(SCH_1):M_M_DQ(15)
DF77 M_M_DQ<14> DDR5_DQ<14> @BASEBOARD_FAB2_LIB.BASEBOARD_FAB2(SCH_1):M_M_DQ(14)
DB75 M_M_DQ<13> DDR5_DQ<13> @BASEBOARD_FAB2_LIB.BASEBOARD_FAB2(SCH_1):M_M_DQ(13)
DC74 M_M_DQ<12> DDR5_DQ<12> @BASEBOARD_FAB2_LIB.BASEBOARD_FAB2(SCH_1):M_M_DQ(12)
DJ76 M_M_DQ<11> DDR5_DQ<11> @BASEBOARD_FAB2_LIB.BASEBOARD_FAB2(SCH_1):M_M_DQ(11)
DH75 M_M_DQ<10> DDR5_DQ<10> @BASEBOARD_FAB2_LIB.BASEBOARD_FAB2(SCH_1):M_M_DQ(10)
DC76 M_M_DQ<9> DDR5_DQ<9> @BASEBOARD_FAB2_LIB.BASEBOARD_FAB2(SCH_1):M_M_DQ(9)
DE74 M_M_DQ<8> DDR5_DQ<8> @BASEBOARD_FAB2_LIB.BASEBOARD_FAB2(SCH_1):M_M_DQ(8)
CT77 M_M_DQ<7> DDR5_DQ<7> @BASEBOARD_FAB2_LIB.BASEBOARD_FAB2(SCH_1):M_M_DQ(7)
CV75 M_M_DQ<6> DDR5_DQ<6> @BASEBOARD_FAB2_LIB.BASEBOARD_FAB2(SCH_1):M_M_DQ(6)
CM75 M_M_DQ<5> DDR5_DQ<5> @BASEBOARD_FAB2_LIB.BASEBOARD_FAB2(SCH_1):M_M_DQ(5)
CN74 M_M_DQ<4> DDR5_DQ<4> @BASEBOARD_FAB2_LIB.BASEBOARD_FAB2(SCH_1):M_M_DQ(4)
CV77 M_M_DQ<3> DDR5_DQ<3> @BASEBOARD_FAB2_LIB.BASEBOARD_FAB2(SCH_1):M_M_DQ(3)
CW76 M_M_DQ<2> DDR5_DQ<2> @BASEBOARD_FAB2_LIB.BASEBOARD_FAB2(SCH_1):M_M_DQ(2)
CN76 M_M_DQ<1> DDR5_DQ<1> @BASEBOARD_FAB2_LIB.BASEBOARD_FAB2(SCH_1):M_M_DQ(1)
CR74 M_M_DQ<0> DDR5_DQ<0> @BASEBOARD_FAB2_LIB.BASEBOARD_FAB2(SCH_1):M_M_DQ(0)
CJ70 M_M_DQS_DN<17> DDR5_DQS_DN<17> @BASEBOARD_FAB2_LIB.BASEBOARD_FAB2(SCH_1):M_M_DQS_DN(17)
CY29 M_M_DQS_DN<16> DDR5_DQS_DN<16> @BASEBOARD_FAB2_LIB.BASEBOARD_FAB2(SCH_1):M_M_DQS_DN(16)
CY35 M_M_DQS_DN<15> DDR5_DQS_DN<15> @BASEBOARD_FAB2_LIB.BASEBOARD_FAB2(SCH_1):M_M_DQS_DN(15)
DG32 M_M_DQS_DN<14> DDR5_DQS_DN<14> @BASEBOARD_FAB2_LIB.BASEBOARD_FAB2(SCH_1):M_M_DQS_DN(14)
DE40 M_M_DQS_DN<13> DDR5_DQS_DN<13> @BASEBOARD_FAB2_LIB.BASEBOARD_FAB2(SCH_1):M_M_DQS_DN(13)
CP65 M_M_DQS_DN<12> DDR5_DQS_DN<12> @BASEBOARD_FAB2_LIB.BASEBOARD_FAB2(SCH_1):M_M_DQS_DN(12)
DJ70 M_M_DQS_DN<11> DDR5_DQS_DN<11> @BASEBOARD_FAB2_LIB.BASEBOARD_FAB2(SCH_1):M_M_DQS_DN(11)
DF75 M_M_DQS_DN<10> DDR5_DQS_DN<10> @BASEBOARD_FAB2_LIB.BASEBOARD_FAB2(SCH_1):M_M_DQS_DN(10)
CT75 M_M_DQS_DN<9> DDR5_DQS_DN<9> @BASEBOARD_FAB2_LIB.BASEBOARD_FAB2(SCH_1):M_M_DQS_DN(9)
CN70 M_M_DQS_DN<8> DDR5_DQS_DN<8> @BASEBOARD_FAB2_LIB.BASEBOARD_FAB2(SCH_1):M_M_DQS_DN(8)
DD29 M_M_DQS_DN<7> DDR5_DQS_DN<7> @BASEBOARD_FAB2_LIB.BASEBOARD_FAB2(SCH_1):M_M_DQS_DN(7)
DD35 M_M_DQS_DN<6> DDR5_DQS_DN<6> @BASEBOARD_FAB2_LIB.BASEBOARD_FAB2(SCH_1):M_M_DQS_DN(6)
DL32 M_M_DQS_DN<5> DDR5_DQS_DN<5> @BASEBOARD_FAB2_LIB.BASEBOARD_FAB2(SCH_1):M_M_DQS_DN(5)
DG40 M_M_DQS_DN<4> DDR5_DQS_DN<4> @BASEBOARD_FAB2_LIB.BASEBOARD_FAB2(SCH_1):M_M_DQS_DN(4)
CV65 M_M_DQS_DN<3> DDR5_DQS_DN<3> @BASEBOARD_FAB2_LIB.BASEBOARD_FAB2(SCH_1):M_M_DQS_DN(3)
DL72 M_M_DQS_DN<2> DDR5_DQS_DN<2> @BASEBOARD_FAB2_LIB.BASEBOARD_FAB2(SCH_1):M_M_DQS_DN(2)
DD77 M_M_DQS_DN<1> DDR5_DQS_DN<1> @BASEBOARD_FAB2_LIB.BASEBOARD_FAB2(SCH_1):M_M_DQS_DN(1)
CP77 M_M_DQS_DN<0> DDR5_DQS_DN<0> @BASEBOARD_FAB2_LIB.BASEBOARD_FAB2(SCH_1):M_M_DQS_DN(0)
CG70 M_M_DQS_DP<17> DDR5_DQS_DP<17> @BASEBOARD_FAB2_LIB.BASEBOARD_FAB2(SCH_1):M_M_DQS_DP(17)
CV29 M_M_DQS_DP<16> DDR5_DQS_DP<16> @BASEBOARD_FAB2_LIB.BASEBOARD_FAB2(SCH_1):M_M_DQS_DP(16)
CV35 M_M_DQS_DP<15> DDR5_DQS_DP<15> @BASEBOARD_FAB2_LIB.BASEBOARD_FAB2(SCH_1):M_M_DQS_DP(15)
DE32 M_M_DQS_DP<14> DDR5_DQS_DP<14> @BASEBOARD_FAB2_LIB.BASEBOARD_FAB2(SCH_1):M_M_DQS_DP(14)
DC40 M_M_DQS_DP<13> DDR5_DQS_DP<13> @BASEBOARD_FAB2_LIB.BASEBOARD_FAB2(SCH_1):M_M_DQS_DP(13)
CM65 M_M_DQS_DP<12> DDR5_DQS_DP<12> @BASEBOARD_FAB2_LIB.BASEBOARD_FAB2(SCH_1):M_M_DQS_DP(12)
DH69 M_M_DQS_DP<11> DDR5_DQS_DP<11> @BASEBOARD_FAB2_LIB.BASEBOARD_FAB2(SCH_1):M_M_DQS_DP(11)
DG74 M_M_DQS_DP<10> DDR5_DQS_DP<10> @BASEBOARD_FAB2_LIB.BASEBOARD_FAB2(SCH_1):M_M_DQS_DP(10)
CU74 M_M_DQS_DP<9> DDR5_DQS_DP<9> @BASEBOARD_FAB2_LIB.BASEBOARD_FAB2(SCH_1):M_M_DQS_DP(9)
CL70 M_M_DQS_DP<8> DDR5_DQS_DP<8> @BASEBOARD_FAB2_LIB.BASEBOARD_FAB2(SCH_1):M_M_DQS_DP(8)
DB29 M_M_DQS_DP<7> DDR5_DQS_DP<7> @BASEBOARD_FAB2_LIB.BASEBOARD_FAB2(SCH_1):M_M_DQS_DP(7)
DB35 M_M_DQS_DP<6> DDR5_DQS_DP<6> @BASEBOARD_FAB2_LIB.BASEBOARD_FAB2(SCH_1):M_M_DQS_DP(6)
DJ32 M_M_DQS_DP<5> DDR5_DQS_DP<5> @BASEBOARD_FAB2_LIB.BASEBOARD_FAB2(SCH_1):M_M_DQS_DP(5)
DJ40 M_M_DQS_DP<4> DDR5_DQS_DP<4> @BASEBOARD_FAB2_LIB.BASEBOARD_FAB2(SCH_1):M_M_DQS_DP(4)
CT65 M_M_DQS_DP<3> DDR5_DQS_DP<3> @BASEBOARD_FAB2_LIB.BASEBOARD_FAB2(SCH_1):M_M_DQS_DP(3)
DK71 M_M_DQS_DP<2> DDR5_DQS_DP<2> @BASEBOARD_FAB2_LIB.BASEBOARD_FAB2(SCH_1):M_M_DQS_DP(2)
DE76 M_M_DQS_DP<1> DDR5_DQS_DP<1> @BASEBOARD_FAB2_LIB.BASEBOARD_FAB2(SCH_1):M_M_DQS_DP(1)
CR76 M_M_DQS_DP<0> DDR5_DQS_DP<0> @BASEBOARD_FAB2_LIB.BASEBOARD_FAB2(SCH_1):M_M_DQS_DP(0)
CM69 M_M_ECC<7> DDR5_ECC<7> @BASEBOARD_FAB2_LIB.BASEBOARD_FAB2(SCH_1):M_M_ECC(7)
CH69 M_M_ECC<6> DDR5_ECC<6> @BASEBOARD_FAB2_LIB.BASEBOARD_FAB2(SCH_1):M_M_ECC(6)
CL72 M_M_ECC<5> DDR5_ECC<5> @BASEBOARD_FAB2_LIB.BASEBOARD_FAB2(SCH_1):M_M_ECC(5)
CJ72 M_M_ECC<4> DDR5_ECC<4> @BASEBOARD_FAB2_LIB.BASEBOARD_FAB2(SCH_1):M_M_ECC(4)
CL68 M_M_ECC<3> DDR5_ECC<3> @BASEBOARD_FAB2_LIB.BASEBOARD_FAB2(SCH_1):M_M_ECC(3)
CJ68 M_M_ECC<2> DDR5_ECC<2> @BASEBOARD_FAB2_LIB.BASEBOARD_FAB2(SCH_1):M_M_ECC(2)
CM71 M_M_ECC<1> DDR5_ECC<1> @BASEBOARD_FAB2_LIB.BASEBOARD_FAB2(SCH_1):M_M_ECC(1)
CH71 M_M_ECC<0> DDR5_ECC<0> @BASEBOARD_FAB2_LIB.BASEBOARD_FAB2(SCH_1):M_M_ECC(0)
DE46 M_M_MA<17> DDR5_MA<17> @BASEBOARD_FAB2_LIB.BASEBOARD_FAB2(SCH_1):M_M_MA(17)
DG52 M_M_MA<16> DDR5_MA<16> @BASEBOARD_FAB2_LIB.BASEBOARD_FAB2(SCH_1):M_M_MA(16)
DC54 M_M_MA<15> DDR5_MA<15> @BASEBOARD_FAB2_LIB.BASEBOARD_FAB2(SCH_1):M_M_MA(15)
DJ50 M_M_MA<14> DDR5_MA<14> @BASEBOARD_FAB2_LIB.BASEBOARD_FAB2(SCH_1):M_M_MA(14)
DD53 M_M_MA<13> DDR5_MA<13> @BASEBOARD_FAB2_LIB.BASEBOARD_FAB2(SCH_1):M_M_MA(13)
DG60 M_M_MA<12> DDR5_MA<12> @BASEBOARD_FAB2_LIB.BASEBOARD_FAB2(SCH_1):M_M_MA(12)
DA60 M_M_MA<11> DDR5_MA<11> @BASEBOARD_FAB2_LIB.BASEBOARD_FAB2(SCH_1):M_M_MA(11)
DD55 M_M_MA<10> DDR5_MA<10> @BASEBOARD_FAB2_LIB.BASEBOARD_FAB2(SCH_1):M_M_MA(10)
DA58 M_M_MA<9> DDR5_MA<9> @BASEBOARD_FAB2_LIB.BASEBOARD_FAB2(SCH_1):M_M_MA(9)
DD59 M_M_MA<8> DDR5_MA<8> @BASEBOARD_FAB2_LIB.BASEBOARD_FAB2(SCH_1):M_M_MA(8)
DC60 M_M_MA<7> DDR5_MA<7> @BASEBOARD_FAB2_LIB.BASEBOARD_FAB2(SCH_1):M_M_MA(7)
DK59 M_M_MA<6> DDR5_MA<6> @BASEBOARD_FAB2_LIB.BASEBOARD_FAB2(SCH_1):M_M_MA(6)
DF59 M_M_MA<5> DDR5_MA<5> @BASEBOARD_FAB2_LIB.BASEBOARD_FAB2(SCH_1):M_M_MA(5)
DJ58 M_M_MA<4> DDR5_MA<4> @BASEBOARD_FAB2_LIB.BASEBOARD_FAB2(SCH_1):M_M_MA(4)
DG58 M_M_MA<3> DDR5_MA<3> @BASEBOARD_FAB2_LIB.BASEBOARD_FAB2(SCH_1):M_M_MA(3)
DD57 M_M_MA<2> DDR5_MA<2> @BASEBOARD_FAB2_LIB.BASEBOARD_FAB2(SCH_1):M_M_MA(2)
DC58 M_M_MA<1> DDR5_MA<1> @BASEBOARD_FAB2_LIB.BASEBOARD_FAB2(SCH_1):M_M_MA(1)
DF53 M_M_MA<0> DDR5_MA<0> @BASEBOARD_FAB2_LIB.BASEBOARD_FAB2(SCH_1):M_M_MA(0)
DF47 M_M_ODT<3> DDR5_ODT<3> @BASEBOARD_FAB2_LIB.BASEBOARD_FAB2(SCH_1):M_M_ODT(3)
DK49 M_M_ODT<2> DDR5_ODT<2> @BASEBOARD_FAB2_LIB.BASEBOARD_FAB2(SCH_1):M_M_ODT(2)
DG48 M_M_ODT<1> DDR5_ODT<1> @BASEBOARD_FAB2_LIB.BASEBOARD_FAB2(SCH_1):M_M_ODT(1)
DG50 M_M_ODT<0> DDR5_ODT<0> @BASEBOARD_FAB2_LIB.BASEBOARD_FAB2(SCH_1):M_M_ODT(0)
DK53 M_M_PAR DDR5_PAR @BASEBOARD_FAB2_LIB.BASEBOARD_FAB2(SCH_1):M_M_PAR


DRAWING: @BASEBOARD_FAB2_LIB.BASEBOARD_FAB2(SCH_1):PAGE63 

SKX_EXT_B_BGA1-IC,TBD  I23  U2D1
BN22 TP_SMB_CPU1_CD_HFI0_I2CCLK CD_HFI0_I2CCLK @BASEBOARD_FAB2_LIB.BASEBOARD_FAB2(SCH_1):TP_SMB_CPU1_CD_HFI0_I2CCLK
BP23 TP_SMB_CPU1_CD_HFI0_I2CDAT CD_HFI0_I2CDAT @BASEBOARD_FAB2_LIB.BASEBOARD_FAB2(SCH_1):TP_SMB_CPU1_CD_HFI0_I2CDAT
BP19 TP_IRQ_CPU1_CD_HFI0_N CD_HFI0_INT_N @BASEBOARD_FAB2_LIB.BASEBOARD_FAB2(SCH_1):TP_IRQ_CPU1_CD_HFI0_N
BK21 TP_LED_CPU1_CD_HFI0_N CD_HFI0_LED_N @BASEBOARD_FAB2_LIB.BASEBOARD_FAB2(SCH_1):TP_LED_CPU1_CD_HFI0_N
BR20 TP_FM_CPU1_CD_HFI0_MODPRST_N CD_HFI0_MODPRST_N @BASEBOARD_FAB2_LIB.BASEBOARD_FAB2(SCH_1):TP_FM_CPU1_CD_HFI0_MODPRST_N
BN24 TP_RST_CPU1_CD_HFI0_N CD_HFI0_RESET_N @BASEBOARD_FAB2_LIB.BASEBOARD_FAB2(SCH_1):TP_RST_CPU1_CD_HFI0_N
BJ22 TP_CD_HFI1_CPU1_I2CLK CD_HFI1_I2CCLK @BASEBOARD_FAB2_LIB.BASEBOARD_FAB2(SCH_1):TP_CD_HFI1_CPU1_I2CLK
BH23 TP_CD_HFI1_CPU1_I2CDAT CD_HFI1_I2CDAT @BASEBOARD_FAB2_LIB.BASEBOARD_FAB2(SCH_1):TP_CD_HFI1_CPU1_I2CDAT
BM21 TP_CD_HFI1_CPU1_INT_N CD_HFI1_INT_N @BASEBOARD_FAB2_LIB.BASEBOARD_FAB2(SCH_1):TP_CD_HFI1_CPU1_INT_N
BM23 TP_CD_HFI1_CPU1_LED_N CD_HFI1_LED_N @BASEBOARD_FAB2_LIB.BASEBOARD_FAB2(SCH_1):TP_CD_HFI1_CPU1_LED_N
BT19 TP_CD_HFI1_CPU1_MODPRST_N CD_HFI1_MODPRST_N @BASEBOARD_FAB2_LIB.BASEBOARD_FAB2(SCH_1):TP_CD_HFI1_CPU1_MODPRST_N
BK23 TP_CD_HFI1_CPU1_RESET_N CD_HFI1_RESET_N @BASEBOARD_FAB2_LIB.BASEBOARD_FAB2(SCH_1):TP_CD_HFI1_CPU1_RESET_N
BE16 CLK_156M_OSC_CPU1_HFI_DN CD_HFI_REFCLK_DN @BASEBOARD_FAB2_LIB.BASEBOARD_FAB2(SCH_1):CLK_156M_OSC_CPU1_HFI_DN
BG16 CLK_156M_OSC_CPU1_HFI_DP CD_HFI_REFCLK_DP @BASEBOARD_FAB2_LIB.BASEBOARD_FAB2(SCH_1):CLK_156M_OSC_CPU1_HFI_DP
BU24 CLK_100M_CPU1_PE_REFCLK_DN CD_PE_REFCLK_DN @BASEBOARD_FAB2_LIB.BASEBOARD_FAB2(SCH_1):CLK_100M_CPU1_PE_REFCLK_DN
BW24 CLK_100M_CPU1_PE_REFCLK_DP CD_PE_REFCLK_DP @BASEBOARD_FAB2_LIB.BASEBOARD_FAB2(SCH_1):CLK_100M_CPU1_PE_REFCLK_DP
CF25 RST_CD_CPU1_POR_N CD_POR_N @BASEBOARD_FAB2_LIB.BASEBOARD_FAB2(SCH_1):RST_CD_CPU1_POR_N
CB23 JTAG_MCP_TCK CD_TCLK @BASEBOARD_FAB2_LIB.BASEBOARD_FAB2(SCH_1):JTAG_MCP_TCK
BY21 JTAG_MCP_CPU1_TDI CD_TDI @BASEBOARD_FAB2_LIB.BASEBOARD_FAB2(SCH_1):JTAG_MCP_CPU1_TDI
CC22 JTAG_MCP_CPU1_TDO CD_TDO @BASEBOARD_FAB2_LIB.BASEBOARD_FAB2(SCH_1):JTAG_MCP_CPU1_TDO
CE24 JTAG_MCP_TMS CD_TMS @BASEBOARD_FAB2_LIB.BASEBOARD_FAB2(SCH_1):JTAG_MCP_TMS
CD23 JTAG_MCP_TRST_N CD_TRST_N @BASEBOARD_FAB2_LIB.BASEBOARD_FAB2(SCH_1):JTAG_MCP_TRST_N
CT11 TP_CPU1_DMI_RX_DN3 DMI_RX_DN<3> @BASEBOARD_FAB2_LIB.BASEBOARD_FAB2(SCH_1):TP_CPU1_DMI_RX_DN3
CR12 TP_CPU1_DMI_RX_DN2 DMI_RX_DN<2> @BASEBOARD_FAB2_LIB.BASEBOARD_FAB2(SCH_1):TP_CPU1_DMI_RX_DN2
CM11 TP_CPU1_DMI_RX_DN1 DMI_RX_DN<1> @BASEBOARD_FAB2_LIB.BASEBOARD_FAB2(SCH_1):TP_CPU1_DMI_RX_DN1
 CK9 TP_CPU1_DMI_RX_DN0 DMI_RX_DN<0> @BASEBOARD_FAB2_LIB.BASEBOARD_FAB2(SCH_1):TP_CPU1_DMI_RX_DN0
CV11 TP_CPU1_DMI_RX_DP3 DMI_RX_DP<3> @BASEBOARD_FAB2_LIB.BASEBOARD_FAB2(SCH_1):TP_CPU1_DMI_RX_DP3
CP11 TP_CPU1_DMI_RX_DP2 DMI_RX_DP<2> @BASEBOARD_FAB2_LIB.BASEBOARD_FAB2(SCH_1):TP_CPU1_DMI_RX_DP2
CN10 TP_CPU1_DMI_RX_DP1 DMI_RX_DP<1> @BASEBOARD_FAB2_LIB.BASEBOARD_FAB2(SCH_1):TP_CPU1_DMI_RX_DP1
CL10 TP_CPU1_DMI_RX_DP0 DMI_RX_DP<0> @BASEBOARD_FAB2_LIB.BASEBOARD_FAB2(SCH_1):TP_CPU1_DMI_RX_DP0
 CP5 TP_CPU1_DMI_TX_DN3 DMI_TX_DN<3> @BASEBOARD_FAB2_LIB.BASEBOARD_FAB2(SCH_1):TP_CPU1_DMI_TX_DN3
 CN4 TP_CPU1_DMI_TX_DN2 DMI_TX_DN<2> @BASEBOARD_FAB2_LIB.BASEBOARD_FAB2(SCH_1):TP_CPU1_DMI_TX_DN2
 CJ4 TP_CPU1_DMI_TX_DN1 DMI_TX_DN<1> @BASEBOARD_FAB2_LIB.BASEBOARD_FAB2(SCH_1):TP_CPU1_DMI_TX_DN1
 CG4 TP_CPU1_DMI_TX_DN0 DMI_TX_DN<0> @BASEBOARD_FAB2_LIB.BASEBOARD_FAB2(SCH_1):TP_CPU1_DMI_TX_DN0
 CR4 TP_CPU1_DMI_TX_DP3 DMI_TX_DP<3> @BASEBOARD_FAB2_LIB.BASEBOARD_FAB2(SCH_1):TP_CPU1_DMI_TX_DP3
 CM3 TP_CPU1_DMI_TX_DP2 DMI_TX_DP<2> @BASEBOARD_FAB2_LIB.BASEBOARD_FAB2(SCH_1):TP_CPU1_DMI_TX_DP2
 CL4 TP_CPU1_DMI_TX_DP1 DMI_TX_DP<1> @BASEBOARD_FAB2_LIB.BASEBOARD_FAB2(SCH_1):TP_CPU1_DMI_TX_DP1
 CH5 TP_CPU1_DMI_TX_DP0 DMI_TX_DP<0> @BASEBOARD_FAB2_LIB.BASEBOARD_FAB2(SCH_1):TP_CPU1_DMI_TX_DP0
AR20 PVCCMCP_CPU1 RSVD<193> @BASEBOARD_FAB2_LIB.BASEBOARD_FAB2(SCH_1):PVCCMCP_CPU1
AR22 PVCCMCP_CPU1 RSVD<192> @BASEBOARD_FAB2_LIB.BASEBOARD_FAB2(SCH_1):PVCCMCP_CPU1
AR26 PVCCMCP_CPU1 RSVD<191> @BASEBOARD_FAB2_LIB.BASEBOARD_FAB2(SCH_1):PVCCMCP_CPU1
AR62 TP_CPU1_RSVD_190 RSVD<190> @BASEBOARD_FAB2_LIB.BASEBOARD_FAB2(SCH_1):TP_CPU1_RSVD_190
AT13 TP_CPU1_RSVD_189 RSVD<189> @BASEBOARD_FAB2_LIB.BASEBOARD_FAB2(SCH_1):TP_CPU1_RSVD_189
AT23 PVCCMCP_CPU1 RSVD<188> @BASEBOARD_FAB2_LIB.BASEBOARD_FAB2(SCH_1):PVCCMCP_CPU1
AT25 PVCCMCP_CPU1 RSVD<187> @BASEBOARD_FAB2_LIB.BASEBOARD_FAB2(SCH_1):PVCCMCP_CPU1
AV77 TP_CPU1_RSVD_186 RSVD<186> @BASEBOARD_FAB2_LIB.BASEBOARD_FAB2(SCH_1):TP_CPU1_RSVD_186
AW64 TP_CPU1_RSVD_184 RSVD<184> @BASEBOARD_FAB2_LIB.BASEBOARD_FAB2(SCH_1):TP_CPU1_RSVD_184
AW76 TP_CPU1_RSVD_183 RSVD<183> @BASEBOARD_FAB2_LIB.BASEBOARD_FAB2(SCH_1):TP_CPU1_RSVD_183
AY65 TP_CPU1_RSVD_182 RSVD<182> @BASEBOARD_FAB2_LIB.BASEBOARD_FAB2(SCH_1):TP_CPU1_RSVD_182
AY67 TP_CPU1_RSVD_181 RSVD<181> @BASEBOARD_FAB2_LIB.BASEBOARD_FAB2(SCH_1):TP_CPU1_RSVD_181
AY75 TP_CPU1_RSVD_180 RSVD<180> @BASEBOARD_FAB2_LIB.BASEBOARD_FAB2(SCH_1):TP_CPU1_RSVD_180
AY77 TP_CPU1_RSVD_179 RSVD<179> @BASEBOARD_FAB2_LIB.BASEBOARD_FAB2(SCH_1):TP_CPU1_RSVD_179
BA14 TP_CPU1_RSVD_178 RSVD<178> @BASEBOARD_FAB2_LIB.BASEBOARD_FAB2(SCH_1):TP_CPU1_RSVD_178
BA16 TP_CPU1_RSVD_177 RSVD<177> @BASEBOARD_FAB2_LIB.BASEBOARD_FAB2(SCH_1):TP_CPU1_RSVD_177
BA18 TP_CPU1_RSVD_176 RSVD<176> @BASEBOARD_FAB2_LIB.BASEBOARD_FAB2(SCH_1):TP_CPU1_RSVD_176
BA22 TP_CPU1_RSVD_175 RSVD<175> @BASEBOARD_FAB2_LIB.BASEBOARD_FAB2(SCH_1):TP_CPU1_RSVD_175
BA64 TP_CPU1_RSVD_174 RSVD<174> @BASEBOARD_FAB2_LIB.BASEBOARD_FAB2(SCH_1):TP_CPU1_RSVD_174
BA66 TP_CPU1_RSVD_173 RSVD<173> @BASEBOARD_FAB2_LIB.BASEBOARD_FAB2(SCH_1):TP_CPU1_RSVD_173
BA76 TP_CPU1_RSVD_172 RSVD<172> @BASEBOARD_FAB2_LIB.BASEBOARD_FAB2(SCH_1):TP_CPU1_RSVD_172


DRAWING: @BASEBOARD_FAB2_LIB.BASEBOARD_FAB2(SCH_1):PAGE64 

SKX_EXT_B_BGA1-IC,TBD  I68  U2D1
DU16 TP_P3E_CPU1_PE1_RSR3_RXN<15> PE1_RX_DN<15> @BASEBOARD_FAB2_LIB.BASEBOARD_FAB2(SCH_1):TP_P3E_CPU1_PE1_RSR3_RXN(15)
DY15 TP_P3E_CPU1_PE1_RSR3_RXN<14> PE1_RX_DN<14> @BASEBOARD_FAB2_LIB.BASEBOARD_FAB2(SCH_1):TP_P3E_CPU1_PE1_RSR3_RXN(14)
DW14 TP_P3E_CPU1_PE1_RSR3_RXN<13> PE1_RX_DN<13> @BASEBOARD_FAB2_LIB.BASEBOARD_FAB2(SCH_1):TP_P3E_CPU1_PE1_RSR3_RXN(13)
DV13 TP_P3E_CPU1_PE1_RSR3_RXN<12> PE1_RX_DN<12> @BASEBOARD_FAB2_LIB.BASEBOARD_FAB2(SCH_1):TP_P3E_CPU1_PE1_RSR3_RXN(12)
DT13 TP_P3E_CPU1_PE1_RSR3_RXN<11> PE1_RX_DN<11> @BASEBOARD_FAB2_LIB.BASEBOARD_FAB2(SCH_1):TP_P3E_CPU1_PE1_RSR3_RXN(11)
DT11 TP_P3E_CPU1_PE1_RSR3_RXN<10> PE1_RX_DN<10> @BASEBOARD_FAB2_LIB.BASEBOARD_FAB2(SCH_1):TP_P3E_CPU1_PE1_RSR3_RXN(10)
DP11 TP_P3E_CPU1_PE1_RSR3_RXN<9> PE1_RX_DN<9> @BASEBOARD_FAB2_LIB.BASEBOARD_FAB2(SCH_1):TP_P3E_CPU1_PE1_RSR3_RXN(9)
DM11 TP_P3E_CPU1_PE1_RSR3_RXN<8> PE1_RX_DN<8> @BASEBOARD_FAB2_LIB.BASEBOARD_FAB2(SCH_1):TP_P3E_CPU1_PE1_RSR3_RXN(8)
 DM9 TP_P3E_CPU1_PE1_MP_RXN<7> PE1_RX_DN<7> @BASEBOARD_FAB2_LIB.BASEBOARD_FAB2(SCH_1):TP_P3E_CPU1_PE1_MP_RXN(7)
 DK9 TP_P3E_CPU1_PE1_MP_RXN<6> PE1_RX_DN<6> @BASEBOARD_FAB2_LIB.BASEBOARD_FAB2(SCH_1):TP_P3E_CPU1_PE1_MP_RXN(6)
 DH9 TP_P3E_CPU1_PE1_MP_RXN<5> PE1_RX_DN<5> @BASEBOARD_FAB2_LIB.BASEBOARD_FAB2(SCH_1):TP_P3E_CPU1_PE1_MP_RXN(5)
DE10 TP_P3E_CPU1_PE1_MP_RXN<4> PE1_RX_DN<4> @BASEBOARD_FAB2_LIB.BASEBOARD_FAB2(SCH_1):TP_P3E_CPU1_PE1_MP_RXN(4)
DC10 TP_P3E_CPU1_PE1_MP_RXN<3> PE1_RX_DN<3> @BASEBOARD_FAB2_LIB.BASEBOARD_FAB2(SCH_1):TP_P3E_CPU1_PE1_MP_RXN(3)
 DC8 TP_P3E_CPU1_PE1_MP_RXN<2> PE1_RX_DN<2> @BASEBOARD_FAB2_LIB.BASEBOARD_FAB2(SCH_1):TP_P3E_CPU1_PE1_MP_RXN(2)
 DA8 TP_P3E_CPU1_PE1_MP_RXN<1> PE1_RX_DN<1> @BASEBOARD_FAB2_LIB.BASEBOARD_FAB2(SCH_1):TP_P3E_CPU1_PE1_MP_RXN(1)
 CW8 TP_P3E_CPU1_PE1_MP_RXN<0> PE1_RX_DN<0> @BASEBOARD_FAB2_LIB.BASEBOARD_FAB2(SCH_1):TP_P3E_CPU1_PE1_MP_RXN(0)
DT15 TP_P3E_CPU1_PE1_RSR3_RXP<15> PE1_RX_DP<15> @BASEBOARD_FAB2_LIB.BASEBOARD_FAB2(SCH_1):TP_P3E_CPU1_PE1_RSR3_RXP(15)
DV15 TP_P3E_CPU1_PE1_RSR3_RXP<14> PE1_RX_DP<14> @BASEBOARD_FAB2_LIB.BASEBOARD_FAB2(SCH_1):TP_P3E_CPU1_PE1_RSR3_RXP(14)
DY13 TP_P3E_CPU1_PE1_RSR3_RXP<13> PE1_RX_DP<13> @BASEBOARD_FAB2_LIB.BASEBOARD_FAB2(SCH_1):TP_P3E_CPU1_PE1_RSR3_RXP(13)
DU12 TP_P3E_CPU1_PE1_RSR3_RXP<12> PE1_RX_DP<12> @BASEBOARD_FAB2_LIB.BASEBOARD_FAB2(SCH_1):TP_P3E_CPU1_PE1_RSR3_RXP(12)
DP13 TP_P3E_CPU1_PE1_RSR3_RXP<11> PE1_RX_DP<11> @BASEBOARD_FAB2_LIB.BASEBOARD_FAB2(SCH_1):TP_P3E_CPU1_PE1_RSR3_RXP(11)
DR12 TP_P3E_CPU1_PE1_RSR3_RXP<10> PE1_RX_DP<10> @BASEBOARD_FAB2_LIB.BASEBOARD_FAB2(SCH_1):TP_P3E_CPU1_PE1_RSR3_RXP(10)
DN10 TP_P3E_CPU1_PE1_RSR3_RXP<9> PE1_RX_DP<9> @BASEBOARD_FAB2_LIB.BASEBOARD_FAB2(SCH_1):TP_P3E_CPU1_PE1_RSR3_RXP(9)
DK11 TP_P3E_CPU1_PE1_RSR3_RXP<8> PE1_RX_DP<8> @BASEBOARD_FAB2_LIB.BASEBOARD_FAB2(SCH_1):TP_P3E_CPU1_PE1_RSR3_RXP(8)
DL10 TP_P3E_CPU1_PE1_MP_RXP<7> PE1_RX_DP<7> @BASEBOARD_FAB2_LIB.BASEBOARD_FAB2(SCH_1):TP_P3E_CPU1_PE1_MP_RXP(7)
 DJ8 TP_P3E_CPU1_PE1_MP_RXP<6> PE1_RX_DP<6> @BASEBOARD_FAB2_LIB.BASEBOARD_FAB2(SCH_1):TP_P3E_CPU1_PE1_MP_RXP(6)
 DF9 TP_P3E_CPU1_PE1_MP_RXP<5> PE1_RX_DP<5> @BASEBOARD_FAB2_LIB.BASEBOARD_FAB2(SCH_1):TP_P3E_CPU1_PE1_MP_RXP(5)
 DD9 TP_P3E_CPU1_PE1_MP_RXP<4> PE1_RX_DP<4> @BASEBOARD_FAB2_LIB.BASEBOARD_FAB2(SCH_1):TP_P3E_CPU1_PE1_MP_RXP(4)
DA10 TP_P3E_CPU1_PE1_MP_RXP<3> PE1_RX_DP<3> @BASEBOARD_FAB2_LIB.BASEBOARD_FAB2(SCH_1):TP_P3E_CPU1_PE1_MP_RXP(3)
 DB9 TP_P3E_CPU1_PE1_MP_RXP<2> PE1_RX_DP<2> @BASEBOARD_FAB2_LIB.BASEBOARD_FAB2(SCH_1):TP_P3E_CPU1_PE1_MP_RXP(2)
 CY7 TP_P3E_CPU1_PE1_MP_RXP<1> PE1_RX_DP<1> @BASEBOARD_FAB2_LIB.BASEBOARD_FAB2(SCH_1):TP_P3E_CPU1_PE1_MP_RXP(1)
 CU8 TP_P3E_CPU1_PE1_MP_RXP<0> PE1_RX_DP<0> @BASEBOARD_FAB2_LIB.BASEBOARD_FAB2(SCH_1):TP_P3E_CPU1_PE1_MP_RXP(0)
 ED9 TP_P3E_CPU1_PE1_RSR3_TXN<15> PE1_TX_DN<15> @BASEBOARD_FAB2_LIB.BASEBOARD_FAB2(SCH_1):TP_P3E_CPU1_PE1_RSR3_TXN(15)
 EA8 TP_P3E_CPU1_PE1_RSR3_TXN<14> PE1_TX_DN<14> @BASEBOARD_FAB2_LIB.BASEBOARD_FAB2(SCH_1):TP_P3E_CPU1_PE1_RSR3_TXN(14)
 DY7 TP_P3E_CPU1_PE1_RSR3_TXN<13> PE1_TX_DN<13> @BASEBOARD_FAB2_LIB.BASEBOARD_FAB2(SCH_1):TP_P3E_CPU1_PE1_RSR3_TXN(13)
 DV7 TP_P3E_CPU1_PE1_RSR3_TXN<12> PE1_TX_DN<12> @BASEBOARD_FAB2_LIB.BASEBOARD_FAB2(SCH_1):TP_P3E_CPU1_PE1_RSR3_TXN(12)
 DU6 TP_P3E_CPU1_PE1_RSR3_TXN<11> PE1_TX_DN<11> @BASEBOARD_FAB2_LIB.BASEBOARD_FAB2(SCH_1):TP_P3E_CPU1_PE1_RSR3_TXN(11)
 DW4 TP_P3E_CPU1_PE1_RSR3_TXN<10> PE1_TX_DN<10> @BASEBOARD_FAB2_LIB.BASEBOARD_FAB2(SCH_1):TP_P3E_CPU1_PE1_RSR3_TXN(10)
 DV3 TP_P3E_CPU1_PE1_RSR3_TXN<9> PE1_TX_DN<9> @BASEBOARD_FAB2_LIB.BASEBOARD_FAB2(SCH_1):TP_P3E_CPU1_PE1_RSR3_TXN(9)
 DT5 TP_P3E_CPU1_PE1_RSR3_TXN<8> PE1_TX_DN<8> @BASEBOARD_FAB2_LIB.BASEBOARD_FAB2(SCH_1):TP_P3E_CPU1_PE1_RSR3_TXN(8)
 DN4 TP_P3E_CPU1_PE1_MP_TXN<7> PE1_TX_DN<7> @BASEBOARD_FAB2_LIB.BASEBOARD_FAB2(SCH_1):TP_P3E_CPU1_PE1_MP_TXN(7)
 DM3 TP_P3E_CPU1_PE1_MP_TXN<6> PE1_TX_DN<6> @BASEBOARD_FAB2_LIB.BASEBOARD_FAB2(SCH_1):TP_P3E_CPU1_PE1_MP_TXN(6)
 DK3 TP_P3E_CPU1_PE1_MP_TXN<5> PE1_TX_DN<5> @BASEBOARD_FAB2_LIB.BASEBOARD_FAB2(SCH_1):TP_P3E_CPU1_PE1_MP_TXN(5)
 DG4 TP_P3E_CPU1_PE1_MP_TXN<4> PE1_TX_DN<4> @BASEBOARD_FAB2_LIB.BASEBOARD_FAB2(SCH_1):TP_P3E_CPU1_PE1_MP_TXN(4)
 DE4 TP_P3E_CPU1_PE1_MP_TXN<3> PE1_TX_DN<3> @BASEBOARD_FAB2_LIB.BASEBOARD_FAB2(SCH_1):TP_P3E_CPU1_PE1_MP_TXN(3)
 DE2 TP_P3E_CPU1_PE1_MP_TXN<2> PE1_TX_DN<2> @BASEBOARD_FAB2_LIB.BASEBOARD_FAB2(SCH_1):TP_P3E_CPU1_PE1_MP_TXN(2)
 DC2 TP_P3E_CPU1_PE1_MP_TXN<1> PE1_TX_DN<1> @BASEBOARD_FAB2_LIB.BASEBOARD_FAB2(SCH_1):TP_P3E_CPU1_PE1_MP_TXN(1)
 DA2 TP_P3E_CPU1_PE1_MP_TXN<0> PE1_TX_DN<0> @BASEBOARD_FAB2_LIB.BASEBOARD_FAB2(SCH_1):TP_P3E_CPU1_PE1_MP_TXN(0)
 EC8 TP_P3E_CPU1_PE1_RSR3_TXP<15> PE1_TX_DP<15> @BASEBOARD_FAB2_LIB.BASEBOARD_FAB2(SCH_1):TP_P3E_CPU1_PE1_RSR3_TXP(15)
 EB7 TP_P3E_CPU1_PE1_RSR3_TXP<14> PE1_TX_DP<14> @BASEBOARD_FAB2_LIB.BASEBOARD_FAB2(SCH_1):TP_P3E_CPU1_PE1_RSR3_TXP(14)
 DW6 TP_P3E_CPU1_PE1_RSR3_TXP<13> PE1_TX_DP<13> @BASEBOARD_FAB2_LIB.BASEBOARD_FAB2(SCH_1):TP_P3E_CPU1_PE1_RSR3_TXP(13)
 DT7 TP_P3E_CPU1_PE1_RSR3_TXP<12> PE1_TX_DP<12> @BASEBOARD_FAB2_LIB.BASEBOARD_FAB2(SCH_1):TP_P3E_CPU1_PE1_RSR3_TXP(12)
 DV5 TP_P3E_CPU1_PE1_RSR3_TXP<11> PE1_TX_DP<11> @BASEBOARD_FAB2_LIB.BASEBOARD_FAB2(SCH_1):TP_P3E_CPU1_PE1_RSR3_TXP(11)
 DU4 TP_P3E_CPU1_PE1_RSR3_TXP<10> PE1_TX_DP<10> @BASEBOARD_FAB2_LIB.BASEBOARD_FAB2(SCH_1):TP_P3E_CPU1_PE1_RSR3_TXP(10)
 DU2 TP_P3E_CPU1_PE1_RSR3_TXP<9> PE1_TX_DP<9> @BASEBOARD_FAB2_LIB.BASEBOARD_FAB2(SCH_1):TP_P3E_CPU1_PE1_RSR3_TXP(9)
 DR4 TP_P3E_CPU1_PE1_RSR3_TXP<8> PE1_TX_DP<8> @BASEBOARD_FAB2_LIB.BASEBOARD_FAB2(SCH_1):TP_P3E_CPU1_PE1_RSR3_TXP(8)
 DP3 TP_P3E_CPU1_PE1_MP_TXP<7> PE1_TX_DP<7> @BASEBOARD_FAB2_LIB.BASEBOARD_FAB2(SCH_1):TP_P3E_CPU1_PE1_MP_TXP(7)
 DL2 TP_P3E_CPU1_PE1_MP_TXP<6> PE1_TX_DP<6> @BASEBOARD_FAB2_LIB.BASEBOARD_FAB2(SCH_1):TP_P3E_CPU1_PE1_MP_TXP(6)
 DH3 TP_P3E_CPU1_PE1_MP_TXP<5> PE1_TX_DP<5> @BASEBOARD_FAB2_LIB.BASEBOARD_FAB2(SCH_1):TP_P3E_CPU1_PE1_MP_TXP(5)
 DF3 TP_P3E_CPU1_PE1_MP_TXP<4> PE1_TX_DP<4> @BASEBOARD_FAB2_LIB.BASEBOARD_FAB2(SCH_1):TP_P3E_CPU1_PE1_MP_TXP(4)
 DC4 TP_P3E_CPU1_PE1_MP_TXP<3> PE1_TX_DP<3> @BASEBOARD_FAB2_LIB.BASEBOARD_FAB2(SCH_1):TP_P3E_CPU1_PE1_MP_TXP(3)
 DD3 TP_P3E_CPU1_PE1_MP_TXP<2> PE1_TX_DP<2> @BASEBOARD_FAB2_LIB.BASEBOARD_FAB2(SCH_1):TP_P3E_CPU1_PE1_MP_TXP(2)
 DB1 TP_P3E_CPU1_PE1_MP_TXP<1> PE1_TX_DP<1> @BASEBOARD_FAB2_LIB.BASEBOARD_FAB2(SCH_1):TP_P3E_CPU1_PE1_MP_TXP(1)
 CW2 TP_P3E_CPU1_PE1_MP_TXP<0> PE1_TX_DP<0> @BASEBOARD_FAB2_LIB.BASEBOARD_FAB2(SCH_1):TP_P3E_CPU1_PE1_MP_TXP(0)


DRAWING: @BASEBOARD_FAB2_LIB.BASEBOARD_FAB2(SCH_1):PAGE65 

SKX_EXT_B_BGA1-IC,TBD  I68  U2D1
 BK9 TP_P3E_CPU1_PE2_RSR_RXN<15> PE2_RX_DN<15> @BASEBOARD_FAB2_LIB.BASEBOARD_FAB2(SCH_1):TP_P3E_CPU1_PE2_RSR_RXN(15)
 BL8 TP_P3E_CPU1_PE2_RSR_RXN<14> PE2_RX_DN<14> @BASEBOARD_FAB2_LIB.BASEBOARD_FAB2(SCH_1):TP_P3E_CPU1_PE2_RSR_RXN(14)
 BN8 TP_P3E_CPU1_PE2_RSR_RXN<13> PE2_RX_DN<13> @BASEBOARD_FAB2_LIB.BASEBOARD_FAB2(SCH_1):TP_P3E_CPU1_PE2_RSR_RXN(13)
 BR8 TP_P3E_CPU1_PE2_RSR_RXN<12> PE2_RX_DN<12> @BASEBOARD_FAB2_LIB.BASEBOARD_FAB2(SCH_1):TP_P3E_CPU1_PE2_RSR_RXN(12)
 BT7 TP_P3E_CPU1_PE2_RSR_RXN<11> PE2_RX_DN<11> @BASEBOARD_FAB2_LIB.BASEBOARD_FAB2(SCH_1):TP_P3E_CPU1_PE2_RSR_RXN(11)
 BV7 TP_P3E_CPU1_PE2_RSR_RXN<10> PE2_RX_DN<10> @BASEBOARD_FAB2_LIB.BASEBOARD_FAB2(SCH_1):TP_P3E_CPU1_PE2_RSR_RXN(10)
 BY7 TP_P3E_CPU1_PE2_RSR_RXN<9> PE2_RX_DN<9> @BASEBOARD_FAB2_LIB.BASEBOARD_FAB2(SCH_1):TP_P3E_CPU1_PE2_RSR_RXN(9)
 BY9 TP_P3E_CPU1_PE2_RSR_RXN<8> PE2_RX_DN<8> @BASEBOARD_FAB2_LIB.BASEBOARD_FAB2(SCH_1):TP_P3E_CPU1_PE2_RSR_RXN(8)
 CE8 TP_P3E_CPU1_PE2_RSR_RXN<7> PE2_RX_DN<7> @BASEBOARD_FAB2_LIB.BASEBOARD_FAB2(SCH_1):TP_P3E_CPU1_PE2_RSR_RXN(7)
 CE6 TP_P3E_CPU1_PE2_RSR_RXN<6> PE2_RX_DN<6> @BASEBOARD_FAB2_LIB.BASEBOARD_FAB2(SCH_1):TP_P3E_CPU1_PE2_RSR_RXN(6)
 CG8 TP_P3E_CPU1_PE2_RSR_RXN<5> PE2_RX_DN<5> @BASEBOARD_FAB2_LIB.BASEBOARD_FAB2(SCH_1):TP_P3E_CPU1_PE2_RSR_RXN(5)
 CK7 TP_P3E_CPU1_PE2_RSR_RXN<4> PE2_RX_DN<4> @BASEBOARD_FAB2_LIB.BASEBOARD_FAB2(SCH_1):TP_P3E_CPU1_PE2_RSR_RXN(4)
 CM7 TP_P3E_CPU1_PE2_RSR_RXN<3> PE2_RX_DN<3> @BASEBOARD_FAB2_LIB.BASEBOARD_FAB2(SCH_1):TP_P3E_CPU1_PE2_RSR_RXN(3)
 CP7 TP_P3E_CPU1_PE2_RSR_RXN<2> PE2_RX_DN<2> @BASEBOARD_FAB2_LIB.BASEBOARD_FAB2(SCH_1):TP_P3E_CPU1_PE2_RSR_RXN(2)
 CP9 TP_P3E_CPU1_PE2_RSR_RXN<1> PE2_RX_DN<1> @BASEBOARD_FAB2_LIB.BASEBOARD_FAB2(SCH_1):TP_P3E_CPU1_PE2_RSR_RXN(1)
 CT9 TP_P3E_CPU1_PE2_RSR_RXN<0> PE2_RX_DN<0> @BASEBOARD_FAB2_LIB.BASEBOARD_FAB2(SCH_1):TP_P3E_CPU1_PE2_RSR_RXN(0)
BJ10 TP_P3E_CPU1_PE2_RSR_RXP<15> PE2_RX_DP<15> @BASEBOARD_FAB2_LIB.BASEBOARD_FAB2(SCH_1):TP_P3E_CPU1_PE2_RSR_RXP(15)
 BJ8 TP_P3E_CPU1_PE2_RSR_RXP<14> PE2_RX_DP<14> @BASEBOARD_FAB2_LIB.BASEBOARD_FAB2(SCH_1):TP_P3E_CPU1_PE2_RSR_RXP(14)
 BM7 TP_P3E_CPU1_PE2_RSR_RXP<13> PE2_RX_DP<13> @BASEBOARD_FAB2_LIB.BASEBOARD_FAB2(SCH_1):TP_P3E_CPU1_PE2_RSR_RXP(13)
 BP9 TP_P3E_CPU1_PE2_RSR_RXP<12> PE2_RX_DP<12> @BASEBOARD_FAB2_LIB.BASEBOARD_FAB2(SCH_1):TP_P3E_CPU1_PE2_RSR_RXP(12)
 BP7 TP_P3E_CPU1_PE2_RSR_RXP<11> PE2_RX_DP<11> @BASEBOARD_FAB2_LIB.BASEBOARD_FAB2(SCH_1):TP_P3E_CPU1_PE2_RSR_RXP(11)
 BU6 TP_P3E_CPU1_PE2_RSR_RXP<10> PE2_RX_DP<10> @BASEBOARD_FAB2_LIB.BASEBOARD_FAB2(SCH_1):TP_P3E_CPU1_PE2_RSR_RXP(10)
 BW8 TP_P3E_CPU1_PE2_RSR_RXP<9> PE2_RX_DP<9> @BASEBOARD_FAB2_LIB.BASEBOARD_FAB2(SCH_1):TP_P3E_CPU1_PE2_RSR_RXP(9)
 BV9 TP_P3E_CPU1_PE2_RSR_RXP<8> PE2_RX_DP<8> @BASEBOARD_FAB2_LIB.BASEBOARD_FAB2(SCH_1):TP_P3E_CPU1_PE2_RSR_RXP(8)
 CC8 TP_P3E_CPU1_PE2_RSR_RXP<7> PE2_RX_DP<7> @BASEBOARD_FAB2_LIB.BASEBOARD_FAB2(SCH_1):TP_P3E_CPU1_PE2_RSR_RXP(7)
 CD7 TP_P3E_CPU1_PE2_RSR_RXP<6> PE2_RX_DP<6> @BASEBOARD_FAB2_LIB.BASEBOARD_FAB2(SCH_1):TP_P3E_CPU1_PE2_RSR_RXP(6)
 CF7 TP_P3E_CPU1_PE2_RSR_RXP<5> PE2_RX_DP<5> @BASEBOARD_FAB2_LIB.BASEBOARD_FAB2(SCH_1):TP_P3E_CPU1_PE2_RSR_RXP(5)
 CH7 TP_P3E_CPU1_PE2_RSR_RXP<4> PE2_RX_DP<4> @BASEBOARD_FAB2_LIB.BASEBOARD_FAB2(SCH_1):TP_P3E_CPU1_PE2_RSR_RXP(4)
 CL6 TP_P3E_CPU1_PE2_RSR_RXP<3> PE2_RX_DP<3> @BASEBOARD_FAB2_LIB.BASEBOARD_FAB2(SCH_1):TP_P3E_CPU1_PE2_RSR_RXP(3)
 CN8 TP_P3E_CPU1_PE2_RSR_RXP<2> PE2_RX_DP<2> @BASEBOARD_FAB2_LIB.BASEBOARD_FAB2(SCH_1):TP_P3E_CPU1_PE2_RSR_RXP(2)
 CM9 TP_P3E_CPU1_PE2_RSR_RXP<1> PE2_RX_DP<1> @BASEBOARD_FAB2_LIB.BASEBOARD_FAB2(SCH_1):TP_P3E_CPU1_PE2_RSR_RXP(1)
 CR8 TP_P3E_CPU1_PE2_RSR_RXP<0> PE2_RX_DP<0> @BASEBOARD_FAB2_LIB.BASEBOARD_FAB2(SCH_1):TP_P3E_CPU1_PE2_RSR_RXP(0)
 BM5 TP_P3E_CPU1_PE2_RSR_TXN<15> PE2_TX_DN<15> @BASEBOARD_FAB2_LIB.BASEBOARD_FAB2(SCH_1):TP_P3E_CPU1_PE2_RSR_TXN(15)
 BL4 TP_P3E_CPU1_PE2_RSR_TXN<14> PE2_TX_DN<14> @BASEBOARD_FAB2_LIB.BASEBOARD_FAB2(SCH_1):TP_P3E_CPU1_PE2_RSR_TXN(14)
 BP5 TP_P3E_CPU1_PE2_RSR_TXN<13> PE2_TX_DN<13> @BASEBOARD_FAB2_LIB.BASEBOARD_FAB2(SCH_1):TP_P3E_CPU1_PE2_RSR_TXN(13)
 BU4 TP_P3E_CPU1_PE2_RSR_TXN<12> PE2_TX_DN<12> @BASEBOARD_FAB2_LIB.BASEBOARD_FAB2(SCH_1):TP_P3E_CPU1_PE2_RSR_TXN(12)
 BW4 TP_P3E_CPU1_PE2_RSR_TXN<11> PE2_TX_DN<11> @BASEBOARD_FAB2_LIB.BASEBOARD_FAB2(SCH_1):TP_P3E_CPU1_PE2_RSR_TXN(11)
 CA4 TP_P3E_CPU1_PE2_RSR_TXN<10> PE2_TX_DN<10> @BASEBOARD_FAB2_LIB.BASEBOARD_FAB2(SCH_1):TP_P3E_CPU1_PE2_RSR_TXN(10)
 CB3 TP_P3E_CPU1_PE2_RSR_TXN<9> PE2_TX_DN<9> @BASEBOARD_FAB2_LIB.BASEBOARD_FAB2(SCH_1):TP_P3E_CPU1_PE2_RSR_TXN(9)
 CC2 TP_P3E_CPU1_PE2_RSR_TXN<8> PE2_TX_DN<8> @BASEBOARD_FAB2_LIB.BASEBOARD_FAB2(SCH_1):TP_P3E_CPU1_PE2_RSR_TXN(8)
 CF3 TP_P3E_CPU1_PE2_RSR_TXN<7> PE2_TX_DN<7> @BASEBOARD_FAB2_LIB.BASEBOARD_FAB2(SCH_1):TP_P3E_CPU1_PE2_RSR_TXN(7)
 CG2 TP_P3E_CPU1_PE2_RSR_TXN<6> PE2_TX_DN<6> @BASEBOARD_FAB2_LIB.BASEBOARD_FAB2(SCH_1):TP_P3E_CPU1_PE2_RSR_TXN(6)
 CL2 TP_P3E_CPU1_PE2_RSR_TXN<5> PE2_TX_DN<5> @BASEBOARD_FAB2_LIB.BASEBOARD_FAB2(SCH_1):TP_P3E_CPU1_PE2_RSR_TXN(5)
 CM1 TP_P3E_CPU1_PE2_RSR_TXN<4> PE2_TX_DN<4> @BASEBOARD_FAB2_LIB.BASEBOARD_FAB2(SCH_1):TP_P3E_CPU1_PE2_RSR_TXN(4)
 CT3 TP_P3E_CPU1_PE2_RSR_TXN<3> PE2_TX_DN<3> @BASEBOARD_FAB2_LIB.BASEBOARD_FAB2(SCH_1):TP_P3E_CPU1_PE2_RSR_TXN(3)
 CT1 TP_P3E_CPU1_PE2_RSR_TXN<2> PE2_TX_DN<2> @BASEBOARD_FAB2_LIB.BASEBOARD_FAB2(SCH_1):TP_P3E_CPU1_PE2_RSR_TXN(2)
 CV3 TP_P3E_CPU1_PE2_RSR_TXN<1> PE2_TX_DN<1> @BASEBOARD_FAB2_LIB.BASEBOARD_FAB2(SCH_1):TP_P3E_CPU1_PE2_RSR_TXN(1)
 CY3 TP_P3E_CPU1_PE2_RSR_TXN<0> PE2_TX_DN<0> @BASEBOARD_FAB2_LIB.BASEBOARD_FAB2(SCH_1):TP_P3E_CPU1_PE2_RSR_TXN(0)
 BK5 TP_P3E_CPU1_PE2_RSR_TXP<15> PE2_TX_DP<15> @BASEBOARD_FAB2_LIB.BASEBOARD_FAB2(SCH_1):TP_P3E_CPU1_PE2_RSR_TXP(15)
 BM3 TP_P3E_CPU1_PE2_RSR_TXP<14> PE2_TX_DP<14> @BASEBOARD_FAB2_LIB.BASEBOARD_FAB2(SCH_1):TP_P3E_CPU1_PE2_RSR_TXP(14)
 BN4 TP_P3E_CPU1_PE2_RSR_TXP<13> PE2_TX_DP<13> @BASEBOARD_FAB2_LIB.BASEBOARD_FAB2(SCH_1):TP_P3E_CPU1_PE2_RSR_TXP(13)
 BR4 TP_P3E_CPU1_PE2_RSR_TXP<12> PE2_TX_DP<12> @BASEBOARD_FAB2_LIB.BASEBOARD_FAB2(SCH_1):TP_P3E_CPU1_PE2_RSR_TXP(12)
 BV3 TP_P3E_CPU1_PE2_RSR_TXP<11> PE2_TX_DP<11> @BASEBOARD_FAB2_LIB.BASEBOARD_FAB2(SCH_1):TP_P3E_CPU1_PE2_RSR_TXP(11)
 BY5 TP_P3E_CPU1_PE2_RSR_TXP<10> PE2_TX_DP<10> @BASEBOARD_FAB2_LIB.BASEBOARD_FAB2(SCH_1):TP_P3E_CPU1_PE2_RSR_TXP(10)
 BY3 TP_P3E_CPU1_PE2_RSR_TXP<9> PE2_TX_DP<9> @BASEBOARD_FAB2_LIB.BASEBOARD_FAB2(SCH_1):TP_P3E_CPU1_PE2_RSR_TXP(9)
 CD3 TP_P3E_CPU1_PE2_RSR_TXP<8> PE2_TX_DP<8> @BASEBOARD_FAB2_LIB.BASEBOARD_FAB2(SCH_1):TP_P3E_CPU1_PE2_RSR_TXP(8)
 CE4 TP_P3E_CPU1_PE2_RSR_TXP<7> PE2_TX_DP<7> @BASEBOARD_FAB2_LIB.BASEBOARD_FAB2(SCH_1):TP_P3E_CPU1_PE2_RSR_TXP(7)
 CE2 TP_P3E_CPU1_PE2_RSR_TXP<6> PE2_TX_DP<6> @BASEBOARD_FAB2_LIB.BASEBOARD_FAB2(SCH_1):TP_P3E_CPU1_PE2_RSR_TXP(6)
 CK3 TP_P3E_CPU1_PE2_RSR_TXP<5> PE2_TX_DP<5> @BASEBOARD_FAB2_LIB.BASEBOARD_FAB2(SCH_1):TP_P3E_CPU1_PE2_RSR_TXP(5)
 CK1 TP_P3E_CPU1_PE2_RSR_TXP<4> PE2_TX_DP<4> @BASEBOARD_FAB2_LIB.BASEBOARD_FAB2(SCH_1):TP_P3E_CPU1_PE2_RSR_TXP(4)
 CP3 TP_P3E_CPU1_PE2_RSR_TXP<3> PE2_TX_DP<3> @BASEBOARD_FAB2_LIB.BASEBOARD_FAB2(SCH_1):TP_P3E_CPU1_PE2_RSR_TXP(3)
 CR2 TP_P3E_CPU1_PE2_RSR_TXP<2> PE2_TX_DP<2> @BASEBOARD_FAB2_LIB.BASEBOARD_FAB2(SCH_1):TP_P3E_CPU1_PE2_RSR_TXP(2)
 CU2 TP_P3E_CPU1_PE2_RSR_TXP<1> PE2_TX_DP<1> @BASEBOARD_FAB2_LIB.BASEBOARD_FAB2(SCH_1):TP_P3E_CPU1_PE2_RSR_TXP(1)
 CW4 TP_P3E_CPU1_PE2_RSR_TXP<0> PE2_TX_DP<0> @BASEBOARD_FAB2_LIB.BASEBOARD_FAB2(SCH_1):TP_P3E_CPU1_PE2_RSR_TXP(0)


DRAWING: @BASEBOARD_FAB2_LIB.BASEBOARD_FAB2(SCH_1):PAGE66 

SKX_EXT_B_BGA1-IC,TBD  I84  U2D1
 CV9 P3E_CPU1_PE3_MP_RXN<15> PE3_RX_DN<15> @BASEBOARD_FAB2_LIB.BASEBOARD_FAB2(SCH_1):P3E_CPU1_PE3_MP_RXN(15)
CY11 P3E_CPU1_PE3_MP_RXN<14> PE3_RX_DN<14> @BASEBOARD_FAB2_LIB.BASEBOARD_FAB2(SCH_1):P3E_CPU1_PE3_MP_RXN(14)
DB11 P3E_CPU1_PE3_MP_RXN<13> PE3_RX_DN<13> @BASEBOARD_FAB2_LIB.BASEBOARD_FAB2(SCH_1):P3E_CPU1_PE3_MP_RXN(13)
DD13 P3E_CPU1_PE3_MP_RXP<12> PE3_RX_DN<12> @BASEBOARD_FAB2_LIB.BASEBOARD_FAB2(SCH_1):P3E_CPU1_PE3_MP_RXP(12)
DG10 P3E_CPU1_PE3_MP_RXN<11> PE3_RX_DN<11> @BASEBOARD_FAB2_LIB.BASEBOARD_FAB2(SCH_1):P3E_CPU1_PE3_MP_RXN(11)
DG12 P3E_CPU1_PE3_MP_RXN<10> PE3_RX_DN<10> @BASEBOARD_FAB2_LIB.BASEBOARD_FAB2(SCH_1):P3E_CPU1_PE3_MP_RXN(10)
DJ12 P3E_CPU1_PE3_MP_RXN<9> PE3_RX_DN<9> @BASEBOARD_FAB2_LIB.BASEBOARD_FAB2(SCH_1):P3E_CPU1_PE3_MP_RXN(9)
DL12 P3E_CPU1_PE3_MP_RXN<8> PE3_RX_DN<8> @BASEBOARD_FAB2_LIB.BASEBOARD_FAB2(SCH_1):P3E_CPU1_PE3_MP_RXN(8)
DL14 P3E_CPU1_PE3_MP_RXN<7> PE3_RX_DN<7> @BASEBOARD_FAB2_LIB.BASEBOARD_FAB2(SCH_1):P3E_CPU1_PE3_MP_RXN(7)
DN14 P3E_CPU1_PE3_MP_RXN<6> PE3_RX_DN<6> @BASEBOARD_FAB2_LIB.BASEBOARD_FAB2(SCH_1):P3E_CPU1_PE3_MP_RXN(6)
DR14 P3E_CPU1_PE3_MP_RXN<5> PE3_RX_DN<5> @BASEBOARD_FAB2_LIB.BASEBOARD_FAB2(SCH_1):P3E_CPU1_PE3_MP_RXN(5)
DR16 P3E_CPU1_PE3_MP_RXN<4> PE3_RX_DN<4> @BASEBOARD_FAB2_LIB.BASEBOARD_FAB2(SCH_1):P3E_CPU1_PE3_MP_RXN(4)
DT19 P3E_CPU1_PE3_MP_RXN<3> PE3_RX_DN<3> @BASEBOARD_FAB2_LIB.BASEBOARD_FAB2(SCH_1):P3E_CPU1_PE3_MP_RXN(3)
DW16 P3E_CPU1_PE3_MP_RXN<2> PE3_RX_DN<2> @BASEBOARD_FAB2_LIB.BASEBOARD_FAB2(SCH_1):P3E_CPU1_PE3_MP_RXN(2)
DW18 P3E_CPU1_PE3_MP_RXN<1> PE3_RX_DN<1> @BASEBOARD_FAB2_LIB.BASEBOARD_FAB2(SCH_1):P3E_CPU1_PE3_MP_RXN(1)
EA18 P3E_CPU1_PE3_MP_RXN<0> PE3_RX_DN<0> @BASEBOARD_FAB2_LIB.BASEBOARD_FAB2(SCH_1):P3E_CPU1_PE3_MP_RXN(0)
CU10 P3E_CPU1_PE3_MP_RXP<15> PE3_RX_DP<15> @BASEBOARD_FAB2_LIB.BASEBOARD_FAB2(SCH_1):P3E_CPU1_PE3_MP_RXP(15)
CW10 P3E_CPU1_PE3_MP_RXP<14> PE3_RX_DP<14> @BASEBOARD_FAB2_LIB.BASEBOARD_FAB2(SCH_1):P3E_CPU1_PE3_MP_RXP(14)
DA12 P3E_CPU1_PE3_MP_RXP<13> PE3_RX_DP<13> @BASEBOARD_FAB2_LIB.BASEBOARD_FAB2(SCH_1):P3E_CPU1_PE3_MP_RXP(13)
DC12 P3E_CPU1_PE3_MP_RXN<12> PE3_RX_DP<12> @BASEBOARD_FAB2_LIB.BASEBOARD_FAB2(SCH_1):P3E_CPU1_PE3_MP_RXN(12)
DF11 P3E_CPU1_PE3_MP_RXP<11> PE3_RX_DP<11> @BASEBOARD_FAB2_LIB.BASEBOARD_FAB2(SCH_1):P3E_CPU1_PE3_MP_RXP(11)
DE12 P3E_CPU1_PE3_MP_RXP<10> PE3_RX_DP<10> @BASEBOARD_FAB2_LIB.BASEBOARD_FAB2(SCH_1):P3E_CPU1_PE3_MP_RXP(10)
DH11 P3E_CPU1_PE3_MP_RXP<9> PE3_RX_DP<9> @BASEBOARD_FAB2_LIB.BASEBOARD_FAB2(SCH_1):P3E_CPU1_PE3_MP_RXP(9)
DK13 P3E_CPU1_PE3_MP_RXP<8> PE3_RX_DP<8> @BASEBOARD_FAB2_LIB.BASEBOARD_FAB2(SCH_1):P3E_CPU1_PE3_MP_RXP(8)
DJ14 P3E_CPU1_PE3_MP_RXP<7> PE3_RX_DP<7> @BASEBOARD_FAB2_LIB.BASEBOARD_FAB2(SCH_1):P3E_CPU1_PE3_MP_RXP(7)
DM13 P3E_CPU1_PE3_MP_RXP<6> PE3_RX_DP<6> @BASEBOARD_FAB2_LIB.BASEBOARD_FAB2(SCH_1):P3E_CPU1_PE3_MP_RXP(6)
DP15 P3E_CPU1_PE3_MP_RXP<5> PE3_RX_DP<5> @BASEBOARD_FAB2_LIB.BASEBOARD_FAB2(SCH_1):P3E_CPU1_PE3_MP_RXP(5)
DN16 P3E_CPU1_PE3_MP_RXP<4> PE3_RX_DP<4> @BASEBOARD_FAB2_LIB.BASEBOARD_FAB2(SCH_1):P3E_CPU1_PE3_MP_RXP(4)
DR18 P3E_CPU1_PE3_MP_RXP<3> PE3_RX_DP<3> @BASEBOARD_FAB2_LIB.BASEBOARD_FAB2(SCH_1):P3E_CPU1_PE3_MP_RXP(3)
DV17 P3E_CPU1_PE3_MP_RXP<2> PE3_RX_DP<2> @BASEBOARD_FAB2_LIB.BASEBOARD_FAB2(SCH_1):P3E_CPU1_PE3_MP_RXP(2)
DU18 P3E_CPU1_PE3_MP_RXP<1> PE3_RX_DP<1> @BASEBOARD_FAB2_LIB.BASEBOARD_FAB2(SCH_1):P3E_CPU1_PE3_MP_RXP(1)
DY17 P3E_CPU1_PE3_MP_RXP<0> PE3_RX_DP<0> @BASEBOARD_FAB2_LIB.BASEBOARD_FAB2(SCH_1):P3E_CPU1_PE3_MP_RXP(0)
 CY5 P3E_CPU1_PE3_MP_TXN<15> PE3_TX_DN<15> @BASEBOARD_FAB2_LIB.BASEBOARD_FAB2(SCH_1):P3E_CPU1_PE3_MP_TXN(15)
 DB5 P3E_CPU1_PE3_MP_TXN<14> PE3_TX_DN<14> @BASEBOARD_FAB2_LIB.BASEBOARD_FAB2(SCH_1):P3E_CPU1_PE3_MP_TXN(14)
 DD5 P3E_CPU1_PE3_MP_TXN<13> PE3_TX_DN<13> @BASEBOARD_FAB2_LIB.BASEBOARD_FAB2(SCH_1):P3E_CPU1_PE3_MP_TXN(13)
 DJ6 P3E_CPU1_PE3_MP_TXN<12> PE3_TX_DN<12> @BASEBOARD_FAB2_LIB.BASEBOARD_FAB2(SCH_1):P3E_CPU1_PE3_MP_TXN(12)
 DJ4 P3E_CPU1_PE3_MP_TXN<11> PE3_TX_DN<11> @BASEBOARD_FAB2_LIB.BASEBOARD_FAB2(SCH_1):P3E_CPU1_PE3_MP_TXN(11)
 DL6 P3E_CPU1_PE3_MP_TXN<10> PE3_TX_DN<10> @BASEBOARD_FAB2_LIB.BASEBOARD_FAB2(SCH_1):P3E_CPU1_PE3_MP_TXN(10)
 DP5 P3E_CPU1_PE3_MP_TXN<9> PE3_TX_DN<9> @BASEBOARD_FAB2_LIB.BASEBOARD_FAB2(SCH_1):P3E_CPU1_PE3_MP_TXN(9)
 DM7 P3E_CPU1_PE3_MP_TXN<8> PE3_TX_DN<8> @BASEBOARD_FAB2_LIB.BASEBOARD_FAB2(SCH_1):P3E_CPU1_PE3_MP_TXN(8)
 DR8 P3E_CPU1_PE3_MP_TXN<7> PE3_TX_DN<7> @BASEBOARD_FAB2_LIB.BASEBOARD_FAB2(SCH_1):P3E_CPU1_PE3_MP_TXN(7)
 DU8 P3E_CPU1_PE3_MP_TXN<6> PE3_TX_DN<6> @BASEBOARD_FAB2_LIB.BASEBOARD_FAB2(SCH_1):P3E_CPU1_PE3_MP_TXN(6)
DW10 P3E_CPU1_PE3_MP_TXN<5> PE3_TX_DN<5> @BASEBOARD_FAB2_LIB.BASEBOARD_FAB2(SCH_1):P3E_CPU1_PE3_MP_TXN(5)
 EB9 P3E_CPU1_PE3_MP_TXN<4> PE3_TX_DN<4> @BASEBOARD_FAB2_LIB.BASEBOARD_FAB2(SCH_1):P3E_CPU1_PE3_MP_TXN(4)
DY11 P3E_CPU1_PE3_MP_TXN<3> PE3_TX_DN<3> @BASEBOARD_FAB2_LIB.BASEBOARD_FAB2(SCH_1):P3E_CPU1_PE3_MP_TXN(3)
EC12 P3E_CPU1_PE3_MP_TXN<2> PE3_TX_DN<2> @BASEBOARD_FAB2_LIB.BASEBOARD_FAB2(SCH_1):P3E_CPU1_PE3_MP_TXN(2)
EE12 P3E_CPU1_PE3_MP_TXN<1> PE3_TX_DN<1> @BASEBOARD_FAB2_LIB.BASEBOARD_FAB2(SCH_1):P3E_CPU1_PE3_MP_TXN(1)
EE14 P3E_CPU1_PE3_MP_TXN<0> PE3_TX_DN<0> @BASEBOARD_FAB2_LIB.BASEBOARD_FAB2(SCH_1):P3E_CPU1_PE3_MP_TXN(0)
 CV5 P3E_CPU1_PE3_MP_TXP<15> PE3_TX_DP<15> @BASEBOARD_FAB2_LIB.BASEBOARD_FAB2(SCH_1):P3E_CPU1_PE3_MP_TXP(15)
 DA4 P3E_CPU1_PE3_MP_TXP<14> PE3_TX_DP<14> @BASEBOARD_FAB2_LIB.BASEBOARD_FAB2(SCH_1):P3E_CPU1_PE3_MP_TXP(14)
 DC6 P3E_CPU1_PE3_MP_TXP<13> PE3_TX_DP<13> @BASEBOARD_FAB2_LIB.BASEBOARD_FAB2(SCH_1):P3E_CPU1_PE3_MP_TXP(13)
 DG6 P3E_CPU1_PE3_MP_TXP<12> PE3_TX_DP<12> @BASEBOARD_FAB2_LIB.BASEBOARD_FAB2(SCH_1):P3E_CPU1_PE3_MP_TXP(12)
 DH5 P3E_CPU1_PE3_MP_TXP<11> PE3_TX_DP<11> @BASEBOARD_FAB2_LIB.BASEBOARD_FAB2(SCH_1):P3E_CPU1_PE3_MP_TXP(11)
 DK5 P3E_CPU1_PE3_MP_TXP<10> PE3_TX_DP<10> @BASEBOARD_FAB2_LIB.BASEBOARD_FAB2(SCH_1):P3E_CPU1_PE3_MP_TXP(10)
 DM5 P3E_CPU1_PE3_MP_TXP<9> PE3_TX_DP<9> @BASEBOARD_FAB2_LIB.BASEBOARD_FAB2(SCH_1):P3E_CPU1_PE3_MP_TXP(9)
 DN6 P3E_CPU1_PE3_MP_TXP<8> PE3_TX_DP<8> @BASEBOARD_FAB2_LIB.BASEBOARD_FAB2(SCH_1):P3E_CPU1_PE3_MP_TXP(8)
 DP7 P3E_CPU1_PE3_MP_TXP<7> PE3_TX_DP<7> @BASEBOARD_FAB2_LIB.BASEBOARD_FAB2(SCH_1):P3E_CPU1_PE3_MP_TXP(7)
 DT9 P3E_CPU1_PE3_MP_TXP<6> PE3_TX_DP<6> @BASEBOARD_FAB2_LIB.BASEBOARD_FAB2(SCH_1):P3E_CPU1_PE3_MP_TXP(6)
 DV9 P3E_CPU1_PE3_MP_TXP<5> PE3_TX_DP<5> @BASEBOARD_FAB2_LIB.BASEBOARD_FAB2(SCH_1):P3E_CPU1_PE3_MP_TXP(5)
 DY9 P3E_CPU1_PE3_MP_TXP<4> PE3_TX_DP<4> @BASEBOARD_FAB2_LIB.BASEBOARD_FAB2(SCH_1):P3E_CPU1_PE3_MP_TXP(4)
EA10 P3E_CPU1_PE3_MP_TXP<3> PE3_TX_DP<3> @BASEBOARD_FAB2_LIB.BASEBOARD_FAB2(SCH_1):P3E_CPU1_PE3_MP_TXP(3)
EB11 P3E_CPU1_PE3_MP_TXP<2> PE3_TX_DP<2> @BASEBOARD_FAB2_LIB.BASEBOARD_FAB2(SCH_1):P3E_CPU1_PE3_MP_TXP(2)
ED13 P3E_CPU1_PE3_MP_TXP<1> PE3_TX_DP<1> @BASEBOARD_FAB2_LIB.BASEBOARD_FAB2(SCH_1):P3E_CPU1_PE3_MP_TXP(1)
EC14 P3E_CPU1_PE3_MP_TXP<0> PE3_TX_DP<0> @BASEBOARD_FAB2_LIB.BASEBOARD_FAB2(SCH_1):P3E_CPU1_PE3_MP_TXP(0)


DRAWING: @BASEBOARD_FAB2_LIB.BASEBOARD_FAB2(SCH_1):PAGE67 

SKX_EXT_B_BGA1-IC,TBD  I132  U2D1
BB11 UPI_CPU0_CPU1_P0P0_DP<19> UPI0_RX_DN<19> @BASEBOARD_FAB2_LIB.BASEBOARD_FAB2(SCH_1):UPI_CPU0_CPU1_P0P0_DP(19)
 BD9 UPI_CPU0_CPU1_P0P0_DP<18> UPI0_RX_DN<18> @BASEBOARD_FAB2_LIB.BASEBOARD_FAB2(SCH_1):UPI_CPU0_CPU1_P0P0_DP(18)
 AY9 UPI_CPU0_CPU1_P0P0_DN<17> UPI0_RX_DN<17> @BASEBOARD_FAB2_LIB.BASEBOARD_FAB2(SCH_1):UPI_CPU0_CPU1_P0P0_DN(17)
 AW8 UPI_CPU0_CPU1_P0P0_DN<16> UPI0_RX_DN<16> @BASEBOARD_FAB2_LIB.BASEBOARD_FAB2(SCH_1):UPI_CPU0_CPU1_P0P0_DN(16)
 BD7 UPI_CPU0_CPU1_P0P0_DN<15> UPI0_RX_DN<15> @BASEBOARD_FAB2_LIB.BASEBOARD_FAB2(SCH_1):UPI_CPU0_CPU1_P0P0_DN(15)
 BC6 UPI_CPU0_CPU1_P0P0_DP<14> UPI0_RX_DN<14> @BASEBOARD_FAB2_LIB.BASEBOARD_FAB2(SCH_1):UPI_CPU0_CPU1_P0P0_DP(14)
 BA8 UPI_CPU0_CPU1_P0P0_DN<13> UPI0_RX_DN<13> @BASEBOARD_FAB2_LIB.BASEBOARD_FAB2(SCH_1):UPI_CPU0_CPU1_P0P0_DN(13)
AU10 UPI_CPU0_CPU1_P0P0_DN<12> UPI0_RX_DN<12> @BASEBOARD_FAB2_LIB.BASEBOARD_FAB2(SCH_1):UPI_CPU0_CPU1_P0P0_DN(12)
 AR8 UPI_CPU0_CPU1_P0P0_DP<11> UPI0_RX_DN<11> @BASEBOARD_FAB2_LIB.BASEBOARD_FAB2(SCH_1):UPI_CPU0_CPU1_P0P0_DP(11)
 AP7 UPI_CPU0_CPU1_P0P0_DN<10> UPI0_RX_DN<10> @BASEBOARD_FAB2_LIB.BASEBOARD_FAB2(SCH_1):UPI_CPU0_CPU1_P0P0_DN(10)
 AM9 UPI_CPU0_CPU1_P0P0_DP<9> UPI0_RX_DN<9> @BASEBOARD_FAB2_LIB.BASEBOARD_FAB2(SCH_1):UPI_CPU0_CPU1_P0P0_DP(9)
 AK7 UPI_CPU0_CPU1_P0P0_DP<8> UPI0_RX_DN<8> @BASEBOARD_FAB2_LIB.BASEBOARD_FAB2(SCH_1):UPI_CPU0_CPU1_P0P0_DP(8)
 AL6 UPI_CPU0_CPU1_P0P0_DP<7> UPI0_RX_DN<7> @BASEBOARD_FAB2_LIB.BASEBOARD_FAB2(SCH_1):UPI_CPU0_CPU1_P0P0_DP(7)
 AJ6 UPI_CPU0_CPU1_P0P0_DP<6> UPI0_RX_DN<6> @BASEBOARD_FAB2_LIB.BASEBOARD_FAB2(SCH_1):UPI_CPU0_CPU1_P0P0_DP(6)
 AG8 UPI_CPU0_CPU1_P0P0_DP<5> UPI0_RX_DN<5> @BASEBOARD_FAB2_LIB.BASEBOARD_FAB2(SCH_1):UPI_CPU0_CPU1_P0P0_DP(5)
 AE6 UPI_CPU0_CPU1_P0P0_DP<4> UPI0_RX_DN<4> @BASEBOARD_FAB2_LIB.BASEBOARD_FAB2(SCH_1):UPI_CPU0_CPU1_P0P0_DP(4)
 AD5 UPI_CPU0_CPU1_P0P0_DP<3> UPI0_RX_DN<3> @BASEBOARD_FAB2_LIB.BASEBOARD_FAB2(SCH_1):UPI_CPU0_CPU1_P0P0_DP(3)
 AB7 UPI_CPU0_CPU1_P0P0_DN<2> UPI0_RX_DN<2> @BASEBOARD_FAB2_LIB.BASEBOARD_FAB2(SCH_1):UPI_CPU0_CPU1_P0P0_DN(2)
 AA8 UPI_CPU0_CPU1_P0P0_DN<1> UPI0_RX_DN<1> @BASEBOARD_FAB2_LIB.BASEBOARD_FAB2(SCH_1):UPI_CPU0_CPU1_P0P0_DN(1)
AC10 UPI_CPU0_CPU1_P0P0_DP<0> UPI0_RX_DN<0> @BASEBOARD_FAB2_LIB.BASEBOARD_FAB2(SCH_1):UPI_CPU0_CPU1_P0P0_DP(0)
BA10 UPI_CPU0_CPU1_P0P0_DN<19> UPI0_RX_DP<19> @BASEBOARD_FAB2_LIB.BASEBOARD_FAB2(SCH_1):UPI_CPU0_CPU1_P0P0_DN(19)
BC10 UPI_CPU0_CPU1_P0P0_DN<18> UPI0_RX_DP<18> @BASEBOARD_FAB2_LIB.BASEBOARD_FAB2(SCH_1):UPI_CPU0_CPU1_P0P0_DN(18)
 BB9 UPI_CPU0_CPU1_P0P0_DP<17> UPI0_RX_DP<17> @BASEBOARD_FAB2_LIB.BASEBOARD_FAB2(SCH_1):UPI_CPU0_CPU1_P0P0_DP(17)
 AV9 UPI_CPU0_CPU1_P0P0_DP<16> UPI0_RX_DP<16> @BASEBOARD_FAB2_LIB.BASEBOARD_FAB2(SCH_1):UPI_CPU0_CPU1_P0P0_DP(16)
 BF7 UPI_CPU0_CPU1_P0P0_DP<15> UPI0_RX_DP<15> @BASEBOARD_FAB2_LIB.BASEBOARD_FAB2(SCH_1):UPI_CPU0_CPU1_P0P0_DP(15)
 BB7 UPI_CPU0_CPU1_P0P0_DN<14> UPI0_RX_DP<14> @BASEBOARD_FAB2_LIB.BASEBOARD_FAB2(SCH_1):UPI_CPU0_CPU1_P0P0_DN(14)
 AY7 UPI_CPU0_CPU1_P0P0_DP<13> UPI0_RX_DP<13> @BASEBOARD_FAB2_LIB.BASEBOARD_FAB2(SCH_1):UPI_CPU0_CPU1_P0P0_DP(13)
 AT9 UPI_CPU0_CPU1_P0P0_DP<12> UPI0_RX_DP<12> @BASEBOARD_FAB2_LIB.BASEBOARD_FAB2(SCH_1):UPI_CPU0_CPU1_P0P0_DP(12)
 AU8 UPI_CPU0_CPU1_P0P0_DN<11> UPI0_RX_DP<11> @BASEBOARD_FAB2_LIB.BASEBOARD_FAB2(SCH_1):UPI_CPU0_CPU1_P0P0_DN(11)
 AN8 UPI_CPU0_CPU1_P0P0_DP<10> UPI0_RX_DP<10> @BASEBOARD_FAB2_LIB.BASEBOARD_FAB2(SCH_1):UPI_CPU0_CPU1_P0P0_DP(10)
 AL8 UPI_CPU0_CPU1_P0P0_DN<9> UPI0_RX_DP<9> @BASEBOARD_FAB2_LIB.BASEBOARD_FAB2(SCH_1):UPI_CPU0_CPU1_P0P0_DN(9)
 AM7 UPI_CPU0_CPU1_P0P0_DN<8> UPI0_RX_DP<8> @BASEBOARD_FAB2_LIB.BASEBOARD_FAB2(SCH_1):UPI_CPU0_CPU1_P0P0_DN(8)
 AK5 UPI_CPU0_CPU1_P0P0_DN<7> UPI0_RX_DP<7> @BASEBOARD_FAB2_LIB.BASEBOARD_FAB2(SCH_1):UPI_CPU0_CPU1_P0P0_DN(7)
 AH7 UPI_CPU0_CPU1_P0P0_DN<6> UPI0_RX_DP<6> @BASEBOARD_FAB2_LIB.BASEBOARD_FAB2(SCH_1):UPI_CPU0_CPU1_P0P0_DN(6)
 AF7 UPI_CPU0_CPU1_P0P0_DN<5> UPI0_RX_DP<5> @BASEBOARD_FAB2_LIB.BASEBOARD_FAB2(SCH_1):UPI_CPU0_CPU1_P0P0_DN(5)
 AG6 UPI_CPU0_CPU1_P0P0_DN<4> UPI0_RX_DP<4> @BASEBOARD_FAB2_LIB.BASEBOARD_FAB2(SCH_1):UPI_CPU0_CPU1_P0P0_DN(4)
 AC6 UPI_CPU0_CPU1_P0P0_DN<3> UPI0_RX_DP<3> @BASEBOARD_FAB2_LIB.BASEBOARD_FAB2(SCH_1):UPI_CPU0_CPU1_P0P0_DN(3)
 AA6 UPI_CPU0_CPU1_P0P0_DP<2> UPI0_RX_DP<2> @BASEBOARD_FAB2_LIB.BASEBOARD_FAB2(SCH_1):UPI_CPU0_CPU1_P0P0_DP(2)
 AC8 UPI_CPU0_CPU1_P0P0_DP<1> UPI0_RX_DP<1> @BASEBOARD_FAB2_LIB.BASEBOARD_FAB2(SCH_1):UPI_CPU0_CPU1_P0P0_DP(1)
 AB9 UPI_CPU0_CPU1_P0P0_DN<0> UPI0_RX_DP<0> @BASEBOARD_FAB2_LIB.BASEBOARD_FAB2(SCH_1):UPI_CPU0_CPU1_P0P0_DN(0)
 BG4 UPI_CPU1_CPU0_P0P0_DP<19> UPI0_TX_DN<19> @BASEBOARD_FAB2_LIB.BASEBOARD_FAB2(SCH_1):UPI_CPU1_CPU0_P0P0_DP(19)
 BF3 UPI_CPU1_CPU0_P0P0_DN<18> UPI0_TX_DN<18> @BASEBOARD_FAB2_LIB.BASEBOARD_FAB2(SCH_1):UPI_CPU1_CPU0_P0P0_DN(18)
 BB3 UPI_CPU1_CPU0_P0P0_DN<17> UPI0_TX_DN<17> @BASEBOARD_FAB2_LIB.BASEBOARD_FAB2(SCH_1):UPI_CPU1_CPU0_P0P0_DN(17)
 BA4 UPI_CPU1_CPU0_P0P0_DP<16> UPI0_TX_DN<16> @BASEBOARD_FAB2_LIB.BASEBOARD_FAB2(SCH_1):UPI_CPU1_CPU0_P0P0_DP(16)
 AV5 UPI_CPU1_CPU0_P0P0_DP<15> UPI0_TX_DN<15> @BASEBOARD_FAB2_LIB.BASEBOARD_FAB2(SCH_1):UPI_CPU1_CPU0_P0P0_DP(15)
 AU4 UPI_CPU1_CPU0_P0P0_DP<14> UPI0_TX_DN<14> @BASEBOARD_FAB2_LIB.BASEBOARD_FAB2(SCH_1):UPI_CPU1_CPU0_P0P0_DP(14)
 AT3 UPI_CPU1_CPU0_P0P0_DP<13> UPI0_TX_DN<13> @BASEBOARD_FAB2_LIB.BASEBOARD_FAB2(SCH_1):UPI_CPU1_CPU0_P0P0_DP(13)
 AT1 UPI_CPU1_CPU0_P0P0_DP<12> UPI0_TX_DN<12> @BASEBOARD_FAB2_LIB.BASEBOARD_FAB2(SCH_1):UPI_CPU1_CPU0_P0P0_DP(12)
 AN4 UPI_CPU1_CPU0_P0P0_DP<11> UPI0_TX_DN<11> @BASEBOARD_FAB2_LIB.BASEBOARD_FAB2(SCH_1):UPI_CPU1_CPU0_P0P0_DP(11)
 AM3 UPI_CPU1_CPU0_P0P0_DP<10> UPI0_TX_DN<10> @BASEBOARD_FAB2_LIB.BASEBOARD_FAB2(SCH_1):UPI_CPU1_CPU0_P0P0_DP(10)
 AL2 UPI_CPU1_CPU0_P0P0_DN<9> UPI0_TX_DN<9> @BASEBOARD_FAB2_LIB.BASEBOARD_FAB2(SCH_1):UPI_CPU1_CPU0_P0P0_DN(9)
 AH3 UPI_CPU1_CPU0_P0P0_DP<8> UPI0_TX_DN<8> @BASEBOARD_FAB2_LIB.BASEBOARD_FAB2(SCH_1):UPI_CPU1_CPU0_P0P0_DP(8)
 AE2 UPI_CPU1_CPU0_P0P0_DN<7> UPI0_TX_DN<7> @BASEBOARD_FAB2_LIB.BASEBOARD_FAB2(SCH_1):UPI_CPU1_CPU0_P0P0_DN(7)
 AG4 UPI_CPU1_CPU0_P0P0_DN<6> UPI0_TX_DN<6> @BASEBOARD_FAB2_LIB.BASEBOARD_FAB2(SCH_1):UPI_CPU1_CPU0_P0P0_DN(6)
 AC2 UPI_CPU1_CPU0_P0P0_DP<5> UPI0_TX_DN<5> @BASEBOARD_FAB2_LIB.BASEBOARD_FAB2(SCH_1):UPI_CPU1_CPU0_P0P0_DP(5)
 AB3 UPI_CPU1_CPU0_P0P0_DN<4> UPI0_TX_DN<4> @BASEBOARD_FAB2_LIB.BASEBOARD_FAB2(SCH_1):UPI_CPU1_CPU0_P0P0_DN(4)
  Y1 UPI_CPU1_CPU0_P0P0_DN<3> UPI0_TX_DN<3> @BASEBOARD_FAB2_LIB.BASEBOARD_FAB2(SCH_1):UPI_CPU1_CPU0_P0P0_DN(3)
  V3 UPI_CPU1_CPU0_P0P0_DN<2> UPI0_TX_DN<2> @BASEBOARD_FAB2_LIB.BASEBOARD_FAB2(SCH_1):UPI_CPU1_CPU0_P0P0_DN(2)
  P1 UPI_CPU1_CPU0_P0P0_DP<1> UPI0_TX_DN<1> @BASEBOARD_FAB2_LIB.BASEBOARD_FAB2(SCH_1):UPI_CPU1_CPU0_P0P0_DP(1)
  N2 UPI_CPU1_CPU0_P0P0_DP<0> UPI0_TX_DN<0> @BASEBOARD_FAB2_LIB.BASEBOARD_FAB2(SCH_1):UPI_CPU1_CPU0_P0P0_DP(0)
 BH3 UPI_CPU1_CPU0_P0P0_DN<19> UPI0_TX_DP<19> @BASEBOARD_FAB2_LIB.BASEBOARD_FAB2(SCH_1):UPI_CPU1_CPU0_P0P0_DN(19)
 BD3 UPI_CPU1_CPU0_P0P0_DP<18> UPI0_TX_DP<18> @BASEBOARD_FAB2_LIB.BASEBOARD_FAB2(SCH_1):UPI_CPU1_CPU0_P0P0_DP(18)
 BC2 UPI_CPU1_CPU0_P0P0_DP<17> UPI0_TX_DP<17> @BASEBOARD_FAB2_LIB.BASEBOARD_FAB2(SCH_1):UPI_CPU1_CPU0_P0P0_DP(17)
 AY3 UPI_CPU1_CPU0_P0P0_DN<16> UPI0_TX_DP<16> @BASEBOARD_FAB2_LIB.BASEBOARD_FAB2(SCH_1):UPI_CPU1_CPU0_P0P0_DN(16)
 AW4 UPI_CPU1_CPU0_P0P0_DN<15> UPI0_TX_DP<15> @BASEBOARD_FAB2_LIB.BASEBOARD_FAB2(SCH_1):UPI_CPU1_CPU0_P0P0_DN(15)
 AR4 UPI_CPU1_CPU0_P0P0_DN<14> UPI0_TX_DP<14> @BASEBOARD_FAB2_LIB.BASEBOARD_FAB2(SCH_1):UPI_CPU1_CPU0_P0P0_DN(14)
 AR2 UPI_CPU1_CPU0_P0P0_DN<13> UPI0_TX_DP<13> @BASEBOARD_FAB2_LIB.BASEBOARD_FAB2(SCH_1):UPI_CPU1_CPU0_P0P0_DN(13)
 AP1 UPI_CPU1_CPU0_P0P0_DN<12> UPI0_TX_DP<12> @BASEBOARD_FAB2_LIB.BASEBOARD_FAB2(SCH_1):UPI_CPU1_CPU0_P0P0_DN(12)
 AP3 UPI_CPU1_CPU0_P0P0_DN<11> UPI0_TX_DP<11> @BASEBOARD_FAB2_LIB.BASEBOARD_FAB2(SCH_1):UPI_CPU1_CPU0_P0P0_DN(11)
 AK3 UPI_CPU1_CPU0_P0P0_DN<10> UPI0_TX_DP<10> @BASEBOARD_FAB2_LIB.BASEBOARD_FAB2(SCH_1):UPI_CPU1_CPU0_P0P0_DN(10)
 AK1 UPI_CPU1_CPU0_P0P0_DP<9> UPI0_TX_DP<9> @BASEBOARD_FAB2_LIB.BASEBOARD_FAB2(SCH_1):UPI_CPU1_CPU0_P0P0_DP(9)
 AJ2 UPI_CPU1_CPU0_P0P0_DN<8> UPI0_TX_DP<8> @BASEBOARD_FAB2_LIB.BASEBOARD_FAB2(SCH_1):UPI_CPU1_CPU0_P0P0_DN(8)
 AG2 UPI_CPU1_CPU0_P0P0_DP<7> UPI0_TX_DP<7> @BASEBOARD_FAB2_LIB.BASEBOARD_FAB2(SCH_1):UPI_CPU1_CPU0_P0P0_DP(7)
 AF3 UPI_CPU1_CPU0_P0P0_DP<6> UPI0_TX_DP<6> @BASEBOARD_FAB2_LIB.BASEBOARD_FAB2(SCH_1):UPI_CPU1_CPU0_P0P0_DP(6)
 AD1 UPI_CPU1_CPU0_P0P0_DN<5> UPI0_TX_DP<5> @BASEBOARD_FAB2_LIB.BASEBOARD_FAB2(SCH_1):UPI_CPU1_CPU0_P0P0_DN(5)
 AA2 UPI_CPU1_CPU0_P0P0_DP<4> UPI0_TX_DP<4> @BASEBOARD_FAB2_LIB.BASEBOARD_FAB2(SCH_1):UPI_CPU1_CPU0_P0P0_DP(4)
  W2 UPI_CPU1_CPU0_P0P0_DP<3> UPI0_TX_DP<3> @BASEBOARD_FAB2_LIB.BASEBOARD_FAB2(SCH_1):UPI_CPU1_CPU0_P0P0_DP(3)
  Y3 UPI_CPU1_CPU0_P0P0_DP<2> UPI0_TX_DP<2> @BASEBOARD_FAB2_LIB.BASEBOARD_FAB2(SCH_1):UPI_CPU1_CPU0_P0P0_DP(2)
  T1 UPI_CPU1_CPU0_P0P0_DN<1> UPI0_TX_DP<1> @BASEBOARD_FAB2_LIB.BASEBOARD_FAB2(SCH_1):UPI_CPU1_CPU0_P0P0_DN(1)
  M1 UPI_CPU1_CPU0_P0P0_DN<0> UPI0_TX_DP<0> @BASEBOARD_FAB2_LIB.BASEBOARD_FAB2(SCH_1):UPI_CPU1_CPU0_P0P0_DN(0)


DRAWING: @BASEBOARD_FAB2_LIB.BASEBOARD_FAB2(SCH_1):PAGE68 

SKX_EXT_B_BGA1-IC,TBD  I125  U2D1
AB19 UPI_CPU0_CPU1_P1P1_DP<19> UPI1_RX_DN<19> @BASEBOARD_FAB2_LIB.BASEBOARD_FAB2(SCH_1):UPI_CPU0_CPU1_P1P1_DP(19)
 Y21 UPI_CPU0_CPU1_P1P1_DP<18> UPI1_RX_DN<18> @BASEBOARD_FAB2_LIB.BASEBOARD_FAB2(SCH_1):UPI_CPU0_CPU1_P1P1_DP(18)
 V19 UPI_CPU0_CPU1_P1P1_DN<17> UPI1_RX_DN<17> @BASEBOARD_FAB2_LIB.BASEBOARD_FAB2(SCH_1):UPI_CPU0_CPU1_P1P1_DN(17)
 P21 UPI_CPU0_CPU1_P1P1_DN<16> UPI1_RX_DN<16> @BASEBOARD_FAB2_LIB.BASEBOARD_FAB2(SCH_1):UPI_CPU0_CPU1_P1P1_DN(16)
 U18 UPI_CPU0_CPU1_P1P1_DN<15> UPI1_RX_DN<15> @BASEBOARD_FAB2_LIB.BASEBOARD_FAB2(SCH_1):UPI_CPU0_CPU1_P1P1_DN(15)
 R20 UPI_CPU0_CPU1_P1P1_DN<14> UPI1_RX_DN<14> @BASEBOARD_FAB2_LIB.BASEBOARD_FAB2(SCH_1):UPI_CPU0_CPU1_P1P1_DN(14)
 W18 UPI_CPU0_CPU1_P1P1_DP<13> UPI1_RX_DN<13> @BASEBOARD_FAB2_LIB.BASEBOARD_FAB2(SCH_1):UPI_CPU0_CPU1_P1P1_DP(13)
 U16 UPI_CPU0_CPU1_P1P1_DP<12> UPI1_RX_DN<12> @BASEBOARD_FAB2_LIB.BASEBOARD_FAB2(SCH_1):UPI_CPU0_CPU1_P1P1_DP(12)
 P17 UPI_CPU0_CPU1_P1P1_DP<11> UPI1_RX_DN<11> @BASEBOARD_FAB2_LIB.BASEBOARD_FAB2(SCH_1):UPI_CPU0_CPU1_P1P1_DP(11)
 R16 UPI_CPU0_CPU1_P1P1_DN<10> UPI1_RX_DN<10> @BASEBOARD_FAB2_LIB.BASEBOARD_FAB2(SCH_1):UPI_CPU0_CPU1_P1P1_DN(10)
 R12 UPI_CPU0_CPU1_P1P1_DN<9> UPI1_RX_DN<9> @BASEBOARD_FAB2_LIB.BASEBOARD_FAB2(SCH_1):UPI_CPU0_CPU1_P1P1_DN(9)
 N14 UPI_CPU0_CPU1_P1P1_DP<8> UPI1_RX_DN<8> @BASEBOARD_FAB2_LIB.BASEBOARD_FAB2(SCH_1):UPI_CPU0_CPU1_P1P1_DP(8)
 L12 UPI_CPU0_CPU1_P1P1_DN<7> UPI1_RX_DN<7> @BASEBOARD_FAB2_LIB.BASEBOARD_FAB2(SCH_1):UPI_CPU0_CPU1_P1P1_DN(7)
 U12 UPI_CPU0_CPU1_P1P1_DN<6> UPI1_RX_DN<6> @BASEBOARD_FAB2_LIB.BASEBOARD_FAB2(SCH_1):UPI_CPU0_CPU1_P1P1_DN(6)
 R10 UPI_CPU0_CPU1_P1P1_DN<5> UPI1_RX_DN<5> @BASEBOARD_FAB2_LIB.BASEBOARD_FAB2(SCH_1):UPI_CPU0_CPU1_P1P1_DN(5)
  P9 UPI_CPU0_CPU1_P1P1_DN<4> UPI1_RX_DN<4> @BASEBOARD_FAB2_LIB.BASEBOARD_FAB2(SCH_1):UPI_CPU0_CPU1_P1P1_DN(4)
  T9 UPI_CPU0_CPU1_P1P1_DN<3> UPI1_RX_DN<3> @BASEBOARD_FAB2_LIB.BASEBOARD_FAB2(SCH_1):UPI_CPU0_CPU1_P1P1_DN(3)
  V7 UPI_CPU0_CPU1_P1P1_DN<2> UPI1_RX_DN<2> @BASEBOARD_FAB2_LIB.BASEBOARD_FAB2(SCH_1):UPI_CPU0_CPU1_P1P1_DN(2)
  P7 UPI_CPU0_CPU1_P1P1_DN<1> UPI1_RX_DN<1> @BASEBOARD_FAB2_LIB.BASEBOARD_FAB2(SCH_1):UPI_CPU0_CPU1_P1P1_DN(1)
  T5 UPI_CPU0_CPU1_P1P1_DP<0> UPI1_RX_DN<0> @BASEBOARD_FAB2_LIB.BASEBOARD_FAB2(SCH_1):UPI_CPU0_CPU1_P1P1_DP(0)
AA20 UPI_CPU0_CPU1_P1P1_DN<19> UPI1_RX_DP<19> @BASEBOARD_FAB2_LIB.BASEBOARD_FAB2(SCH_1):UPI_CPU0_CPU1_P1P1_DN(19)
 W20 UPI_CPU0_CPU1_P1P1_DN<18> UPI1_RX_DP<18> @BASEBOARD_FAB2_LIB.BASEBOARD_FAB2(SCH_1):UPI_CPU0_CPU1_P1P1_DN(18)
 Y19 UPI_CPU0_CPU1_P1P1_DP<17> UPI1_RX_DP<17> @BASEBOARD_FAB2_LIB.BASEBOARD_FAB2(SCH_1):UPI_CPU0_CPU1_P1P1_DP(17)
 T21 UPI_CPU0_CPU1_P1P1_DP<16> UPI1_RX_DP<16> @BASEBOARD_FAB2_LIB.BASEBOARD_FAB2(SCH_1):UPI_CPU0_CPU1_P1P1_DP(16)
 T19 UPI_CPU0_CPU1_P1P1_DP<15> UPI1_RX_DP<15> @BASEBOARD_FAB2_LIB.BASEBOARD_FAB2(SCH_1):UPI_CPU0_CPU1_P1P1_DP(15)
 P19 UPI_CPU0_CPU1_P1P1_DP<14> UPI1_RX_DP<14> @BASEBOARD_FAB2_LIB.BASEBOARD_FAB2(SCH_1):UPI_CPU0_CPU1_P1P1_DP(14)
 V17 UPI_CPU0_CPU1_P1P1_DN<13> UPI1_RX_DP<13> @BASEBOARD_FAB2_LIB.BASEBOARD_FAB2(SCH_1):UPI_CPU0_CPU1_P1P1_DN(13)
 W16 UPI_CPU0_CPU1_P1P1_DN<12> UPI1_RX_DP<12> @BASEBOARD_FAB2_LIB.BASEBOARD_FAB2(SCH_1):UPI_CPU0_CPU1_P1P1_DN(12)
 N16 UPI_CPU0_CPU1_P1P1_DN<11> UPI1_RX_DP<11> @BASEBOARD_FAB2_LIB.BASEBOARD_FAB2(SCH_1):UPI_CPU0_CPU1_P1P1_DN(11)
 T15 UPI_CPU0_CPU1_P1P1_DP<10> UPI1_RX_DP<10> @BASEBOARD_FAB2_LIB.BASEBOARD_FAB2(SCH_1):UPI_CPU0_CPU1_P1P1_DP(10)
 P13 UPI_CPU0_CPU1_P1P1_DP<9> UPI1_RX_DP<9> @BASEBOARD_FAB2_LIB.BASEBOARD_FAB2(SCH_1):UPI_CPU0_CPU1_P1P1_DP(9)
 M13 UPI_CPU0_CPU1_P1P1_DN<8> UPI1_RX_DP<8> @BASEBOARD_FAB2_LIB.BASEBOARD_FAB2(SCH_1):UPI_CPU0_CPU1_P1P1_DN(8)
 N12 UPI_CPU0_CPU1_P1P1_DP<7> UPI1_RX_DP<7> @BASEBOARD_FAB2_LIB.BASEBOARD_FAB2(SCH_1):UPI_CPU0_CPU1_P1P1_DP(7)
 T11 UPI_CPU0_CPU1_P1P1_DP<6> UPI1_RX_DP<6> @BASEBOARD_FAB2_LIB.BASEBOARD_FAB2(SCH_1):UPI_CPU0_CPU1_P1P1_DP(6)
 U10 UPI_CPU0_CPU1_P1P1_DP<5> UPI1_RX_DP<5> @BASEBOARD_FAB2_LIB.BASEBOARD_FAB2(SCH_1):UPI_CPU0_CPU1_P1P1_DP(5)
 N10 UPI_CPU0_CPU1_P1P1_DP<4> UPI1_RX_DP<4> @BASEBOARD_FAB2_LIB.BASEBOARD_FAB2(SCH_1):UPI_CPU0_CPU1_P1P1_DP(4)
  R8 UPI_CPU0_CPU1_P1P1_DP<3> UPI1_RX_DP<3> @BASEBOARD_FAB2_LIB.BASEBOARD_FAB2(SCH_1):UPI_CPU0_CPU1_P1P1_DP(3)
  U8 UPI_CPU0_CPU1_P1P1_DP<2> UPI1_RX_DP<2> @BASEBOARD_FAB2_LIB.BASEBOARD_FAB2(SCH_1):UPI_CPU0_CPU1_P1P1_DP(2)
  T7 UPI_CPU0_CPU1_P1P1_DP<1> UPI1_RX_DP<1> @BASEBOARD_FAB2_LIB.BASEBOARD_FAB2(SCH_1):UPI_CPU0_CPU1_P1P1_DP(1)
  R6 UPI_CPU0_CPU1_P1P1_DN<0> UPI1_RX_DP<0> @BASEBOARD_FAB2_LIB.BASEBOARD_FAB2(SCH_1):UPI_CPU0_CPU1_P1P1_DN(0)
 H21 UPI_CPU1_CPU0_P1P1_DP<19> UPI1_TX_DN<19> @BASEBOARD_FAB2_LIB.BASEBOARD_FAB2(SCH_1):UPI_CPU1_CPU0_P1P1_DP(19)
 F21 UPI_CPU1_CPU0_P1P1_DP<18> UPI1_TX_DN<18> @BASEBOARD_FAB2_LIB.BASEBOARD_FAB2(SCH_1):UPI_CPU1_CPU0_P1P1_DP(18)
 J20 UPI_CPU1_CPU0_P1P1_DN<17> UPI1_TX_DN<17> @BASEBOARD_FAB2_LIB.BASEBOARD_FAB2(SCH_1):UPI_CPU1_CPU0_P1P1_DN(17)
 G18 UPI_CPU1_CPU0_P1P1_DN<16> UPI1_TX_DN<16> @BASEBOARD_FAB2_LIB.BASEBOARD_FAB2(SCH_1):UPI_CPU1_CPU0_P1P1_DN(16)
 K19 UPI_CPU1_CPU0_P1P1_DN<15> UPI1_TX_DN<15> @BASEBOARD_FAB2_LIB.BASEBOARD_FAB2(SCH_1):UPI_CPU1_CPU0_P1P1_DN(15)
 H17 UPI_CPU1_CPU0_P1P1_DN<14> UPI1_TX_DN<14> @BASEBOARD_FAB2_LIB.BASEBOARD_FAB2(SCH_1):UPI_CPU1_CPU0_P1P1_DN(14)
 F15 UPI_CPU1_CPU0_P1P1_DN<13> UPI1_TX_DN<13> @BASEBOARD_FAB2_LIB.BASEBOARD_FAB2(SCH_1):UPI_CPU1_CPU0_P1P1_DN(13)
 D15 UPI_CPU1_CPU0_P1P1_DN<12> UPI1_TX_DN<12> @BASEBOARD_FAB2_LIB.BASEBOARD_FAB2(SCH_1):UPI_CPU1_CPU0_P1P1_DN(12)
 G14 UPI_CPU1_CPU0_P1P1_DP<11> UPI1_TX_DN<11> @BASEBOARD_FAB2_LIB.BASEBOARD_FAB2(SCH_1):UPI_CPU1_CPU0_P1P1_DP(11)
 E12 UPI_CPU1_CPU0_P1P1_DN<10> UPI1_TX_DN<10> @BASEBOARD_FAB2_LIB.BASEBOARD_FAB2(SCH_1):UPI_CPU1_CPU0_P1P1_DN(10)
 G10 UPI_CPU1_CPU0_P1P1_DN<9> UPI1_TX_DN<9> @BASEBOARD_FAB2_LIB.BASEBOARD_FAB2(SCH_1):UPI_CPU1_CPU0_P1P1_DN(9)
 F11 UPI_CPU1_CPU0_P1P1_DP<8> UPI1_TX_DN<8> @BASEBOARD_FAB2_LIB.BASEBOARD_FAB2(SCH_1):UPI_CPU1_CPU0_P1P1_DP(8)
  D9 UPI_CPU1_CPU0_P1P1_DP<7> UPI1_TX_DN<7> @BASEBOARD_FAB2_LIB.BASEBOARD_FAB2(SCH_1):UPI_CPU1_CPU0_P1P1_DP(7)
  K9 UPI_CPU1_CPU0_P1P1_DP<6> UPI1_TX_DN<6> @BASEBOARD_FAB2_LIB.BASEBOARD_FAB2(SCH_1):UPI_CPU1_CPU0_P1P1_DP(6)
  H7 UPI_CPU1_CPU0_P1P1_DN<5> UPI1_TX_DN<5> @BASEBOARD_FAB2_LIB.BASEBOARD_FAB2(SCH_1):UPI_CPU1_CPU0_P1P1_DN(5)
  G6 UPI_CPU1_CPU0_P1P1_DN<4> UPI1_TX_DN<4> @BASEBOARD_FAB2_LIB.BASEBOARD_FAB2(SCH_1):UPI_CPU1_CPU0_P1P1_DN(4)
  J6 UPI_CPU1_CPU0_P1P1_DN<3> UPI1_TX_DN<3> @BASEBOARD_FAB2_LIB.BASEBOARD_FAB2(SCH_1):UPI_CPU1_CPU0_P1P1_DN(3)
  K5 UPI_CPU1_CPU0_P1P1_DN<2> UPI1_TX_DN<2> @BASEBOARD_FAB2_LIB.BASEBOARD_FAB2(SCH_1):UPI_CPU1_CPU0_P1P1_DN(2)
  L4 UPI_CPU1_CPU0_P1P1_DP<1> UPI1_TX_DN<1> @BASEBOARD_FAB2_LIB.BASEBOARD_FAB2(SCH_1):UPI_CPU1_CPU0_P1P1_DP(1)
  M3 UPI_CPU1_CPU0_P1P1_DP<0> UPI1_TX_DN<0> @BASEBOARD_FAB2_LIB.BASEBOARD_FAB2(SCH_1):UPI_CPU1_CPU0_P1P1_DP(0)
 K21 UPI_CPU1_CPU0_P1P1_DN<19> UPI1_TX_DP<19> @BASEBOARD_FAB2_LIB.BASEBOARD_FAB2(SCH_1):UPI_CPU1_CPU0_P1P1_DN(19)
 G20 UPI_CPU1_CPU0_P1P1_DN<18> UPI1_TX_DP<18> @BASEBOARD_FAB2_LIB.BASEBOARD_FAB2(SCH_1):UPI_CPU1_CPU0_P1P1_DN(18)
 H19 UPI_CPU1_CPU0_P1P1_DP<17> UPI1_TX_DP<17> @BASEBOARD_FAB2_LIB.BASEBOARD_FAB2(SCH_1):UPI_CPU1_CPU0_P1P1_DP(17)
 J18 UPI_CPU1_CPU0_P1P1_DP<16> UPI1_TX_DP<16> @BASEBOARD_FAB2_LIB.BASEBOARD_FAB2(SCH_1):UPI_CPU1_CPU0_P1P1_DP(16)
 L18 UPI_CPU1_CPU0_P1P1_DP<15> UPI1_TX_DP<15> @BASEBOARD_FAB2_LIB.BASEBOARD_FAB2(SCH_1):UPI_CPU1_CPU0_P1P1_DP(15)
 G16 UPI_CPU1_CPU0_P1P1_DP<14> UPI1_TX_DP<14> @BASEBOARD_FAB2_LIB.BASEBOARD_FAB2(SCH_1):UPI_CPU1_CPU0_P1P1_DP(14)
 H15 UPI_CPU1_CPU0_P1P1_DP<13> UPI1_TX_DP<13> @BASEBOARD_FAB2_LIB.BASEBOARD_FAB2(SCH_1):UPI_CPU1_CPU0_P1P1_DP(13)
 E14 UPI_CPU1_CPU0_P1P1_DP<12> UPI1_TX_DP<12> @BASEBOARD_FAB2_LIB.BASEBOARD_FAB2(SCH_1):UPI_CPU1_CPU0_P1P1_DP(12)
 F13 UPI_CPU1_CPU0_P1P1_DN<11> UPI1_TX_DP<11> @BASEBOARD_FAB2_LIB.BASEBOARD_FAB2(SCH_1):UPI_CPU1_CPU0_P1P1_DN(11)
 G12 UPI_CPU1_CPU0_P1P1_DP<10> UPI1_TX_DP<10> @BASEBOARD_FAB2_LIB.BASEBOARD_FAB2(SCH_1):UPI_CPU1_CPU0_P1P1_DP(10)
  H9 UPI_CPU1_CPU0_P1P1_DP<9> UPI1_TX_DP<9> @BASEBOARD_FAB2_LIB.BASEBOARD_FAB2(SCH_1):UPI_CPU1_CPU0_P1P1_DP(9)
 E10 UPI_CPU1_CPU0_P1P1_DN<8> UPI1_TX_DP<8> @BASEBOARD_FAB2_LIB.BASEBOARD_FAB2(SCH_1):UPI_CPU1_CPU0_P1P1_DN(8)
  F9 UPI_CPU1_CPU0_P1P1_DN<7> UPI1_TX_DP<7> @BASEBOARD_FAB2_LIB.BASEBOARD_FAB2(SCH_1):UPI_CPU1_CPU0_P1P1_DN(7)
  J8 UPI_CPU1_CPU0_P1P1_DN<6> UPI1_TX_DP<6> @BASEBOARD_FAB2_LIB.BASEBOARD_FAB2(SCH_1):UPI_CPU1_CPU0_P1P1_DN(6)
  K7 UPI_CPU1_CPU0_P1P1_DP<5> UPI1_TX_DP<5> @BASEBOARD_FAB2_LIB.BASEBOARD_FAB2(SCH_1):UPI_CPU1_CPU0_P1P1_DP(5)
  F7 UPI_CPU1_CPU0_P1P1_DP<4> UPI1_TX_DP<4> @BASEBOARD_FAB2_LIB.BASEBOARD_FAB2(SCH_1):UPI_CPU1_CPU0_P1P1_DP(4)
  H5 UPI_CPU1_CPU0_P1P1_DP<3> UPI1_TX_DP<3> @BASEBOARD_FAB2_LIB.BASEBOARD_FAB2(SCH_1):UPI_CPU1_CPU0_P1P1_DP(3)
  M5 UPI_CPU1_CPU0_P1P1_DP<2> UPI1_TX_DP<2> @BASEBOARD_FAB2_LIB.BASEBOARD_FAB2(SCH_1):UPI_CPU1_CPU0_P1P1_DP(2)
  K3 UPI_CPU1_CPU0_P1P1_DN<1> UPI1_TX_DP<1> @BASEBOARD_FAB2_LIB.BASEBOARD_FAB2(SCH_1):UPI_CPU1_CPU0_P1P1_DN(1)
  P3 UPI_CPU1_CPU0_P1P1_DN<0> UPI1_TX_DP<0> @BASEBOARD_FAB2_LIB.BASEBOARD_FAB2(SCH_1):UPI_CPU1_CPU0_P1P1_DN(0)


DRAWING: @BASEBOARD_FAB2_LIB.BASEBOARD_FAB2(SCH_1):PAGE69 

SKX_EXT_B_BGA1-IC,TBD  I1  U2D1
BY17    GND UPI2_RX_DN<19> @BASEBOARD_FAB2_LIB.BASEBOARD_FAB2(SCH_1):GND
CB15    GND UPI2_RX_DN<18> @BASEBOARD_FAB2_LIB.BASEBOARD_FAB2(SCH_1):GND
CF17    GND UPI2_RX_DN<17> @BASEBOARD_FAB2_LIB.BASEBOARD_FAB2(SCH_1):GND
CD15    GND UPI2_RX_DN<16> @BASEBOARD_FAB2_LIB.BASEBOARD_FAB2(SCH_1):GND
CE16    GND UPI2_RX_DN<15> @BASEBOARD_FAB2_LIB.BASEBOARD_FAB2(SCH_1):GND
CH17    GND UPI2_RX_DN<14> @BASEBOARD_FAB2_LIB.BASEBOARD_FAB2(SCH_1):GND
CJ18    GND UPI2_RX_DN<13> @BASEBOARD_FAB2_LIB.BASEBOARD_FAB2(SCH_1):GND
CL16    GND UPI2_RX_DN<12> @BASEBOARD_FAB2_LIB.BASEBOARD_FAB2(SCH_1):GND
CP21    GND UPI2_RX_DN<11> @BASEBOARD_FAB2_LIB.BASEBOARD_FAB2(SCH_1):GND
CN20    GND UPI2_RX_DN<10> @BASEBOARD_FAB2_LIB.BASEBOARD_FAB2(SCH_1):GND
CR18    GND UPI2_RX_DN<9> @BASEBOARD_FAB2_LIB.BASEBOARD_FAB2(SCH_1):GND
CT21    GND UPI2_RX_DN<8> @BASEBOARD_FAB2_LIB.BASEBOARD_FAB2(SCH_1):GND
CV19    GND UPI2_RX_DN<7> @BASEBOARD_FAB2_LIB.BASEBOARD_FAB2(SCH_1):GND
CW20    GND UPI2_RX_DN<6> @BASEBOARD_FAB2_LIB.BASEBOARD_FAB2(SCH_1):GND
DA20    GND UPI2_RX_DN<5> @BASEBOARD_FAB2_LIB.BASEBOARD_FAB2(SCH_1):GND
DD19    GND UPI2_RX_DN<4> @BASEBOARD_FAB2_LIB.BASEBOARD_FAB2(SCH_1):GND
DB21    GND UPI2_RX_DN<3> @BASEBOARD_FAB2_LIB.BASEBOARD_FAB2(SCH_1):GND
DC22    GND UPI2_RX_DN<2> @BASEBOARD_FAB2_LIB.BASEBOARD_FAB2(SCH_1):GND
DE22    GND UPI2_RX_DN<1> @BASEBOARD_FAB2_LIB.BASEBOARD_FAB2(SCH_1):GND
DF23    GND UPI2_RX_DN<0> @BASEBOARD_FAB2_LIB.BASEBOARD_FAB2(SCH_1):GND
CA16    GND UPI2_RX_DP<19> @BASEBOARD_FAB2_LIB.BASEBOARD_FAB2(SCH_1):GND
BY15    GND UPI2_RX_DP<18> @BASEBOARD_FAB2_LIB.BASEBOARD_FAB2(SCH_1):GND
CD17    GND UPI2_RX_DP<17> @BASEBOARD_FAB2_LIB.BASEBOARD_FAB2(SCH_1):GND
CC14    GND UPI2_RX_DP<16> @BASEBOARD_FAB2_LIB.BASEBOARD_FAB2(SCH_1):GND
CF15    GND UPI2_RX_DP<15> @BASEBOARD_FAB2_LIB.BASEBOARD_FAB2(SCH_1):GND
CG16    GND UPI2_RX_DP<14> @BASEBOARD_FAB2_LIB.BASEBOARD_FAB2(SCH_1):GND
CK17    GND UPI2_RX_DP<13> @BASEBOARD_FAB2_LIB.BASEBOARD_FAB2(SCH_1):GND
CJ16    GND UPI2_RX_DP<12> @BASEBOARD_FAB2_LIB.BASEBOARD_FAB2(SCH_1):GND
CM21    GND UPI2_RX_DP<11> @BASEBOARD_FAB2_LIB.BASEBOARD_FAB2(SCH_1):GND
CP19    GND UPI2_RX_DP<10> @BASEBOARD_FAB2_LIB.BASEBOARD_FAB2(SCH_1):GND
CN18    GND UPI2_RX_DP<9> @BASEBOARD_FAB2_LIB.BASEBOARD_FAB2(SCH_1):GND
CR20    GND UPI2_RX_DP<8> @BASEBOARD_FAB2_LIB.BASEBOARD_FAB2(SCH_1):GND
CW18    GND UPI2_RX_DP<7> @BASEBOARD_FAB2_LIB.BASEBOARD_FAB2(SCH_1):GND
CU20    GND UPI2_RX_DP<6> @BASEBOARD_FAB2_LIB.BASEBOARD_FAB2(SCH_1):GND
CY19    GND UPI2_RX_DP<5> @BASEBOARD_FAB2_LIB.BASEBOARD_FAB2(SCH_1):GND
DB19    GND UPI2_RX_DP<4> @BASEBOARD_FAB2_LIB.BASEBOARD_FAB2(SCH_1):GND
DC20    GND UPI2_RX_DP<3> @BASEBOARD_FAB2_LIB.BASEBOARD_FAB2(SCH_1):GND
DA22    GND UPI2_RX_DP<2> @BASEBOARD_FAB2_LIB.BASEBOARD_FAB2(SCH_1):GND
DD21    GND UPI2_RX_DP<1> @BASEBOARD_FAB2_LIB.BASEBOARD_FAB2(SCH_1):GND
DG22    GND UPI2_RX_DP<0> @BASEBOARD_FAB2_LIB.BASEBOARD_FAB2(SCH_1):GND
CC12 TP_CPU1_UPI2_RSVD_DT21 UPI2_TX_DN<19> @BASEBOARD_FAB2_LIB.BASEBOARD_FAB2(SCH_1):TP_CPU1_UPI2_RSVD_DT21
CC10 TP_CPU1_UPI2_RSVD_DM21 UPI2_TX_DN<18> @BASEBOARD_FAB2_LIB.BASEBOARD_FAB2(SCH_1):TP_CPU1_UPI2_RSVD_DM21
CE12 TP_CPU1_UPI2_RSVD_DL20 UPI2_TX_DN<17> @BASEBOARD_FAB2_LIB.BASEBOARD_FAB2(SCH_1):TP_CPU1_UPI2_RSVD_DL20
CH11 TP_CPU1_UPI2_RSVD_DG20 UPI2_TX_DN<16> @BASEBOARD_FAB2_LIB.BASEBOARD_FAB2(SCH_1):TP_CPU1_UPI2_RSVD_DG20
CF13 TP_CPU1_UPI2_RSVD_DH19 UPI2_TX_DN<15> @BASEBOARD_FAB2_LIB.BASEBOARD_FAB2(SCH_1):TP_CPU1_UPI2_RSVD_DH19
CJ14 TP_CPU1_UPI2_RSVD_DK17 UPI2_TX_DN<14> @BASEBOARD_FAB2_LIB.BASEBOARD_FAB2(SCH_1):TP_CPU1_UPI2_RSVD_DK17
CM13 TP_CPU1_UPI2_RSVD_DG18 UPI2_TX_DN<13> @BASEBOARD_FAB2_LIB.BASEBOARD_FAB2(SCH_1):TP_CPU1_UPI2_RSVD_DG18
CU14 TP_CPU1_UPI2_RSVD_DD17 UPI2_TX_DN<12> @BASEBOARD_FAB2_LIB.BASEBOARD_FAB2(SCH_1):TP_CPU1_UPI2_RSVD_DD17
CW14 TP_CPU1_UPI2_RSVD_DF15 UPI2_TX_DN<11> @BASEBOARD_FAB2_LIB.BASEBOARD_FAB2(SCH_1):TP_CPU1_UPI2_RSVD_DF15
DA16 TP_CPU1_UPI2_RSVD_DC16 UPI2_TX_DN<10> @BASEBOARD_FAB2_LIB.BASEBOARD_FAB2(SCH_1):TP_CPU1_UPI2_RSVD_DC16
DC16 TP_CPU1_UPI2_RSVD_DA16 UPI2_TX_DN<9> @BASEBOARD_FAB2_LIB.BASEBOARD_FAB2(SCH_1):TP_CPU1_UPI2_RSVD_DA16
DF15 TP_CPU1_UPI2_RSVD_CW14 UPI2_TX_DN<8> @BASEBOARD_FAB2_LIB.BASEBOARD_FAB2(SCH_1):TP_CPU1_UPI2_RSVD_CW14
DD17 TP_CPU1_UPI2_RSVD_CU14 UPI2_TX_DN<7> @BASEBOARD_FAB2_LIB.BASEBOARD_FAB2(SCH_1):TP_CPU1_UPI2_RSVD_CU14
DG18 TP_CPU1_UPI2_RSVD_CM13 UPI2_TX_DN<6> @BASEBOARD_FAB2_LIB.BASEBOARD_FAB2(SCH_1):TP_CPU1_UPI2_RSVD_CM13
DK17 TP_CPU1_UPI2_RSVD_CJ14 UPI2_TX_DN<5> @BASEBOARD_FAB2_LIB.BASEBOARD_FAB2(SCH_1):TP_CPU1_UPI2_RSVD_CJ14
DH19 TP_CPU1_UPI2_RSVD_CF13 UPI2_TX_DN<4> @BASEBOARD_FAB2_LIB.BASEBOARD_FAB2(SCH_1):TP_CPU1_UPI2_RSVD_CF13
DG20 TP_CPU1_UPI2_RSVD_CH11 UPI2_TX_DN<3> @BASEBOARD_FAB2_LIB.BASEBOARD_FAB2(SCH_1):TP_CPU1_UPI2_RSVD_CH11
DL20 TP_CPU1_UPI2_RSVD_CE12 UPI2_TX_DN<2> @BASEBOARD_FAB2_LIB.BASEBOARD_FAB2(SCH_1):TP_CPU1_UPI2_RSVD_CE12
DM21 TP_CPU1_UPI2_RSVD_CC10 UPI2_TX_DN<1> @BASEBOARD_FAB2_LIB.BASEBOARD_FAB2(SCH_1):TP_CPU1_UPI2_RSVD_CC10
DT21 TP_CPU1_UPI2_RSVD_CC12 UPI2_TX_DN<0> @BASEBOARD_FAB2_LIB.BASEBOARD_FAB2(SCH_1):TP_CPU1_UPI2_RSVD_CC12
CA12 TP_CPU1_UPI2_RSVD_DP21 UPI2_TX_DP<19> @BASEBOARD_FAB2_LIB.BASEBOARD_FAB2(SCH_1):TP_CPU1_UPI2_RSVD_DP21
CB11 TP_CPU1_UPI2_RSVD_DN20 UPI2_TX_DP<18> @BASEBOARD_FAB2_LIB.BASEBOARD_FAB2(SCH_1):TP_CPU1_UPI2_RSVD_DN20
CD11 TP_CPU1_UPI2_RSVD_DK19 UPI2_TX_DP<17> @BASEBOARD_FAB2_LIB.BASEBOARD_FAB2(SCH_1):TP_CPU1_UPI2_RSVD_DK19
CF11 TP_CPU1_UPI2_RSVD_DJ20 UPI2_TX_DP<16> @BASEBOARD_FAB2_LIB.BASEBOARD_FAB2(SCH_1):TP_CPU1_UPI2_RSVD_DJ20
CG12 TP_CPU1_UPI2_RSVD_DJ18 UPI2_TX_DP<15> @BASEBOARD_FAB2_LIB.BASEBOARD_FAB2(SCH_1):TP_CPU1_UPI2_RSVD_DJ18
CH13 TP_CPU1_UPI2_RSVD_DH17 UPI2_TX_DP<14> @BASEBOARD_FAB2_LIB.BASEBOARD_FAB2(SCH_1):TP_CPU1_UPI2_RSVD_DH17
CK13 TP_CPU1_UPI2_RSVD_DF17 UPI2_TX_DP<13> @BASEBOARD_FAB2_LIB.BASEBOARD_FAB2(SCH_1):TP_CPU1_UPI2_RSVD_DF17
CR14 TP_CPU1_UPI2_RSVD_DE16 UPI2_TX_DP<12> @BASEBOARD_FAB2_LIB.BASEBOARD_FAB2(SCH_1):TP_CPU1_UPI2_RSVD_DE16
CV13 TP_CPU1_UPI2_RSVD_DD15 UPI2_TX_DP<11> @BASEBOARD_FAB2_LIB.BASEBOARD_FAB2(SCH_1):TP_CPU1_UPI2_RSVD_DD15
CW16 TP_CPU1_UPI2_RSVD_DB15 UPI2_TX_DP<10> @BASEBOARD_FAB2_LIB.BASEBOARD_FAB2(SCH_1):TP_CPU1_UPI2_RSVD_DB15
DB15 TP_CPU1_UPI2_RSVD_CW16 UPI2_TX_DP<9> @BASEBOARD_FAB2_LIB.BASEBOARD_FAB2(SCH_1):TP_CPU1_UPI2_RSVD_CW16
DD15 TP_CPU1_UPI2_RSVD_CV13 UPI2_TX_DP<8> @BASEBOARD_FAB2_LIB.BASEBOARD_FAB2(SCH_1):TP_CPU1_UPI2_RSVD_CV13
DE16 TP_CPU1_UPI2_RSVD_CR14 UPI2_TX_DP<7> @BASEBOARD_FAB2_LIB.BASEBOARD_FAB2(SCH_1):TP_CPU1_UPI2_RSVD_CR14
DF17 TP_CPU1_UPI2_RSVD_CK13 UPI2_TX_DP<6> @BASEBOARD_FAB2_LIB.BASEBOARD_FAB2(SCH_1):TP_CPU1_UPI2_RSVD_CK13
DH17 TP_CPU1_UPI2_RSVD_CH13 UPI2_TX_DP<5> @BASEBOARD_FAB2_LIB.BASEBOARD_FAB2(SCH_1):TP_CPU1_UPI2_RSVD_CH13
DJ18 TP_CPU1_UPI2_RSVD_CG12 UPI2_TX_DP<4> @BASEBOARD_FAB2_LIB.BASEBOARD_FAB2(SCH_1):TP_CPU1_UPI2_RSVD_CG12
DJ20 TP_CPU1_UPI2_RSVD_CF11 UPI2_TX_DP<3> @BASEBOARD_FAB2_LIB.BASEBOARD_FAB2(SCH_1):TP_CPU1_UPI2_RSVD_CF11
DK19 TP_CPU1_UPI2_RSVD_CD11 UPI2_TX_DP<2> @BASEBOARD_FAB2_LIB.BASEBOARD_FAB2(SCH_1):TP_CPU1_UPI2_RSVD_CD11
DN20 TP_CPU1_UPI2_RSVD_CB11 UPI2_TX_DP<1> @BASEBOARD_FAB2_LIB.BASEBOARD_FAB2(SCH_1):TP_CPU1_UPI2_RSVD_CB11
DP21 TP_CPU1_UPI2_RSVD_CA12 UPI2_TX_DP<0> @BASEBOARD_FAB2_LIB.BASEBOARD_FAB2(SCH_1):TP_CPU1_UPI2_RSVD_CA12


DRAWING: @BASEBOARD_FAB2_LIB.BASEBOARD_FAB2(SCH_1):PAGE70 

SKX_EXT_B_BGA1-IC,TBD  I9  U2D1
AY83 TP_CPU1_RSVD_255 RSVD<255> @BASEBOARD_FAB2_LIB.BASEBOARD_FAB2(SCH_1):TP_CPU1_RSVD_255
BA78 TP_CPU1_RSVD_171 RSVD<171> @BASEBOARD_FAB2_LIB.BASEBOARD_FAB2(SCH_1):TP_CPU1_RSVD_171
BA82 TP_CPU1_RSVD_170 RSVD<170> @BASEBOARD_FAB2_LIB.BASEBOARD_FAB2(SCH_1):TP_CPU1_RSVD_170
BB13 TP_CPU1_RSVD_169 RSVD<169> @BASEBOARD_FAB2_LIB.BASEBOARD_FAB2(SCH_1):TP_CPU1_RSVD_169
BB15 TP_CPU1_RSVD_168 RSVD<168> @BASEBOARD_FAB2_LIB.BASEBOARD_FAB2(SCH_1):TP_CPU1_RSVD_168
BB17 TP_CPU1_RSVD_167 RSVD<167> @BASEBOARD_FAB2_LIB.BASEBOARD_FAB2(SCH_1):TP_CPU1_RSVD_167
BB21 TP_CPU1_RSVD_166 RSVD<166> @BASEBOARD_FAB2_LIB.BASEBOARD_FAB2(SCH_1):TP_CPU1_RSVD_166
BB25 CLK_100M_CPU1_RC_REFCLK1_DN RSVD<165> @BASEBOARD_FAB2_LIB.BASEBOARD_FAB2(SCH_1):CLK_100M_CPU1_RC_REFCLK1_DN
BB65 TP_CPU1_RSVD_164 RSVD<164> @BASEBOARD_FAB2_LIB.BASEBOARD_FAB2(SCH_1):TP_CPU1_RSVD_164
BB67 TP_CPU1_RSVD_163 RSVD<163> @BASEBOARD_FAB2_LIB.BASEBOARD_FAB2(SCH_1):TP_CPU1_RSVD_163
BC14 TP_CPU1_RSVD_162 RSVD<162> @BASEBOARD_FAB2_LIB.BASEBOARD_FAB2(SCH_1):TP_CPU1_RSVD_162
BC18 TP_CPU1_RSVD_161 RSVD<161> @BASEBOARD_FAB2_LIB.BASEBOARD_FAB2(SCH_1):TP_CPU1_RSVD_161
BC20 TP_CPU1_RSVD_160 RSVD<160> @BASEBOARD_FAB2_LIB.BASEBOARD_FAB2(SCH_1):TP_CPU1_RSVD_160
BC22 TP_CPU1_RSVD_159 RSVD<159> @BASEBOARD_FAB2_LIB.BASEBOARD_FAB2(SCH_1):TP_CPU1_RSVD_159
BC64 TP_CPU1_RSVD_158 RSVD<158> @BASEBOARD_FAB2_LIB.BASEBOARD_FAB2(SCH_1):TP_CPU1_RSVD_158
BC66 TP_CPU1_RSVD_157 RSVD<157> @BASEBOARD_FAB2_LIB.BASEBOARD_FAB2(SCH_1):TP_CPU1_RSVD_157
BC68 TP_CPU1_RSVD_156 RSVD<156> @BASEBOARD_FAB2_LIB.BASEBOARD_FAB2(SCH_1):TP_CPU1_RSVD_156
BD17 TP_CPU1_RSVD_155 RSVD<155> @BASEBOARD_FAB2_LIB.BASEBOARD_FAB2(SCH_1):TP_CPU1_RSVD_155
BD19 TP_CPU1_RSVD_154 RSVD<154> @BASEBOARD_FAB2_LIB.BASEBOARD_FAB2(SCH_1):TP_CPU1_RSVD_154
BD25 CLK_100M_CPU1_RC_REFCLK1_DP RSVD<153> @BASEBOARD_FAB2_LIB.BASEBOARD_FAB2(SCH_1):CLK_100M_CPU1_RC_REFCLK1_DP
BD65 TP_CPU1_RSVD_152 RSVD<152> @BASEBOARD_FAB2_LIB.BASEBOARD_FAB2(SCH_1):TP_CPU1_RSVD_152
BD67 TP_CPU1_RSVD_151 RSVD<151> @BASEBOARD_FAB2_LIB.BASEBOARD_FAB2(SCH_1):TP_CPU1_RSVD_151
BD69 TP_CPU1_RSVD_150 RSVD<150> @BASEBOARD_FAB2_LIB.BASEBOARD_FAB2(SCH_1):TP_CPU1_RSVD_150
BE18 TP_CPU1_RSVD_149 RSVD<149> @BASEBOARD_FAB2_LIB.BASEBOARD_FAB2(SCH_1):TP_CPU1_RSVD_149
BE20 TP_CPU1_RSVD_148 RSVD<148> @BASEBOARD_FAB2_LIB.BASEBOARD_FAB2(SCH_1):TP_CPU1_RSVD_148
BE22 TP_CPU1_RSVD_147 RSVD<147> @BASEBOARD_FAB2_LIB.BASEBOARD_FAB2(SCH_1):TP_CPU1_RSVD_147
BF21 TP_CPU1_RSVD_146 RSVD<146> @BASEBOARD_FAB2_LIB.BASEBOARD_FAB2(SCH_1):TP_CPU1_RSVD_146
BG18 TP_CPU1_RSVD_145 RSVD<145> @BASEBOARD_FAB2_LIB.BASEBOARD_FAB2(SCH_1):TP_CPU1_RSVD_145
BG20 TP_CPU1_RSVD_144 RSVD<144> @BASEBOARD_FAB2_LIB.BASEBOARD_FAB2(SCH_1):TP_CPU1_RSVD_144
BH19 PVCCMCP_CPU1 RSVD<143> @BASEBOARD_FAB2_LIB.BASEBOARD_FAB2(SCH_1):PVCCMCP_CPU1
BJ16 PVCCMCP_CPU1 RSVD<142> @BASEBOARD_FAB2_LIB.BASEBOARD_FAB2(SCH_1):PVCCMCP_CPU1
BJ18 PVCCMCP_CPU1 RSVD<141> @BASEBOARD_FAB2_LIB.BASEBOARD_FAB2(SCH_1):PVCCMCP_CPU1
BJ20 PVCCMCP_CPU1 RSVD<140> @BASEBOARD_FAB2_LIB.BASEBOARD_FAB2(SCH_1):PVCCMCP_CPU1
BK17 PVCCMCP_CPU1 RSVD<139> @BASEBOARD_FAB2_LIB.BASEBOARD_FAB2(SCH_1):PVCCMCP_CPU1
BL18 PVCCIOMCP_CPU1 RSVD<138> @BASEBOARD_FAB2_LIB.BASEBOARD_FAB2(SCH_1):PVCCIOMCP_CPU1
BL20 PVCCMCP_CPU1 RSVD<137> @BASEBOARD_FAB2_LIB.BASEBOARD_FAB2(SCH_1):PVCCMCP_CPU1
BM17 PVCCIOMCP_CPU1 RSVD<136> @BASEBOARD_FAB2_LIB.BASEBOARD_FAB2(SCH_1):PVCCIOMCP_CPU1
BM19 PVCCMCP_CPU1 RSVD<135> @BASEBOARD_FAB2_LIB.BASEBOARD_FAB2(SCH_1):PVCCMCP_CPU1
BN18 PVCCIOMCP_CPU1 RSVD<134> @BASEBOARD_FAB2_LIB.BASEBOARD_FAB2(SCH_1):PVCCIOMCP_CPU1
BP17 PVCCIOMCP_CPU1 RSVD<133> @BASEBOARD_FAB2_LIB.BASEBOARD_FAB2(SCH_1):PVCCIOMCP_CPU1
BP21 PVCCMCP_CPU1 RSVD<132> @BASEBOARD_FAB2_LIB.BASEBOARD_FAB2(SCH_1):PVCCMCP_CPU1
BR22 PVCCMCP_CPU1 RSVD<131> @BASEBOARD_FAB2_LIB.BASEBOARD_FAB2(SCH_1):PVCCMCP_CPU1
BR24 PVCCMCP_CPU1 RSVD<130> @BASEBOARD_FAB2_LIB.BASEBOARD_FAB2(SCH_1):PVCCMCP_CPU1
BU18 PVCCIOMCP_CPU1 RSVD<129> @BASEBOARD_FAB2_LIB.BASEBOARD_FAB2(SCH_1):PVCCIOMCP_CPU1
BU20 PVCCMCP_CPU1 RSVD<128> @BASEBOARD_FAB2_LIB.BASEBOARD_FAB2(SCH_1):PVCCMCP_CPU1
BU22 PVCCMCP_CPU1 RSVD<127> @BASEBOARD_FAB2_LIB.BASEBOARD_FAB2(SCH_1):PVCCMCP_CPU1
BV19 PVCCMCP_CPU1 RSVD<126> @BASEBOARD_FAB2_LIB.BASEBOARD_FAB2(SCH_1):PVCCMCP_CPU1
BV21 PVCCMCP_CPU1 RSVD<125> @BASEBOARD_FAB2_LIB.BASEBOARD_FAB2(SCH_1):PVCCMCP_CPU1
BV23 TP_CPU1_RSVD_124 RSVD<124> @BASEBOARD_FAB2_LIB.BASEBOARD_FAB2(SCH_1):TP_CPU1_RSVD_124
BW10 TP_CPU1_RSVD_123 RSVD<123> @BASEBOARD_FAB2_LIB.BASEBOARD_FAB2(SCH_1):TP_CPU1_RSVD_123
BW20 PVCCMCP_CPU1 RSVD<122> @BASEBOARD_FAB2_LIB.BASEBOARD_FAB2(SCH_1):PVCCMCP_CPU1
BW22 TP_CPU1_RSVD_121 RSVD<121> @BASEBOARD_FAB2_LIB.BASEBOARD_FAB2(SCH_1):TP_CPU1_RSVD_121
BY19 PVCCMCP_CPU1 RSVD<120> @BASEBOARD_FAB2_LIB.BASEBOARD_FAB2(SCH_1):PVCCMCP_CPU1
BY25 TP_CPU1_RSVD_119 RSVD<119> @BASEBOARD_FAB2_LIB.BASEBOARD_FAB2(SCH_1):TP_CPU1_RSVD_119
CA22 PVCCMCP_CPU1 RSVD<118> @BASEBOARD_FAB2_LIB.BASEBOARD_FAB2(SCH_1):PVCCMCP_CPU1
CA24 TP_CPU1_RSVD_117 RSVD<117> @BASEBOARD_FAB2_LIB.BASEBOARD_FAB2(SCH_1):TP_CPU1_RSVD_117
CB19 PVCCMCP_CPU1 RSVD<116> @BASEBOARD_FAB2_LIB.BASEBOARD_FAB2(SCH_1):PVCCMCP_CPU1
CB21 PVCCMCP_CPU1 RSVD<115> @BASEBOARD_FAB2_LIB.BASEBOARD_FAB2(SCH_1):PVCCMCP_CPU1
CB25 TP_CPU1_RSVD_114 RSVD<114> @BASEBOARD_FAB2_LIB.BASEBOARD_FAB2(SCH_1):TP_CPU1_RSVD_114
 CB5 TP_CPU1_RSVD_113 RSVD<113> @BASEBOARD_FAB2_LIB.BASEBOARD_FAB2(SCH_1):TP_CPU1_RSVD_113
CC20 PVCCMCP_CPU1 RSVD<112> @BASEBOARD_FAB2_LIB.BASEBOARD_FAB2(SCH_1):PVCCMCP_CPU1
 CC6 TP_CPU1_RSVD_111 RSVD<111> @BASEBOARD_FAB2_LIB.BASEBOARD_FAB2(SCH_1):TP_CPU1_RSVD_111
CD19 PVCCMCP_CPU1 RSVD<110> @BASEBOARD_FAB2_LIB.BASEBOARD_FAB2(SCH_1):PVCCMCP_CPU1
CD21 PVCCMCP_CPU1 RSVD<109> @BASEBOARD_FAB2_LIB.BASEBOARD_FAB2(SCH_1):PVCCMCP_CPU1
CD25 TP_CPU1_RSVD_108 RSVD<108> @BASEBOARD_FAB2_LIB.BASEBOARD_FAB2(SCH_1):TP_CPU1_RSVD_108
CE22 PVCCMCP_CPU1 RSVD<107> @BASEBOARD_FAB2_LIB.BASEBOARD_FAB2(SCH_1):PVCCMCP_CPU1
CE78 TP_CPU1_RSVD_106 RSVD<106> @BASEBOARD_FAB2_LIB.BASEBOARD_FAB2(SCH_1):TP_CPU1_RSVD_106
CE80 TP_CPU1_RSVD_105 RSVD<105> @BASEBOARD_FAB2_LIB.BASEBOARD_FAB2(SCH_1):TP_CPU1_RSVD_105
CF19 PVCCMCP_CPU1 RSVD<104> @BASEBOARD_FAB2_LIB.BASEBOARD_FAB2(SCH_1):PVCCMCP_CPU1
CF21 PVCCMCP_CPU1 RSVD<103> @BASEBOARD_FAB2_LIB.BASEBOARD_FAB2(SCH_1):PVCCMCP_CPU1
CF23 PVCCMCP_CPU1 RSVD<102> @BASEBOARD_FAB2_LIB.BASEBOARD_FAB2(SCH_1):PVCCMCP_CPU1
CF79 TP_CPU1_RSVD_101 RSVD<101> @BASEBOARD_FAB2_LIB.BASEBOARD_FAB2(SCH_1):TP_CPU1_RSVD_101
CF81 TP_CPU1_RSVD_100 RSVD<100> @BASEBOARD_FAB2_LIB.BASEBOARD_FAB2(SCH_1):TP_CPU1_RSVD_100
CG10 TP_CPU1_RSVD_99 RSVD<99> @BASEBOARD_FAB2_LIB.BASEBOARD_FAB2(SCH_1):TP_CPU1_RSVD_99
CG20 PVCCMCP_CPU1 RSVD<98> @BASEBOARD_FAB2_LIB.BASEBOARD_FAB2(SCH_1):PVCCMCP_CPU1
CG24 TP_CPU1_RSVD_97 RSVD<97> @BASEBOARD_FAB2_LIB.BASEBOARD_FAB2(SCH_1):TP_CPU1_RSVD_97
CG26 PVCCMCP_CPU1 RSVD<96> @BASEBOARD_FAB2_LIB.BASEBOARD_FAB2(SCH_1):PVCCMCP_CPU1
CG78 TP_CPU1_RSVD_95 RSVD<95> @BASEBOARD_FAB2_LIB.BASEBOARD_FAB2(SCH_1):TP_CPU1_RSVD_95
CG82 TP_CPU1_RSVD_94 RSVD<94> @BASEBOARD_FAB2_LIB.BASEBOARD_FAB2(SCH_1):TP_CPU1_RSVD_94
CH21 PVCCMCP_CPU1 RSVD<93> @BASEBOARD_FAB2_LIB.BASEBOARD_FAB2(SCH_1):PVCCMCP_CPU1
CH23 PVCCMCP_CPU1 RSVD<92> @BASEBOARD_FAB2_LIB.BASEBOARD_FAB2(SCH_1):PVCCMCP_CPU1

SKX_EXT_B_BGA1-IC,TBD  I10  U2D1
CH25 TP_CPU1_RSVD_91 RSVD<91> @BASEBOARD_FAB2_LIB.BASEBOARD_FAB2(SCH_1):TP_CPU1_RSVD_91
CH77 TP_CPU1_RSVD_90 RSVD<90> @BASEBOARD_FAB2_LIB.BASEBOARD_FAB2(SCH_1):TP_CPU1_RSVD_90
CJ20 PVCCMCP_CPU1 RSVD<89> @BASEBOARD_FAB2_LIB.BASEBOARD_FAB2(SCH_1):PVCCMCP_CPU1
CJ22 PVCCMCP_CPU1 RSVD<88> @BASEBOARD_FAB2_LIB.BASEBOARD_FAB2(SCH_1):PVCCMCP_CPU1
CJ24 PVCCMCP_CPU1 RSVD<87> @BASEBOARD_FAB2_LIB.BASEBOARD_FAB2(SCH_1):PVCCMCP_CPU1
CJ26 PVCCMCP_CPU1 RSVD<86> @BASEBOARD_FAB2_LIB.BASEBOARD_FAB2(SCH_1):PVCCMCP_CPU1
CK19 TP_CPU1_RSVD_85 RSVD<85> @BASEBOARD_FAB2_LIB.BASEBOARD_FAB2(SCH_1):TP_CPU1_RSVD_85
CK23 PVCCMCP_CPU1 RSVD<84> @BASEBOARD_FAB2_LIB.BASEBOARD_FAB2(SCH_1):PVCCMCP_CPU1
CK25 PVCCMCP_CPU1 RSVD<83> @BASEBOARD_FAB2_LIB.BASEBOARD_FAB2(SCH_1):PVCCMCP_CPU1
CK77 TP_CPU1_RSVD_82 RSVD<82> @BASEBOARD_FAB2_LIB.BASEBOARD_FAB2(SCH_1):TP_CPU1_RSVD_82
CL24 PVCCMCP_CPU1 RSVD<81> @BASEBOARD_FAB2_LIB.BASEBOARD_FAB2(SCH_1):PVCCMCP_CPU1
AW22 TP_CPU1_TEST_10 TEST_10 @BASEBOARD_FAB2_LIB.BASEBOARD_FAB2(SCH_1):TP_CPU1_TEST_10
AR16 TP_CPU1_TEST_6 TEST_6 @BASEBOARD_FAB2_LIB.BASEBOARD_FAB2(SCH_1):TP_CPU1_TEST_6
AU18 TP_CPU1_TEST_7 TEST_7 @BASEBOARD_FAB2_LIB.BASEBOARD_FAB2(SCH_1):TP_CPU1_TEST_7
AW16 TP_CPU1_TEST_8 TEST_8 @BASEBOARD_FAB2_LIB.BASEBOARD_FAB2(SCH_1):TP_CPU1_TEST_8
AW20 TP_CPU1_TEST_9 TEST_9 @BASEBOARD_FAB2_LIB.BASEBOARD_FAB2(SCH_1):TP_CPU1_TEST_9


DRAWING: @BASEBOARD_FAB2_LIB.BASEBOARD_FAB2(SCH_1):PAGE71 

RES_0402-249,0.1%,1/16W,CHIP,GA  I43  R3D27
   1 VSENSE_PMAX_CPU1      A @BASEBOARD_FAB2_LIB.BASEBOARD_FAB2(SCH_1):VSENSE_PMAX_CPU1
   2    GND      B @BASEBOARD_FAB2_LIB.BASEBOARD_FAB2(SCH_1):GND

RES_0603-100.0K,1%,1/10W,CHIP,A  I49  RT8P1
   1 PVCCIN_CPU1      A @BASEBOARD_FAB2_LIB.BASEBOARD_FAB2(SCH_1):PVCCIN_CPU1
   2 VSENSE_VCCINR2PMAX_CPU1      B @BASEBOARD_FAB2_LIB.BASEBOARD_FAB2(SCH_1):VSENSE_VCCINR2PMAX_CPU1

SKX_EXT_B_BGA1-IC,TBD  I50  U2D1
AF43 PVCCIN_CPU1 VCCIN<267> @BASEBOARD_FAB2_LIB.BASEBOARD_FAB2(SCH_1):PVCCIN_CPU1
AG38 PVCCIN_CPU1 VCCIN<266> @BASEBOARD_FAB2_LIB.BASEBOARD_FAB2(SCH_1):PVCCIN_CPU1
AG40 PVCCIN_CPU1 VCCIN<265> @BASEBOARD_FAB2_LIB.BASEBOARD_FAB2(SCH_1):PVCCIN_CPU1
AG42 PVCCIN_CPU1 VCCIN<264> @BASEBOARD_FAB2_LIB.BASEBOARD_FAB2(SCH_1):PVCCIN_CPU1
AH37 PVCCIN_CPU1 VCCIN<263> @BASEBOARD_FAB2_LIB.BASEBOARD_FAB2(SCH_1):PVCCIN_CPU1
AH39 PVCCIN_CPU1 VCCIN<262> @BASEBOARD_FAB2_LIB.BASEBOARD_FAB2(SCH_1):PVCCIN_CPU1
AH41 PVCCIN_CPU1 VCCIN<261> @BASEBOARD_FAB2_LIB.BASEBOARD_FAB2(SCH_1):PVCCIN_CPU1
AJ36 PVCCIN_CPU1 VCCIN<260> @BASEBOARD_FAB2_LIB.BASEBOARD_FAB2(SCH_1):PVCCIN_CPU1
AK35 PVCCIN_CPU1 VCCIN<259> @BASEBOARD_FAB2_LIB.BASEBOARD_FAB2(SCH_1):PVCCIN_CPU1
AK45 PVCCIN_CPU1 VCCIN<258> @BASEBOARD_FAB2_LIB.BASEBOARD_FAB2(SCH_1):PVCCIN_CPU1
AK47 PVCCIN_CPU1 VCCIN<257> @BASEBOARD_FAB2_LIB.BASEBOARD_FAB2(SCH_1):PVCCIN_CPU1
AK49 PVCCIN_CPU1 VCCIN<256> @BASEBOARD_FAB2_LIB.BASEBOARD_FAB2(SCH_1):PVCCIN_CPU1
AK51 PVCCIN_CPU1 VCCIN<255> @BASEBOARD_FAB2_LIB.BASEBOARD_FAB2(SCH_1):PVCCIN_CPU1
AK53 PVCCIN_CPU1 VCCIN<254> @BASEBOARD_FAB2_LIB.BASEBOARD_FAB2(SCH_1):PVCCIN_CPU1
AL34 PVCCIN_CPU1 VCCIN<253> @BASEBOARD_FAB2_LIB.BASEBOARD_FAB2(SCH_1):PVCCIN_CPU1
AL46 PVCCIN_CPU1 VCCIN<252> @BASEBOARD_FAB2_LIB.BASEBOARD_FAB2(SCH_1):PVCCIN_CPU1
AL48 PVCCIN_CPU1 VCCIN<251> @BASEBOARD_FAB2_LIB.BASEBOARD_FAB2(SCH_1):PVCCIN_CPU1
AL50 PVCCIN_CPU1 VCCIN<250> @BASEBOARD_FAB2_LIB.BASEBOARD_FAB2(SCH_1):PVCCIN_CPU1
AL52 PVCCIN_CPU1 VCCIN<249> @BASEBOARD_FAB2_LIB.BASEBOARD_FAB2(SCH_1):PVCCIN_CPU1
AL54 PVCCIN_CPU1 VCCIN<248> @BASEBOARD_FAB2_LIB.BASEBOARD_FAB2(SCH_1):PVCCIN_CPU1
AM33 PVCCIN_CPU1 VCCIN<247> @BASEBOARD_FAB2_LIB.BASEBOARD_FAB2(SCH_1):PVCCIN_CPU1
AM53 PVCCIN_CPU1 VCCIN<246> @BASEBOARD_FAB2_LIB.BASEBOARD_FAB2(SCH_1):PVCCIN_CPU1
AM55 PVCCIN_CPU1 VCCIN<245> @BASEBOARD_FAB2_LIB.BASEBOARD_FAB2(SCH_1):PVCCIN_CPU1
AN32 PVCCIN_CPU1 VCCIN<244> @BASEBOARD_FAB2_LIB.BASEBOARD_FAB2(SCH_1):PVCCIN_CPU1
AN54 PVCCIN_CPU1 VCCIN<243> @BASEBOARD_FAB2_LIB.BASEBOARD_FAB2(SCH_1):PVCCIN_CPU1
AN56 PVCCIN_CPU1 VCCIN<242> @BASEBOARD_FAB2_LIB.BASEBOARD_FAB2(SCH_1):PVCCIN_CPU1
AP55 PVCCIN_CPU1 VCCIN<241> @BASEBOARD_FAB2_LIB.BASEBOARD_FAB2(SCH_1):PVCCIN_CPU1
AP57 PVCCIN_CPU1 VCCIN<240> @BASEBOARD_FAB2_LIB.BASEBOARD_FAB2(SCH_1):PVCCIN_CPU1
AR56 PVCCIN_CPU1 VCCIN<239> @BASEBOARD_FAB2_LIB.BASEBOARD_FAB2(SCH_1):PVCCIN_CPU1
AR58 PVCCIN_CPU1 VCCIN<238> @BASEBOARD_FAB2_LIB.BASEBOARD_FAB2(SCH_1):PVCCIN_CPU1
AT57 PVCCIN_CPU1 VCCIN<237> @BASEBOARD_FAB2_LIB.BASEBOARD_FAB2(SCH_1):PVCCIN_CPU1
AT59 PVCCIN_CPU1 VCCIN<236> @BASEBOARD_FAB2_LIB.BASEBOARD_FAB2(SCH_1):PVCCIN_CPU1
AU58 PVCCIN_CPU1 VCCIN<235> @BASEBOARD_FAB2_LIB.BASEBOARD_FAB2(SCH_1):PVCCIN_CPU1
AU60 PVCCIN_CPU1 VCCIN<234> @BASEBOARD_FAB2_LIB.BASEBOARD_FAB2(SCH_1):PVCCIN_CPU1
AV59 PVCCIN_CPU1 VCCIN<233> @BASEBOARD_FAB2_LIB.BASEBOARD_FAB2(SCH_1):PVCCIN_CPU1
AV61 PVCCIN_CPU1 VCCIN<232> @BASEBOARD_FAB2_LIB.BASEBOARD_FAB2(SCH_1):PVCCIN_CPU1
AW60 PVCCIN_CPU1 VCCIN<231> @BASEBOARD_FAB2_LIB.BASEBOARD_FAB2(SCH_1):PVCCIN_CPU1
AY61 PVCCIN_CPU1 VCCIN<230> @BASEBOARD_FAB2_LIB.BASEBOARD_FAB2(SCH_1):PVCCIN_CPU1
BA60 PVCCIN_CPU1 VCCIN<229> @BASEBOARD_FAB2_LIB.BASEBOARD_FAB2(SCH_1):PVCCIN_CPU1
BB61 PVCCIN_CPU1 VCCIN<228> @BASEBOARD_FAB2_LIB.BASEBOARD_FAB2(SCH_1):PVCCIN_CPU1
BB85 PVCCIN_CPU1 VCCIN<227> @BASEBOARD_FAB2_LIB.BASEBOARD_FAB2(SCH_1):PVCCIN_CPU1
BC60 PVCCIN_CPU1 VCCIN<226> @BASEBOARD_FAB2_LIB.BASEBOARD_FAB2(SCH_1):PVCCIN_CPU1
BC62 PVCCIN_CPU1 VCCIN<225> @BASEBOARD_FAB2_LIB.BASEBOARD_FAB2(SCH_1):PVCCIN_CPU1
BC84 PVCCIN_CPU1 VCCIN<224> @BASEBOARD_FAB2_LIB.BASEBOARD_FAB2(SCH_1):PVCCIN_CPU1
BD61 PVCCIN_CPU1 VCCIN<223> @BASEBOARD_FAB2_LIB.BASEBOARD_FAB2(SCH_1):PVCCIN_CPU1
BD73 PVCCIN_CPU1 VCCIN<222> @BASEBOARD_FAB2_LIB.BASEBOARD_FAB2(SCH_1):PVCCIN_CPU1
BD75 PVCCIN_CPU1 VCCIN<221> @BASEBOARD_FAB2_LIB.BASEBOARD_FAB2(SCH_1):PVCCIN_CPU1
BD77 PVCCIN_CPU1 VCCIN<220> @BASEBOARD_FAB2_LIB.BASEBOARD_FAB2(SCH_1):PVCCIN_CPU1
BD79 PVCCIN_CPU1 VCCIN<219> @BASEBOARD_FAB2_LIB.BASEBOARD_FAB2(SCH_1):PVCCIN_CPU1
BD81 PVCCIN_CPU1 VCCIN<218> @BASEBOARD_FAB2_LIB.BASEBOARD_FAB2(SCH_1):PVCCIN_CPU1
BD83 PVCCIN_CPU1 VCCIN<217> @BASEBOARD_FAB2_LIB.BASEBOARD_FAB2(SCH_1):PVCCIN_CPU1
BD85 PVCCIN_CPU1 VCCIN<216> @BASEBOARD_FAB2_LIB.BASEBOARD_FAB2(SCH_1):PVCCIN_CPU1
BE60 PVCCIN_CPU1 VCCIN<215> @BASEBOARD_FAB2_LIB.BASEBOARD_FAB2(SCH_1):PVCCIN_CPU1
BE62 PVCCIN_CPU1 VCCIN<214> @BASEBOARD_FAB2_LIB.BASEBOARD_FAB2(SCH_1):PVCCIN_CPU1
BE72 PVCCIN_CPU1 VCCIN<213> @BASEBOARD_FAB2_LIB.BASEBOARD_FAB2(SCH_1):PVCCIN_CPU1
BE74 PVCCIN_CPU1 VCCIN<212> @BASEBOARD_FAB2_LIB.BASEBOARD_FAB2(SCH_1):PVCCIN_CPU1
BE76 PVCCIN_CPU1 VCCIN<211> @BASEBOARD_FAB2_LIB.BASEBOARD_FAB2(SCH_1):PVCCIN_CPU1
BE78 PVCCIN_CPU1 VCCIN<210> @BASEBOARD_FAB2_LIB.BASEBOARD_FAB2(SCH_1):PVCCIN_CPU1
BE80 PVCCIN_CPU1 VCCIN<209> @BASEBOARD_FAB2_LIB.BASEBOARD_FAB2(SCH_1):PVCCIN_CPU1
BE82 PVCCIN_CPU1 VCCIN<208> @BASEBOARD_FAB2_LIB.BASEBOARD_FAB2(SCH_1):PVCCIN_CPU1
BE84 PVCCIN_CPU1 VCCIN<207> @BASEBOARD_FAB2_LIB.BASEBOARD_FAB2(SCH_1):PVCCIN_CPU1
BF61 PVCCIN_CPU1 VCCIN<206> @BASEBOARD_FAB2_LIB.BASEBOARD_FAB2(SCH_1):PVCCIN_CPU1
BF73 PVCCIN_CPU1 VCCIN<205> @BASEBOARD_FAB2_LIB.BASEBOARD_FAB2(SCH_1):PVCCIN_CPU1
BF75 PVCCIN_CPU1 VCCIN<204> @BASEBOARD_FAB2_LIB.BASEBOARD_FAB2(SCH_1):PVCCIN_CPU1
BF77 PVCCIN_CPU1 VCCIN<203> @BASEBOARD_FAB2_LIB.BASEBOARD_FAB2(SCH_1):PVCCIN_CPU1
BF79 PVCCIN_CPU1 VCCIN<202> @BASEBOARD_FAB2_LIB.BASEBOARD_FAB2(SCH_1):PVCCIN_CPU1
BF81 PVCCIN_CPU1 VCCIN<201> @BASEBOARD_FAB2_LIB.BASEBOARD_FAB2(SCH_1):PVCCIN_CPU1
BF83 PVCCIN_CPU1 VCCIN<200> @BASEBOARD_FAB2_LIB.BASEBOARD_FAB2(SCH_1):PVCCIN_CPU1
BF85 PVCCIN_CPU1 VCCIN<199> @BASEBOARD_FAB2_LIB.BASEBOARD_FAB2(SCH_1):PVCCIN_CPU1
BG60 PVCCIN_CPU1 VCCIN<198> @BASEBOARD_FAB2_LIB.BASEBOARD_FAB2(SCH_1):PVCCIN_CPU1
BG62 PVCCIN_CPU1 VCCIN<197> @BASEBOARD_FAB2_LIB.BASEBOARD_FAB2(SCH_1):PVCCIN_CPU1
BG64 PVCCIN_CPU1 VCCIN<196> @BASEBOARD_FAB2_LIB.BASEBOARD_FAB2(SCH_1):PVCCIN_CPU1
BG66 PVCCIN_CPU1 VCCIN<195> @BASEBOARD_FAB2_LIB.BASEBOARD_FAB2(SCH_1):PVCCIN_CPU1
BG68 PVCCIN_CPU1 VCCIN<194> @BASEBOARD_FAB2_LIB.BASEBOARD_FAB2(SCH_1):PVCCIN_CPU1
BG70 PVCCIN_CPU1 VCCIN<193> @BASEBOARD_FAB2_LIB.BASEBOARD_FAB2(SCH_1):PVCCIN_CPU1
BG84 PVCCIN_CPU1 VCCIN<192> @BASEBOARD_FAB2_LIB.BASEBOARD_FAB2(SCH_1):PVCCIN_CPU1
BH61 PVCCIN_CPU1 VCCIN<191> @BASEBOARD_FAB2_LIB.BASEBOARD_FAB2(SCH_1):PVCCIN_CPU1
BH63 PVCCIN_CPU1 VCCIN<190> @BASEBOARD_FAB2_LIB.BASEBOARD_FAB2(SCH_1):PVCCIN_CPU1
BH65 PVCCIN_CPU1 VCCIN<189> @BASEBOARD_FAB2_LIB.BASEBOARD_FAB2(SCH_1):PVCCIN_CPU1
BH67 PVCCIN_CPU1 VCCIN<188> @BASEBOARD_FAB2_LIB.BASEBOARD_FAB2(SCH_1):PVCCIN_CPU1
BH69 PVCCIN_CPU1 VCCIN<187> @BASEBOARD_FAB2_LIB.BASEBOARD_FAB2(SCH_1):PVCCIN_CPU1
BH71 PVCCIN_CPU1 VCCIN<186> @BASEBOARD_FAB2_LIB.BASEBOARD_FAB2(SCH_1):PVCCIN_CPU1
BH73 PVCCIN_CPU1 VCCIN<185> @BASEBOARD_FAB2_LIB.BASEBOARD_FAB2(SCH_1):PVCCIN_CPU1
BH75 PVCCIN_CPU1 VCCIN<184> @BASEBOARD_FAB2_LIB.BASEBOARD_FAB2(SCH_1):PVCCIN_CPU1
BH77 PVCCIN_CPU1 VCCIN<183> @BASEBOARD_FAB2_LIB.BASEBOARD_FAB2(SCH_1):PVCCIN_CPU1
BH79 PVCCIN_CPU1 VCCIN<182> @BASEBOARD_FAB2_LIB.BASEBOARD_FAB2(SCH_1):PVCCIN_CPU1
BH81 PVCCIN_CPU1 VCCIN<181> @BASEBOARD_FAB2_LIB.BASEBOARD_FAB2(SCH_1):PVCCIN_CPU1
BH83 PVCCIN_CPU1 VCCIN<180> @BASEBOARD_FAB2_LIB.BASEBOARD_FAB2(SCH_1):PVCCIN_CPU1
BJ60 PVCCIN_CPU1 VCCIN<179> @BASEBOARD_FAB2_LIB.BASEBOARD_FAB2(SCH_1):PVCCIN_CPU1
BJ62 PVCCIN_CPU1 VCCIN<178> @BASEBOARD_FAB2_LIB.BASEBOARD_FAB2(SCH_1):PVCCIN_CPU1
BJ64 PVCCIN_CPU1 VCCIN<177> @BASEBOARD_FAB2_LIB.BASEBOARD_FAB2(SCH_1):PVCCIN_CPU1
BJ66 PVCCIN_CPU1 VCCIN<176> @BASEBOARD_FAB2_LIB.BASEBOARD_FAB2(SCH_1):PVCCIN_CPU1
BJ68 PVCCIN_CPU1 VCCIN<175> @BASEBOARD_FAB2_LIB.BASEBOARD_FAB2(SCH_1):PVCCIN_CPU1
BJ70 PVCCIN_CPU1 VCCIN<174> @BASEBOARD_FAB2_LIB.BASEBOARD_FAB2(SCH_1):PVCCIN_CPU1
BJ72 PVCCIN_CPU1 VCCIN<173> @BASEBOARD_FAB2_LIB.BASEBOARD_FAB2(SCH_1):PVCCIN_CPU1
BJ74 PVCCIN_CPU1 VCCIN<172> @BASEBOARD_FAB2_LIB.BASEBOARD_FAB2(SCH_1):PVCCIN_CPU1
BJ76 PVCCIN_CPU1 VCCIN<171> @BASEBOARD_FAB2_LIB.BASEBOARD_FAB2(SCH_1):PVCCIN_CPU1
BJ78 PVCCIN_CPU1 VCCIN<170> @BASEBOARD_FAB2_LIB.BASEBOARD_FAB2(SCH_1):PVCCIN_CPU1
BJ80 PVCCIN_CPU1 VCCIN<169> @BASEBOARD_FAB2_LIB.BASEBOARD_FAB2(SCH_1):PVCCIN_CPU1
BJ82 PVCCIN_CPU1 VCCIN<168> @BASEBOARD_FAB2_LIB.BASEBOARD_FAB2(SCH_1):PVCCIN_CPU1
BJ84 PVCCIN_CPU1 VCCIN<167> @BASEBOARD_FAB2_LIB.BASEBOARD_FAB2(SCH_1):PVCCIN_CPU1
BK61 PVCCIN_CPU1 VCCIN<166> @BASEBOARD_FAB2_LIB.BASEBOARD_FAB2(SCH_1):PVCCIN_CPU1
BK63 PVCCIN_CPU1 VCCIN<165> @BASEBOARD_FAB2_LIB.BASEBOARD_FAB2(SCH_1):PVCCIN_CPU1
BK65 PVCCIN_CPU1 VCCIN<164> @BASEBOARD_FAB2_LIB.BASEBOARD_FAB2(SCH_1):PVCCIN_CPU1
BK67 PVCCIN_CPU1 VCCIN<163> @BASEBOARD_FAB2_LIB.BASEBOARD_FAB2(SCH_1):PVCCIN_CPU1
BK69 PVCCIN_CPU1 VCCIN<162> @BASEBOARD_FAB2_LIB.BASEBOARD_FAB2(SCH_1):PVCCIN_CPU1
BK71 PVCCIN_CPU1 VCCIN<161> @BASEBOARD_FAB2_LIB.BASEBOARD_FAB2(SCH_1):PVCCIN_CPU1
BK73 PVCCIN_CPU1 VCCIN<160> @BASEBOARD_FAB2_LIB.BASEBOARD_FAB2(SCH_1):PVCCIN_CPU1
BK75 PVCCIN_CPU1 VCCIN<159> @BASEBOARD_FAB2_LIB.BASEBOARD_FAB2(SCH_1):PVCCIN_CPU1
BK77 PVCCIN_CPU1 VCCIN<158> @BASEBOARD_FAB2_LIB.BASEBOARD_FAB2(SCH_1):PVCCIN_CPU1
BK79 PVCCIN_CPU1 VCCIN<157> @BASEBOARD_FAB2_LIB.BASEBOARD_FAB2(SCH_1):PVCCIN_CPU1
BK81 PVCCIN_CPU1 VCCIN<156> @BASEBOARD_FAB2_LIB.BASEBOARD_FAB2(SCH_1):PVCCIN_CPU1
BK83 PVCCIN_CPU1 VCCIN<155> @BASEBOARD_FAB2_LIB.BASEBOARD_FAB2(SCH_1):PVCCIN_CPU1
BL60 PVCCIN_CPU1 VCCIN<154> @BASEBOARD_FAB2_LIB.BASEBOARD_FAB2(SCH_1):PVCCIN_CPU1
BL62 PVCCIN_CPU1 VCCIN<153> @BASEBOARD_FAB2_LIB.BASEBOARD_FAB2(SCH_1):PVCCIN_CPU1
BL84 PVCCIN_CPU1 VCCIN<152> @BASEBOARD_FAB2_LIB.BASEBOARD_FAB2(SCH_1):PVCCIN_CPU1
BM61 PVCCIN_CPU1 VCCIN<151> @BASEBOARD_FAB2_LIB.BASEBOARD_FAB2(SCH_1):PVCCIN_CPU1
BM63 PVCCIN_CPU1 VCCIN<150> @BASEBOARD_FAB2_LIB.BASEBOARD_FAB2(SCH_1):PVCCIN_CPU1
BM65 PVCCIN_CPU1 VCCIN<149> @BASEBOARD_FAB2_LIB.BASEBOARD_FAB2(SCH_1):PVCCIN_CPU1
BM67 PVCCIN_CPU1 VCCIN<148> @BASEBOARD_FAB2_LIB.BASEBOARD_FAB2(SCH_1):PVCCIN_CPU1
BM69 PVCCIN_CPU1 VCCIN<147> @BASEBOARD_FAB2_LIB.BASEBOARD_FAB2(SCH_1):PVCCIN_CPU1
BM71 PVCCIN_CPU1 VCCIN<146> @BASEBOARD_FAB2_LIB.BASEBOARD_FAB2(SCH_1):PVCCIN_CPU1
BM73 PVCCIN_CPU1 VCCIN<145> @BASEBOARD_FAB2_LIB.BASEBOARD_FAB2(SCH_1):PVCCIN_CPU1
BM75 PVCCIN_CPU1 VCCIN<144> @BASEBOARD_FAB2_LIB.BASEBOARD_FAB2(SCH_1):PVCCIN_CPU1
BM77 PVCCIN_CPU1 VCCIN<143> @BASEBOARD_FAB2_LIB.BASEBOARD_FAB2(SCH_1):PVCCIN_CPU1
BM79 PVCCIN_CPU1 VCCIN<142> @BASEBOARD_FAB2_LIB.BASEBOARD_FAB2(SCH_1):PVCCIN_CPU1
BM81 PVCCIN_CPU1 VCCIN<141> @BASEBOARD_FAB2_LIB.BASEBOARD_FAB2(SCH_1):PVCCIN_CPU1
BM83 PVCCIN_CPU1 VCCIN<140> @BASEBOARD_FAB2_LIB.BASEBOARD_FAB2(SCH_1):PVCCIN_CPU1
BN60 PVCCIN_CPU1 VCCIN<139> @BASEBOARD_FAB2_LIB.BASEBOARD_FAB2(SCH_1):PVCCIN_CPU1
BN62 PVCCIN_CPU1 VCCIN<138> @BASEBOARD_FAB2_LIB.BASEBOARD_FAB2(SCH_1):PVCCIN_CPU1
BN64 PVCCIN_CPU1 VCCIN<137> @BASEBOARD_FAB2_LIB.BASEBOARD_FAB2(SCH_1):PVCCIN_CPU1
BN66 PVCCIN_CPU1 VCCIN<136> @BASEBOARD_FAB2_LIB.BASEBOARD_FAB2(SCH_1):PVCCIN_CPU1
BN68 PVCCIN_CPU1 VCCIN<135> @BASEBOARD_FAB2_LIB.BASEBOARD_FAB2(SCH_1):PVCCIN_CPU1
BN70 PVCCIN_CPU1 VCCIN<134> @BASEBOARD_FAB2_LIB.BASEBOARD_FAB2(SCH_1):PVCCIN_CPU1
BN72 PVCCIN_CPU1 VCCIN<133> @BASEBOARD_FAB2_LIB.BASEBOARD_FAB2(SCH_1):PVCCIN_CPU1
BN74 PVCCIN_CPU1 VCCIN<132> @BASEBOARD_FAB2_LIB.BASEBOARD_FAB2(SCH_1):PVCCIN_CPU1
BN76 PVCCIN_CPU1 VCCIN<131> @BASEBOARD_FAB2_LIB.BASEBOARD_FAB2(SCH_1):PVCCIN_CPU1
BN78 PVCCIN_CPU1 VCCIN<130> @BASEBOARD_FAB2_LIB.BASEBOARD_FAB2(SCH_1):PVCCIN_CPU1

SKX_EXT_B_BGA1-IC,TBD  I51  U2D1
BN80 PVCCIN_CPU1 VCCIN<129> @BASEBOARD_FAB2_LIB.BASEBOARD_FAB2(SCH_1):PVCCIN_CPU1
BN82 PVCCIN_CPU1 VCCIN<128> @BASEBOARD_FAB2_LIB.BASEBOARD_FAB2(SCH_1):PVCCIN_CPU1
BN84 PVCCIN_CPU1 VCCIN<127> @BASEBOARD_FAB2_LIB.BASEBOARD_FAB2(SCH_1):PVCCIN_CPU1
BP61 PVCCIN_CPU1 VCCIN<126> @BASEBOARD_FAB2_LIB.BASEBOARD_FAB2(SCH_1):PVCCIN_CPU1
BP63 PVCCIN_CPU1 VCCIN<125> @BASEBOARD_FAB2_LIB.BASEBOARD_FAB2(SCH_1):PVCCIN_CPU1
BP65 PVCCIN_CPU1 VCCIN<124> @BASEBOARD_FAB2_LIB.BASEBOARD_FAB2(SCH_1):PVCCIN_CPU1
BP67 PVCCIN_CPU1 VCCIN<123> @BASEBOARD_FAB2_LIB.BASEBOARD_FAB2(SCH_1):PVCCIN_CPU1
BP69 PVCCIN_CPU1 VCCIN<122> @BASEBOARD_FAB2_LIB.BASEBOARD_FAB2(SCH_1):PVCCIN_CPU1
BP71 PVCCIN_CPU1 VCCIN<121> @BASEBOARD_FAB2_LIB.BASEBOARD_FAB2(SCH_1):PVCCIN_CPU1
BP73 PVCCIN_CPU1 VCCIN<120> @BASEBOARD_FAB2_LIB.BASEBOARD_FAB2(SCH_1):PVCCIN_CPU1
BP75 PVCCIN_CPU1 VCCIN<119> @BASEBOARD_FAB2_LIB.BASEBOARD_FAB2(SCH_1):PVCCIN_CPU1
BP77 PVCCIN_CPU1 VCCIN<118> @BASEBOARD_FAB2_LIB.BASEBOARD_FAB2(SCH_1):PVCCIN_CPU1
BP79 PVCCIN_CPU1 VCCIN<117> @BASEBOARD_FAB2_LIB.BASEBOARD_FAB2(SCH_1):PVCCIN_CPU1
BP81 PVCCIN_CPU1 VCCIN<116> @BASEBOARD_FAB2_LIB.BASEBOARD_FAB2(SCH_1):PVCCIN_CPU1
BP83 PVCCIN_CPU1 VCCIN<115> @BASEBOARD_FAB2_LIB.BASEBOARD_FAB2(SCH_1):PVCCIN_CPU1
BR60 PVCCIN_CPU1 VCCIN<114> @BASEBOARD_FAB2_LIB.BASEBOARD_FAB2(SCH_1):PVCCIN_CPU1
BR62 PVCCIN_CPU1 VCCIN<113> @BASEBOARD_FAB2_LIB.BASEBOARD_FAB2(SCH_1):PVCCIN_CPU1
BR84 PVCCIN_CPU1 VCCIN<112> @BASEBOARD_FAB2_LIB.BASEBOARD_FAB2(SCH_1):PVCCIN_CPU1
BT61 PVCCIN_CPU1 VCCIN<111> @BASEBOARD_FAB2_LIB.BASEBOARD_FAB2(SCH_1):PVCCIN_CPU1
BT63 PVCCIN_CPU1 VCCIN<110> @BASEBOARD_FAB2_LIB.BASEBOARD_FAB2(SCH_1):PVCCIN_CPU1
BT65 PVCCIN_CPU1 VCCIN<109> @BASEBOARD_FAB2_LIB.BASEBOARD_FAB2(SCH_1):PVCCIN_CPU1
BT67 PVCCIN_CPU1 VCCIN<108> @BASEBOARD_FAB2_LIB.BASEBOARD_FAB2(SCH_1):PVCCIN_CPU1
BT69 PVCCIN_CPU1 VCCIN<107> @BASEBOARD_FAB2_LIB.BASEBOARD_FAB2(SCH_1):PVCCIN_CPU1
BT71 PVCCIN_CPU1 VCCIN<106> @BASEBOARD_FAB2_LIB.BASEBOARD_FAB2(SCH_1):PVCCIN_CPU1
BT73 PVCCIN_CPU1 VCCIN<105> @BASEBOARD_FAB2_LIB.BASEBOARD_FAB2(SCH_1):PVCCIN_CPU1
BT75 PVCCIN_CPU1 VCCIN<104> @BASEBOARD_FAB2_LIB.BASEBOARD_FAB2(SCH_1):PVCCIN_CPU1
BT77 PVCCIN_CPU1 VCCIN<103> @BASEBOARD_FAB2_LIB.BASEBOARD_FAB2(SCH_1):PVCCIN_CPU1
BT79 PVCCIN_CPU1 VCCIN<102> @BASEBOARD_FAB2_LIB.BASEBOARD_FAB2(SCH_1):PVCCIN_CPU1
BT81 PVCCIN_CPU1 VCCIN<101> @BASEBOARD_FAB2_LIB.BASEBOARD_FAB2(SCH_1):PVCCIN_CPU1
BT83 PVCCIN_CPU1 VCCIN<100> @BASEBOARD_FAB2_LIB.BASEBOARD_FAB2(SCH_1):PVCCIN_CPU1
BU60 PVCCIN_CPU1 VCCIN<99> @BASEBOARD_FAB2_LIB.BASEBOARD_FAB2(SCH_1):PVCCIN_CPU1
BU62 PVCCIN_CPU1 VCCIN<98> @BASEBOARD_FAB2_LIB.BASEBOARD_FAB2(SCH_1):PVCCIN_CPU1
BU64 PVCCIN_CPU1 VCCIN<97> @BASEBOARD_FAB2_LIB.BASEBOARD_FAB2(SCH_1):PVCCIN_CPU1
BU66 PVCCIN_CPU1 VCCIN<96> @BASEBOARD_FAB2_LIB.BASEBOARD_FAB2(SCH_1):PVCCIN_CPU1
BU68 PVCCIN_CPU1 VCCIN<95> @BASEBOARD_FAB2_LIB.BASEBOARD_FAB2(SCH_1):PVCCIN_CPU1
BU70 PVCCIN_CPU1 VCCIN<94> @BASEBOARD_FAB2_LIB.BASEBOARD_FAB2(SCH_1):PVCCIN_CPU1
BU72 PVCCIN_CPU1 VCCIN<93> @BASEBOARD_FAB2_LIB.BASEBOARD_FAB2(SCH_1):PVCCIN_CPU1
BU74 PVCCIN_CPU1 VCCIN<92> @BASEBOARD_FAB2_LIB.BASEBOARD_FAB2(SCH_1):PVCCIN_CPU1
BU76 PVCCIN_CPU1 VCCIN<91> @BASEBOARD_FAB2_LIB.BASEBOARD_FAB2(SCH_1):PVCCIN_CPU1
BU78 PVCCIN_CPU1 VCCIN<90> @BASEBOARD_FAB2_LIB.BASEBOARD_FAB2(SCH_1):PVCCIN_CPU1
BU80 PVCCIN_CPU1 VCCIN<89> @BASEBOARD_FAB2_LIB.BASEBOARD_FAB2(SCH_1):PVCCIN_CPU1
BU82 PVCCIN_CPU1 VCCIN<88> @BASEBOARD_FAB2_LIB.BASEBOARD_FAB2(SCH_1):PVCCIN_CPU1
BU84 PVCCIN_CPU1 VCCIN<87> @BASEBOARD_FAB2_LIB.BASEBOARD_FAB2(SCH_1):PVCCIN_CPU1
BV61 PVCCIN_CPU1 VCCIN<86> @BASEBOARD_FAB2_LIB.BASEBOARD_FAB2(SCH_1):PVCCIN_CPU1
BV63 PVCCIN_CPU1 VCCIN<85> @BASEBOARD_FAB2_LIB.BASEBOARD_FAB2(SCH_1):PVCCIN_CPU1
BV65 PVCCIN_CPU1 VCCIN<84> @BASEBOARD_FAB2_LIB.BASEBOARD_FAB2(SCH_1):PVCCIN_CPU1
BV67 PVCCIN_CPU1 VCCIN<83> @BASEBOARD_FAB2_LIB.BASEBOARD_FAB2(SCH_1):PVCCIN_CPU1
BV69 PVCCIN_CPU1 VCCIN<82> @BASEBOARD_FAB2_LIB.BASEBOARD_FAB2(SCH_1):PVCCIN_CPU1
BV71 PVCCIN_CPU1 VCCIN<81> @BASEBOARD_FAB2_LIB.BASEBOARD_FAB2(SCH_1):PVCCIN_CPU1
BV73 PVCCIN_CPU1 VCCIN<80> @BASEBOARD_FAB2_LIB.BASEBOARD_FAB2(SCH_1):PVCCIN_CPU1
BV75 PVCCIN_CPU1 VCCIN<79> @BASEBOARD_FAB2_LIB.BASEBOARD_FAB2(SCH_1):PVCCIN_CPU1
BV77 PVCCIN_CPU1 VCCIN<78> @BASEBOARD_FAB2_LIB.BASEBOARD_FAB2(SCH_1):PVCCIN_CPU1
BV79 PVCCIN_CPU1 VCCIN<77> @BASEBOARD_FAB2_LIB.BASEBOARD_FAB2(SCH_1):PVCCIN_CPU1
BV81 PVCCIN_CPU1 VCCIN<76> @BASEBOARD_FAB2_LIB.BASEBOARD_FAB2(SCH_1):PVCCIN_CPU1
BV83 PVCCIN_CPU1 VCCIN<75> @BASEBOARD_FAB2_LIB.BASEBOARD_FAB2(SCH_1):PVCCIN_CPU1
BW60 PVCCIN_CPU1 VCCIN<74> @BASEBOARD_FAB2_LIB.BASEBOARD_FAB2(SCH_1):PVCCIN_CPU1
BW62 PVCCIN_CPU1 VCCIN<73> @BASEBOARD_FAB2_LIB.BASEBOARD_FAB2(SCH_1):PVCCIN_CPU1
BW64 PVCCIN_CPU1 VCCIN<72> @BASEBOARD_FAB2_LIB.BASEBOARD_FAB2(SCH_1):PVCCIN_CPU1
BW66 PVCCIN_CPU1 VCCIN<71> @BASEBOARD_FAB2_LIB.BASEBOARD_FAB2(SCH_1):PVCCIN_CPU1
BW68 PVCCIN_CPU1 VCCIN<70> @BASEBOARD_FAB2_LIB.BASEBOARD_FAB2(SCH_1):PVCCIN_CPU1
BW70 PVCCIN_CPU1 VCCIN<69> @BASEBOARD_FAB2_LIB.BASEBOARD_FAB2(SCH_1):PVCCIN_CPU1
BW84 PVCCIN_CPU1 VCCIN<68> @BASEBOARD_FAB2_LIB.BASEBOARD_FAB2(SCH_1):PVCCIN_CPU1
BY61 PVCCIN_CPU1 VCCIN<67> @BASEBOARD_FAB2_LIB.BASEBOARD_FAB2(SCH_1):PVCCIN_CPU1
BY73 PVCCIN_CPU1 VCCIN<66> @BASEBOARD_FAB2_LIB.BASEBOARD_FAB2(SCH_1):PVCCIN_CPU1
BY75 PVCCIN_CPU1 VCCIN<65> @BASEBOARD_FAB2_LIB.BASEBOARD_FAB2(SCH_1):PVCCIN_CPU1
BY77 PVCCIN_CPU1 VCCIN<64> @BASEBOARD_FAB2_LIB.BASEBOARD_FAB2(SCH_1):PVCCIN_CPU1
BY79 PVCCIN_CPU1 VCCIN<63> @BASEBOARD_FAB2_LIB.BASEBOARD_FAB2(SCH_1):PVCCIN_CPU1
BY81 PVCCIN_CPU1 VCCIN<62> @BASEBOARD_FAB2_LIB.BASEBOARD_FAB2(SCH_1):PVCCIN_CPU1
BY83 PVCCIN_CPU1 VCCIN<61> @BASEBOARD_FAB2_LIB.BASEBOARD_FAB2(SCH_1):PVCCIN_CPU1
CA60 PVCCIN_CPU1 VCCIN<60> @BASEBOARD_FAB2_LIB.BASEBOARD_FAB2(SCH_1):PVCCIN_CPU1
CA62 PVCCIN_CPU1 VCCIN<59> @BASEBOARD_FAB2_LIB.BASEBOARD_FAB2(SCH_1):PVCCIN_CPU1
CA72 PVCCIN_CPU1 VCCIN<58> @BASEBOARD_FAB2_LIB.BASEBOARD_FAB2(SCH_1):PVCCIN_CPU1
CA74 PVCCIN_CPU1 VCCIN<57> @BASEBOARD_FAB2_LIB.BASEBOARD_FAB2(SCH_1):PVCCIN_CPU1
CA76 PVCCIN_CPU1 VCCIN<56> @BASEBOARD_FAB2_LIB.BASEBOARD_FAB2(SCH_1):PVCCIN_CPU1
CA78 PVCCIN_CPU1 VCCIN<55> @BASEBOARD_FAB2_LIB.BASEBOARD_FAB2(SCH_1):PVCCIN_CPU1
CA80 PVCCIN_CPU1 VCCIN<54> @BASEBOARD_FAB2_LIB.BASEBOARD_FAB2(SCH_1):PVCCIN_CPU1
CA82 PVCCIN_CPU1 VCCIN<53> @BASEBOARD_FAB2_LIB.BASEBOARD_FAB2(SCH_1):PVCCIN_CPU1
CA84 PVCCIN_CPU1 VCCIN<52> @BASEBOARD_FAB2_LIB.BASEBOARD_FAB2(SCH_1):PVCCIN_CPU1
CB61 PVCCIN_CPU1 VCCIN<51> @BASEBOARD_FAB2_LIB.BASEBOARD_FAB2(SCH_1):PVCCIN_CPU1
CB73 PVCCIN_CPU1 VCCIN<50> @BASEBOARD_FAB2_LIB.BASEBOARD_FAB2(SCH_1):PVCCIN_CPU1
CB75 PVCCIN_CPU1 VCCIN<49> @BASEBOARD_FAB2_LIB.BASEBOARD_FAB2(SCH_1):PVCCIN_CPU1
CB77 PVCCIN_CPU1 VCCIN<48> @BASEBOARD_FAB2_LIB.BASEBOARD_FAB2(SCH_1):PVCCIN_CPU1
CB79 PVCCIN_CPU1 VCCIN<47> @BASEBOARD_FAB2_LIB.BASEBOARD_FAB2(SCH_1):PVCCIN_CPU1
CB81 PVCCIN_CPU1 VCCIN<46> @BASEBOARD_FAB2_LIB.BASEBOARD_FAB2(SCH_1):PVCCIN_CPU1
CB83 PVCCIN_CPU1 VCCIN<45> @BASEBOARD_FAB2_LIB.BASEBOARD_FAB2(SCH_1):PVCCIN_CPU1
CC60 PVCCIN_CPU1 VCCIN<44> @BASEBOARD_FAB2_LIB.BASEBOARD_FAB2(SCH_1):PVCCIN_CPU1
CC62 PVCCIN_CPU1 VCCIN<43> @BASEBOARD_FAB2_LIB.BASEBOARD_FAB2(SCH_1):PVCCIN_CPU1
CC84 PVCCIN_CPU1 VCCIN<42> @BASEBOARD_FAB2_LIB.BASEBOARD_FAB2(SCH_1):PVCCIN_CPU1
CD61 PVCCIN_CPU1 VCCIN<41> @BASEBOARD_FAB2_LIB.BASEBOARD_FAB2(SCH_1):PVCCIN_CPU1
CD83 PVCCIN_CPU1 VCCIN<40> @BASEBOARD_FAB2_LIB.BASEBOARD_FAB2(SCH_1):PVCCIN_CPU1
CD85 PVCCIN_CPU1 VCCIN<39> @BASEBOARD_FAB2_LIB.BASEBOARD_FAB2(SCH_1):PVCCIN_CPU1
CE60 PVCCIN_CPU1 VCCIN<38> @BASEBOARD_FAB2_LIB.BASEBOARD_FAB2(SCH_1):PVCCIN_CPU1
CE84 PVCCIN_CPU1 VCCIN<37> @BASEBOARD_FAB2_LIB.BASEBOARD_FAB2(SCH_1):PVCCIN_CPU1
CF61 PVCCIN_CPU1 VCCIN<36> @BASEBOARD_FAB2_LIB.BASEBOARD_FAB2(SCH_1):PVCCIN_CPU1
CF85 PVCCIN_CPU1 VCCIN<35> @BASEBOARD_FAB2_LIB.BASEBOARD_FAB2(SCH_1):PVCCIN_CPU1
CG60 PVCCIN_CPU1 VCCIN<34> @BASEBOARD_FAB2_LIB.BASEBOARD_FAB2(SCH_1):PVCCIN_CPU1
CG84 PVCCIN_CPU1 VCCIN<33> @BASEBOARD_FAB2_LIB.BASEBOARD_FAB2(SCH_1):PVCCIN_CPU1
CH61 PVCCIN_CPU1 VCCIN<32> @BASEBOARD_FAB2_LIB.BASEBOARD_FAB2(SCH_1):PVCCIN_CPU1
CH85 PVCCIN_CPU1 VCCIN<31> @BASEBOARD_FAB2_LIB.BASEBOARD_FAB2(SCH_1):PVCCIN_CPU1
CJ60 PVCCIN_CPU1 VCCIN<30> @BASEBOARD_FAB2_LIB.BASEBOARD_FAB2(SCH_1):PVCCIN_CPU1
CK59 PVCCIN_CPU1 VCCIN<29> @BASEBOARD_FAB2_LIB.BASEBOARD_FAB2(SCH_1):PVCCIN_CPU1
CK61 PVCCIN_CPU1 VCCIN<28> @BASEBOARD_FAB2_LIB.BASEBOARD_FAB2(SCH_1):PVCCIN_CPU1
CL58 PVCCIN_CPU1 VCCIN<27> @BASEBOARD_FAB2_LIB.BASEBOARD_FAB2(SCH_1):PVCCIN_CPU1
CL60 PVCCIN_CPU1 VCCIN<26> @BASEBOARD_FAB2_LIB.BASEBOARD_FAB2(SCH_1):PVCCIN_CPU1
CM57 PVCCIN_CPU1 VCCIN<25> @BASEBOARD_FAB2_LIB.BASEBOARD_FAB2(SCH_1):PVCCIN_CPU1
CM59 PVCCIN_CPU1 VCCIN<24> @BASEBOARD_FAB2_LIB.BASEBOARD_FAB2(SCH_1):PVCCIN_CPU1
CN56 PVCCIN_CPU1 VCCIN<23> @BASEBOARD_FAB2_LIB.BASEBOARD_FAB2(SCH_1):PVCCIN_CPU1
CN58 PVCCIN_CPU1 VCCIN<22> @BASEBOARD_FAB2_LIB.BASEBOARD_FAB2(SCH_1):PVCCIN_CPU1
CP33 PVCCIN_CPU1 VCCIN<21> @BASEBOARD_FAB2_LIB.BASEBOARD_FAB2(SCH_1):PVCCIN_CPU1
CP55 PVCCIN_CPU1 VCCIN<20> @BASEBOARD_FAB2_LIB.BASEBOARD_FAB2(SCH_1):PVCCIN_CPU1
CP57 PVCCIN_CPU1 VCCIN<19> @BASEBOARD_FAB2_LIB.BASEBOARD_FAB2(SCH_1):PVCCIN_CPU1
CR34 PVCCIN_CPU1 VCCIN<18> @BASEBOARD_FAB2_LIB.BASEBOARD_FAB2(SCH_1):PVCCIN_CPU1
CR54 PVCCIN_CPU1 VCCIN<17> @BASEBOARD_FAB2_LIB.BASEBOARD_FAB2(SCH_1):PVCCIN_CPU1
CR56 PVCCIN_CPU1 VCCIN<16> @BASEBOARD_FAB2_LIB.BASEBOARD_FAB2(SCH_1):PVCCIN_CPU1
CT37 PVCCIN_CPU1 VCCIN<15> @BASEBOARD_FAB2_LIB.BASEBOARD_FAB2(SCH_1):PVCCIN_CPU1
CT39 PVCCIN_CPU1 VCCIN<14> @BASEBOARD_FAB2_LIB.BASEBOARD_FAB2(SCH_1):PVCCIN_CPU1
CT41 PVCCIN_CPU1 VCCIN<13> @BASEBOARD_FAB2_LIB.BASEBOARD_FAB2(SCH_1):PVCCIN_CPU1
CT53 PVCCIN_CPU1 VCCIN<12> @BASEBOARD_FAB2_LIB.BASEBOARD_FAB2(SCH_1):PVCCIN_CPU1
CT55 PVCCIN_CPU1 VCCIN<11> @BASEBOARD_FAB2_LIB.BASEBOARD_FAB2(SCH_1):PVCCIN_CPU1
CU38 PVCCIN_CPU1 VCCIN<10> @BASEBOARD_FAB2_LIB.BASEBOARD_FAB2(SCH_1):PVCCIN_CPU1
CU40 PVCCIN_CPU1 VCCIN<9> @BASEBOARD_FAB2_LIB.BASEBOARD_FAB2(SCH_1):PVCCIN_CPU1
CU42 PVCCIN_CPU1 VCCIN<8> @BASEBOARD_FAB2_LIB.BASEBOARD_FAB2(SCH_1):PVCCIN_CPU1
CU52 PVCCIN_CPU1 VCCIN<7> @BASEBOARD_FAB2_LIB.BASEBOARD_FAB2(SCH_1):PVCCIN_CPU1
CU54 PVCCIN_CPU1 VCCIN<6> @BASEBOARD_FAB2_LIB.BASEBOARD_FAB2(SCH_1):PVCCIN_CPU1
CV51 PVCCIN_CPU1 VCCIN<5> @BASEBOARD_FAB2_LIB.BASEBOARD_FAB2(SCH_1):PVCCIN_CPU1
CW46 PVCCIN_CPU1 VCCIN<4> @BASEBOARD_FAB2_LIB.BASEBOARD_FAB2(SCH_1):PVCCIN_CPU1
CW48 PVCCIN_CPU1 VCCIN<3> @BASEBOARD_FAB2_LIB.BASEBOARD_FAB2(SCH_1):PVCCIN_CPU1
CW50 PVCCIN_CPU1 VCCIN<2> @BASEBOARD_FAB2_LIB.BASEBOARD_FAB2(SCH_1):PVCCIN_CPU1
CY47 PVCCIN_CPU1 VCCIN<1> @BASEBOARD_FAB2_LIB.BASEBOARD_FAB2(SCH_1):PVCCIN_CPU1
CY49 PVCCIN_CPU1 VCCIN<0> @BASEBOARD_FAB2_LIB.BASEBOARD_FAB2(SCH_1):PVCCIN_CPU1
AV85 VSENSE_VCCINR2PMAX_CPU1 VCCINPMAX<1> @BASEBOARD_FAB2_LIB.BASEBOARD_FAB2(SCH_1):VSENSE_VCCINR2PMAX_CPU1
AW86 VSENSE_VCCINR2PMAX_CPU1 VCCINPMAX<0> @BASEBOARD_FAB2_LIB.BASEBOARD_FAB2(SCH_1):VSENSE_VCCINR2PMAX_CPU1
BA86 VSENSE_PVCCIN_CPU1_SKT_VSEN VCCIN_SENSE @BASEBOARD_FAB2_LIB.BASEBOARD_FAB2(SCH_1):VSENSE_PVCCIN_CPU1_SKT_VSEN
AD41 VSENSE_PMAX_CPU1 VSENSEPMAX @BASEBOARD_FAB2_LIB.BASEBOARD_FAB2(SCH_1):VSENSE_PMAX_CPU1
AY85 VSENSE_PVCCIN_CPU1_SKT_VRTN VSS_VCCIN_SENSE @BASEBOARD_FAB2_LIB.BASEBOARD_FAB2(SCH_1):VSENSE_PVCCIN_CPU1_SKT_VRTN

RES_0402-10.0,1%,1/16W,EMPTY,GA  I53  R3D32
   1 PVCCIO_CPU1      A @BASEBOARD_FAB2_LIB.BASEBOARD_FAB2(SCH_1):PVCCIO_CPU1
   2 VSENSE_PMAX_CPU1      B @BASEBOARD_FAB2_LIB.BASEBOARD_FAB2(SCH_1):VSENSE_PMAX_CPU1


DRAWING: @BASEBOARD_FAB2_LIB.BASEBOARD_FAB2(SCH_1):PAGE72 

CAP_0603LF-10UF,4V,20%,X6S,E15A  I25  C3D3
   1 P1V8_MCP_CPU1      A @BASEBOARD_FAB2_LIB.BASEBOARD_FAB2(SCH_1):P1V8_MCP_CPU1
   2    GND      B @BASEBOARD_FAB2_LIB.BASEBOARD_FAB2(SCH_1):GND

SKX_EXT_B_BGA1-IC,TBD  I32  U2D1
 B47 PVDDQ_GHJ VCCD012<51> @BASEBOARD_FAB2_LIB.BASEBOARD_FAB2(SCH_1):PVDDQ_GHJ
 C46 PVDDQ_GHJ VCCD012<50> @BASEBOARD_FAB2_LIB.BASEBOARD_FAB2(SCH_1):PVDDQ_GHJ
 D45 PVDDQ_GHJ VCCD012<49> @BASEBOARD_FAB2_LIB.BASEBOARD_FAB2(SCH_1):PVDDQ_GHJ
AF63 PVDDQ_GHJ VCCD012<48> @BASEBOARD_FAB2_LIB.BASEBOARD_FAB2(SCH_1):PVDDQ_GHJ
AF61 PVDDQ_GHJ VCCD012<47> @BASEBOARD_FAB2_LIB.BASEBOARD_FAB2(SCH_1):PVDDQ_GHJ
AF59 PVDDQ_GHJ VCCD012<46> @BASEBOARD_FAB2_LIB.BASEBOARD_FAB2(SCH_1):PVDDQ_GHJ
AF57 PVDDQ_GHJ VCCD012<45> @BASEBOARD_FAB2_LIB.BASEBOARD_FAB2(SCH_1):PVDDQ_GHJ
AF55 PVDDQ_GHJ VCCD012<44> @BASEBOARD_FAB2_LIB.BASEBOARD_FAB2(SCH_1):PVDDQ_GHJ
AD45 PVDDQ_GHJ VCCD012<43> @BASEBOARD_FAB2_LIB.BASEBOARD_FAB2(SCH_1):PVDDQ_GHJ
 Y63 PVDDQ_GHJ VCCD012<42> @BASEBOARD_FAB2_LIB.BASEBOARD_FAB2(SCH_1):PVDDQ_GHJ
 Y61 PVDDQ_GHJ VCCD012<41> @BASEBOARD_FAB2_LIB.BASEBOARD_FAB2(SCH_1):PVDDQ_GHJ
 Y59 PVDDQ_GHJ VCCD012<40> @BASEBOARD_FAB2_LIB.BASEBOARD_FAB2(SCH_1):PVDDQ_GHJ
 Y57 PVDDQ_GHJ VCCD012<39> @BASEBOARD_FAB2_LIB.BASEBOARD_FAB2(SCH_1):PVDDQ_GHJ
 Y55 PVDDQ_GHJ VCCD012<38> @BASEBOARD_FAB2_LIB.BASEBOARD_FAB2(SCH_1):PVDDQ_GHJ
 Y53 PVDDQ_GHJ VCCD012<37> @BASEBOARD_FAB2_LIB.BASEBOARD_FAB2(SCH_1):PVDDQ_GHJ
 Y51 PVDDQ_GHJ VCCD012<36> @BASEBOARD_FAB2_LIB.BASEBOARD_FAB2(SCH_1):PVDDQ_GHJ
 Y49 PVDDQ_GHJ VCCD012<35> @BASEBOARD_FAB2_LIB.BASEBOARD_FAB2(SCH_1):PVDDQ_GHJ
 Y47 PVDDQ_GHJ VCCD012<34> @BASEBOARD_FAB2_LIB.BASEBOARD_FAB2(SCH_1):PVDDQ_GHJ
 Y45 PVDDQ_GHJ VCCD012<33> @BASEBOARD_FAB2_LIB.BASEBOARD_FAB2(SCH_1):PVDDQ_GHJ
 W64 PVDDQ_GHJ VCCD012<32> @BASEBOARD_FAB2_LIB.BASEBOARD_FAB2(SCH_1):PVDDQ_GHJ
 U62 PVDDQ_GHJ VCCD012<31> @BASEBOARD_FAB2_LIB.BASEBOARD_FAB2(SCH_1):PVDDQ_GHJ
 U60 PVDDQ_GHJ VCCD012<30> @BASEBOARD_FAB2_LIB.BASEBOARD_FAB2(SCH_1):PVDDQ_GHJ
 U58 PVDDQ_GHJ VCCD012<29> @BASEBOARD_FAB2_LIB.BASEBOARD_FAB2(SCH_1):PVDDQ_GHJ
 U56 PVDDQ_GHJ VCCD012<28> @BASEBOARD_FAB2_LIB.BASEBOARD_FAB2(SCH_1):PVDDQ_GHJ
 U54 PVDDQ_GHJ VCCD012<27> @BASEBOARD_FAB2_LIB.BASEBOARD_FAB2(SCH_1):PVDDQ_GHJ
 U52 PVDDQ_GHJ VCCD012<26> @BASEBOARD_FAB2_LIB.BASEBOARD_FAB2(SCH_1):PVDDQ_GHJ
 U50 PVDDQ_GHJ VCCD012<25> @BASEBOARD_FAB2_LIB.BASEBOARD_FAB2(SCH_1):PVDDQ_GHJ
 U48 PVDDQ_GHJ VCCD012<24> @BASEBOARD_FAB2_LIB.BASEBOARD_FAB2(SCH_1):PVDDQ_GHJ
 U46 PVDDQ_GHJ VCCD012<23> @BASEBOARD_FAB2_LIB.BASEBOARD_FAB2(SCH_1):PVDDQ_GHJ
 N64 PVDDQ_GHJ VCCD012<22> @BASEBOARD_FAB2_LIB.BASEBOARD_FAB2(SCH_1):PVDDQ_GHJ
 L62 PVDDQ_GHJ VCCD012<21> @BASEBOARD_FAB2_LIB.BASEBOARD_FAB2(SCH_1):PVDDQ_GHJ
 L60 PVDDQ_GHJ VCCD012<20> @BASEBOARD_FAB2_LIB.BASEBOARD_FAB2(SCH_1):PVDDQ_GHJ
 L58 PVDDQ_GHJ VCCD012<19> @BASEBOARD_FAB2_LIB.BASEBOARD_FAB2(SCH_1):PVDDQ_GHJ
 L56 PVDDQ_GHJ VCCD012<18> @BASEBOARD_FAB2_LIB.BASEBOARD_FAB2(SCH_1):PVDDQ_GHJ
 L54 PVDDQ_GHJ VCCD012<17> @BASEBOARD_FAB2_LIB.BASEBOARD_FAB2(SCH_1):PVDDQ_GHJ
 L52 PVDDQ_GHJ VCCD012<16> @BASEBOARD_FAB2_LIB.BASEBOARD_FAB2(SCH_1):PVDDQ_GHJ
 L50 PVDDQ_GHJ VCCD012<15> @BASEBOARD_FAB2_LIB.BASEBOARD_FAB2(SCH_1):PVDDQ_GHJ
 L48 PVDDQ_GHJ VCCD012<14> @BASEBOARD_FAB2_LIB.BASEBOARD_FAB2(SCH_1):PVDDQ_GHJ
 L46 PVDDQ_GHJ VCCD012<13> @BASEBOARD_FAB2_LIB.BASEBOARD_FAB2(SCH_1):PVDDQ_GHJ
 E64 PVDDQ_GHJ VCCD012<12> @BASEBOARD_FAB2_LIB.BASEBOARD_FAB2(SCH_1):PVDDQ_GHJ
 E62 PVDDQ_GHJ VCCD012<11> @BASEBOARD_FAB2_LIB.BASEBOARD_FAB2(SCH_1):PVDDQ_GHJ
 E60 PVDDQ_GHJ VCCD012<10> @BASEBOARD_FAB2_LIB.BASEBOARD_FAB2(SCH_1):PVDDQ_GHJ
 E58 PVDDQ_GHJ VCCD012<9> @BASEBOARD_FAB2_LIB.BASEBOARD_FAB2(SCH_1):PVDDQ_GHJ
 E56 PVDDQ_GHJ VCCD012<8> @BASEBOARD_FAB2_LIB.BASEBOARD_FAB2(SCH_1):PVDDQ_GHJ
 E54 PVDDQ_GHJ VCCD012<7> @BASEBOARD_FAB2_LIB.BASEBOARD_FAB2(SCH_1):PVDDQ_GHJ
 E52 PVDDQ_GHJ VCCD012<6> @BASEBOARD_FAB2_LIB.BASEBOARD_FAB2(SCH_1):PVDDQ_GHJ
 E50 PVDDQ_GHJ VCCD012<5> @BASEBOARD_FAB2_LIB.BASEBOARD_FAB2(SCH_1):PVDDQ_GHJ
 E48 PVDDQ_GHJ VCCD012<4> @BASEBOARD_FAB2_LIB.BASEBOARD_FAB2(SCH_1):PVDDQ_GHJ
 E46 PVDDQ_GHJ VCCD012<3> @BASEBOARD_FAB2_LIB.BASEBOARD_FAB2(SCH_1):PVDDQ_GHJ
 B59 PVDDQ_GHJ VCCD012<2> @BASEBOARD_FAB2_LIB.BASEBOARD_FAB2(SCH_1):PVDDQ_GHJ
 B53 PVDDQ_GHJ VCCD012<1> @BASEBOARD_FAB2_LIB.BASEBOARD_FAB2(SCH_1):PVDDQ_GHJ
 B49 PVDDQ_GHJ VCCD012<0> @BASEBOARD_FAB2_LIB.BASEBOARD_FAB2(SCH_1):PVDDQ_GHJ
EE44 PVDDQ_KLM VCCD345<50> @BASEBOARD_FAB2_LIB.BASEBOARD_FAB2(SCH_1):PVDDQ_KLM
EF45 PVDDQ_KLM VCCD345<49> @BASEBOARD_FAB2_LIB.BASEBOARD_FAB2(SCH_1):PVDDQ_KLM
DB53 PVDDQ_KLM VCCD345<48> @BASEBOARD_FAB2_LIB.BASEBOARD_FAB2(SCH_1):PVDDQ_KLM
DB55 PVDDQ_KLM VCCD345<47> @BASEBOARD_FAB2_LIB.BASEBOARD_FAB2(SCH_1):PVDDQ_KLM
DB57 PVDDQ_KLM VCCD345<46> @BASEBOARD_FAB2_LIB.BASEBOARD_FAB2(SCH_1):PVDDQ_KLM
DB59 PVDDQ_KLM VCCD345<45> @BASEBOARD_FAB2_LIB.BASEBOARD_FAB2(SCH_1):PVDDQ_KLM
DB61 PVDDQ_KLM VCCD345<44> @BASEBOARD_FAB2_LIB.BASEBOARD_FAB2(SCH_1):PVDDQ_KLM
DB63 PVDDQ_KLM VCCD345<43> @BASEBOARD_FAB2_LIB.BASEBOARD_FAB2(SCH_1):PVDDQ_KLM
DD45 PVDDQ_KLM VCCD345<42> @BASEBOARD_FAB2_LIB.BASEBOARD_FAB2(SCH_1):PVDDQ_KLM
DH45 PVDDQ_KLM VCCD345<41> @BASEBOARD_FAB2_LIB.BASEBOARD_FAB2(SCH_1):PVDDQ_KLM
DH47 PVDDQ_KLM VCCD345<40> @BASEBOARD_FAB2_LIB.BASEBOARD_FAB2(SCH_1):PVDDQ_KLM
DH49 PVDDQ_KLM VCCD345<39> @BASEBOARD_FAB2_LIB.BASEBOARD_FAB2(SCH_1):PVDDQ_KLM
DH51 PVDDQ_KLM VCCD345<38> @BASEBOARD_FAB2_LIB.BASEBOARD_FAB2(SCH_1):PVDDQ_KLM
DH53 PVDDQ_KLM VCCD345<37> @BASEBOARD_FAB2_LIB.BASEBOARD_FAB2(SCH_1):PVDDQ_KLM
DH55 PVDDQ_KLM VCCD345<36> @BASEBOARD_FAB2_LIB.BASEBOARD_FAB2(SCH_1):PVDDQ_KLM
DH57 PVDDQ_KLM VCCD345<35> @BASEBOARD_FAB2_LIB.BASEBOARD_FAB2(SCH_1):PVDDQ_KLM
DH59 PVDDQ_KLM VCCD345<34> @BASEBOARD_FAB2_LIB.BASEBOARD_FAB2(SCH_1):PVDDQ_KLM
DH61 PVDDQ_KLM VCCD345<33> @BASEBOARD_FAB2_LIB.BASEBOARD_FAB2(SCH_1):PVDDQ_KLM
DH63 PVDDQ_KLM VCCD345<32> @BASEBOARD_FAB2_LIB.BASEBOARD_FAB2(SCH_1):PVDDQ_KLM
DJ64 PVDDQ_KLM VCCD345<31> @BASEBOARD_FAB2_LIB.BASEBOARD_FAB2(SCH_1):PVDDQ_KLM
DL46 PVDDQ_KLM VCCD345<30> @BASEBOARD_FAB2_LIB.BASEBOARD_FAB2(SCH_1):PVDDQ_KLM
DL48 PVDDQ_KLM VCCD345<29> @BASEBOARD_FAB2_LIB.BASEBOARD_FAB2(SCH_1):PVDDQ_KLM
DL50 PVDDQ_KLM VCCD345<28> @BASEBOARD_FAB2_LIB.BASEBOARD_FAB2(SCH_1):PVDDQ_KLM
DL52 PVDDQ_KLM VCCD345<27> @BASEBOARD_FAB2_LIB.BASEBOARD_FAB2(SCH_1):PVDDQ_KLM
DL54 PVDDQ_KLM VCCD345<26> @BASEBOARD_FAB2_LIB.BASEBOARD_FAB2(SCH_1):PVDDQ_KLM
DL56 PVDDQ_KLM VCCD345<25> @BASEBOARD_FAB2_LIB.BASEBOARD_FAB2(SCH_1):PVDDQ_KLM
DL58 PVDDQ_KLM VCCD345<24> @BASEBOARD_FAB2_LIB.BASEBOARD_FAB2(SCH_1):PVDDQ_KLM
DL60 PVDDQ_KLM VCCD345<23> @BASEBOARD_FAB2_LIB.BASEBOARD_FAB2(SCH_1):PVDDQ_KLM
DL62 PVDDQ_KLM VCCD345<22> @BASEBOARD_FAB2_LIB.BASEBOARD_FAB2(SCH_1):PVDDQ_KLM
DU46 PVDDQ_KLM VCCD345<21> @BASEBOARD_FAB2_LIB.BASEBOARD_FAB2(SCH_1):PVDDQ_KLM
DU48 PVDDQ_KLM VCCD345<20> @BASEBOARD_FAB2_LIB.BASEBOARD_FAB2(SCH_1):PVDDQ_KLM
DU50 PVDDQ_KLM VCCD345<19> @BASEBOARD_FAB2_LIB.BASEBOARD_FAB2(SCH_1):PVDDQ_KLM
DU52 PVDDQ_KLM VCCD345<18> @BASEBOARD_FAB2_LIB.BASEBOARD_FAB2(SCH_1):PVDDQ_KLM
DU54 PVDDQ_KLM VCCD345<17> @BASEBOARD_FAB2_LIB.BASEBOARD_FAB2(SCH_1):PVDDQ_KLM
DU56 PVDDQ_KLM VCCD345<16> @BASEBOARD_FAB2_LIB.BASEBOARD_FAB2(SCH_1):PVDDQ_KLM
DU58 PVDDQ_KLM VCCD345<15> @BASEBOARD_FAB2_LIB.BASEBOARD_FAB2(SCH_1):PVDDQ_KLM
DU60 PVDDQ_KLM VCCD345<14> @BASEBOARD_FAB2_LIB.BASEBOARD_FAB2(SCH_1):PVDDQ_KLM
DU62 PVDDQ_KLM VCCD345<13> @BASEBOARD_FAB2_LIB.BASEBOARD_FAB2(SCH_1):PVDDQ_KLM
DU64 PVDDQ_KLM VCCD345<12> @BASEBOARD_FAB2_LIB.BASEBOARD_FAB2(SCH_1):PVDDQ_KLM
EC46 PVDDQ_KLM VCCD345<11> @BASEBOARD_FAB2_LIB.BASEBOARD_FAB2(SCH_1):PVDDQ_KLM
EC48 PVDDQ_KLM VCCD345<10> @BASEBOARD_FAB2_LIB.BASEBOARD_FAB2(SCH_1):PVDDQ_KLM
EC50 PVDDQ_KLM VCCD345<9> @BASEBOARD_FAB2_LIB.BASEBOARD_FAB2(SCH_1):PVDDQ_KLM
EC52 PVDDQ_KLM VCCD345<8> @BASEBOARD_FAB2_LIB.BASEBOARD_FAB2(SCH_1):PVDDQ_KLM
EC54 PVDDQ_KLM VCCD345<7> @BASEBOARD_FAB2_LIB.BASEBOARD_FAB2(SCH_1):PVDDQ_KLM
EC56 PVDDQ_KLM VCCD345<6> @BASEBOARD_FAB2_LIB.BASEBOARD_FAB2(SCH_1):PVDDQ_KLM
EC58 PVDDQ_KLM VCCD345<5> @BASEBOARD_FAB2_LIB.BASEBOARD_FAB2(SCH_1):PVDDQ_KLM
EC60 PVDDQ_KLM VCCD345<4> @BASEBOARD_FAB2_LIB.BASEBOARD_FAB2(SCH_1):PVDDQ_KLM
EC62 PVDDQ_KLM VCCD345<3> @BASEBOARD_FAB2_LIB.BASEBOARD_FAB2(SCH_1):PVDDQ_KLM
EF49 PVDDQ_KLM VCCD345<2> @BASEBOARD_FAB2_LIB.BASEBOARD_FAB2(SCH_1):PVDDQ_KLM
EF53 PVDDQ_KLM VCCD345<1> @BASEBOARD_FAB2_LIB.BASEBOARD_FAB2(SCH_1):PVDDQ_KLM
EF59 PVDDQ_KLM VCCD345<0> @BASEBOARD_FAB2_LIB.BASEBOARD_FAB2(SCH_1):PVDDQ_KLM

SKX_EXT_B_BGA1-IC,TBD  I33  U2D1
BY27 P1V8_MCP_CPU1 CD_VCCIN<3> @BASEBOARD_FAB2_LIB.BASEBOARD_FAB2(SCH_1):P1V8_MCP_CPU1
BV27 P1V8_MCP_CPU1 CD_VCCIN<2> @BASEBOARD_FAB2_LIB.BASEBOARD_FAB2(SCH_1):P1V8_MCP_CPU1
BU26 P1V8_MCP_CPU1 CD_VCCIN<1> @BASEBOARD_FAB2_LIB.BASEBOARD_FAB2(SCH_1):P1V8_MCP_CPU1
BT27 P1V8_MCP_CPU1 CD_VCCIN<0> @BASEBOARD_FAB2_LIB.BASEBOARD_FAB2(SCH_1):P1V8_MCP_CPU1
BM11 PVCCIOMCP_CPU1 CD_VCCP<15> @BASEBOARD_FAB2_LIB.BASEBOARD_FAB2(SCH_1):PVCCIOMCP_CPU1
BN12 PVCCIOMCP_CPU1 CD_VCCP<14> @BASEBOARD_FAB2_LIB.BASEBOARD_FAB2(SCH_1):PVCCIOMCP_CPU1
BN14 PVCCIOMCP_CPU1 CD_VCCP<13> @BASEBOARD_FAB2_LIB.BASEBOARD_FAB2(SCH_1):PVCCIOMCP_CPU1
BP11 PVCCIOMCP_CPU1 CD_VCCP<12> @BASEBOARD_FAB2_LIB.BASEBOARD_FAB2(SCH_1):PVCCIOMCP_CPU1
BP13 PVCCIOMCP_CPU1 CD_VCCP<11> @BASEBOARD_FAB2_LIB.BASEBOARD_FAB2(SCH_1):PVCCIOMCP_CPU1
BP15 PVCCIOMCP_CPU1 CD_VCCP<10> @BASEBOARD_FAB2_LIB.BASEBOARD_FAB2(SCH_1):PVCCIOMCP_CPU1
BR12 PVCCIOMCP_CPU1 CD_VCCP<9> @BASEBOARD_FAB2_LIB.BASEBOARD_FAB2(SCH_1):PVCCIOMCP_CPU1
BR14 PVCCIOMCP_CPU1 CD_VCCP<8> @BASEBOARD_FAB2_LIB.BASEBOARD_FAB2(SCH_1):PVCCIOMCP_CPU1
BT11 PVCCIOMCP_CPU1 CD_VCCP<7> @BASEBOARD_FAB2_LIB.BASEBOARD_FAB2(SCH_1):PVCCIOMCP_CPU1
BT13 PVCCIOMCP_CPU1 CD_VCCP<6> @BASEBOARD_FAB2_LIB.BASEBOARD_FAB2(SCH_1):PVCCIOMCP_CPU1
BT15 PVCCIOMCP_CPU1 CD_VCCP<5> @BASEBOARD_FAB2_LIB.BASEBOARD_FAB2(SCH_1):PVCCIOMCP_CPU1
BU12 PVCCIOMCP_CPU1 CD_VCCP<4> @BASEBOARD_FAB2_LIB.BASEBOARD_FAB2(SCH_1):PVCCIOMCP_CPU1
BU14 PVCCIOMCP_CPU1 CD_VCCP<3> @BASEBOARD_FAB2_LIB.BASEBOARD_FAB2(SCH_1):PVCCIOMCP_CPU1
BV11 PVCCIOMCP_CPU1 CD_VCCP<2> @BASEBOARD_FAB2_LIB.BASEBOARD_FAB2(SCH_1):PVCCIOMCP_CPU1
BV13 PVCCIOMCP_CPU1 CD_VCCP<1> @BASEBOARD_FAB2_LIB.BASEBOARD_FAB2(SCH_1):PVCCIOMCP_CPU1
BV15 PVCCIOMCP_CPU1 CD_VCCP<0> @BASEBOARD_FAB2_LIB.BASEBOARD_FAB2(SCH_1):PVCCIOMCP_CPU1
BD13 PVCCMCP_CPU1 CD_VCC_CORE<12> @BASEBOARD_FAB2_LIB.BASEBOARD_FAB2(SCH_1):PVCCMCP_CPU1
BE12 PVCCMCP_CPU1 CD_VCC_CORE<11> @BASEBOARD_FAB2_LIB.BASEBOARD_FAB2(SCH_1):PVCCMCP_CPU1
BE14 PVCCMCP_CPU1 CD_VCC_CORE<10> @BASEBOARD_FAB2_LIB.BASEBOARD_FAB2(SCH_1):PVCCMCP_CPU1
BF11 PVCCMCP_CPU1 CD_VCC_CORE<9> @BASEBOARD_FAB2_LIB.BASEBOARD_FAB2(SCH_1):PVCCMCP_CPU1
BF13 PVCCMCP_CPU1 CD_VCC_CORE<8> @BASEBOARD_FAB2_LIB.BASEBOARD_FAB2(SCH_1):PVCCMCP_CPU1
BG12 PVCCMCP_CPU1 CD_VCC_CORE<7> @BASEBOARD_FAB2_LIB.BASEBOARD_FAB2(SCH_1):PVCCMCP_CPU1
BG14 PVCCMCP_CPU1 CD_VCC_CORE<6> @BASEBOARD_FAB2_LIB.BASEBOARD_FAB2(SCH_1):PVCCMCP_CPU1
BH13 PVCCMCP_CPU1 CD_VCC_CORE<5> @BASEBOARD_FAB2_LIB.BASEBOARD_FAB2(SCH_1):PVCCMCP_CPU1
BJ12 PVCCMCP_CPU1 CD_VCC_CORE<4> @BASEBOARD_FAB2_LIB.BASEBOARD_FAB2(SCH_1):PVCCMCP_CPU1
BJ14 PVCCMCP_CPU1 CD_VCC_CORE<3> @BASEBOARD_FAB2_LIB.BASEBOARD_FAB2(SCH_1):PVCCMCP_CPU1
BK13 PVCCMCP_CPU1 CD_VCC_CORE<2> @BASEBOARD_FAB2_LIB.BASEBOARD_FAB2(SCH_1):PVCCMCP_CPU1
BK15 PVCCMCP_CPU1 CD_VCC_CORE<1> @BASEBOARD_FAB2_LIB.BASEBOARD_FAB2(SCH_1):PVCCMCP_CPU1
BL14 PVCCMCP_CPU1 CD_VCC_CORE<0> @BASEBOARD_FAB2_LIB.BASEBOARD_FAB2(SCH_1):PVCCMCP_CPU1
  A8 PVPP_GHJ CD_VPP<3> @BASEBOARD_FAB2_LIB.BASEBOARD_FAB2(SCH_1):PVPP_GHJ
 A10 PVPP_GHJ CD_VPP<2> @BASEBOARD_FAB2_LIB.BASEBOARD_FAB2(SCH_1):PVPP_GHJ
 A12 PVPP_GHJ CD_VPP<1> @BASEBOARD_FAB2_LIB.BASEBOARD_FAB2(SCH_1):PVPP_GHJ
 B11 PVPP_GHJ CD_VPP<0> @BASEBOARD_FAB2_LIB.BASEBOARD_FAB2(SCH_1):PVPP_GHJ
CY55 P3V3_STBY  VCC33 @BASEBOARD_FAB2_LIB.BASEBOARD_FAB2(SCH_1):P3V3_STBY
AR28 PVCCIO_CPU1 VCCIO<104> @BASEBOARD_FAB2_LIB.BASEBOARD_FAB2(SCH_1):PVCCIO_CPU1
AL28 PVCCIO_CPU1 VCCIO<103> @BASEBOARD_FAB2_LIB.BASEBOARD_FAB2(SCH_1):PVCCIO_CPU1
AM29 PVCCIO_CPU1 VCCIO<102> @BASEBOARD_FAB2_LIB.BASEBOARD_FAB2(SCH_1):PVCCIO_CPU1
AG34 PVCCIO_CPU1 VCCIO<101> @BASEBOARD_FAB2_LIB.BASEBOARD_FAB2(SCH_1):PVCCIO_CPU1
AE34 PVCCIO_CPU1 VCCIO<100> @BASEBOARD_FAB2_LIB.BASEBOARD_FAB2(SCH_1):PVCCIO_CPU1
AD35 PVCCIO_CPU1 VCCIO<99> @BASEBOARD_FAB2_LIB.BASEBOARD_FAB2(SCH_1):PVCCIO_CPU1
AF35 PVCCIO_CPU1 VCCIO<98> @BASEBOARD_FAB2_LIB.BASEBOARD_FAB2(SCH_1):PVCCIO_CPU1
AC36 PVCCIO_CPU1 VCCIO<97> @BASEBOARD_FAB2_LIB.BASEBOARD_FAB2(SCH_1):PVCCIO_CPU1
AD37 PVCCIO_CPU1 VCCIO<96> @BASEBOARD_FAB2_LIB.BASEBOARD_FAB2(SCH_1):PVCCIO_CPU1
AE36 PVCCIO_CPU1 VCCIO<95> @BASEBOARD_FAB2_LIB.BASEBOARD_FAB2(SCH_1):PVCCIO_CPU1
BF27 PVCCIO_CPU1 VCCIO<94> @BASEBOARD_FAB2_LIB.BASEBOARD_FAB2(SCH_1):PVCCIO_CPU1
BG26 PVCCIO_CPU1 VCCIO<93> @BASEBOARD_FAB2_LIB.BASEBOARD_FAB2(SCH_1):PVCCIO_CPU1
BH25 PVCCIO_CPU1 VCCIO<92> @BASEBOARD_FAB2_LIB.BASEBOARD_FAB2(SCH_1):PVCCIO_CPU1
BH27 PVCCIO_CPU1 VCCIO<91> @BASEBOARD_FAB2_LIB.BASEBOARD_FAB2(SCH_1):PVCCIO_CPU1
BJ26 PVCCIO_CPU1 VCCIO<90> @BASEBOARD_FAB2_LIB.BASEBOARD_FAB2(SCH_1):PVCCIO_CPU1
BK25 PVCCIO_CPU1 VCCIO<89> @BASEBOARD_FAB2_LIB.BASEBOARD_FAB2(SCH_1):PVCCIO_CPU1
BK27 PVCCIO_CPU1 VCCIO<88> @BASEBOARD_FAB2_LIB.BASEBOARD_FAB2(SCH_1):PVCCIO_CPU1
BL26 PVCCIO_CPU1 VCCIO<87> @BASEBOARD_FAB2_LIB.BASEBOARD_FAB2(SCH_1):PVCCIO_CPU1
BM27 PVCCIO_CPU1 VCCIO<86> @BASEBOARD_FAB2_LIB.BASEBOARD_FAB2(SCH_1):PVCCIO_CPU1
CH27 PVCCIO_CPU1 VCCIO<85> @BASEBOARD_FAB2_LIB.BASEBOARD_FAB2(SCH_1):PVCCIO_CPU1
CJ28 PVCCIO_CPU1 VCCIO<84> @BASEBOARD_FAB2_LIB.BASEBOARD_FAB2(SCH_1):PVCCIO_CPU1
CC26 PVCCIO_CPU1 VCCIO<83> @BASEBOARD_FAB2_LIB.BASEBOARD_FAB2(SCH_1):PVCCIO_CPU1
CD27 PVCCIO_CPU1 VCCIO<82> @BASEBOARD_FAB2_LIB.BASEBOARD_FAB2(SCH_1):PVCCIO_CPU1
CF27 PVCCIO_CPU1 VCCIO<81> @BASEBOARD_FAB2_LIB.BASEBOARD_FAB2(SCH_1):PVCCIO_CPU1
AV27 PVCCIO_CPU1 VCCIO<80> @BASEBOARD_FAB2_LIB.BASEBOARD_FAB2(SCH_1):PVCCIO_CPU1
AW26 PVCCIO_CPU1 VCCIO<79> @BASEBOARD_FAB2_LIB.BASEBOARD_FAB2(SCH_1):PVCCIO_CPU1
AY27 PVCCIO_CPU1 VCCIO<78> @BASEBOARD_FAB2_LIB.BASEBOARD_FAB2(SCH_1):PVCCIO_CPU1
BA26 PVCCIO_CPU1 VCCIO<77> @BASEBOARD_FAB2_LIB.BASEBOARD_FAB2(SCH_1):PVCCIO_CPU1
BB27 PVCCIO_CPU1 VCCIO<76> @BASEBOARD_FAB2_LIB.BASEBOARD_FAB2(SCH_1):PVCCIO_CPU1
BC26 PVCCIO_CPU1 VCCIO<75> @BASEBOARD_FAB2_LIB.BASEBOARD_FAB2(SCH_1):PVCCIO_CPU1
 W10 PVCCIO_CPU1 VCCIO<74> @BASEBOARD_FAB2_LIB.BASEBOARD_FAB2(SCH_1):PVCCIO_CPU1
 N18 PVCCIO_CPU1 VCCIO<73> @BASEBOARD_FAB2_LIB.BASEBOARD_FAB2(SCH_1):PVCCIO_CPU1
  M9 PVCCIO_CPU1 VCCIO<72> @BASEBOARD_FAB2_LIB.BASEBOARD_FAB2(SCH_1):PVCCIO_CPU1
  M7 PVCCIO_CPU1 VCCIO<71> @BASEBOARD_FAB2_LIB.BASEBOARD_FAB2(SCH_1):PVCCIO_CPU1
 K15 PVCCIO_CPU1 VCCIO<70> @BASEBOARD_FAB2_LIB.BASEBOARD_FAB2(SCH_1):PVCCIO_CPU1
  J2 PVCCIO_CPU1 VCCIO<69> @BASEBOARD_FAB2_LIB.BASEBOARD_FAB2(SCH_1):PVCCIO_CPU1
EB15 PVCCIO_CPU1 VCCIO<68> @BASEBOARD_FAB2_LIB.BASEBOARD_FAB2(SCH_1):PVCCIO_CPU1
EA12 PVCCIO_CPU1 VCCIO<67> @BASEBOARD_FAB2_LIB.BASEBOARD_FAB2(SCH_1):PVCCIO_CPU1
DU20 PVCCIO_CPU1 VCCIO<66> @BASEBOARD_FAB2_LIB.BASEBOARD_FAB2(SCH_1):PVCCIO_CPU1
 DR2 PVCCIO_CPU1 VCCIO<65> @BASEBOARD_FAB2_LIB.BASEBOARD_FAB2(SCH_1):PVCCIO_CPU1
DR10 PVCCIO_CPU1 VCCIO<64> @BASEBOARD_FAB2_LIB.BASEBOARD_FAB2(SCH_1):PVCCIO_CPU1
DP19 PVCCIO_CPU1 VCCIO<63> @BASEBOARD_FAB2_LIB.BASEBOARD_FAB2(SCH_1):PVCCIO_CPU1
 DN8 PVCCIO_CPU1 VCCIO<62> @BASEBOARD_FAB2_LIB.BASEBOARD_FAB2(SCH_1):PVCCIO_CPU1
DM17 PVCCIO_CPU1 VCCIO<61> @BASEBOARD_FAB2_LIB.BASEBOARD_FAB2(SCH_1):PVCCIO_CPU1
DJ16 PVCCIO_CPU1 VCCIO<60> @BASEBOARD_FAB2_LIB.BASEBOARD_FAB2(SCH_1):PVCCIO_CPU1
 H13 PVCCIO_CPU1 VCCIO<59> @BASEBOARD_FAB2_LIB.BASEBOARD_FAB2(SCH_1):PVCCIO_CPU1
 J10 PVCCIO_CPU1 VCCIO<58> @BASEBOARD_FAB2_LIB.BASEBOARD_FAB2(SCH_1):PVCCIO_CPU1
 L14 PVCCIO_CPU1 VCCIO<57> @BASEBOARD_FAB2_LIB.BASEBOARD_FAB2(SCH_1):PVCCIO_CPU1
 L16 PVCCIO_CPU1 VCCIO<56> @BASEBOARD_FAB2_LIB.BASEBOARD_FAB2(SCH_1):PVCCIO_CPU1
 DH7 PVCCIO_CPU1 VCCIO<55> @BASEBOARD_FAB2_LIB.BASEBOARD_FAB2(SCH_1):PVCCIO_CPU1
 DG8 PVCCIO_CPU1 VCCIO<54> @BASEBOARD_FAB2_LIB.BASEBOARD_FAB2(SCH_1):PVCCIO_CPU1
 M11 PVCCIO_CPU1 VCCIO<53> @BASEBOARD_FAB2_LIB.BASEBOARD_FAB2(SCH_1):PVCCIO_CPU1
 M21 PVCCIO_CPU1 VCCIO<52> @BASEBOARD_FAB2_LIB.BASEBOARD_FAB2(SCH_1):PVCCIO_CPU1
  P5 PVCCIO_CPU1 VCCIO<51> @BASEBOARD_FAB2_LIB.BASEBOARD_FAB2(SCH_1):PVCCIO_CPU1
  T3 PVCCIO_CPU1 VCCIO<50> @BASEBOARD_FAB2_LIB.BASEBOARD_FAB2(SCH_1):PVCCIO_CPU1
 U14 PVCCIO_CPU1 VCCIO<49> @BASEBOARD_FAB2_LIB.BASEBOARD_FAB2(SCH_1):PVCCIO_CPU1
DF21 PVCCIO_CPU1 VCCIO<48> @BASEBOARD_FAB2_LIB.BASEBOARD_FAB2(SCH_1):PVCCIO_CPU1
  W4 PVCCIO_CPU1 VCCIO<47> @BASEBOARD_FAB2_LIB.BASEBOARD_FAB2(SCH_1):PVCCIO_CPU1
  W6 PVCCIO_CPU1 VCCIO<46> @BASEBOARD_FAB2_LIB.BASEBOARD_FAB2(SCH_1):PVCCIO_CPU1
AA10 PVCCIO_CPU1 VCCIO<45> @BASEBOARD_FAB2_LIB.BASEBOARD_FAB2(SCH_1):PVCCIO_CPU1
AC20 PVCCIO_CPU1 VCCIO<44> @BASEBOARD_FAB2_LIB.BASEBOARD_FAB2(SCH_1):PVCCIO_CPU1
 AC4 PVCCIO_CPU1 VCCIO<43> @BASEBOARD_FAB2_LIB.BASEBOARD_FAB2(SCH_1):PVCCIO_CPU1
 AH9 PVCCIO_CPU1 VCCIO<42> @BASEBOARD_FAB2_LIB.BASEBOARD_FAB2(SCH_1):PVCCIO_CPU1
DF13 PVCCIO_CPU1 VCCIO<41> @BASEBOARD_FAB2_LIB.BASEBOARD_FAB2(SCH_1):PVCCIO_CPU1
AN10 PVCCIO_CPU1 VCCIO<40> @BASEBOARD_FAB2_LIB.BASEBOARD_FAB2(SCH_1):PVCCIO_CPU1
 DD7 PVCCIO_CPU1 VCCIO<39> @BASEBOARD_FAB2_LIB.BASEBOARD_FAB2(SCH_1):PVCCIO_CPU1
AT11 PVCCIO_CPU1 VCCIO<38> @BASEBOARD_FAB2_LIB.BASEBOARD_FAB2(SCH_1):PVCCIO_CPU1
 AW6 PVCCIO_CPU1 VCCIO<37> @BASEBOARD_FAB2_LIB.BASEBOARD_FAB2(SCH_1):PVCCIO_CPU1
AY11 PVCCIO_CPU1 VCCIO<36> @BASEBOARD_FAB2_LIB.BASEBOARD_FAB2(SCH_1):PVCCIO_CPU1
BA24 PVCCIO_CPU1 VCCIO<35> @BASEBOARD_FAB2_LIB.BASEBOARD_FAB2(SCH_1):PVCCIO_CPU1
 BB5 PVCCIO_CPU1 VCCIO<34> @BASEBOARD_FAB2_LIB.BASEBOARD_FAB2(SCH_1):PVCCIO_CPU1
DA14 PVCCIO_CPU1 VCCIO<33> @BASEBOARD_FAB2_LIB.BASEBOARD_FAB2(SCH_1):PVCCIO_CPU1
BF23 PVCCIO_CPU1 VCCIO<32> @BASEBOARD_FAB2_LIB.BASEBOARD_FAB2(SCH_1):PVCCIO_CPU1
BJ24 PVCCIO_CPU1 VCCIO<31> @BASEBOARD_FAB2_LIB.BASEBOARD_FAB2(SCH_1):PVCCIO_CPU1
BP25 PVCCIO_CPU1 VCCIO<30> @BASEBOARD_FAB2_LIB.BASEBOARD_FAB2(SCH_1):PVCCIO_CPU1
CB13 PVCCIO_CPU1 VCCIO<29> @BASEBOARD_FAB2_LIB.BASEBOARD_FAB2(SCH_1):PVCCIO_CPU1
CB17 PVCCIO_CPU1 VCCIO<28> @BASEBOARD_FAB2_LIB.BASEBOARD_FAB2(SCH_1):PVCCIO_CPU1
 CD9 PVCCIO_CPU1 VCCIO<27> @BASEBOARD_FAB2_LIB.BASEBOARD_FAB2(SCH_1):PVCCIO_CPU1
CE18 PVCCIO_CPU1 VCCIO<26> @BASEBOARD_FAB2_LIB.BASEBOARD_FAB2(SCH_1):PVCCIO_CPU1
  D7 PVCCIO_CPU1 VCCIO<25> @BASEBOARD_FAB2_LIB.BASEBOARD_FAB2(SCH_1):PVCCIO_CPU1
 CH9 PVCCIO_CPU1 VCCIO<24> @BASEBOARD_FAB2_LIB.BASEBOARD_FAB2(SCH_1):PVCCIO_CPU1
 CV7 PVCCIO_CPU1 VCCIO<23> @BASEBOARD_FAB2_LIB.BASEBOARD_FAB2(SCH_1):PVCCIO_CPU1
 CK5 PVCCIO_CPU1 VCCIO<22> @BASEBOARD_FAB2_LIB.BASEBOARD_FAB2(SCH_1):PVCCIO_CPU1
CL12 PVCCIO_CPU1 VCCIO<21> @BASEBOARD_FAB2_LIB.BASEBOARD_FAB2(SCH_1):PVCCIO_CPU1
CM15 PVCCIO_CPU1 VCCIO<20> @BASEBOARD_FAB2_LIB.BASEBOARD_FAB2(SCH_1):PVCCIO_CPU1
CB65 PVSA_CPU1 VCCSA<25> @BASEBOARD_FAB2_LIB.BASEBOARD_FAB2(SCH_1):PVSA_CPU1
CB67 PVSA_CPU1 VCCSA<24> @BASEBOARD_FAB2_LIB.BASEBOARD_FAB2(SCH_1):PVSA_CPU1
CB69 PVSA_CPU1 VCCSA<23> @BASEBOARD_FAB2_LIB.BASEBOARD_FAB2(SCH_1):PVSA_CPU1
CC66 PVSA_CPU1 VCCSA<22> @BASEBOARD_FAB2_LIB.BASEBOARD_FAB2(SCH_1):PVSA_CPU1
CC68 PVSA_CPU1 VCCSA<21> @BASEBOARD_FAB2_LIB.BASEBOARD_FAB2(SCH_1):PVSA_CPU1
CC70 PVSA_CPU1 VCCSA<20> @BASEBOARD_FAB2_LIB.BASEBOARD_FAB2(SCH_1):PVSA_CPU1
CD65 PVSA_CPU1 VCCSA<19> @BASEBOARD_FAB2_LIB.BASEBOARD_FAB2(SCH_1):PVSA_CPU1
CD67 PVSA_CPU1 VCCSA<18> @BASEBOARD_FAB2_LIB.BASEBOARD_FAB2(SCH_1):PVSA_CPU1
CD69 PVSA_CPU1 VCCSA<17> @BASEBOARD_FAB2_LIB.BASEBOARD_FAB2(SCH_1):PVSA_CPU1
CD71 PVSA_CPU1 VCCSA<16> @BASEBOARD_FAB2_LIB.BASEBOARD_FAB2(SCH_1):PVSA_CPU1
CE64 PVSA_CPU1 VCCSA<15> @BASEBOARD_FAB2_LIB.BASEBOARD_FAB2(SCH_1):PVSA_CPU1
CE66 PVSA_CPU1 VCCSA<14> @BASEBOARD_FAB2_LIB.BASEBOARD_FAB2(SCH_1):PVSA_CPU1
CE68 PVSA_CPU1 VCCSA<13> @BASEBOARD_FAB2_LIB.BASEBOARD_FAB2(SCH_1):PVSA_CPU1
CE72 PVSA_CPU1 VCCSA<12> @BASEBOARD_FAB2_LIB.BASEBOARD_FAB2(SCH_1):PVSA_CPU1
CE74 PVSA_CPU1 VCCSA<11> @BASEBOARD_FAB2_LIB.BASEBOARD_FAB2(SCH_1):PVSA_CPU1
CF65 PVSA_CPU1 VCCSA<10> @BASEBOARD_FAB2_LIB.BASEBOARD_FAB2(SCH_1):PVSA_CPU1
CF67 PVSA_CPU1 VCCSA<9> @BASEBOARD_FAB2_LIB.BASEBOARD_FAB2(SCH_1):PVSA_CPU1
CF73 PVSA_CPU1 VCCSA<8> @BASEBOARD_FAB2_LIB.BASEBOARD_FAB2(SCH_1):PVSA_CPU1
CF75 PVSA_CPU1 VCCSA<7> @BASEBOARD_FAB2_LIB.BASEBOARD_FAB2(SCH_1):PVSA_CPU1
CG64 PVSA_CPU1 VCCSA<6> @BASEBOARD_FAB2_LIB.BASEBOARD_FAB2(SCH_1):PVSA_CPU1
CG66 PVSA_CPU1 VCCSA<5> @BASEBOARD_FAB2_LIB.BASEBOARD_FAB2(SCH_1):PVSA_CPU1
CG74 PVSA_CPU1 VCCSA<4> @BASEBOARD_FAB2_LIB.BASEBOARD_FAB2(SCH_1):PVSA_CPU1
CH65 PVSA_CPU1 VCCSA<3> @BASEBOARD_FAB2_LIB.BASEBOARD_FAB2(SCH_1):PVSA_CPU1
CH75 PVSA_CPU1 VCCSA<2> @BASEBOARD_FAB2_LIB.BASEBOARD_FAB2(SCH_1):PVSA_CPU1
CJ64 PVSA_CPU1 VCCSA<1> @BASEBOARD_FAB2_LIB.BASEBOARD_FAB2(SCH_1):PVSA_CPU1
CJ66 PVSA_CPU1 VCCSA<0> @BASEBOARD_FAB2_LIB.BASEBOARD_FAB2(SCH_1):PVSA_CPU1


DRAWING: @BASEBOARD_FAB2_LIB.BASEBOARD_FAB2(SCH_1):PAGE73 

SKX_EXT_B_BGA1-IC,TBD  I107  U2D1
BT17 VSENSE_PVCCIOMCP_CPU1_SKT_VSEN CD_VCCP_SENSE<1> @BASEBOARD_FAB2_LIB.BASEBOARD_FAB2(SCH_1):VSENSE_PVCCIOMCP_CPU1_SKT_VSEN
BU16 VSENSE_PVCCIOMCP_CPU1_SKT_VRTN CD_VCCP_SENSE<0> @BASEBOARD_FAB2_LIB.BASEBOARD_FAB2(SCH_1):VSENSE_PVCCIOMCP_CPU1_SKT_VRTN
BN16 VSENSE_PVCCMCP_CPU1_SKT_VSEN CD_VCC_CORE_SENSE @BASEBOARD_FAB2_LIB.BASEBOARD_FAB2(SCH_1):VSENSE_PVCCMCP_CPU1_SKT_VSEN
BL16 VSENSE_PVCCMCP_CPU1_SKT_VRTN CD_VSS_VCC_CORE_SENSE @BASEBOARD_FAB2_LIB.BASEBOARD_FAB2(SCH_1):VSENSE_PVCCMCP_CPU1_SKT_VRTN
CL26 PVCCMCP_CPU1 RSVD<80> @BASEBOARD_FAB2_LIB.BASEBOARD_FAB2(SCH_1):PVCCMCP_CPU1
CM23 PVCCMCP_CPU1 RSVD<79> @BASEBOARD_FAB2_LIB.BASEBOARD_FAB2(SCH_1):PVCCMCP_CPU1
CM25 PVCCMCP_CPU1 RSVD<78> @BASEBOARD_FAB2_LIB.BASEBOARD_FAB2(SCH_1):PVCCMCP_CPU1
CN22 TP_CPU1_KTI2_AMONV RSVD<77> @BASEBOARD_FAB2_LIB.BASEBOARD_FAB2(SCH_1):TP_CPU1_KTI2_AMONV
CN24 PVCCMCP_CPU1 RSVD<76> @BASEBOARD_FAB2_LIB.BASEBOARD_FAB2(SCH_1):PVCCMCP_CPU1
CN28 PD_CPU1_MCP01_DMON RSVD<75> @BASEBOARD_FAB2_LIB.BASEBOARD_FAB2(SCH_1):PD_CPU1_MCP01_DMON
CP23 PVCCMCP_CPU1 RSVD<74> @BASEBOARD_FAB2_LIB.BASEBOARD_FAB2(SCH_1):PVCCMCP_CPU1
CP31 TP_CPU1_RSVD_73 RSVD<73> @BASEBOARD_FAB2_LIB.BASEBOARD_FAB2(SCH_1):TP_CPU1_RSVD_73
CR60 TP_CPU1_RSVD_72 RSVD<72> @BASEBOARD_FAB2_LIB.BASEBOARD_FAB2(SCH_1):TP_CPU1_RSVD_72
CT23 PVCCMCP_CPU1 RSVD<71> @BASEBOARD_FAB2_LIB.BASEBOARD_FAB2(SCH_1):PVCCMCP_CPU1
 CT5 TP_CPU1_RSVD_70 RSVD<70> @BASEBOARD_FAB2_LIB.BASEBOARD_FAB2(SCH_1):TP_CPU1_RSVD_70
CT69 TP_CPU1_RSVD_69 RSVD<69> @BASEBOARD_FAB2_LIB.BASEBOARD_FAB2(SCH_1):TP_CPU1_RSVD_69
CU24 PVCCMCP_CPU1 RSVD<68> @BASEBOARD_FAB2_LIB.BASEBOARD_FAB2(SCH_1):PVCCMCP_CPU1
 CU6 TP_CPU1_RSVD_67 RSVD<67> @BASEBOARD_FAB2_LIB.BASEBOARD_FAB2(SCH_1):TP_CPU1_RSVD_67
CU60 TP_CPU1_RSVD_66 RSVD<66> @BASEBOARD_FAB2_LIB.BASEBOARD_FAB2(SCH_1):TP_CPU1_RSVD_66
CV23 PVCCMCP_CPU1 RSVD<65> @BASEBOARD_FAB2_LIB.BASEBOARD_FAB2(SCH_1):PVCCMCP_CPU1
CV69 TP_CPU1_RSVD_64 RSVD<64> @BASEBOARD_FAB2_LIB.BASEBOARD_FAB2(SCH_1):TP_CPU1_RSVD_64
CW22 TP_CPU1_KTI2_DFX_DN RSVD<63> @BASEBOARD_FAB2_LIB.BASEBOARD_FAB2(SCH_1):TP_CPU1_KTI2_DFX_DN
CW24 PVCCMCP_CPU1 RSVD<62> @BASEBOARD_FAB2_LIB.BASEBOARD_FAB2(SCH_1):PVCCMCP_CPU1
CW60 TP_CPU1_RSVD_61 RSVD<61> @BASEBOARD_FAB2_LIB.BASEBOARD_FAB2(SCH_1):TP_CPU1_RSVD_61
CW62 TP_CPU1_RSVD_60 RSVD<60> @BASEBOARD_FAB2_LIB.BASEBOARD_FAB2(SCH_1):TP_CPU1_RSVD_60
CY23 TP_CPU1_RSVD_59 RSVD<59> @BASEBOARD_FAB2_LIB.BASEBOARD_FAB2(SCH_1):TP_CPU1_RSVD_59
CY25 PVCCMCP_CPU1 RSVD<58> @BASEBOARD_FAB2_LIB.BASEBOARD_FAB2(SCH_1):PVCCMCP_CPU1
CY39 TP_CPU1_RSVD_57 RSVD<57> @BASEBOARD_FAB2_LIB.BASEBOARD_FAB2(SCH_1):TP_CPU1_RSVD_57
CY53 TP_CPU1_RSVD_56 RSVD<56> @BASEBOARD_FAB2_LIB.BASEBOARD_FAB2(SCH_1):TP_CPU1_RSVD_56
CY57 TP_CPU1_RSVD_55 RSVD<55> @BASEBOARD_FAB2_LIB.BASEBOARD_FAB2(SCH_1):TP_CPU1_RSVD_55
CY63 TP_CPU1_RSVD_54 RSVD<54> @BASEBOARD_FAB2_LIB.BASEBOARD_FAB2(SCH_1):TP_CPU1_RSVD_54
CY73 TP_CPU1_RSVD_53 RSVD<53> @BASEBOARD_FAB2_LIB.BASEBOARD_FAB2(SCH_1):TP_CPU1_RSVD_53
DA24 PVCCMCP_CPU1 RSVD<52> @BASEBOARD_FAB2_LIB.BASEBOARD_FAB2(SCH_1):PVCCMCP_CPU1
DA40 TP_CPU1_RSVD_51 RSVD<51> @BASEBOARD_FAB2_LIB.BASEBOARD_FAB2(SCH_1):TP_CPU1_RSVD_51
DA52 TP_CPU1_RSVD_50 RSVD<50> @BASEBOARD_FAB2_LIB.BASEBOARD_FAB2(SCH_1):TP_CPU1_RSVD_50
DA54 TP_CPU1_RSVD_49 RSVD<49> @BASEBOARD_FAB2_LIB.BASEBOARD_FAB2(SCH_1):TP_CPU1_RSVD_49
DA56 TP_CPU1_RSVD_48 RSVD<48> @BASEBOARD_FAB2_LIB.BASEBOARD_FAB2(SCH_1):TP_CPU1_RSVD_48
DC46 TP_CPU1_RSVD_47 RSVD<47> @BASEBOARD_FAB2_LIB.BASEBOARD_FAB2(SCH_1):TP_CPU1_RSVD_47
DC52 TP_CPU1_RSVD_46 RSVD<46> @BASEBOARD_FAB2_LIB.BASEBOARD_FAB2(SCH_1):TP_CPU1_RSVD_46
DD51 TP_CPU1_RSVD_45 RSVD<45> @BASEBOARD_FAB2_LIB.BASEBOARD_FAB2(SCH_1):TP_CPU1_RSVD_45
DG36 TP_CPU1_RSVD_44 RSVD<44> @BASEBOARD_FAB2_LIB.BASEBOARD_FAB2(SCH_1):TP_CPU1_RSVD_44
DG64 TP_CPU1_RSVD_43 RSVD<43> @BASEBOARD_FAB2_LIB.BASEBOARD_FAB2(SCH_1):TP_CPU1_RSVD_43
DH65 TP_CPU1_RSVD_42 RSVD<42> @BASEBOARD_FAB2_LIB.BASEBOARD_FAB2(SCH_1):TP_CPU1_RSVD_42
DJ36 TP_CPU1_RSVD_41 RSVD<41> @BASEBOARD_FAB2_LIB.BASEBOARD_FAB2(SCH_1):TP_CPU1_RSVD_41
DJ66 TP_CPU1_RSVD_40 RSVD<40> @BASEBOARD_FAB2_LIB.BASEBOARD_FAB2(SCH_1):TP_CPU1_RSVD_40
DK15 TP_CPU1_RSVD_39 RSVD<39> @BASEBOARD_FAB2_LIB.BASEBOARD_FAB2(SCH_1):TP_CPU1_RSVD_39
DK37 TP_CPU1_RSVD_38 RSVD<38> @BASEBOARD_FAB2_LIB.BASEBOARD_FAB2(SCH_1):TP_CPU1_RSVD_38
DK65 TP_CPU1_RSVD_37 RSVD<37> @BASEBOARD_FAB2_LIB.BASEBOARD_FAB2(SCH_1):TP_CPU1_RSVD_37
DK67 TP_CPU1_RSVD_36 RSVD<36> @BASEBOARD_FAB2_LIB.BASEBOARD_FAB2(SCH_1):TP_CPU1_RSVD_36
DL38 TP_CPU1_RSVD_35 RSVD<35> @BASEBOARD_FAB2_LIB.BASEBOARD_FAB2(SCH_1):TP_CPU1_RSVD_35
DL66 TP_CPU1_RSVD_34 RSVD<34> @BASEBOARD_FAB2_LIB.BASEBOARD_FAB2(SCH_1):TP_CPU1_RSVD_34
DM67 TP_CPU1_RSVD_33 RSVD<33> @BASEBOARD_FAB2_LIB.BASEBOARD_FAB2(SCH_1):TP_CPU1_RSVD_33
DN62 TP_CPU1_RSVD_32 RSVD<32> @BASEBOARD_FAB2_LIB.BASEBOARD_FAB2(SCH_1):TP_CPU1_RSVD_32
DN66 TP_CPU1_RSVD_31 RSVD<31> @BASEBOARD_FAB2_LIB.BASEBOARD_FAB2(SCH_1):TP_CPU1_RSVD_31
DP17 TP_CPU1_RSVD_30 RSVD<30> @BASEBOARD_FAB2_LIB.BASEBOARD_FAB2(SCH_1):TP_CPU1_RSVD_30
DP65 TP_CPU1_RSVD_29 RSVD<29> @BASEBOARD_FAB2_LIB.BASEBOARD_FAB2(SCH_1):TP_CPU1_RSVD_29
DR44 TP_CPU1_RSVD_28 RSVD<28> @BASEBOARD_FAB2_LIB.BASEBOARD_FAB2(SCH_1):TP_CPU1_RSVD_28
DT71 TP_CPU1_RSVD_27 RSVD<27> @BASEBOARD_FAB2_LIB.BASEBOARD_FAB2(SCH_1):TP_CPU1_RSVD_27
DU44 TP_CPU1_RSVD_26 RSVD<26> @BASEBOARD_FAB2_LIB.BASEBOARD_FAB2(SCH_1):TP_CPU1_RSVD_26
DV61 TP_CPU1_RSVD_25 RSVD<25> @BASEBOARD_FAB2_LIB.BASEBOARD_FAB2(SCH_1):TP_CPU1_RSVD_25
DV71 TP_CPU1_RSVD_24 RSVD<24> @BASEBOARD_FAB2_LIB.BASEBOARD_FAB2(SCH_1):TP_CPU1_RSVD_24
DW44 TP_CPU1_RSVD_23 RSVD<23> @BASEBOARD_FAB2_LIB.BASEBOARD_FAB2(SCH_1):TP_CPU1_RSVD_23
DW46 TP_CPU1_RSVD_22 RSVD<22> @BASEBOARD_FAB2_LIB.BASEBOARD_FAB2(SCH_1):TP_CPU1_RSVD_22
 DY3 TP_CPU1_RSVD_21 RSVD<21> @BASEBOARD_FAB2_LIB.BASEBOARD_FAB2(SCH_1):TP_CPU1_RSVD_21
 EA4 TP_CPU1_RSVD_20 RSVD<20> @BASEBOARD_FAB2_LIB.BASEBOARD_FAB2(SCH_1):TP_CPU1_RSVD_20
EA44 TP_CPU1_RSVD_19 RSVD<19> @BASEBOARD_FAB2_LIB.BASEBOARD_FAB2(SCH_1):TP_CPU1_RSVD_19
 EB3 TP_CPU1_RSVD_18 RSVD<18> @BASEBOARD_FAB2_LIB.BASEBOARD_FAB2(SCH_1):TP_CPU1_RSVD_18
 EB5 TP_CPU1_RSVD_17 RSVD<17> @BASEBOARD_FAB2_LIB.BASEBOARD_FAB2(SCH_1):TP_CPU1_RSVD_17
EB85 TP_CPU1_RSVD_16 RSVD<16> @BASEBOARD_FAB2_LIB.BASEBOARD_FAB2(SCH_1):TP_CPU1_RSVD_16
EC16 TP_CPU1_RSVD_15 RSVD<15> @BASEBOARD_FAB2_LIB.BASEBOARD_FAB2(SCH_1):TP_CPU1_RSVD_15
 EC4 TP_CPU1_RSVD_14 RSVD<14> @BASEBOARD_FAB2_LIB.BASEBOARD_FAB2(SCH_1):TP_CPU1_RSVD_14
EC44 TP_CPU1_RSVD_13 RSVD<13> @BASEBOARD_FAB2_LIB.BASEBOARD_FAB2(SCH_1):TP_CPU1_RSVD_13
EC84 TP_CPU1_RSVD_12 RSVD<12> @BASEBOARD_FAB2_LIB.BASEBOARD_FAB2(SCH_1):TP_CPU1_RSVD_12
ED45 TP_CPU1_RSVD_11 RSVD<11> @BASEBOARD_FAB2_LIB.BASEBOARD_FAB2(SCH_1):TP_CPU1_RSVD_11
 ED5 TP_CPU1_RSVD_10 RSVD<10> @BASEBOARD_FAB2_LIB.BASEBOARD_FAB2(SCH_1):TP_CPU1_RSVD_10
ED83 TP_CPU1_RSVD_9 RSVD<9> @BASEBOARD_FAB2_LIB.BASEBOARD_FAB2(SCH_1):TP_CPU1_RSVD_9
EE16 TP_CPU1_RSVD_8 RSVD<8> @BASEBOARD_FAB2_LIB.BASEBOARD_FAB2(SCH_1):TP_CPU1_RSVD_8
EE46 TP_CPU1_RSVD_7 RSVD<7> @BASEBOARD_FAB2_LIB.BASEBOARD_FAB2(SCH_1):TP_CPU1_RSVD_7
 EE6 TP_CPU1_RSVD_6 RSVD<6> @BASEBOARD_FAB2_LIB.BASEBOARD_FAB2(SCH_1):TP_CPU1_RSVD_6
EE82 TP_CPU1_RSVD_5 RSVD<5> @BASEBOARD_FAB2_LIB.BASEBOARD_FAB2(SCH_1):TP_CPU1_RSVD_5
EE84 TP_CPU1_RSVD_4 RSVD<4> @BASEBOARD_FAB2_LIB.BASEBOARD_FAB2(SCH_1):TP_CPU1_RSVD_4
EF47 TP_CPU1_RSVD_3 RSVD<3> @BASEBOARD_FAB2_LIB.BASEBOARD_FAB2(SCH_1):TP_CPU1_RSVD_3
EF77 TP_CPU1_RSVD_2 RSVD<2> @BASEBOARD_FAB2_LIB.BASEBOARD_FAB2(SCH_1):TP_CPU1_RSVD_2
EF81 TP_CPU1_RSVD_1 RSVD<1> @BASEBOARD_FAB2_LIB.BASEBOARD_FAB2(SCH_1):TP_CPU1_RSVD_1
EF83 TP_CPU1_RSVD_0 RSVD<0> @BASEBOARD_FAB2_LIB.BASEBOARD_FAB2(SCH_1):TP_CPU1_RSVD_0
 CN6 PVCCIO_CPU1 VCCIO<19> @BASEBOARD_FAB2_LIB.BASEBOARD_FAB2(SCH_1):PVCCIO_CPU1
CU12 PVCCIO_CPU1 VCCIO<18> @BASEBOARD_FAB2_LIB.BASEBOARD_FAB2(SCH_1):PVCCIO_CPU1
CV21 PVCCIO_CPU1 VCCIO<17> @BASEBOARD_FAB2_LIB.BASEBOARD_FAB2(SCH_1):PVCCIO_CPU1
CU18 PVCCIO_CPU1 VCCIO<16> @BASEBOARD_FAB2_LIB.BASEBOARD_FAB2(SCH_1):PVCCIO_CPU1
CY17 PVCCIO_CPU1 VCCIO<15> @BASEBOARD_FAB2_LIB.BASEBOARD_FAB2(SCH_1):PVCCIO_CPU1
DC18 PVCCIO_CPU1 VCCIO<14> @BASEBOARD_FAB2_LIB.BASEBOARD_FAB2(SCH_1):PVCCIO_CPU1
DE14 PVCCIO_CPU1 VCCIO<13> @BASEBOARD_FAB2_LIB.BASEBOARD_FAB2(SCH_1):PVCCIO_CPU1
CP13 PVCCIO_CPU1 VCCIO<12> @BASEBOARD_FAB2_LIB.BASEBOARD_FAB2(SCH_1):PVCCIO_CPU1
CL20 PVCCIO_CPU1 VCCIO<11> @BASEBOARD_FAB2_LIB.BASEBOARD_FAB2(SCH_1):PVCCIO_CPU1
CG14 PVCCIO_CPU1 VCCIO<10> @BASEBOARD_FAB2_LIB.BASEBOARD_FAB2(SCH_1):PVCCIO_CPU1
 CF5 PVCCIO_CPU1 VCCIO<9> @BASEBOARD_FAB2_LIB.BASEBOARD_FAB2(SCH_1):PVCCIO_CPU1
DK21 PVCCIO_CPU1 VCCIO<8> @BASEBOARD_FAB2_LIB.BASEBOARD_FAB2(SCH_1):PVCCIO_CPU1
BE24 PVCCIO_CPU1 VCCIO<7> @BASEBOARD_FAB2_LIB.BASEBOARD_FAB2(SCH_1):PVCCIO_CPU1
 AT7 PVCCIO_CPU1 VCCIO<6> @BASEBOARD_FAB2_LIB.BASEBOARD_FAB2(SCH_1):PVCCIO_CPU1
 AT5 PVCCIO_CPU1 VCCIO<5> @BASEBOARD_FAB2_LIB.BASEBOARD_FAB2(SCH_1):PVCCIO_CPU1
 AM5 PVCCIO_CPU1 VCCIO<4> @BASEBOARD_FAB2_LIB.BASEBOARD_FAB2(SCH_1):PVCCIO_CPU1
DV11 PVCCIO_CPU1 VCCIO<3> @BASEBOARD_FAB2_LIB.BASEBOARD_FAB2(SCH_1):PVCCIO_CPU1
 AF5 PVCCIO_CPU1 VCCIO<2> @BASEBOARD_FAB2_LIB.BASEBOARD_FAB2(SCH_1):PVCCIO_CPU1
AE10 PVCCIO_CPU1 VCCIO<1> @BASEBOARD_FAB2_LIB.BASEBOARD_FAB2(SCH_1):PVCCIO_CPU1
EE10 PVCCIO_CPU1 VCCIO<0> @BASEBOARD_FAB2_LIB.BASEBOARD_FAB2(SCH_1):PVCCIO_CPU1
 BH5 VSENSE_PVCCIO_CPU1_SKT_VSEN VCCIO_SENSE @BASEBOARD_FAB2_LIB.BASEBOARD_FAB2(SCH_1):VSENSE_PVCCIO_CPU1_SKT_VSEN
CE76 VSENSE_PVSA_CPU1_SKT_VSEN VCCSA_SENSE @BASEBOARD_FAB2_LIB.BASEBOARD_FAB2(SCH_1):VSENSE_PVSA_CPU1_SKT_VSEN
 BF5 VSENSE_PVCCIO_CPU1_SKT_VRTN VSS_VCCIO_SENSE @BASEBOARD_FAB2_LIB.BASEBOARD_FAB2(SCH_1):VSENSE_PVCCIO_CPU1_SKT_VRTN
CG76 VSENSE_PVSA_CPU1_SKT_VRTN VSS_VCCSA_SENSE @BASEBOARD_FAB2_LIB.BASEBOARD_FAB2(SCH_1):VSENSE_PVSA_CPU1_SKT_VRTN


DRAWING: @BASEBOARD_FAB2_LIB.BASEBOARD_FAB2(SCH_1):PAGE74 

SKX_EXT_B_BGA1-IC,TBD  I20  U2D1
  B9    GND VSS<1253> @BASEBOARD_FAB2_LIB.BASEBOARD_FAB2(SCH_1):GND
 A42    GND VSS<1252> @BASEBOARD_FAB2_LIB.BASEBOARD_FAB2(SCH_1):GND
 B43    GND VSS<1251> @BASEBOARD_FAB2_LIB.BASEBOARD_FAB2(SCH_1):GND
  B5    GND VSS<1250> @BASEBOARD_FAB2_LIB.BASEBOARD_FAB2(SCH_1):GND
 B79    GND VSS<1249> @BASEBOARD_FAB2_LIB.BASEBOARD_FAB2(SCH_1):GND
  C4    GND VSS<1248> @BASEBOARD_FAB2_LIB.BASEBOARD_FAB2(SCH_1):GND
 C80    GND VSS<1247> @BASEBOARD_FAB2_LIB.BASEBOARD_FAB2(SCH_1):GND
  D3    GND VSS<1246> @BASEBOARD_FAB2_LIB.BASEBOARD_FAB2(SCH_1):GND
 D81    GND VSS<1245> @BASEBOARD_FAB2_LIB.BASEBOARD_FAB2(SCH_1):GND
 E82    GND VSS<1244> @BASEBOARD_FAB2_LIB.BASEBOARD_FAB2(SCH_1):GND
 J86    GND VSS<1243> @BASEBOARD_FAB2_LIB.BASEBOARD_FAB2(SCH_1):GND
DY85    GND VSS<1242> @BASEBOARD_FAB2_LIB.BASEBOARD_FAB2(SCH_1):GND
EA84    GND VSS<1241> @BASEBOARD_FAB2_LIB.BASEBOARD_FAB2(SCH_1):GND
EB83    GND VSS<1240> @BASEBOARD_FAB2_LIB.BASEBOARD_FAB2(SCH_1):GND
 DW2    GND VSS<1239> @BASEBOARD_FAB2_LIB.BASEBOARD_FAB2(SCH_1):GND
EC42    GND VSS<1238> @BASEBOARD_FAB2_LIB.BASEBOARD_FAB2(SCH_1):GND
 EC6    GND VSS<1237> @BASEBOARD_FAB2_LIB.BASEBOARD_FAB2(SCH_1):GND
EC82    GND VSS<1236> @BASEBOARD_FAB2_LIB.BASEBOARD_FAB2(SCH_1):GND
ED41    GND VSS<1235> @BASEBOARD_FAB2_LIB.BASEBOARD_FAB2(SCH_1):GND
 ED7    GND VSS<1234> @BASEBOARD_FAB2_LIB.BASEBOARD_FAB2(SCH_1):GND
ED81    GND VSS<1233> @BASEBOARD_FAB2_LIB.BASEBOARD_FAB2(SCH_1):GND
EE40    GND VSS<1232> @BASEBOARD_FAB2_LIB.BASEBOARD_FAB2(SCH_1):GND
 EE8    GND VSS<1231> @BASEBOARD_FAB2_LIB.BASEBOARD_FAB2(SCH_1):GND
EE80    GND VSS<1230> @BASEBOARD_FAB2_LIB.BASEBOARD_FAB2(SCH_1):GND
ED69    GND VSS<1229> @BASEBOARD_FAB2_LIB.BASEBOARD_FAB2(SCH_1):GND
 E66    GND VSS<1228> @BASEBOARD_FAB2_LIB.BASEBOARD_FAB2(SCH_1):GND
 V11    GND VSS<1227> @BASEBOARD_FAB2_LIB.BASEBOARD_FAB2(SCH_1):GND
  L8    GND VSS<1226> @BASEBOARD_FAB2_LIB.BASEBOARD_FAB2(SCH_1):GND
EA14    GND VSS<1225> @BASEBOARD_FAB2_LIB.BASEBOARD_FAB2(SCH_1):GND
DY63    GND VSS<1224> @BASEBOARD_FAB2_LIB.BASEBOARD_FAB2(SCH_1):GND
DY61    GND VSS<1223> @BASEBOARD_FAB2_LIB.BASEBOARD_FAB2(SCH_1):GND
DY59    GND VSS<1222> @BASEBOARD_FAB2_LIB.BASEBOARD_FAB2(SCH_1):GND
DY57    GND VSS<1221> @BASEBOARD_FAB2_LIB.BASEBOARD_FAB2(SCH_1):GND
DY55    GND VSS<1220> @BASEBOARD_FAB2_LIB.BASEBOARD_FAB2(SCH_1):GND
DY53    GND VSS<1219> @BASEBOARD_FAB2_LIB.BASEBOARD_FAB2(SCH_1):GND
DY51    GND VSS<1218> @BASEBOARD_FAB2_LIB.BASEBOARD_FAB2(SCH_1):GND
DY49    GND VSS<1217> @BASEBOARD_FAB2_LIB.BASEBOARD_FAB2(SCH_1):GND
DY47    GND VSS<1216> @BASEBOARD_FAB2_LIB.BASEBOARD_FAB2(SCH_1):GND
DY45    GND VSS<1215> @BASEBOARD_FAB2_LIB.BASEBOARD_FAB2(SCH_1):GND
DV19    GND VSS<1214> @BASEBOARD_FAB2_LIB.BASEBOARD_FAB2(SCH_1):GND
 DP9    GND VSS<1213> @BASEBOARD_FAB2_LIB.BASEBOARD_FAB2(SCH_1):GND
DP63    GND VSS<1212> @BASEBOARD_FAB2_LIB.BASEBOARD_FAB2(SCH_1):GND
DP61    GND VSS<1211> @BASEBOARD_FAB2_LIB.BASEBOARD_FAB2(SCH_1):GND
DP59    GND VSS<1210> @BASEBOARD_FAB2_LIB.BASEBOARD_FAB2(SCH_1):GND
DP57    GND VSS<1209> @BASEBOARD_FAB2_LIB.BASEBOARD_FAB2(SCH_1):GND
DP55    GND VSS<1208> @BASEBOARD_FAB2_LIB.BASEBOARD_FAB2(SCH_1):GND
DP53    GND VSS<1207> @BASEBOARD_FAB2_LIB.BASEBOARD_FAB2(SCH_1):GND
DP51    GND VSS<1206> @BASEBOARD_FAB2_LIB.BASEBOARD_FAB2(SCH_1):GND
DP49    GND VSS<1205> @BASEBOARD_FAB2_LIB.BASEBOARD_FAB2(SCH_1):GND
DP47    GND VSS<1204> @BASEBOARD_FAB2_LIB.BASEBOARD_FAB2(SCH_1):GND
DP45    GND VSS<1203> @BASEBOARD_FAB2_LIB.BASEBOARD_FAB2(SCH_1):GND
DN18    GND VSS<1202> @BASEBOARD_FAB2_LIB.BASEBOARD_FAB2(SCH_1):GND
 DL8    GND VSS<1201> @BASEBOARD_FAB2_LIB.BASEBOARD_FAB2(SCH_1):GND
DE62    GND VSS<1200> @BASEBOARD_FAB2_LIB.BASEBOARD_FAB2(SCH_1):GND
DE60    GND VSS<1199> @BASEBOARD_FAB2_LIB.BASEBOARD_FAB2(SCH_1):GND
DE58    GND VSS<1198> @BASEBOARD_FAB2_LIB.BASEBOARD_FAB2(SCH_1):GND
DE56    GND VSS<1197> @BASEBOARD_FAB2_LIB.BASEBOARD_FAB2(SCH_1):GND
DE54    GND VSS<1196> @BASEBOARD_FAB2_LIB.BASEBOARD_FAB2(SCH_1):GND
DE52    GND VSS<1195> @BASEBOARD_FAB2_LIB.BASEBOARD_FAB2(SCH_1):GND
DE50    GND VSS<1194> @BASEBOARD_FAB2_LIB.BASEBOARD_FAB2(SCH_1):GND
DE48    GND VSS<1193> @BASEBOARD_FAB2_LIB.BASEBOARD_FAB2(SCH_1):GND
 CW6    GND VSS<1192> @BASEBOARD_FAB2_LIB.BASEBOARD_FAB2(SCH_1):GND
 CG6    GND VSS<1191> @BASEBOARD_FAB2_LIB.BASEBOARD_FAB2(SCH_1):GND
 AR6    GND VSS<1190> @BASEBOARD_FAB2_LIB.BASEBOARD_FAB2(SCH_1):GND
 AJ4    GND VSS<1189> @BASEBOARD_FAB2_LIB.BASEBOARD_FAB2(SCH_1):GND
AC62    GND VSS<1188> @BASEBOARD_FAB2_LIB.BASEBOARD_FAB2(SCH_1):GND
AC60    GND VSS<1187> @BASEBOARD_FAB2_LIB.BASEBOARD_FAB2(SCH_1):GND
AC58    GND VSS<1186> @BASEBOARD_FAB2_LIB.BASEBOARD_FAB2(SCH_1):GND
 A26    GND VSS<1185> @BASEBOARD_FAB2_LIB.BASEBOARD_FAB2(SCH_1):GND
 A30    GND VSS<1184> @BASEBOARD_FAB2_LIB.BASEBOARD_FAB2(SCH_1):GND
 A32    GND VSS<1183> @BASEBOARD_FAB2_LIB.BASEBOARD_FAB2(SCH_1):GND
 A36    GND VSS<1182> @BASEBOARD_FAB2_LIB.BASEBOARD_FAB2(SCH_1):GND
 A38    GND VSS<1181> @BASEBOARD_FAB2_LIB.BASEBOARD_FAB2(SCH_1):GND
 B25    GND VSS<1180> @BASEBOARD_FAB2_LIB.BASEBOARD_FAB2(SCH_1):GND
 B31    GND VSS<1179> @BASEBOARD_FAB2_LIB.BASEBOARD_FAB2(SCH_1):GND
 B37    GND VSS<1178> @BASEBOARD_FAB2_LIB.BASEBOARD_FAB2(SCH_1):GND
 B71    GND VSS<1177> @BASEBOARD_FAB2_LIB.BASEBOARD_FAB2(SCH_1):GND
 B75    GND VSS<1176> @BASEBOARD_FAB2_LIB.BASEBOARD_FAB2(SCH_1):GND
  C8    GND VSS<1175> @BASEBOARD_FAB2_LIB.BASEBOARD_FAB2(SCH_1):GND
 C10    GND VSS<1174> @BASEBOARD_FAB2_LIB.BASEBOARD_FAB2(SCH_1):GND
 C12    GND VSS<1173> @BASEBOARD_FAB2_LIB.BASEBOARD_FAB2(SCH_1):GND
 C14    GND VSS<1172> @BASEBOARD_FAB2_LIB.BASEBOARD_FAB2(SCH_1):GND
 C16    GND VSS<1171> @BASEBOARD_FAB2_LIB.BASEBOARD_FAB2(SCH_1):GND
 C76    GND VSS<1170> @BASEBOARD_FAB2_LIB.BASEBOARD_FAB2(SCH_1):GND
 C78    GND VSS<1169> @BASEBOARD_FAB2_LIB.BASEBOARD_FAB2(SCH_1):GND
CM27    GND VSS<1168> @BASEBOARD_FAB2_LIB.BASEBOARD_FAB2(SCH_1):GND
 D11    GND VSS<1167> @BASEBOARD_FAB2_LIB.BASEBOARD_FAB2(SCH_1):GND
 D13    GND VSS<1166> @BASEBOARD_FAB2_LIB.BASEBOARD_FAB2(SCH_1):GND
 D25    GND VSS<1165> @BASEBOARD_FAB2_LIB.BASEBOARD_FAB2(SCH_1):GND
 D27    GND VSS<1164> @BASEBOARD_FAB2_LIB.BASEBOARD_FAB2(SCH_1):GND
 D29    GND VSS<1163> @BASEBOARD_FAB2_LIB.BASEBOARD_FAB2(SCH_1):GND
 D31    GND VSS<1162> @BASEBOARD_FAB2_LIB.BASEBOARD_FAB2(SCH_1):GND
 D33    GND VSS<1161> @BASEBOARD_FAB2_LIB.BASEBOARD_FAB2(SCH_1):GND
 D35    GND VSS<1160> @BASEBOARD_FAB2_LIB.BASEBOARD_FAB2(SCH_1):GND
 D37    GND VSS<1159> @BASEBOARD_FAB2_LIB.BASEBOARD_FAB2(SCH_1):GND
 D39    GND VSS<1158> @BASEBOARD_FAB2_LIB.BASEBOARD_FAB2(SCH_1):GND
 D41    GND VSS<1157> @BASEBOARD_FAB2_LIB.BASEBOARD_FAB2(SCH_1):GND
 D43    GND VSS<1156> @BASEBOARD_FAB2_LIB.BASEBOARD_FAB2(SCH_1):GND
 D77    GND VSS<1155> @BASEBOARD_FAB2_LIB.BASEBOARD_FAB2(SCH_1):GND
  E6    GND VSS<1154> @BASEBOARD_FAB2_LIB.BASEBOARD_FAB2(SCH_1):GND
  E8    GND VSS<1153> @BASEBOARD_FAB2_LIB.BASEBOARD_FAB2(SCH_1):GND
 E16    GND VSS<1152> @BASEBOARD_FAB2_LIB.BASEBOARD_FAB2(SCH_1):GND
 E18    GND VSS<1151> @BASEBOARD_FAB2_LIB.BASEBOARD_FAB2(SCH_1):GND
 E20    GND VSS<1150> @BASEBOARD_FAB2_LIB.BASEBOARD_FAB2(SCH_1):GND
 E22    GND VSS<1149> @BASEBOARD_FAB2_LIB.BASEBOARD_FAB2(SCH_1):GND
 E72    GND VSS<1148> @BASEBOARD_FAB2_LIB.BASEBOARD_FAB2(SCH_1):GND
 E74    GND VSS<1147> @BASEBOARD_FAB2_LIB.BASEBOARD_FAB2(SCH_1):GND
 E76    GND VSS<1146> @BASEBOARD_FAB2_LIB.BASEBOARD_FAB2(SCH_1):GND
  F5    GND VSS<1145> @BASEBOARD_FAB2_LIB.BASEBOARD_FAB2(SCH_1):GND
 F17    GND VSS<1144> @BASEBOARD_FAB2_LIB.BASEBOARD_FAB2(SCH_1):GND
 F19    GND VSS<1143> @BASEBOARD_FAB2_LIB.BASEBOARD_FAB2(SCH_1):GND
 F25    GND VSS<1142> @BASEBOARD_FAB2_LIB.BASEBOARD_FAB2(SCH_1):GND
 F31    GND VSS<1141> @BASEBOARD_FAB2_LIB.BASEBOARD_FAB2(SCH_1):GND
 F37    GND VSS<1140> @BASEBOARD_FAB2_LIB.BASEBOARD_FAB2(SCH_1):GND
 F43    GND VSS<1139> @BASEBOARD_FAB2_LIB.BASEBOARD_FAB2(SCH_1):GND
 F67    GND VSS<1138> @BASEBOARD_FAB2_LIB.BASEBOARD_FAB2(SCH_1):GND
 F69    GND VSS<1137> @BASEBOARD_FAB2_LIB.BASEBOARD_FAB2(SCH_1):GND
  G4    GND VSS<1136> @BASEBOARD_FAB2_LIB.BASEBOARD_FAB2(SCH_1):GND
  G8    GND VSS<1135> @BASEBOARD_FAB2_LIB.BASEBOARD_FAB2(SCH_1):GND
 G22    GND VSS<1134> @BASEBOARD_FAB2_LIB.BASEBOARD_FAB2(SCH_1):GND
 G24    GND VSS<1133> @BASEBOARD_FAB2_LIB.BASEBOARD_FAB2(SCH_1):GND
 G26    GND VSS<1132> @BASEBOARD_FAB2_LIB.BASEBOARD_FAB2(SCH_1):GND
 G30    GND VSS<1131> @BASEBOARD_FAB2_LIB.BASEBOARD_FAB2(SCH_1):GND
 G32    GND VSS<1130> @BASEBOARD_FAB2_LIB.BASEBOARD_FAB2(SCH_1):GND
 G36    GND VSS<1129> @BASEBOARD_FAB2_LIB.BASEBOARD_FAB2(SCH_1):GND
 G38    GND VSS<1128> @BASEBOARD_FAB2_LIB.BASEBOARD_FAB2(SCH_1):GND
 G42    GND VSS<1127> @BASEBOARD_FAB2_LIB.BASEBOARD_FAB2(SCH_1):GND
 G66    GND VSS<1126> @BASEBOARD_FAB2_LIB.BASEBOARD_FAB2(SCH_1):GND
 G70    GND VSS<1125> @BASEBOARD_FAB2_LIB.BASEBOARD_FAB2(SCH_1):GND
 G76    GND VSS<1124> @BASEBOARD_FAB2_LIB.BASEBOARD_FAB2(SCH_1):GND
 G78    GND VSS<1123> @BASEBOARD_FAB2_LIB.BASEBOARD_FAB2(SCH_1):GND
 G80    GND VSS<1122> @BASEBOARD_FAB2_LIB.BASEBOARD_FAB2(SCH_1):GND
 G82    GND VSS<1121> @BASEBOARD_FAB2_LIB.BASEBOARD_FAB2(SCH_1):GND
  H3    GND VSS<1120> @BASEBOARD_FAB2_LIB.BASEBOARD_FAB2(SCH_1):GND
 H11    GND VSS<1119> @BASEBOARD_FAB2_LIB.BASEBOARD_FAB2(SCH_1):GND
 H25    GND VSS<1118> @BASEBOARD_FAB2_LIB.BASEBOARD_FAB2(SCH_1):GND
 H27    GND VSS<1117> @BASEBOARD_FAB2_LIB.BASEBOARD_FAB2(SCH_1):GND
 H29    GND VSS<1116> @BASEBOARD_FAB2_LIB.BASEBOARD_FAB2(SCH_1):GND
 H31    GND VSS<1115> @BASEBOARD_FAB2_LIB.BASEBOARD_FAB2(SCH_1):GND
 H33    GND VSS<1114> @BASEBOARD_FAB2_LIB.BASEBOARD_FAB2(SCH_1):GND
 H35    GND VSS<1113> @BASEBOARD_FAB2_LIB.BASEBOARD_FAB2(SCH_1):GND
 H37    GND VSS<1112> @BASEBOARD_FAB2_LIB.BASEBOARD_FAB2(SCH_1):GND
 H39    GND VSS<1111> @BASEBOARD_FAB2_LIB.BASEBOARD_FAB2(SCH_1):GND
 H41    GND VSS<1110> @BASEBOARD_FAB2_LIB.BASEBOARD_FAB2(SCH_1):GND
 H65    GND VSS<1109> @BASEBOARD_FAB2_LIB.BASEBOARD_FAB2(SCH_1):GND
 H71    GND VSS<1108> @BASEBOARD_FAB2_LIB.BASEBOARD_FAB2(SCH_1):GND
 H75    GND VSS<1107> @BASEBOARD_FAB2_LIB.BASEBOARD_FAB2(SCH_1):GND
DN44    GND VSS<1106> @BASEBOARD_FAB2_LIB.BASEBOARD_FAB2(SCH_1):GND
  J4    GND VSS<1105> @BASEBOARD_FAB2_LIB.BASEBOARD_FAB2(SCH_1):GND
 J12    GND VSS<1104> @BASEBOARD_FAB2_LIB.BASEBOARD_FAB2(SCH_1):GND
 J14    GND VSS<1103> @BASEBOARD_FAB2_LIB.BASEBOARD_FAB2(SCH_1):GND
 J22    GND VSS<1102> @BASEBOARD_FAB2_LIB.BASEBOARD_FAB2(SCH_1):GND
 J26    GND VSS<1101> @BASEBOARD_FAB2_LIB.BASEBOARD_FAB2(SCH_1):GND
 J28    GND VSS<1100> @BASEBOARD_FAB2_LIB.BASEBOARD_FAB2(SCH_1):GND
 J32    GND VSS<1099> @BASEBOARD_FAB2_LIB.BASEBOARD_FAB2(SCH_1):GND
 J34    GND VSS<1098> @BASEBOARD_FAB2_LIB.BASEBOARD_FAB2(SCH_1):GND
 J38    GND VSS<1097> @BASEBOARD_FAB2_LIB.BASEBOARD_FAB2(SCH_1):GND
 J40    GND VSS<1096> @BASEBOARD_FAB2_LIB.BASEBOARD_FAB2(SCH_1):GND
 J72    GND VSS<1095> @BASEBOARD_FAB2_LIB.BASEBOARD_FAB2(SCH_1):GND
 J74    GND VSS<1094> @BASEBOARD_FAB2_LIB.BASEBOARD_FAB2(SCH_1):GND

SKX_EXT_B_BGA1-IC,TBD  I21  U2D1
 J76    GND VSS<1093> @BASEBOARD_FAB2_LIB.BASEBOARD_FAB2(SCH_1):GND
 J82    GND VSS<1092> @BASEBOARD_FAB2_LIB.BASEBOARD_FAB2(SCH_1):GND
 J84    GND VSS<1091> @BASEBOARD_FAB2_LIB.BASEBOARD_FAB2(SCH_1):GND
  K1    GND VSS<1090> @BASEBOARD_FAB2_LIB.BASEBOARD_FAB2(SCH_1):GND
 K11    GND VSS<1089> @BASEBOARD_FAB2_LIB.BASEBOARD_FAB2(SCH_1):GND
 K13    GND VSS<1088> @BASEBOARD_FAB2_LIB.BASEBOARD_FAB2(SCH_1):GND
 K17    GND VSS<1087> @BASEBOARD_FAB2_LIB.BASEBOARD_FAB2(SCH_1):GND
 DB7    GND VSS<1086> @BASEBOARD_FAB2_LIB.BASEBOARD_FAB2(SCH_1):GND
 K27    GND VSS<1085> @BASEBOARD_FAB2_LIB.BASEBOARD_FAB2(SCH_1):GND
 K33    GND VSS<1084> @BASEBOARD_FAB2_LIB.BASEBOARD_FAB2(SCH_1):GND
 K39    GND VSS<1083> @BASEBOARD_FAB2_LIB.BASEBOARD_FAB2(SCH_1):GND
 K65    GND VSS<1082> @BASEBOARD_FAB2_LIB.BASEBOARD_FAB2(SCH_1):GND
 K67    GND VSS<1081> @BASEBOARD_FAB2_LIB.BASEBOARD_FAB2(SCH_1):GND
 K69    GND VSS<1080> @BASEBOARD_FAB2_LIB.BASEBOARD_FAB2(SCH_1):GND
 K71    GND VSS<1079> @BASEBOARD_FAB2_LIB.BASEBOARD_FAB2(SCH_1):GND
 K73    GND VSS<1078> @BASEBOARD_FAB2_LIB.BASEBOARD_FAB2(SCH_1):GND
 K77    GND VSS<1077> @BASEBOARD_FAB2_LIB.BASEBOARD_FAB2(SCH_1):GND
 K81    GND VSS<1076> @BASEBOARD_FAB2_LIB.BASEBOARD_FAB2(SCH_1):GND
 K83    GND VSS<1075> @BASEBOARD_FAB2_LIB.BASEBOARD_FAB2(SCH_1):GND
 K85    GND VSS<1074> @BASEBOARD_FAB2_LIB.BASEBOARD_FAB2(SCH_1):GND
 L10    GND VSS<1073> @BASEBOARD_FAB2_LIB.BASEBOARD_FAB2(SCH_1):GND
  L2    GND VSS<1072> @BASEBOARD_FAB2_LIB.BASEBOARD_FAB2(SCH_1):GND
  L6    GND VSS<1071> @BASEBOARD_FAB2_LIB.BASEBOARD_FAB2(SCH_1):GND
 L20    GND VSS<1070> @BASEBOARD_FAB2_LIB.BASEBOARD_FAB2(SCH_1):GND
 L22    GND VSS<1069> @BASEBOARD_FAB2_LIB.BASEBOARD_FAB2(SCH_1):GND
 L72    GND VSS<1068> @BASEBOARD_FAB2_LIB.BASEBOARD_FAB2(SCH_1):GND
 L78    GND VSS<1067> @BASEBOARD_FAB2_LIB.BASEBOARD_FAB2(SCH_1):GND
 L80    GND VSS<1066> @BASEBOARD_FAB2_LIB.BASEBOARD_FAB2(SCH_1):GND
 L82    GND VSS<1065> @BASEBOARD_FAB2_LIB.BASEBOARD_FAB2(SCH_1):GND
 BT9    GND VSS<1064> @BASEBOARD_FAB2_LIB.BASEBOARD_FAB2(SCH_1):GND
 CT7    GND VSS<1063> @BASEBOARD_FAB2_LIB.BASEBOARD_FAB2(SCH_1):GND
 M15    GND VSS<1062> @BASEBOARD_FAB2_LIB.BASEBOARD_FAB2(SCH_1):GND
 M17    GND VSS<1061> @BASEBOARD_FAB2_LIB.BASEBOARD_FAB2(SCH_1):GND
 M19    GND VSS<1060> @BASEBOARD_FAB2_LIB.BASEBOARD_FAB2(SCH_1):GND
 M23    GND VSS<1059> @BASEBOARD_FAB2_LIB.BASEBOARD_FAB2(SCH_1):GND
 M25    GND VSS<1058> @BASEBOARD_FAB2_LIB.BASEBOARD_FAB2(SCH_1):GND
 M27    GND VSS<1057> @BASEBOARD_FAB2_LIB.BASEBOARD_FAB2(SCH_1):GND
 M29    GND VSS<1056> @BASEBOARD_FAB2_LIB.BASEBOARD_FAB2(SCH_1):GND
 M31    GND VSS<1055> @BASEBOARD_FAB2_LIB.BASEBOARD_FAB2(SCH_1):GND
 M33    GND VSS<1054> @BASEBOARD_FAB2_LIB.BASEBOARD_FAB2(SCH_1):GND
 M35    GND VSS<1053> @BASEBOARD_FAB2_LIB.BASEBOARD_FAB2(SCH_1):GND
 M37    GND VSS<1052> @BASEBOARD_FAB2_LIB.BASEBOARD_FAB2(SCH_1):GND
 M39    GND VSS<1051> @BASEBOARD_FAB2_LIB.BASEBOARD_FAB2(SCH_1):GND
 M41    GND VSS<1050> @BASEBOARD_FAB2_LIB.BASEBOARD_FAB2(SCH_1):GND
 M43    GND VSS<1049> @BASEBOARD_FAB2_LIB.BASEBOARD_FAB2(SCH_1):GND
 M65    GND VSS<1048> @BASEBOARD_FAB2_LIB.BASEBOARD_FAB2(SCH_1):GND
 M71    GND VSS<1047> @BASEBOARD_FAB2_LIB.BASEBOARD_FAB2(SCH_1):GND
 M79    GND VSS<1046> @BASEBOARD_FAB2_LIB.BASEBOARD_FAB2(SCH_1):GND
 M83    GND VSS<1045> @BASEBOARD_FAB2_LIB.BASEBOARD_FAB2(SCH_1):GND
 M85    GND VSS<1044> @BASEBOARD_FAB2_LIB.BASEBOARD_FAB2(SCH_1):GND
DM19    GND VSS<1043> @BASEBOARD_FAB2_LIB.BASEBOARD_FAB2(SCH_1):GND
 N20    GND VSS<1042> @BASEBOARD_FAB2_LIB.BASEBOARD_FAB2(SCH_1):GND
 N22    GND VSS<1041> @BASEBOARD_FAB2_LIB.BASEBOARD_FAB2(SCH_1):GND
  N6    GND VSS<1040> @BASEBOARD_FAB2_LIB.BASEBOARD_FAB2(SCH_1):GND
 N66    GND VSS<1039> @BASEBOARD_FAB2_LIB.BASEBOARD_FAB2(SCH_1):GND
 N70    GND VSS<1038> @BASEBOARD_FAB2_LIB.BASEBOARD_FAB2(SCH_1):GND
 N72    GND VSS<1037> @BASEBOARD_FAB2_LIB.BASEBOARD_FAB2(SCH_1):GND
 N74    GND VSS<1036> @BASEBOARD_FAB2_LIB.BASEBOARD_FAB2(SCH_1):GND
 N76    GND VSS<1035> @BASEBOARD_FAB2_LIB.BASEBOARD_FAB2(SCH_1):GND
 N78    GND VSS<1034> @BASEBOARD_FAB2_LIB.BASEBOARD_FAB2(SCH_1):GND
  N4    GND VSS<1033> @BASEBOARD_FAB2_LIB.BASEBOARD_FAB2(SCH_1):GND
  N8    GND VSS<1032> @BASEBOARD_FAB2_LIB.BASEBOARD_FAB2(SCH_1):GND
 P11    GND VSS<1031> @BASEBOARD_FAB2_LIB.BASEBOARD_FAB2(SCH_1):GND
 P15    GND VSS<1030> @BASEBOARD_FAB2_LIB.BASEBOARD_FAB2(SCH_1):GND
 P27    GND VSS<1029> @BASEBOARD_FAB2_LIB.BASEBOARD_FAB2(SCH_1):GND
 P33    GND VSS<1028> @BASEBOARD_FAB2_LIB.BASEBOARD_FAB2(SCH_1):GND
 P39    GND VSS<1027> @BASEBOARD_FAB2_LIB.BASEBOARD_FAB2(SCH_1):GND
 P67    GND VSS<1026> @BASEBOARD_FAB2_LIB.BASEBOARD_FAB2(SCH_1):GND
 P69    GND VSS<1025> @BASEBOARD_FAB2_LIB.BASEBOARD_FAB2(SCH_1):GND
 P71    GND VSS<1024> @BASEBOARD_FAB2_LIB.BASEBOARD_FAB2(SCH_1):GND
 P81    GND VSS<1023> @BASEBOARD_FAB2_LIB.BASEBOARD_FAB2(SCH_1):GND
 P83    GND VSS<1022> @BASEBOARD_FAB2_LIB.BASEBOARD_FAB2(SCH_1):GND
 R14    GND VSS<1021> @BASEBOARD_FAB2_LIB.BASEBOARD_FAB2(SCH_1):GND
 R18    GND VSS<1020> @BASEBOARD_FAB2_LIB.BASEBOARD_FAB2(SCH_1):GND
  R2    GND VSS<1019> @BASEBOARD_FAB2_LIB.BASEBOARD_FAB2(SCH_1):GND
  R4    GND VSS<1018> @BASEBOARD_FAB2_LIB.BASEBOARD_FAB2(SCH_1):GND
 R22    GND VSS<1017> @BASEBOARD_FAB2_LIB.BASEBOARD_FAB2(SCH_1):GND
 R26    GND VSS<1016> @BASEBOARD_FAB2_LIB.BASEBOARD_FAB2(SCH_1):GND
 R28    GND VSS<1015> @BASEBOARD_FAB2_LIB.BASEBOARD_FAB2(SCH_1):GND
 R32    GND VSS<1014> @BASEBOARD_FAB2_LIB.BASEBOARD_FAB2(SCH_1):GND
 R34    GND VSS<1013> @BASEBOARD_FAB2_LIB.BASEBOARD_FAB2(SCH_1):GND
 R38    GND VSS<1012> @BASEBOARD_FAB2_LIB.BASEBOARD_FAB2(SCH_1):GND
 R40    GND VSS<1011> @BASEBOARD_FAB2_LIB.BASEBOARD_FAB2(SCH_1):GND
 R68    GND VSS<1010> @BASEBOARD_FAB2_LIB.BASEBOARD_FAB2(SCH_1):GND
 R72    GND VSS<1009> @BASEBOARD_FAB2_LIB.BASEBOARD_FAB2(SCH_1):GND
 R78    GND VSS<1008> @BASEBOARD_FAB2_LIB.BASEBOARD_FAB2(SCH_1):GND
 R86    GND VSS<1007> @BASEBOARD_FAB2_LIB.BASEBOARD_FAB2(SCH_1):GND
 T13    GND VSS<1006> @BASEBOARD_FAB2_LIB.BASEBOARD_FAB2(SCH_1):GND
 T17    GND VSS<1005> @BASEBOARD_FAB2_LIB.BASEBOARD_FAB2(SCH_1):GND
 T25    GND VSS<1004> @BASEBOARD_FAB2_LIB.BASEBOARD_FAB2(SCH_1):GND
 T29    GND VSS<1003> @BASEBOARD_FAB2_LIB.BASEBOARD_FAB2(SCH_1):GND
 T31    GND VSS<1002> @BASEBOARD_FAB2_LIB.BASEBOARD_FAB2(SCH_1):GND
 T35    GND VSS<1001> @BASEBOARD_FAB2_LIB.BASEBOARD_FAB2(SCH_1):GND
 T37    GND VSS<1000> @BASEBOARD_FAB2_LIB.BASEBOARD_FAB2(SCH_1):GND
 T41    GND VSS<999> @BASEBOARD_FAB2_LIB.BASEBOARD_FAB2(SCH_1):GND
 T65    GND VSS<998> @BASEBOARD_FAB2_LIB.BASEBOARD_FAB2(SCH_1):GND
 T73    GND VSS<997> @BASEBOARD_FAB2_LIB.BASEBOARD_FAB2(SCH_1):GND
 T77    GND VSS<996> @BASEBOARD_FAB2_LIB.BASEBOARD_FAB2(SCH_1):GND
 T83    GND VSS<995> @BASEBOARD_FAB2_LIB.BASEBOARD_FAB2(SCH_1):GND
 T85    GND VSS<994> @BASEBOARD_FAB2_LIB.BASEBOARD_FAB2(SCH_1):GND
  U2    GND VSS<993> @BASEBOARD_FAB2_LIB.BASEBOARD_FAB2(SCH_1):GND
  U4    GND VSS<992> @BASEBOARD_FAB2_LIB.BASEBOARD_FAB2(SCH_1):GND
  U6    GND VSS<991> @BASEBOARD_FAB2_LIB.BASEBOARD_FAB2(SCH_1):GND
 U20    GND VSS<990> @BASEBOARD_FAB2_LIB.BASEBOARD_FAB2(SCH_1):GND
 U22    GND VSS<989> @BASEBOARD_FAB2_LIB.BASEBOARD_FAB2(SCH_1):GND
 U24    GND VSS<988> @BASEBOARD_FAB2_LIB.BASEBOARD_FAB2(SCH_1):GND
 U30    GND VSS<987> @BASEBOARD_FAB2_LIB.BASEBOARD_FAB2(SCH_1):GND
 U36    GND VSS<986> @BASEBOARD_FAB2_LIB.BASEBOARD_FAB2(SCH_1):GND
 U42    GND VSS<985> @BASEBOARD_FAB2_LIB.BASEBOARD_FAB2(SCH_1):GND
 U68    GND VSS<984> @BASEBOARD_FAB2_LIB.BASEBOARD_FAB2(SCH_1):GND
 U70    GND VSS<983> @BASEBOARD_FAB2_LIB.BASEBOARD_FAB2(SCH_1):GND
 U74    GND VSS<982> @BASEBOARD_FAB2_LIB.BASEBOARD_FAB2(SCH_1):GND
 U76    GND VSS<981> @BASEBOARD_FAB2_LIB.BASEBOARD_FAB2(SCH_1):GND
 U78    GND VSS<980> @BASEBOARD_FAB2_LIB.BASEBOARD_FAB2(SCH_1):GND
 U80    GND VSS<979> @BASEBOARD_FAB2_LIB.BASEBOARD_FAB2(SCH_1):GND
 U86    GND VSS<978> @BASEBOARD_FAB2_LIB.BASEBOARD_FAB2(SCH_1):GND
  V1    GND VSS<977> @BASEBOARD_FAB2_LIB.BASEBOARD_FAB2(SCH_1):GND
  V5    GND VSS<976> @BASEBOARD_FAB2_LIB.BASEBOARD_FAB2(SCH_1):GND
  V9    GND VSS<975> @BASEBOARD_FAB2_LIB.BASEBOARD_FAB2(SCH_1):GND
 V13    GND VSS<974> @BASEBOARD_FAB2_LIB.BASEBOARD_FAB2(SCH_1):GND
 V15    GND VSS<973> @BASEBOARD_FAB2_LIB.BASEBOARD_FAB2(SCH_1):GND
 V21    GND VSS<972> @BASEBOARD_FAB2_LIB.BASEBOARD_FAB2(SCH_1):GND
 V23    GND VSS<971> @BASEBOARD_FAB2_LIB.BASEBOARD_FAB2(SCH_1):GND
 V43    GND VSS<970> @BASEBOARD_FAB2_LIB.BASEBOARD_FAB2(SCH_1):GND
 V73    GND VSS<969> @BASEBOARD_FAB2_LIB.BASEBOARD_FAB2(SCH_1):GND
 V75    GND VSS<968> @BASEBOARD_FAB2_LIB.BASEBOARD_FAB2(SCH_1):GND
 V77    GND VSS<967> @BASEBOARD_FAB2_LIB.BASEBOARD_FAB2(SCH_1):GND
 V83    GND VSS<966> @BASEBOARD_FAB2_LIB.BASEBOARD_FAB2(SCH_1):GND
  W8    GND VSS<965> @BASEBOARD_FAB2_LIB.BASEBOARD_FAB2(SCH_1):GND
AC56    GND VSS<964> @BASEBOARD_FAB2_LIB.BASEBOARD_FAB2(SCH_1):GND
 W12    GND VSS<963> @BASEBOARD_FAB2_LIB.BASEBOARD_FAB2(SCH_1):GND
 W22    GND VSS<962> @BASEBOARD_FAB2_LIB.BASEBOARD_FAB2(SCH_1):GND
 W24    GND VSS<961> @BASEBOARD_FAB2_LIB.BASEBOARD_FAB2(SCH_1):GND
 W26    GND VSS<960> @BASEBOARD_FAB2_LIB.BASEBOARD_FAB2(SCH_1):GND
 W28    GND VSS<959> @BASEBOARD_FAB2_LIB.BASEBOARD_FAB2(SCH_1):GND
 W30    GND VSS<958> @BASEBOARD_FAB2_LIB.BASEBOARD_FAB2(SCH_1):GND
 W32    GND VSS<957> @BASEBOARD_FAB2_LIB.BASEBOARD_FAB2(SCH_1):GND
 W34    GND VSS<956> @BASEBOARD_FAB2_LIB.BASEBOARD_FAB2(SCH_1):GND
 W36    GND VSS<955> @BASEBOARD_FAB2_LIB.BASEBOARD_FAB2(SCH_1):GND
 W38    GND VSS<954> @BASEBOARD_FAB2_LIB.BASEBOARD_FAB2(SCH_1):GND
 W40    GND VSS<953> @BASEBOARD_FAB2_LIB.BASEBOARD_FAB2(SCH_1):GND
 W42    GND VSS<952> @BASEBOARD_FAB2_LIB.BASEBOARD_FAB2(SCH_1):GND
 W68    GND VSS<951> @BASEBOARD_FAB2_LIB.BASEBOARD_FAB2(SCH_1):GND
 W74    GND VSS<950> @BASEBOARD_FAB2_LIB.BASEBOARD_FAB2(SCH_1):GND
 W78    GND VSS<949> @BASEBOARD_FAB2_LIB.BASEBOARD_FAB2(SCH_1):GND
 W82    GND VSS<948> @BASEBOARD_FAB2_LIB.BASEBOARD_FAB2(SCH_1):GND
 Y15    GND VSS<947> @BASEBOARD_FAB2_LIB.BASEBOARD_FAB2(SCH_1):GND
 Y17    GND VSS<946> @BASEBOARD_FAB2_LIB.BASEBOARD_FAB2(SCH_1):GND
  Y5    GND VSS<945> @BASEBOARD_FAB2_LIB.BASEBOARD_FAB2(SCH_1):GND
 Y67    GND VSS<944> @BASEBOARD_FAB2_LIB.BASEBOARD_FAB2(SCH_1):GND
  Y7    GND VSS<943> @BASEBOARD_FAB2_LIB.BASEBOARD_FAB2(SCH_1):GND
  Y9    GND VSS<942> @BASEBOARD_FAB2_LIB.BASEBOARD_FAB2(SCH_1):GND
 Y71    GND VSS<941> @BASEBOARD_FAB2_LIB.BASEBOARD_FAB2(SCH_1):GND
 Y73    GND VSS<940> @BASEBOARD_FAB2_LIB.BASEBOARD_FAB2(SCH_1):GND
 Y79    GND VSS<939> @BASEBOARD_FAB2_LIB.BASEBOARD_FAB2(SCH_1):GND
 Y81    GND VSS<938> @BASEBOARD_FAB2_LIB.BASEBOARD_FAB2(SCH_1):GND
 Y83    GND VSS<937> @BASEBOARD_FAB2_LIB.BASEBOARD_FAB2(SCH_1):GND
 Y85    GND VSS<936> @BASEBOARD_FAB2_LIB.BASEBOARD_FAB2(SCH_1):GND
 AA4    GND VSS<935> @BASEBOARD_FAB2_LIB.BASEBOARD_FAB2(SCH_1):GND
AA16    GND VSS<934> @BASEBOARD_FAB2_LIB.BASEBOARD_FAB2(SCH_1):GND

SKX_EXT_B_BGA1-IC,TBD  I22  U2D1
AA18    GND VSS<933> @BASEBOARD_FAB2_LIB.BASEBOARD_FAB2(SCH_1):GND
AA22    GND VSS<932> @BASEBOARD_FAB2_LIB.BASEBOARD_FAB2(SCH_1):GND
AA24    GND VSS<931> @BASEBOARD_FAB2_LIB.BASEBOARD_FAB2(SCH_1):GND
AA30    GND VSS<930> @BASEBOARD_FAB2_LIB.BASEBOARD_FAB2(SCH_1):GND
AA36    GND VSS<929> @BASEBOARD_FAB2_LIB.BASEBOARD_FAB2(SCH_1):GND
AA42    GND VSS<928> @BASEBOARD_FAB2_LIB.BASEBOARD_FAB2(SCH_1):GND
AA64    GND VSS<927> @BASEBOARD_FAB2_LIB.BASEBOARD_FAB2(SCH_1):GND
AA66    GND VSS<926> @BASEBOARD_FAB2_LIB.BASEBOARD_FAB2(SCH_1):GND
AA68    GND VSS<925> @BASEBOARD_FAB2_LIB.BASEBOARD_FAB2(SCH_1):GND
AA76    GND VSS<924> @BASEBOARD_FAB2_LIB.BASEBOARD_FAB2(SCH_1):GND
AA78    GND VSS<923> @BASEBOARD_FAB2_LIB.BASEBOARD_FAB2(SCH_1):GND
AA80    GND VSS<922> @BASEBOARD_FAB2_LIB.BASEBOARD_FAB2(SCH_1):GND
AA82    GND VSS<921> @BASEBOARD_FAB2_LIB.BASEBOARD_FAB2(SCH_1):GND
 AB1    GND VSS<920> @BASEBOARD_FAB2_LIB.BASEBOARD_FAB2(SCH_1):GND
 AB5    GND VSS<919> @BASEBOARD_FAB2_LIB.BASEBOARD_FAB2(SCH_1):GND
AB11    GND VSS<918> @BASEBOARD_FAB2_LIB.BASEBOARD_FAB2(SCH_1):GND
AB21    GND VSS<917> @BASEBOARD_FAB2_LIB.BASEBOARD_FAB2(SCH_1):GND
AB23    GND VSS<916> @BASEBOARD_FAB2_LIB.BASEBOARD_FAB2(SCH_1):GND
AB25    GND VSS<915> @BASEBOARD_FAB2_LIB.BASEBOARD_FAB2(SCH_1):GND
AB29    GND VSS<914> @BASEBOARD_FAB2_LIB.BASEBOARD_FAB2(SCH_1):GND
AB31    GND VSS<913> @BASEBOARD_FAB2_LIB.BASEBOARD_FAB2(SCH_1):GND
AB35    GND VSS<912> @BASEBOARD_FAB2_LIB.BASEBOARD_FAB2(SCH_1):GND
AB37    GND VSS<911> @BASEBOARD_FAB2_LIB.BASEBOARD_FAB2(SCH_1):GND
AB41    GND VSS<910> @BASEBOARD_FAB2_LIB.BASEBOARD_FAB2(SCH_1):GND
AB65    GND VSS<909> @BASEBOARD_FAB2_LIB.BASEBOARD_FAB2(SCH_1):GND
AB69    GND VSS<908> @BASEBOARD_FAB2_LIB.BASEBOARD_FAB2(SCH_1):GND
AB73    GND VSS<907> @BASEBOARD_FAB2_LIB.BASEBOARD_FAB2(SCH_1):GND
AB79    GND VSS<906> @BASEBOARD_FAB2_LIB.BASEBOARD_FAB2(SCH_1):GND
AB83    GND VSS<905> @BASEBOARD_FAB2_LIB.BASEBOARD_FAB2(SCH_1):GND
AB85    GND VSS<904> @BASEBOARD_FAB2_LIB.BASEBOARD_FAB2(SCH_1):GND
AC18    GND VSS<903> @BASEBOARD_FAB2_LIB.BASEBOARD_FAB2(SCH_1):GND
AC22    GND VSS<902> @BASEBOARD_FAB2_LIB.BASEBOARD_FAB2(SCH_1):GND
AC26    GND VSS<901> @BASEBOARD_FAB2_LIB.BASEBOARD_FAB2(SCH_1):GND
AC28    GND VSS<900> @BASEBOARD_FAB2_LIB.BASEBOARD_FAB2(SCH_1):GND
AC32    GND VSS<899> @BASEBOARD_FAB2_LIB.BASEBOARD_FAB2(SCH_1):GND
AC34    GND VSS<898> @BASEBOARD_FAB2_LIB.BASEBOARD_FAB2(SCH_1):GND
AC38    GND VSS<897> @BASEBOARD_FAB2_LIB.BASEBOARD_FAB2(SCH_1):GND
AC40    GND VSS<896> @BASEBOARD_FAB2_LIB.BASEBOARD_FAB2(SCH_1):GND
AC64    GND VSS<895> @BASEBOARD_FAB2_LIB.BASEBOARD_FAB2(SCH_1):GND
AC70    GND VSS<894> @BASEBOARD_FAB2_LIB.BASEBOARD_FAB2(SCH_1):GND
AC72    GND VSS<893> @BASEBOARD_FAB2_LIB.BASEBOARD_FAB2(SCH_1):GND
AC78    GND VSS<892> @BASEBOARD_FAB2_LIB.BASEBOARD_FAB2(SCH_1):GND
AC84    GND VSS<891> @BASEBOARD_FAB2_LIB.BASEBOARD_FAB2(SCH_1):GND
AC86    GND VSS<890> @BASEBOARD_FAB2_LIB.BASEBOARD_FAB2(SCH_1):GND
 AD3    GND VSS<889> @BASEBOARD_FAB2_LIB.BASEBOARD_FAB2(SCH_1):GND
 AD7    GND VSS<888> @BASEBOARD_FAB2_LIB.BASEBOARD_FAB2(SCH_1):GND
 AD9    GND VSS<887> @BASEBOARD_FAB2_LIB.BASEBOARD_FAB2(SCH_1):GND
AD11    GND VSS<886> @BASEBOARD_FAB2_LIB.BASEBOARD_FAB2(SCH_1):GND
AD13    GND VSS<885> @BASEBOARD_FAB2_LIB.BASEBOARD_FAB2(SCH_1):GND
AD15    GND VSS<884> @BASEBOARD_FAB2_LIB.BASEBOARD_FAB2(SCH_1):GND
AD19    GND VSS<883> @BASEBOARD_FAB2_LIB.BASEBOARD_FAB2(SCH_1):GND
AD21    GND VSS<882> @BASEBOARD_FAB2_LIB.BASEBOARD_FAB2(SCH_1):GND
AD27    GND VSS<881> @BASEBOARD_FAB2_LIB.BASEBOARD_FAB2(SCH_1):GND
AD33    GND VSS<880> @BASEBOARD_FAB2_LIB.BASEBOARD_FAB2(SCH_1):GND
AD39    GND VSS<879> @BASEBOARD_FAB2_LIB.BASEBOARD_FAB2(SCH_1):GND
AD43    GND VSS<878> @BASEBOARD_FAB2_LIB.BASEBOARD_FAB2(SCH_1):GND
AD71    GND VSS<877> @BASEBOARD_FAB2_LIB.BASEBOARD_FAB2(SCH_1):GND
AD73    GND VSS<876> @BASEBOARD_FAB2_LIB.BASEBOARD_FAB2(SCH_1):GND
AD75    GND VSS<875> @BASEBOARD_FAB2_LIB.BASEBOARD_FAB2(SCH_1):GND
AD81    GND VSS<874> @BASEBOARD_FAB2_LIB.BASEBOARD_FAB2(SCH_1):GND
AD83    GND VSS<873> @BASEBOARD_FAB2_LIB.BASEBOARD_FAB2(SCH_1):GND
AD85    GND VSS<872> @BASEBOARD_FAB2_LIB.BASEBOARD_FAB2(SCH_1):GND
 AE4    GND VSS<871> @BASEBOARD_FAB2_LIB.BASEBOARD_FAB2(SCH_1):GND
 AE8    GND VSS<870> @BASEBOARD_FAB2_LIB.BASEBOARD_FAB2(SCH_1):GND
AC54    GND VSS<869> @BASEBOARD_FAB2_LIB.BASEBOARD_FAB2(SCH_1):GND
AE16    GND VSS<868> @BASEBOARD_FAB2_LIB.BASEBOARD_FAB2(SCH_1):GND
AE38    GND VSS<867> @BASEBOARD_FAB2_LIB.BASEBOARD_FAB2(SCH_1):GND
AE40    GND VSS<866> @BASEBOARD_FAB2_LIB.BASEBOARD_FAB2(SCH_1):GND
AE42    GND VSS<865> @BASEBOARD_FAB2_LIB.BASEBOARD_FAB2(SCH_1):GND
AE64    GND VSS<864> @BASEBOARD_FAB2_LIB.BASEBOARD_FAB2(SCH_1):GND
AE66    GND VSS<863> @BASEBOARD_FAB2_LIB.BASEBOARD_FAB2(SCH_1):GND
AE68    GND VSS<862> @BASEBOARD_FAB2_LIB.BASEBOARD_FAB2(SCH_1):GND
AE70    GND VSS<861> @BASEBOARD_FAB2_LIB.BASEBOARD_FAB2(SCH_1):GND
AE78    GND VSS<860> @BASEBOARD_FAB2_LIB.BASEBOARD_FAB2(SCH_1):GND
 AF1    GND VSS<859> @BASEBOARD_FAB2_LIB.BASEBOARD_FAB2(SCH_1):GND
AC52    GND VSS<858> @BASEBOARD_FAB2_LIB.BASEBOARD_FAB2(SCH_1):GND
 AF9    GND VSS<857> @BASEBOARD_FAB2_LIB.BASEBOARD_FAB2(SCH_1):GND
AF21    GND VSS<856> @BASEBOARD_FAB2_LIB.BASEBOARD_FAB2(SCH_1):GND
AF23    GND VSS<855> @BASEBOARD_FAB2_LIB.BASEBOARD_FAB2(SCH_1):GND
AF25    GND VSS<854> @BASEBOARD_FAB2_LIB.BASEBOARD_FAB2(SCH_1):GND
AF27    GND VSS<853> @BASEBOARD_FAB2_LIB.BASEBOARD_FAB2(SCH_1):GND
AF29    GND VSS<852> @BASEBOARD_FAB2_LIB.BASEBOARD_FAB2(SCH_1):GND
AF31    GND VSS<851> @BASEBOARD_FAB2_LIB.BASEBOARD_FAB2(SCH_1):GND
AF33    GND VSS<850> @BASEBOARD_FAB2_LIB.BASEBOARD_FAB2(SCH_1):GND
AF37    GND VSS<849> @BASEBOARD_FAB2_LIB.BASEBOARD_FAB2(SCH_1):GND
AF39    GND VSS<848> @BASEBOARD_FAB2_LIB.BASEBOARD_FAB2(SCH_1):GND
AF41    GND VSS<847> @BASEBOARD_FAB2_LIB.BASEBOARD_FAB2(SCH_1):GND
AF73    GND VSS<846> @BASEBOARD_FAB2_LIB.BASEBOARD_FAB2(SCH_1):GND
AF77    GND VSS<845> @BASEBOARD_FAB2_LIB.BASEBOARD_FAB2(SCH_1):GND
AF83    GND VSS<844> @BASEBOARD_FAB2_LIB.BASEBOARD_FAB2(SCH_1):GND
AF85    GND VSS<843> @BASEBOARD_FAB2_LIB.BASEBOARD_FAB2(SCH_1):GND
AG12    GND VSS<842> @BASEBOARD_FAB2_LIB.BASEBOARD_FAB2(SCH_1):GND
AG14    GND VSS<841> @BASEBOARD_FAB2_LIB.BASEBOARD_FAB2(SCH_1):GND
AG18    GND VSS<840> @BASEBOARD_FAB2_LIB.BASEBOARD_FAB2(SCH_1):GND
AG36    GND VSS<839> @BASEBOARD_FAB2_LIB.BASEBOARD_FAB2(SCH_1):GND
AG64    GND VSS<838> @BASEBOARD_FAB2_LIB.BASEBOARD_FAB2(SCH_1):GND
AG70    GND VSS<837> @BASEBOARD_FAB2_LIB.BASEBOARD_FAB2(SCH_1):GND
AG74    GND VSS<836> @BASEBOARD_FAB2_LIB.BASEBOARD_FAB2(SCH_1):GND
AG76    GND VSS<835> @BASEBOARD_FAB2_LIB.BASEBOARD_FAB2(SCH_1):GND
AG78    GND VSS<834> @BASEBOARD_FAB2_LIB.BASEBOARD_FAB2(SCH_1):GND
AG80    GND VSS<833> @BASEBOARD_FAB2_LIB.BASEBOARD_FAB2(SCH_1):GND
 AH1    GND VSS<832> @BASEBOARD_FAB2_LIB.BASEBOARD_FAB2(SCH_1):GND
 AH5    GND VSS<831> @BASEBOARD_FAB2_LIB.BASEBOARD_FAB2(SCH_1):GND
AH21    GND VSS<830> @BASEBOARD_FAB2_LIB.BASEBOARD_FAB2(SCH_1):GND
AH27    GND VSS<829> @BASEBOARD_FAB2_LIB.BASEBOARD_FAB2(SCH_1):GND
AH33    GND VSS<828> @BASEBOARD_FAB2_LIB.BASEBOARD_FAB2(SCH_1):GND
AH35    GND VSS<827> @BASEBOARD_FAB2_LIB.BASEBOARD_FAB2(SCH_1):GND
AH45    GND VSS<826> @BASEBOARD_FAB2_LIB.BASEBOARD_FAB2(SCH_1):GND
AH47    GND VSS<825> @BASEBOARD_FAB2_LIB.BASEBOARD_FAB2(SCH_1):GND
AH49    GND VSS<824> @BASEBOARD_FAB2_LIB.BASEBOARD_FAB2(SCH_1):GND
AH51    GND VSS<823> @BASEBOARD_FAB2_LIB.BASEBOARD_FAB2(SCH_1):GND
AH53    GND VSS<822> @BASEBOARD_FAB2_LIB.BASEBOARD_FAB2(SCH_1):GND
AH59    GND VSS<821> @BASEBOARD_FAB2_LIB.BASEBOARD_FAB2(SCH_1):GND
AH61    GND VSS<820> @BASEBOARD_FAB2_LIB.BASEBOARD_FAB2(SCH_1):GND
AH65    GND VSS<819> @BASEBOARD_FAB2_LIB.BASEBOARD_FAB2(SCH_1):GND
AH69    GND VSS<818> @BASEBOARD_FAB2_LIB.BASEBOARD_FAB2(SCH_1):GND
AH75    GND VSS<817> @BASEBOARD_FAB2_LIB.BASEBOARD_FAB2(SCH_1):GND
AH77    GND VSS<816> @BASEBOARD_FAB2_LIB.BASEBOARD_FAB2(SCH_1):GND
AH83    GND VSS<815> @BASEBOARD_FAB2_LIB.BASEBOARD_FAB2(SCH_1):GND
 AJ8    GND VSS<814> @BASEBOARD_FAB2_LIB.BASEBOARD_FAB2(SCH_1):GND
AJ22    GND VSS<813> @BASEBOARD_FAB2_LIB.BASEBOARD_FAB2(SCH_1):GND
AJ26    GND VSS<812> @BASEBOARD_FAB2_LIB.BASEBOARD_FAB2(SCH_1):GND
AJ28    GND VSS<811> @BASEBOARD_FAB2_LIB.BASEBOARD_FAB2(SCH_1):GND
AJ32    GND VSS<810> @BASEBOARD_FAB2_LIB.BASEBOARD_FAB2(SCH_1):GND
AJ34    GND VSS<809> @BASEBOARD_FAB2_LIB.BASEBOARD_FAB2(SCH_1):GND
AJ46    GND VSS<808> @BASEBOARD_FAB2_LIB.BASEBOARD_FAB2(SCH_1):GND
AJ48    GND VSS<807> @BASEBOARD_FAB2_LIB.BASEBOARD_FAB2(SCH_1):GND
AJ50    GND VSS<806> @BASEBOARD_FAB2_LIB.BASEBOARD_FAB2(SCH_1):GND
AJ52    GND VSS<805> @BASEBOARD_FAB2_LIB.BASEBOARD_FAB2(SCH_1):GND
AJ54    GND VSS<804> @BASEBOARD_FAB2_LIB.BASEBOARD_FAB2(SCH_1):GND
AJ66    GND VSS<803> @BASEBOARD_FAB2_LIB.BASEBOARD_FAB2(SCH_1):GND
AJ68    GND VSS<802> @BASEBOARD_FAB2_LIB.BASEBOARD_FAB2(SCH_1):GND
AJ74    GND VSS<801> @BASEBOARD_FAB2_LIB.BASEBOARD_FAB2(SCH_1):GND
AJ78    GND VSS<800> @BASEBOARD_FAB2_LIB.BASEBOARD_FAB2(SCH_1):GND
AJ82    GND VSS<799> @BASEBOARD_FAB2_LIB.BASEBOARD_FAB2(SCH_1):GND
AJ86    GND VSS<798> @BASEBOARD_FAB2_LIB.BASEBOARD_FAB2(SCH_1):GND
 AK9    GND VSS<797> @BASEBOARD_FAB2_LIB.BASEBOARD_FAB2(SCH_1):GND
AK13    GND VSS<796> @BASEBOARD_FAB2_LIB.BASEBOARD_FAB2(SCH_1):GND
AK19    GND VSS<795> @BASEBOARD_FAB2_LIB.BASEBOARD_FAB2(SCH_1):GND
AK23    GND VSS<794> @BASEBOARD_FAB2_LIB.BASEBOARD_FAB2(SCH_1):GND
AK25    GND VSS<793> @BASEBOARD_FAB2_LIB.BASEBOARD_FAB2(SCH_1):GND
AK29    GND VSS<792> @BASEBOARD_FAB2_LIB.BASEBOARD_FAB2(SCH_1):GND
AK31    GND VSS<791> @BASEBOARD_FAB2_LIB.BASEBOARD_FAB2(SCH_1):GND
AK33    GND VSS<790> @BASEBOARD_FAB2_LIB.BASEBOARD_FAB2(SCH_1):GND
AK55    GND VSS<789> @BASEBOARD_FAB2_LIB.BASEBOARD_FAB2(SCH_1):GND
AK65    GND VSS<788> @BASEBOARD_FAB2_LIB.BASEBOARD_FAB2(SCH_1):GND
AK67    GND VSS<787> @BASEBOARD_FAB2_LIB.BASEBOARD_FAB2(SCH_1):GND
AK73    GND VSS<786> @BASEBOARD_FAB2_LIB.BASEBOARD_FAB2(SCH_1):GND
AK79    GND VSS<785> @BASEBOARD_FAB2_LIB.BASEBOARD_FAB2(SCH_1):GND
AK81    GND VSS<784> @BASEBOARD_FAB2_LIB.BASEBOARD_FAB2(SCH_1):GND
AK83    GND VSS<783> @BASEBOARD_FAB2_LIB.BASEBOARD_FAB2(SCH_1):GND
AK85    GND VSS<782> @BASEBOARD_FAB2_LIB.BASEBOARD_FAB2(SCH_1):GND
 AL4    GND VSS<781> @BASEBOARD_FAB2_LIB.BASEBOARD_FAB2(SCH_1):GND
AL10    GND VSS<780> @BASEBOARD_FAB2_LIB.BASEBOARD_FAB2(SCH_1):GND
AL24    GND VSS<779> @BASEBOARD_FAB2_LIB.BASEBOARD_FAB2(SCH_1):GND
AL30    GND VSS<778> @BASEBOARD_FAB2_LIB.BASEBOARD_FAB2(SCH_1):GND
AL32    GND VSS<777> @BASEBOARD_FAB2_LIB.BASEBOARD_FAB2(SCH_1):GND
AL56    GND VSS<776> @BASEBOARD_FAB2_LIB.BASEBOARD_FAB2(SCH_1):GND
AL64    GND VSS<775> @BASEBOARD_FAB2_LIB.BASEBOARD_FAB2(SCH_1):GND
AL68    GND VSS<774> @BASEBOARD_FAB2_LIB.BASEBOARD_FAB2(SCH_1):GND

SKX_EXT_B_BGA1-IC,TBD  I23  U2D1
AL76    GND VSS<773> @BASEBOARD_FAB2_LIB.BASEBOARD_FAB2(SCH_1):GND
AL78    GND VSS<772> @BASEBOARD_FAB2_LIB.BASEBOARD_FAB2(SCH_1):GND
AL80    GND VSS<771> @BASEBOARD_FAB2_LIB.BASEBOARD_FAB2(SCH_1):GND
AL82    GND VSS<770> @BASEBOARD_FAB2_LIB.BASEBOARD_FAB2(SCH_1):GND
AL86    GND VSS<769> @BASEBOARD_FAB2_LIB.BASEBOARD_FAB2(SCH_1):GND
 AM1    GND VSS<768> @BASEBOARD_FAB2_LIB.BASEBOARD_FAB2(SCH_1):GND
AC50    GND VSS<767> @BASEBOARD_FAB2_LIB.BASEBOARD_FAB2(SCH_1):GND
AM31    GND VSS<766> @BASEBOARD_FAB2_LIB.BASEBOARD_FAB2(SCH_1):GND
AM57    GND VSS<765> @BASEBOARD_FAB2_LIB.BASEBOARD_FAB2(SCH_1):GND
AM63    GND VSS<764> @BASEBOARD_FAB2_LIB.BASEBOARD_FAB2(SCH_1):GND
AM69    GND VSS<763> @BASEBOARD_FAB2_LIB.BASEBOARD_FAB2(SCH_1):GND
AM73    GND VSS<762> @BASEBOARD_FAB2_LIB.BASEBOARD_FAB2(SCH_1):GND
AM79    GND VSS<761> @BASEBOARD_FAB2_LIB.BASEBOARD_FAB2(SCH_1):GND
AM83    GND VSS<760> @BASEBOARD_FAB2_LIB.BASEBOARD_FAB2(SCH_1):GND
 AN2    GND VSS<759> @BASEBOARD_FAB2_LIB.BASEBOARD_FAB2(SCH_1):GND
 AN6    GND VSS<758> @BASEBOARD_FAB2_LIB.BASEBOARD_FAB2(SCH_1):GND
AN28    GND VSS<757> @BASEBOARD_FAB2_LIB.BASEBOARD_FAB2(SCH_1):GND
AN58    GND VSS<756> @BASEBOARD_FAB2_LIB.BASEBOARD_FAB2(SCH_1):GND
AN78    GND VSS<755> @BASEBOARD_FAB2_LIB.BASEBOARD_FAB2(SCH_1):GND
 AP5    GND VSS<754> @BASEBOARD_FAB2_LIB.BASEBOARD_FAB2(SCH_1):GND
 AP9    GND VSS<753> @BASEBOARD_FAB2_LIB.BASEBOARD_FAB2(SCH_1):GND
AP13    GND VSS<752> @BASEBOARD_FAB2_LIB.BASEBOARD_FAB2(SCH_1):GND
AP19    GND VSS<751> @BASEBOARD_FAB2_LIB.BASEBOARD_FAB2(SCH_1):GND
AP31    GND VSS<750> @BASEBOARD_FAB2_LIB.BASEBOARD_FAB2(SCH_1):GND
AP59    GND VSS<749> @BASEBOARD_FAB2_LIB.BASEBOARD_FAB2(SCH_1):GND
AP63    GND VSS<748> @BASEBOARD_FAB2_LIB.BASEBOARD_FAB2(SCH_1):GND
AP65    GND VSS<747> @BASEBOARD_FAB2_LIB.BASEBOARD_FAB2(SCH_1):GND
AP67    GND VSS<746> @BASEBOARD_FAB2_LIB.BASEBOARD_FAB2(SCH_1):GND
AP69    GND VSS<745> @BASEBOARD_FAB2_LIB.BASEBOARD_FAB2(SCH_1):GND
AP73    GND VSS<744> @BASEBOARD_FAB2_LIB.BASEBOARD_FAB2(SCH_1):GND
AP75    GND VSS<743> @BASEBOARD_FAB2_LIB.BASEBOARD_FAB2(SCH_1):GND
AP81    GND VSS<742> @BASEBOARD_FAB2_LIB.BASEBOARD_FAB2(SCH_1):GND
AP83    GND VSS<741> @BASEBOARD_FAB2_LIB.BASEBOARD_FAB2(SCH_1):GND
AP85    GND VSS<740> @BASEBOARD_FAB2_LIB.BASEBOARD_FAB2(SCH_1):GND
AR10    GND VSS<739> @BASEBOARD_FAB2_LIB.BASEBOARD_FAB2(SCH_1):GND
AR24    GND VSS<738> @BASEBOARD_FAB2_LIB.BASEBOARD_FAB2(SCH_1):GND
AR30    GND VSS<737> @BASEBOARD_FAB2_LIB.BASEBOARD_FAB2(SCH_1):GND
AR60    GND VSS<736> @BASEBOARD_FAB2_LIB.BASEBOARD_FAB2(SCH_1):GND
AR72    GND VSS<735> @BASEBOARD_FAB2_LIB.BASEBOARD_FAB2(SCH_1):GND
AR78    GND VSS<734> @BASEBOARD_FAB2_LIB.BASEBOARD_FAB2(SCH_1):GND
AC48    GND VSS<733> @BASEBOARD_FAB2_LIB.BASEBOARD_FAB2(SCH_1):GND
 P63    GND VSS<732> @BASEBOARD_FAB2_LIB.BASEBOARD_FAB2(SCH_1):GND
AT15    GND VSS<731> @BASEBOARD_FAB2_LIB.BASEBOARD_FAB2(SCH_1):GND
AT17    GND VSS<730> @BASEBOARD_FAB2_LIB.BASEBOARD_FAB2(SCH_1):GND
AT21    GND VSS<729> @BASEBOARD_FAB2_LIB.BASEBOARD_FAB2(SCH_1):GND
AT27    GND VSS<728> @BASEBOARD_FAB2_LIB.BASEBOARD_FAB2(SCH_1):GND
AT61    GND VSS<727> @BASEBOARD_FAB2_LIB.BASEBOARD_FAB2(SCH_1):GND
AT63    GND VSS<726> @BASEBOARD_FAB2_LIB.BASEBOARD_FAB2(SCH_1):GND
AT69    GND VSS<725> @BASEBOARD_FAB2_LIB.BASEBOARD_FAB2(SCH_1):GND
AT73    GND VSS<724> @BASEBOARD_FAB2_LIB.BASEBOARD_FAB2(SCH_1):GND
AT77    GND VSS<723> @BASEBOARD_FAB2_LIB.BASEBOARD_FAB2(SCH_1):GND
AT83    GND VSS<722> @BASEBOARD_FAB2_LIB.BASEBOARD_FAB2(SCH_1):GND
AT85    GND VSS<721> @BASEBOARD_FAB2_LIB.BASEBOARD_FAB2(SCH_1):GND
 AU2    GND VSS<720> @BASEBOARD_FAB2_LIB.BASEBOARD_FAB2(SCH_1):GND
 AU6    GND VSS<719> @BASEBOARD_FAB2_LIB.BASEBOARD_FAB2(SCH_1):GND
AU26    GND VSS<718> @BASEBOARD_FAB2_LIB.BASEBOARD_FAB2(SCH_1):GND
AU28    GND VSS<717> @BASEBOARD_FAB2_LIB.BASEBOARD_FAB2(SCH_1):GND
AU62    GND VSS<716> @BASEBOARD_FAB2_LIB.BASEBOARD_FAB2(SCH_1):GND
AU64    GND VSS<715> @BASEBOARD_FAB2_LIB.BASEBOARD_FAB2(SCH_1):GND
AU68    GND VSS<714> @BASEBOARD_FAB2_LIB.BASEBOARD_FAB2(SCH_1):GND
AU74    GND VSS<713> @BASEBOARD_FAB2_LIB.BASEBOARD_FAB2(SCH_1):GND
AU76    GND VSS<712> @BASEBOARD_FAB2_LIB.BASEBOARD_FAB2(SCH_1):GND
AU78    GND VSS<711> @BASEBOARD_FAB2_LIB.BASEBOARD_FAB2(SCH_1):GND
AU80    GND VSS<710> @BASEBOARD_FAB2_LIB.BASEBOARD_FAB2(SCH_1):GND
AU84    GND VSS<709> @BASEBOARD_FAB2_LIB.BASEBOARD_FAB2(SCH_1):GND
AU86    GND VSS<708> @BASEBOARD_FAB2_LIB.BASEBOARD_FAB2(SCH_1):GND
 AV1    GND VSS<707> @BASEBOARD_FAB2_LIB.BASEBOARD_FAB2(SCH_1):GND
 AV3    GND VSS<706> @BASEBOARD_FAB2_LIB.BASEBOARD_FAB2(SCH_1):GND
 AV7    GND VSS<705> @BASEBOARD_FAB2_LIB.BASEBOARD_FAB2(SCH_1):GND
AV11    GND VSS<704> @BASEBOARD_FAB2_LIB.BASEBOARD_FAB2(SCH_1):GND
AV13    GND VSS<703> @BASEBOARD_FAB2_LIB.BASEBOARD_FAB2(SCH_1):GND
AV19    GND VSS<702> @BASEBOARD_FAB2_LIB.BASEBOARD_FAB2(SCH_1):GND
AV23    GND VSS<701> @BASEBOARD_FAB2_LIB.BASEBOARD_FAB2(SCH_1):GND
AV25    GND VSS<700> @BASEBOARD_FAB2_LIB.BASEBOARD_FAB2(SCH_1):GND
AV63    GND VSS<699> @BASEBOARD_FAB2_LIB.BASEBOARD_FAB2(SCH_1):GND
AV65    GND VSS<698> @BASEBOARD_FAB2_LIB.BASEBOARD_FAB2(SCH_1):GND
AV67    GND VSS<697> @BASEBOARD_FAB2_LIB.BASEBOARD_FAB2(SCH_1):GND
AV75    GND VSS<696> @BASEBOARD_FAB2_LIB.BASEBOARD_FAB2(SCH_1):GND
AV83    GND VSS<695> @BASEBOARD_FAB2_LIB.BASEBOARD_FAB2(SCH_1):GND
 AW2    GND VSS<694> @BASEBOARD_FAB2_LIB.BASEBOARD_FAB2(SCH_1):GND
AW10    GND VSS<693> @BASEBOARD_FAB2_LIB.BASEBOARD_FAB2(SCH_1):GND
AW62    GND VSS<692> @BASEBOARD_FAB2_LIB.BASEBOARD_FAB2(SCH_1):GND
AW66    GND VSS<691> @BASEBOARD_FAB2_LIB.BASEBOARD_FAB2(SCH_1):GND
AW68    GND VSS<690> @BASEBOARD_FAB2_LIB.BASEBOARD_FAB2(SCH_1):GND
AW70    GND VSS<689> @BASEBOARD_FAB2_LIB.BASEBOARD_FAB2(SCH_1):GND
AW72    GND VSS<688> @BASEBOARD_FAB2_LIB.BASEBOARD_FAB2(SCH_1):GND
AW74    GND VSS<687> @BASEBOARD_FAB2_LIB.BASEBOARD_FAB2(SCH_1):GND
AW78    GND VSS<686> @BASEBOARD_FAB2_LIB.BASEBOARD_FAB2(SCH_1):GND
AW82    GND VSS<685> @BASEBOARD_FAB2_LIB.BASEBOARD_FAB2(SCH_1):GND
AW84    GND VSS<684> @BASEBOARD_FAB2_LIB.BASEBOARD_FAB2(SCH_1):GND
 AY5    GND VSS<683> @BASEBOARD_FAB2_LIB.BASEBOARD_FAB2(SCH_1):GND
AY15    GND VSS<682> @BASEBOARD_FAB2_LIB.BASEBOARD_FAB2(SCH_1):GND
AY17    GND VSS<681> @BASEBOARD_FAB2_LIB.BASEBOARD_FAB2(SCH_1):GND
AY21    GND VSS<680> @BASEBOARD_FAB2_LIB.BASEBOARD_FAB2(SCH_1):GND
AY23    GND VSS<679> @BASEBOARD_FAB2_LIB.BASEBOARD_FAB2(SCH_1):GND
AY25    GND VSS<678> @BASEBOARD_FAB2_LIB.BASEBOARD_FAB2(SCH_1):GND
AY63    GND VSS<677> @BASEBOARD_FAB2_LIB.BASEBOARD_FAB2(SCH_1):GND
AY79    GND VSS<676> @BASEBOARD_FAB2_LIB.BASEBOARD_FAB2(SCH_1):GND
AY81    GND VSS<675> @BASEBOARD_FAB2_LIB.BASEBOARD_FAB2(SCH_1):GND
 BA2    GND VSS<674> @BASEBOARD_FAB2_LIB.BASEBOARD_FAB2(SCH_1):GND
 BA6    GND VSS<673> @BASEBOARD_FAB2_LIB.BASEBOARD_FAB2(SCH_1):GND
BA12    GND VSS<672> @BASEBOARD_FAB2_LIB.BASEBOARD_FAB2(SCH_1):GND
BA62    GND VSS<671> @BASEBOARD_FAB2_LIB.BASEBOARD_FAB2(SCH_1):GND
BA68    GND VSS<670> @BASEBOARD_FAB2_LIB.BASEBOARD_FAB2(SCH_1):GND
BA74    GND VSS<669> @BASEBOARD_FAB2_LIB.BASEBOARD_FAB2(SCH_1):GND
BA80    GND VSS<668> @BASEBOARD_FAB2_LIB.BASEBOARD_FAB2(SCH_1):GND
BA84    GND VSS<667> @BASEBOARD_FAB2_LIB.BASEBOARD_FAB2(SCH_1):GND
BB19    GND VSS<666> @BASEBOARD_FAB2_LIB.BASEBOARD_FAB2(SCH_1):GND
BB23    GND VSS<665> @BASEBOARD_FAB2_LIB.BASEBOARD_FAB2(SCH_1):GND
BB63    GND VSS<664> @BASEBOARD_FAB2_LIB.BASEBOARD_FAB2(SCH_1):GND
BB69    GND VSS<663> @BASEBOARD_FAB2_LIB.BASEBOARD_FAB2(SCH_1):GND
BB73    GND VSS<662> @BASEBOARD_FAB2_LIB.BASEBOARD_FAB2(SCH_1):GND
BB75    GND VSS<661> @BASEBOARD_FAB2_LIB.BASEBOARD_FAB2(SCH_1):GND
BB77    GND VSS<660> @BASEBOARD_FAB2_LIB.BASEBOARD_FAB2(SCH_1):GND
BB79    GND VSS<659> @BASEBOARD_FAB2_LIB.BASEBOARD_FAB2(SCH_1):GND
BB81    GND VSS<658> @BASEBOARD_FAB2_LIB.BASEBOARD_FAB2(SCH_1):GND
BB83    GND VSS<657> @BASEBOARD_FAB2_LIB.BASEBOARD_FAB2(SCH_1):GND
 BC4    GND VSS<656> @BASEBOARD_FAB2_LIB.BASEBOARD_FAB2(SCH_1):GND
 BC8    GND VSS<655> @BASEBOARD_FAB2_LIB.BASEBOARD_FAB2(SCH_1):GND
BC12    GND VSS<654> @BASEBOARD_FAB2_LIB.BASEBOARD_FAB2(SCH_1):GND
BC16    GND VSS<653> @BASEBOARD_FAB2_LIB.BASEBOARD_FAB2(SCH_1):GND
BC70    GND VSS<652> @BASEBOARD_FAB2_LIB.BASEBOARD_FAB2(SCH_1):GND
BC72    GND VSS<651> @BASEBOARD_FAB2_LIB.BASEBOARD_FAB2(SCH_1):GND
BC74    GND VSS<650> @BASEBOARD_FAB2_LIB.BASEBOARD_FAB2(SCH_1):GND
BC76    GND VSS<649> @BASEBOARD_FAB2_LIB.BASEBOARD_FAB2(SCH_1):GND
BC78    GND VSS<648> @BASEBOARD_FAB2_LIB.BASEBOARD_FAB2(SCH_1):GND
BC80    GND VSS<647> @BASEBOARD_FAB2_LIB.BASEBOARD_FAB2(SCH_1):GND
BC82    GND VSS<646> @BASEBOARD_FAB2_LIB.BASEBOARD_FAB2(SCH_1):GND
 BD5    GND VSS<645> @BASEBOARD_FAB2_LIB.BASEBOARD_FAB2(SCH_1):GND
BD11    GND VSS<644> @BASEBOARD_FAB2_LIB.BASEBOARD_FAB2(SCH_1):GND
BD15    GND VSS<643> @BASEBOARD_FAB2_LIB.BASEBOARD_FAB2(SCH_1):GND
BD21    GND VSS<642> @BASEBOARD_FAB2_LIB.BASEBOARD_FAB2(SCH_1):GND
BD27    GND VSS<641> @BASEBOARD_FAB2_LIB.BASEBOARD_FAB2(SCH_1):GND
BD63    GND VSS<640> @BASEBOARD_FAB2_LIB.BASEBOARD_FAB2(SCH_1):GND
BD71    GND VSS<639> @BASEBOARD_FAB2_LIB.BASEBOARD_FAB2(SCH_1):GND
 BE4    GND VSS<638> @BASEBOARD_FAB2_LIB.BASEBOARD_FAB2(SCH_1):GND
 BE6    GND VSS<637> @BASEBOARD_FAB2_LIB.BASEBOARD_FAB2(SCH_1):GND
 BE8    GND VSS<636> @BASEBOARD_FAB2_LIB.BASEBOARD_FAB2(SCH_1):GND
BE10    GND VSS<635> @BASEBOARD_FAB2_LIB.BASEBOARD_FAB2(SCH_1):GND
BE26    GND VSS<634> @BASEBOARD_FAB2_LIB.BASEBOARD_FAB2(SCH_1):GND
BE64    GND VSS<633> @BASEBOARD_FAB2_LIB.BASEBOARD_FAB2(SCH_1):GND
BE66    GND VSS<632> @BASEBOARD_FAB2_LIB.BASEBOARD_FAB2(SCH_1):GND
BE68    GND VSS<631> @BASEBOARD_FAB2_LIB.BASEBOARD_FAB2(SCH_1):GND
BE70    GND VSS<630> @BASEBOARD_FAB2_LIB.BASEBOARD_FAB2(SCH_1):GND
 BF9    GND VSS<629> @BASEBOARD_FAB2_LIB.BASEBOARD_FAB2(SCH_1):GND
BF15    GND VSS<628> @BASEBOARD_FAB2_LIB.BASEBOARD_FAB2(SCH_1):GND
BF17    GND VSS<627> @BASEBOARD_FAB2_LIB.BASEBOARD_FAB2(SCH_1):GND
BF19    GND VSS<626> @BASEBOARD_FAB2_LIB.BASEBOARD_FAB2(SCH_1):GND
BF25    GND VSS<625> @BASEBOARD_FAB2_LIB.BASEBOARD_FAB2(SCH_1):GND
BF63    GND VSS<624> @BASEBOARD_FAB2_LIB.BASEBOARD_FAB2(SCH_1):GND
BF65    GND VSS<623> @BASEBOARD_FAB2_LIB.BASEBOARD_FAB2(SCH_1):GND
BF67    GND VSS<622> @BASEBOARD_FAB2_LIB.BASEBOARD_FAB2(SCH_1):GND
BF69    GND VSS<621> @BASEBOARD_FAB2_LIB.BASEBOARD_FAB2(SCH_1):GND
BF71    GND VSS<620> @BASEBOARD_FAB2_LIB.BASEBOARD_FAB2(SCH_1):GND
 BG6    GND VSS<619> @BASEBOARD_FAB2_LIB.BASEBOARD_FAB2(SCH_1):GND
 BG8    GND VSS<618> @BASEBOARD_FAB2_LIB.BASEBOARD_FAB2(SCH_1):GND
BG10    GND VSS<617> @BASEBOARD_FAB2_LIB.BASEBOARD_FAB2(SCH_1):GND
BG22    GND VSS<616> @BASEBOARD_FAB2_LIB.BASEBOARD_FAB2(SCH_1):GND
BG24    GND VSS<615> @BASEBOARD_FAB2_LIB.BASEBOARD_FAB2(SCH_1):GND
BG72    GND VSS<614> @BASEBOARD_FAB2_LIB.BASEBOARD_FAB2(SCH_1):GND


DRAWING: @BASEBOARD_FAB2_LIB.BASEBOARD_FAB2(SCH_1):PAGE75 

SKX_EXT_B_BGA1-IC,TBD  I17  U2D1
BG74    GND VSS<613> @BASEBOARD_FAB2_LIB.BASEBOARD_FAB2(SCH_1):GND
BG76    GND VSS<612> @BASEBOARD_FAB2_LIB.BASEBOARD_FAB2(SCH_1):GND
BG78    GND VSS<611> @BASEBOARD_FAB2_LIB.BASEBOARD_FAB2(SCH_1):GND
BG80    GND VSS<610> @BASEBOARD_FAB2_LIB.BASEBOARD_FAB2(SCH_1):GND
BG82    GND VSS<609> @BASEBOARD_FAB2_LIB.BASEBOARD_FAB2(SCH_1):GND
 BH7    GND VSS<608> @BASEBOARD_FAB2_LIB.BASEBOARD_FAB2(SCH_1):GND
 BH9    GND VSS<607> @BASEBOARD_FAB2_LIB.BASEBOARD_FAB2(SCH_1):GND
BH11    GND VSS<606> @BASEBOARD_FAB2_LIB.BASEBOARD_FAB2(SCH_1):GND
BH15    GND VSS<605> @BASEBOARD_FAB2_LIB.BASEBOARD_FAB2(SCH_1):GND
BH21    GND VSS<604> @BASEBOARD_FAB2_LIB.BASEBOARD_FAB2(SCH_1):GND
 BJ4    GND VSS<603> @BASEBOARD_FAB2_LIB.BASEBOARD_FAB2(SCH_1):GND
 BJ6    GND VSS<602> @BASEBOARD_FAB2_LIB.BASEBOARD_FAB2(SCH_1):GND
 BK3    GND VSS<601> @BASEBOARD_FAB2_LIB.BASEBOARD_FAB2(SCH_1):GND
 BK7    GND VSS<600> @BASEBOARD_FAB2_LIB.BASEBOARD_FAB2(SCH_1):GND
BK11    GND VSS<599> @BASEBOARD_FAB2_LIB.BASEBOARD_FAB2(SCH_1):GND
BK19    GND VSS<598> @BASEBOARD_FAB2_LIB.BASEBOARD_FAB2(SCH_1):GND
 BL6    GND VSS<597> @BASEBOARD_FAB2_LIB.BASEBOARD_FAB2(SCH_1):GND
BL10    GND VSS<596> @BASEBOARD_FAB2_LIB.BASEBOARD_FAB2(SCH_1):GND
BL12    GND VSS<595> @BASEBOARD_FAB2_LIB.BASEBOARD_FAB2(SCH_1):GND
 P61    GND VSS<594> @BASEBOARD_FAB2_LIB.BASEBOARD_FAB2(SCH_1):GND
BL22    GND VSS<593> @BASEBOARD_FAB2_LIB.BASEBOARD_FAB2(SCH_1):GND
BL24    GND VSS<592> @BASEBOARD_FAB2_LIB.BASEBOARD_FAB2(SCH_1):GND
BL64    GND VSS<591> @BASEBOARD_FAB2_LIB.BASEBOARD_FAB2(SCH_1):GND
BL66    GND VSS<590> @BASEBOARD_FAB2_LIB.BASEBOARD_FAB2(SCH_1):GND
BL68    GND VSS<589> @BASEBOARD_FAB2_LIB.BASEBOARD_FAB2(SCH_1):GND
BL70    GND VSS<588> @BASEBOARD_FAB2_LIB.BASEBOARD_FAB2(SCH_1):GND
BL72    GND VSS<587> @BASEBOARD_FAB2_LIB.BASEBOARD_FAB2(SCH_1):GND
BL74    GND VSS<586> @BASEBOARD_FAB2_LIB.BASEBOARD_FAB2(SCH_1):GND
BL76    GND VSS<585> @BASEBOARD_FAB2_LIB.BASEBOARD_FAB2(SCH_1):GND
BL78    GND VSS<584> @BASEBOARD_FAB2_LIB.BASEBOARD_FAB2(SCH_1):GND
BL80    GND VSS<583> @BASEBOARD_FAB2_LIB.BASEBOARD_FAB2(SCH_1):GND
BL82    GND VSS<582> @BASEBOARD_FAB2_LIB.BASEBOARD_FAB2(SCH_1):GND
 BM9    GND VSS<581> @BASEBOARD_FAB2_LIB.BASEBOARD_FAB2(SCH_1):GND
BM13    GND VSS<580> @BASEBOARD_FAB2_LIB.BASEBOARD_FAB2(SCH_1):GND
BM15    GND VSS<579> @BASEBOARD_FAB2_LIB.BASEBOARD_FAB2(SCH_1):GND
 P59    GND VSS<578> @BASEBOARD_FAB2_LIB.BASEBOARD_FAB2(SCH_1):GND
BM25    GND VSS<577> @BASEBOARD_FAB2_LIB.BASEBOARD_FAB2(SCH_1):GND
 BN6    GND VSS<576> @BASEBOARD_FAB2_LIB.BASEBOARD_FAB2(SCH_1):GND
BN10    GND VSS<575> @BASEBOARD_FAB2_LIB.BASEBOARD_FAB2(SCH_1):GND
BN20    GND VSS<574> @BASEBOARD_FAB2_LIB.BASEBOARD_FAB2(SCH_1):GND
BN26    GND VSS<573> @BASEBOARD_FAB2_LIB.BASEBOARD_FAB2(SCH_1):GND
 BP3    GND VSS<572> @BASEBOARD_FAB2_LIB.BASEBOARD_FAB2(SCH_1):GND
BP27    GND VSS<571> @BASEBOARD_FAB2_LIB.BASEBOARD_FAB2(SCH_1):GND
 BR6    GND VSS<570> @BASEBOARD_FAB2_LIB.BASEBOARD_FAB2(SCH_1):GND
BR10    GND VSS<569> @BASEBOARD_FAB2_LIB.BASEBOARD_FAB2(SCH_1):GND
BR16    GND VSS<568> @BASEBOARD_FAB2_LIB.BASEBOARD_FAB2(SCH_1):GND
 P57    GND VSS<567> @BASEBOARD_FAB2_LIB.BASEBOARD_FAB2(SCH_1):GND
BR64    GND VSS<566> @BASEBOARD_FAB2_LIB.BASEBOARD_FAB2(SCH_1):GND
BR66    GND VSS<565> @BASEBOARD_FAB2_LIB.BASEBOARD_FAB2(SCH_1):GND
BR68    GND VSS<564> @BASEBOARD_FAB2_LIB.BASEBOARD_FAB2(SCH_1):GND
BR70    GND VSS<563> @BASEBOARD_FAB2_LIB.BASEBOARD_FAB2(SCH_1):GND
BR72    GND VSS<562> @BASEBOARD_FAB2_LIB.BASEBOARD_FAB2(SCH_1):GND
BR74    GND VSS<561> @BASEBOARD_FAB2_LIB.BASEBOARD_FAB2(SCH_1):GND
BR76    GND VSS<560> @BASEBOARD_FAB2_LIB.BASEBOARD_FAB2(SCH_1):GND
BR78    GND VSS<559> @BASEBOARD_FAB2_LIB.BASEBOARD_FAB2(SCH_1):GND
BR80    GND VSS<558> @BASEBOARD_FAB2_LIB.BASEBOARD_FAB2(SCH_1):GND
BR82    GND VSS<557> @BASEBOARD_FAB2_LIB.BASEBOARD_FAB2(SCH_1):GND
 BT3    GND VSS<556> @BASEBOARD_FAB2_LIB.BASEBOARD_FAB2(SCH_1):GND
 BT5    GND VSS<555> @BASEBOARD_FAB2_LIB.BASEBOARD_FAB2(SCH_1):GND
BT21    GND VSS<554> @BASEBOARD_FAB2_LIB.BASEBOARD_FAB2(SCH_1):GND
BT23    GND VSS<553> @BASEBOARD_FAB2_LIB.BASEBOARD_FAB2(SCH_1):GND
BT25    GND VSS<552> @BASEBOARD_FAB2_LIB.BASEBOARD_FAB2(SCH_1):GND
 BU8    GND VSS<551> @BASEBOARD_FAB2_LIB.BASEBOARD_FAB2(SCH_1):GND
 BV5    GND VSS<550> @BASEBOARD_FAB2_LIB.BASEBOARD_FAB2(SCH_1):GND
BU10    GND VSS<549> @BASEBOARD_FAB2_LIB.BASEBOARD_FAB2(SCH_1):GND
BV17    GND VSS<548> @BASEBOARD_FAB2_LIB.BASEBOARD_FAB2(SCH_1):GND
BV25    GND VSS<547> @BASEBOARD_FAB2_LIB.BASEBOARD_FAB2(SCH_1):GND
 BW6    GND VSS<546> @BASEBOARD_FAB2_LIB.BASEBOARD_FAB2(SCH_1):GND
 P55    GND VSS<545> @BASEBOARD_FAB2_LIB.BASEBOARD_FAB2(SCH_1):GND
BW12    GND VSS<544> @BASEBOARD_FAB2_LIB.BASEBOARD_FAB2(SCH_1):GND
BW14    GND VSS<543> @BASEBOARD_FAB2_LIB.BASEBOARD_FAB2(SCH_1):GND
BW16    GND VSS<542> @BASEBOARD_FAB2_LIB.BASEBOARD_FAB2(SCH_1):GND
BW18    GND VSS<541> @BASEBOARD_FAB2_LIB.BASEBOARD_FAB2(SCH_1):GND
BW26    GND VSS<540> @BASEBOARD_FAB2_LIB.BASEBOARD_FAB2(SCH_1):GND
BW72    GND VSS<539> @BASEBOARD_FAB2_LIB.BASEBOARD_FAB2(SCH_1):GND
BW74    GND VSS<538> @BASEBOARD_FAB2_LIB.BASEBOARD_FAB2(SCH_1):GND
BW76    GND VSS<537> @BASEBOARD_FAB2_LIB.BASEBOARD_FAB2(SCH_1):GND
BW78    GND VSS<536> @BASEBOARD_FAB2_LIB.BASEBOARD_FAB2(SCH_1):GND
BW80    GND VSS<535> @BASEBOARD_FAB2_LIB.BASEBOARD_FAB2(SCH_1):GND
BW82    GND VSS<534> @BASEBOARD_FAB2_LIB.BASEBOARD_FAB2(SCH_1):GND
BY11    GND VSS<533> @BASEBOARD_FAB2_LIB.BASEBOARD_FAB2(SCH_1):GND
BY13    GND VSS<532> @BASEBOARD_FAB2_LIB.BASEBOARD_FAB2(SCH_1):GND
BY23    GND VSS<531> @BASEBOARD_FAB2_LIB.BASEBOARD_FAB2(SCH_1):GND
BY63    GND VSS<530> @BASEBOARD_FAB2_LIB.BASEBOARD_FAB2(SCH_1):GND
BY65    GND VSS<529> @BASEBOARD_FAB2_LIB.BASEBOARD_FAB2(SCH_1):GND
BY67    GND VSS<528> @BASEBOARD_FAB2_LIB.BASEBOARD_FAB2(SCH_1):GND
BY69    GND VSS<527> @BASEBOARD_FAB2_LIB.BASEBOARD_FAB2(SCH_1):GND
BY71    GND VSS<526> @BASEBOARD_FAB2_LIB.BASEBOARD_FAB2(SCH_1):GND
 CA2    GND VSS<525> @BASEBOARD_FAB2_LIB.BASEBOARD_FAB2(SCH_1):GND
 CA6    GND VSS<524> @BASEBOARD_FAB2_LIB.BASEBOARD_FAB2(SCH_1):GND
 CA8    GND VSS<523> @BASEBOARD_FAB2_LIB.BASEBOARD_FAB2(SCH_1):GND
CA10    GND VSS<522> @BASEBOARD_FAB2_LIB.BASEBOARD_FAB2(SCH_1):GND
CA14    GND VSS<521> @BASEBOARD_FAB2_LIB.BASEBOARD_FAB2(SCH_1):GND
CA18    GND VSS<520> @BASEBOARD_FAB2_LIB.BASEBOARD_FAB2(SCH_1):GND
CA26    GND VSS<519> @BASEBOARD_FAB2_LIB.BASEBOARD_FAB2(SCH_1):GND
CA64    GND VSS<518> @BASEBOARD_FAB2_LIB.BASEBOARD_FAB2(SCH_1):GND
CA66    GND VSS<517> @BASEBOARD_FAB2_LIB.BASEBOARD_FAB2(SCH_1):GND
CA68    GND VSS<516> @BASEBOARD_FAB2_LIB.BASEBOARD_FAB2(SCH_1):GND
CA70    GND VSS<515> @BASEBOARD_FAB2_LIB.BASEBOARD_FAB2(SCH_1):GND
 CB7    GND VSS<514> @BASEBOARD_FAB2_LIB.BASEBOARD_FAB2(SCH_1):GND
 CB9    GND VSS<513> @BASEBOARD_FAB2_LIB.BASEBOARD_FAB2(SCH_1):GND
CB27    GND VSS<512> @BASEBOARD_FAB2_LIB.BASEBOARD_FAB2(SCH_1):GND
CB63    GND VSS<511> @BASEBOARD_FAB2_LIB.BASEBOARD_FAB2(SCH_1):GND
CB71    GND VSS<510> @BASEBOARD_FAB2_LIB.BASEBOARD_FAB2(SCH_1):GND
 CC4    GND VSS<509> @BASEBOARD_FAB2_LIB.BASEBOARD_FAB2(SCH_1):GND
CC16    GND VSS<508> @BASEBOARD_FAB2_LIB.BASEBOARD_FAB2(SCH_1):GND
CC18    GND VSS<507> @BASEBOARD_FAB2_LIB.BASEBOARD_FAB2(SCH_1):GND
CC24    GND VSS<506> @BASEBOARD_FAB2_LIB.BASEBOARD_FAB2(SCH_1):GND
CC64    GND VSS<505> @BASEBOARD_FAB2_LIB.BASEBOARD_FAB2(SCH_1):GND
CC72    GND VSS<504> @BASEBOARD_FAB2_LIB.BASEBOARD_FAB2(SCH_1):GND
CC74    GND VSS<503> @BASEBOARD_FAB2_LIB.BASEBOARD_FAB2(SCH_1):GND
CC76    GND VSS<502> @BASEBOARD_FAB2_LIB.BASEBOARD_FAB2(SCH_1):GND
CC78    GND VSS<501> @BASEBOARD_FAB2_LIB.BASEBOARD_FAB2(SCH_1):GND
CC80    GND VSS<500> @BASEBOARD_FAB2_LIB.BASEBOARD_FAB2(SCH_1):GND
CC82    GND VSS<499> @BASEBOARD_FAB2_LIB.BASEBOARD_FAB2(SCH_1):GND
 CD5    GND VSS<498> @BASEBOARD_FAB2_LIB.BASEBOARD_FAB2(SCH_1):GND
CD13    GND VSS<497> @BASEBOARD_FAB2_LIB.BASEBOARD_FAB2(SCH_1):GND
CD63    GND VSS<496> @BASEBOARD_FAB2_LIB.BASEBOARD_FAB2(SCH_1):GND
CD73    GND VSS<495> @BASEBOARD_FAB2_LIB.BASEBOARD_FAB2(SCH_1):GND
CD75    GND VSS<494> @BASEBOARD_FAB2_LIB.BASEBOARD_FAB2(SCH_1):GND
CD77    GND VSS<493> @BASEBOARD_FAB2_LIB.BASEBOARD_FAB2(SCH_1):GND
CD79    GND VSS<492> @BASEBOARD_FAB2_LIB.BASEBOARD_FAB2(SCH_1):GND
CD81    GND VSS<491> @BASEBOARD_FAB2_LIB.BASEBOARD_FAB2(SCH_1):GND
CE10    GND VSS<490> @BASEBOARD_FAB2_LIB.BASEBOARD_FAB2(SCH_1):GND
CE14    GND VSS<489> @BASEBOARD_FAB2_LIB.BASEBOARD_FAB2(SCH_1):GND
CE20    GND VSS<488> @BASEBOARD_FAB2_LIB.BASEBOARD_FAB2(SCH_1):GND
CE26    GND VSS<487> @BASEBOARD_FAB2_LIB.BASEBOARD_FAB2(SCH_1):GND
CE62    GND VSS<486> @BASEBOARD_FAB2_LIB.BASEBOARD_FAB2(SCH_1):GND
CE70    GND VSS<485> @BASEBOARD_FAB2_LIB.BASEBOARD_FAB2(SCH_1):GND
CE82    GND VSS<484> @BASEBOARD_FAB2_LIB.BASEBOARD_FAB2(SCH_1):GND
 P53    GND VSS<483> @BASEBOARD_FAB2_LIB.BASEBOARD_FAB2(SCH_1):GND
 CF9    GND VSS<482> @BASEBOARD_FAB2_LIB.BASEBOARD_FAB2(SCH_1):GND
CF63    GND VSS<481> @BASEBOARD_FAB2_LIB.BASEBOARD_FAB2(SCH_1):GND
CF69    GND VSS<480> @BASEBOARD_FAB2_LIB.BASEBOARD_FAB2(SCH_1):GND
CF71    GND VSS<479> @BASEBOARD_FAB2_LIB.BASEBOARD_FAB2(SCH_1):GND
CF77    GND VSS<478> @BASEBOARD_FAB2_LIB.BASEBOARD_FAB2(SCH_1):GND
CF83    GND VSS<477> @BASEBOARD_FAB2_LIB.BASEBOARD_FAB2(SCH_1):GND
 P51    GND VSS<476> @BASEBOARD_FAB2_LIB.BASEBOARD_FAB2(SCH_1):GND
CG18    GND VSS<475> @BASEBOARD_FAB2_LIB.BASEBOARD_FAB2(SCH_1):GND
CG22    GND VSS<474> @BASEBOARD_FAB2_LIB.BASEBOARD_FAB2(SCH_1):GND
CG62    GND VSS<473> @BASEBOARD_FAB2_LIB.BASEBOARD_FAB2(SCH_1):GND
CG68    GND VSS<472> @BASEBOARD_FAB2_LIB.BASEBOARD_FAB2(SCH_1):GND
CG72    GND VSS<471> @BASEBOARD_FAB2_LIB.BASEBOARD_FAB2(SCH_1):GND
CG80    GND VSS<470> @BASEBOARD_FAB2_LIB.BASEBOARD_FAB2(SCH_1):GND
 CH1    GND VSS<469> @BASEBOARD_FAB2_LIB.BASEBOARD_FAB2(SCH_1):GND
 CH3    GND VSS<468> @BASEBOARD_FAB2_LIB.BASEBOARD_FAB2(SCH_1):GND
CH15    GND VSS<467> @BASEBOARD_FAB2_LIB.BASEBOARD_FAB2(SCH_1):GND
CH19    GND VSS<466> @BASEBOARD_FAB2_LIB.BASEBOARD_FAB2(SCH_1):GND
CH63    GND VSS<465> @BASEBOARD_FAB2_LIB.BASEBOARD_FAB2(SCH_1):GND
CH67    GND VSS<464> @BASEBOARD_FAB2_LIB.BASEBOARD_FAB2(SCH_1):GND
CH73    GND VSS<463> @BASEBOARD_FAB2_LIB.BASEBOARD_FAB2(SCH_1):GND
CH79    GND VSS<462> @BASEBOARD_FAB2_LIB.BASEBOARD_FAB2(SCH_1):GND
CH81    GND VSS<461> @BASEBOARD_FAB2_LIB.BASEBOARD_FAB2(SCH_1):GND
CH83    GND VSS<460> @BASEBOARD_FAB2_LIB.BASEBOARD_FAB2(SCH_1):GND
 CJ2    GND VSS<459> @BASEBOARD_FAB2_LIB.BASEBOARD_FAB2(SCH_1):GND
 CJ6    GND VSS<458> @BASEBOARD_FAB2_LIB.BASEBOARD_FAB2(SCH_1):GND
 CJ8    GND VSS<457> @BASEBOARD_FAB2_LIB.BASEBOARD_FAB2(SCH_1):GND
CJ10    GND VSS<456> @BASEBOARD_FAB2_LIB.BASEBOARD_FAB2(SCH_1):GND
CJ12    GND VSS<455> @BASEBOARD_FAB2_LIB.BASEBOARD_FAB2(SCH_1):GND
 P49    GND VSS<454> @BASEBOARD_FAB2_LIB.BASEBOARD_FAB2(SCH_1):GND

SKX_EXT_B_BGA1-IC,TBD  I18  U2D1
 P47    GND VSS<453> @BASEBOARD_FAB2_LIB.BASEBOARD_FAB2(SCH_1):GND
CJ62    GND VSS<452> @BASEBOARD_FAB2_LIB.BASEBOARD_FAB2(SCH_1):GND
CJ74    GND VSS<451> @BASEBOARD_FAB2_LIB.BASEBOARD_FAB2(SCH_1):GND
CJ76    GND VSS<450> @BASEBOARD_FAB2_LIB.BASEBOARD_FAB2(SCH_1):GND
CJ78    GND VSS<449> @BASEBOARD_FAB2_LIB.BASEBOARD_FAB2(SCH_1):GND
CJ82    GND VSS<448> @BASEBOARD_FAB2_LIB.BASEBOARD_FAB2(SCH_1):GND
CJ84    GND VSS<447> @BASEBOARD_FAB2_LIB.BASEBOARD_FAB2(SCH_1):GND
CJ86    GND VSS<446> @BASEBOARD_FAB2_LIB.BASEBOARD_FAB2(SCH_1):GND
CK11    GND VSS<445> @BASEBOARD_FAB2_LIB.BASEBOARD_FAB2(SCH_1):GND
CK15    GND VSS<444> @BASEBOARD_FAB2_LIB.BASEBOARD_FAB2(SCH_1):GND
CK21    GND VSS<443> @BASEBOARD_FAB2_LIB.BASEBOARD_FAB2(SCH_1):GND
CK27    GND VSS<442> @BASEBOARD_FAB2_LIB.BASEBOARD_FAB2(SCH_1):GND
CK63    GND VSS<441> @BASEBOARD_FAB2_LIB.BASEBOARD_FAB2(SCH_1):GND
CK65    GND VSS<440> @BASEBOARD_FAB2_LIB.BASEBOARD_FAB2(SCH_1):GND
CK67    GND VSS<439> @BASEBOARD_FAB2_LIB.BASEBOARD_FAB2(SCH_1):GND
CK69    GND VSS<438> @BASEBOARD_FAB2_LIB.BASEBOARD_FAB2(SCH_1):GND
CK71    GND VSS<437> @BASEBOARD_FAB2_LIB.BASEBOARD_FAB2(SCH_1):GND
CK73    GND VSS<436> @BASEBOARD_FAB2_LIB.BASEBOARD_FAB2(SCH_1):GND
CK75    GND VSS<435> @BASEBOARD_FAB2_LIB.BASEBOARD_FAB2(SCH_1):GND
CK83    GND VSS<434> @BASEBOARD_FAB2_LIB.BASEBOARD_FAB2(SCH_1):GND
CK85    GND VSS<433> @BASEBOARD_FAB2_LIB.BASEBOARD_FAB2(SCH_1):GND
 CL8    GND VSS<432> @BASEBOARD_FAB2_LIB.BASEBOARD_FAB2(SCH_1):GND
CL14    GND VSS<431> @BASEBOARD_FAB2_LIB.BASEBOARD_FAB2(SCH_1):GND
CL18    GND VSS<430> @BASEBOARD_FAB2_LIB.BASEBOARD_FAB2(SCH_1):GND
 P45    GND VSS<429> @BASEBOARD_FAB2_LIB.BASEBOARD_FAB2(SCH_1):GND
 H63    GND VSS<428> @BASEBOARD_FAB2_LIB.BASEBOARD_FAB2(SCH_1):GND
CL62    GND VSS<427> @BASEBOARD_FAB2_LIB.BASEBOARD_FAB2(SCH_1):GND
CL64    GND VSS<426> @BASEBOARD_FAB2_LIB.BASEBOARD_FAB2(SCH_1):GND
CL66    GND VSS<425> @BASEBOARD_FAB2_LIB.BASEBOARD_FAB2(SCH_1):GND
CL74    GND VSS<424> @BASEBOARD_FAB2_LIB.BASEBOARD_FAB2(SCH_1):GND
CL76    GND VSS<423> @BASEBOARD_FAB2_LIB.BASEBOARD_FAB2(SCH_1):GND
CL78    GND VSS<422> @BASEBOARD_FAB2_LIB.BASEBOARD_FAB2(SCH_1):GND
CL80    GND VSS<421> @BASEBOARD_FAB2_LIB.BASEBOARD_FAB2(SCH_1):GND
CM19    GND VSS<420> @BASEBOARD_FAB2_LIB.BASEBOARD_FAB2(SCH_1):GND
CM29    GND VSS<419> @BASEBOARD_FAB2_LIB.BASEBOARD_FAB2(SCH_1):GND
 CM5    GND VSS<418> @BASEBOARD_FAB2_LIB.BASEBOARD_FAB2(SCH_1):GND
CM31    GND VSS<417> @BASEBOARD_FAB2_LIB.BASEBOARD_FAB2(SCH_1):GND
CM61    GND VSS<416> @BASEBOARD_FAB2_LIB.BASEBOARD_FAB2(SCH_1):GND
CM63    GND VSS<415> @BASEBOARD_FAB2_LIB.BASEBOARD_FAB2(SCH_1):GND
CM67    GND VSS<414> @BASEBOARD_FAB2_LIB.BASEBOARD_FAB2(SCH_1):GND
CM73    GND VSS<413> @BASEBOARD_FAB2_LIB.BASEBOARD_FAB2(SCH_1):GND
CM77    GND VSS<412> @BASEBOARD_FAB2_LIB.BASEBOARD_FAB2(SCH_1):GND
CM83    GND VSS<411> @BASEBOARD_FAB2_LIB.BASEBOARD_FAB2(SCH_1):GND
CM85    GND VSS<410> @BASEBOARD_FAB2_LIB.BASEBOARD_FAB2(SCH_1):GND
 CN2    GND VSS<409> @BASEBOARD_FAB2_LIB.BASEBOARD_FAB2(SCH_1):GND
CN12    GND VSS<408> @BASEBOARD_FAB2_LIB.BASEBOARD_FAB2(SCH_1):GND
 H61    GND VSS<407> @BASEBOARD_FAB2_LIB.BASEBOARD_FAB2(SCH_1):GND
CN26    GND VSS<406> @BASEBOARD_FAB2_LIB.BASEBOARD_FAB2(SCH_1):GND
CN32    GND VSS<405> @BASEBOARD_FAB2_LIB.BASEBOARD_FAB2(SCH_1):GND
CN60    GND VSS<404> @BASEBOARD_FAB2_LIB.BASEBOARD_FAB2(SCH_1):GND
CN62    GND VSS<403> @BASEBOARD_FAB2_LIB.BASEBOARD_FAB2(SCH_1):GND
CN68    GND VSS<402> @BASEBOARD_FAB2_LIB.BASEBOARD_FAB2(SCH_1):GND
CN78    GND VSS<401> @BASEBOARD_FAB2_LIB.BASEBOARD_FAB2(SCH_1):GND
 CP1    GND VSS<400> @BASEBOARD_FAB2_LIB.BASEBOARD_FAB2(SCH_1):GND
 H59    GND VSS<399> @BASEBOARD_FAB2_LIB.BASEBOARD_FAB2(SCH_1):GND
CP25    GND VSS<398> @BASEBOARD_FAB2_LIB.BASEBOARD_FAB2(SCH_1):GND
CP59    GND VSS<397> @BASEBOARD_FAB2_LIB.BASEBOARD_FAB2(SCH_1):GND
CP69    GND VSS<396> @BASEBOARD_FAB2_LIB.BASEBOARD_FAB2(SCH_1):GND
CP73    GND VSS<395> @BASEBOARD_FAB2_LIB.BASEBOARD_FAB2(SCH_1):GND
CP75    GND VSS<394> @BASEBOARD_FAB2_LIB.BASEBOARD_FAB2(SCH_1):GND
CP81    GND VSS<393> @BASEBOARD_FAB2_LIB.BASEBOARD_FAB2(SCH_1):GND
CP83    GND VSS<392> @BASEBOARD_FAB2_LIB.BASEBOARD_FAB2(SCH_1):GND
 CR6    GND VSS<391> @BASEBOARD_FAB2_LIB.BASEBOARD_FAB2(SCH_1):GND
CR10    GND VSS<390> @BASEBOARD_FAB2_LIB.BASEBOARD_FAB2(SCH_1):GND
CR22    GND VSS<389> @BASEBOARD_FAB2_LIB.BASEBOARD_FAB2(SCH_1):GND
CR24    GND VSS<388> @BASEBOARD_FAB2_LIB.BASEBOARD_FAB2(SCH_1):GND
CR32    GND VSS<387> @BASEBOARD_FAB2_LIB.BASEBOARD_FAB2(SCH_1):GND
CR58    GND VSS<386> @BASEBOARD_FAB2_LIB.BASEBOARD_FAB2(SCH_1):GND
CR62    GND VSS<385> @BASEBOARD_FAB2_LIB.BASEBOARD_FAB2(SCH_1):GND
CR64    GND VSS<384> @BASEBOARD_FAB2_LIB.BASEBOARD_FAB2(SCH_1):GND
CR66    GND VSS<383> @BASEBOARD_FAB2_LIB.BASEBOARD_FAB2(SCH_1):GND
CR68    GND VSS<382> @BASEBOARD_FAB2_LIB.BASEBOARD_FAB2(SCH_1):GND
CR78    GND VSS<381> @BASEBOARD_FAB2_LIB.BASEBOARD_FAB2(SCH_1):GND
CR86    GND VSS<380> @BASEBOARD_FAB2_LIB.BASEBOARD_FAB2(SCH_1):GND
 H57    GND VSS<379> @BASEBOARD_FAB2_LIB.BASEBOARD_FAB2(SCH_1):GND
CT13    GND VSS<378> @BASEBOARD_FAB2_LIB.BASEBOARD_FAB2(SCH_1):GND
CT19    GND VSS<377> @BASEBOARD_FAB2_LIB.BASEBOARD_FAB2(SCH_1):GND
CT27    GND VSS<376> @BASEBOARD_FAB2_LIB.BASEBOARD_FAB2(SCH_1):GND
CT29    GND VSS<375> @BASEBOARD_FAB2_LIB.BASEBOARD_FAB2(SCH_1):GND
CT33    GND VSS<374> @BASEBOARD_FAB2_LIB.BASEBOARD_FAB2(SCH_1):GND
CT35    GND VSS<373> @BASEBOARD_FAB2_LIB.BASEBOARD_FAB2(SCH_1):GND
CT57    GND VSS<372> @BASEBOARD_FAB2_LIB.BASEBOARD_FAB2(SCH_1):GND
CT73    GND VSS<371> @BASEBOARD_FAB2_LIB.BASEBOARD_FAB2(SCH_1):GND
CT79    GND VSS<370> @BASEBOARD_FAB2_LIB.BASEBOARD_FAB2(SCH_1):GND
CT83    GND VSS<369> @BASEBOARD_FAB2_LIB.BASEBOARD_FAB2(SCH_1):GND
CT85    GND VSS<368> @BASEBOARD_FAB2_LIB.BASEBOARD_FAB2(SCH_1):GND
 CU4    GND VSS<367> @BASEBOARD_FAB2_LIB.BASEBOARD_FAB2(SCH_1):GND
CU22    GND VSS<366> @BASEBOARD_FAB2_LIB.BASEBOARD_FAB2(SCH_1):GND
CU28    GND VSS<365> @BASEBOARD_FAB2_LIB.BASEBOARD_FAB2(SCH_1):GND
CU30    GND VSS<364> @BASEBOARD_FAB2_LIB.BASEBOARD_FAB2(SCH_1):GND
CU34    GND VSS<363> @BASEBOARD_FAB2_LIB.BASEBOARD_FAB2(SCH_1):GND
CU36    GND VSS<362> @BASEBOARD_FAB2_LIB.BASEBOARD_FAB2(SCH_1):GND
CU56    GND VSS<361> @BASEBOARD_FAB2_LIB.BASEBOARD_FAB2(SCH_1):GND
CU62    GND VSS<360> @BASEBOARD_FAB2_LIB.BASEBOARD_FAB2(SCH_1):GND
CU68    GND VSS<359> @BASEBOARD_FAB2_LIB.BASEBOARD_FAB2(SCH_1):GND
CU76    GND VSS<358> @BASEBOARD_FAB2_LIB.BASEBOARD_FAB2(SCH_1):GND
CU78    GND VSS<357> @BASEBOARD_FAB2_LIB.BASEBOARD_FAB2(SCH_1):GND
CU80    GND VSS<356> @BASEBOARD_FAB2_LIB.BASEBOARD_FAB2(SCH_1):GND
CU82    GND VSS<355> @BASEBOARD_FAB2_LIB.BASEBOARD_FAB2(SCH_1):GND
CU86    GND VSS<354> @BASEBOARD_FAB2_LIB.BASEBOARD_FAB2(SCH_1):GND
 CV1    GND VSS<353> @BASEBOARD_FAB2_LIB.BASEBOARD_FAB2(SCH_1):GND
 H55    GND VSS<352> @BASEBOARD_FAB2_LIB.BASEBOARD_FAB2(SCH_1):GND
CV17    GND VSS<351> @BASEBOARD_FAB2_LIB.BASEBOARD_FAB2(SCH_1):GND
CV25    GND VSS<350> @BASEBOARD_FAB2_LIB.BASEBOARD_FAB2(SCH_1):GND
CV27    GND VSS<349> @BASEBOARD_FAB2_LIB.BASEBOARD_FAB2(SCH_1):GND
CV31    GND VSS<348> @BASEBOARD_FAB2_LIB.BASEBOARD_FAB2(SCH_1):GND
CV33    GND VSS<347> @BASEBOARD_FAB2_LIB.BASEBOARD_FAB2(SCH_1):GND
CV37    GND VSS<346> @BASEBOARD_FAB2_LIB.BASEBOARD_FAB2(SCH_1):GND
CV39    GND VSS<345> @BASEBOARD_FAB2_LIB.BASEBOARD_FAB2(SCH_1):GND
CV41    GND VSS<344> @BASEBOARD_FAB2_LIB.BASEBOARD_FAB2(SCH_1):GND
CV53    GND VSS<343> @BASEBOARD_FAB2_LIB.BASEBOARD_FAB2(SCH_1):GND
CV55    GND VSS<342> @BASEBOARD_FAB2_LIB.BASEBOARD_FAB2(SCH_1):GND
CV63    GND VSS<341> @BASEBOARD_FAB2_LIB.BASEBOARD_FAB2(SCH_1):GND
CV67    GND VSS<340> @BASEBOARD_FAB2_LIB.BASEBOARD_FAB2(SCH_1):GND
CV73    GND VSS<339> @BASEBOARD_FAB2_LIB.BASEBOARD_FAB2(SCH_1):GND
CV79    GND VSS<338> @BASEBOARD_FAB2_LIB.BASEBOARD_FAB2(SCH_1):GND
CV81    GND VSS<337> @BASEBOARD_FAB2_LIB.BASEBOARD_FAB2(SCH_1):GND
CV83    GND VSS<336> @BASEBOARD_FAB2_LIB.BASEBOARD_FAB2(SCH_1):GND
CW12    GND VSS<335> @BASEBOARD_FAB2_LIB.BASEBOARD_FAB2(SCH_1):GND
CW26    GND VSS<334> @BASEBOARD_FAB2_LIB.BASEBOARD_FAB2(SCH_1):GND
CW32    GND VSS<333> @BASEBOARD_FAB2_LIB.BASEBOARD_FAB2(SCH_1):GND
CW38    GND VSS<332> @BASEBOARD_FAB2_LIB.BASEBOARD_FAB2(SCH_1):GND
CW40    GND VSS<331> @BASEBOARD_FAB2_LIB.BASEBOARD_FAB2(SCH_1):GND
CW42    GND VSS<330> @BASEBOARD_FAB2_LIB.BASEBOARD_FAB2(SCH_1):GND
CW52    GND VSS<329> @BASEBOARD_FAB2_LIB.BASEBOARD_FAB2(SCH_1):GND
CW54    GND VSS<328> @BASEBOARD_FAB2_LIB.BASEBOARD_FAB2(SCH_1):GND
CW64    GND VSS<327> @BASEBOARD_FAB2_LIB.BASEBOARD_FAB2(SCH_1):GND
CW66    GND VSS<326> @BASEBOARD_FAB2_LIB.BASEBOARD_FAB2(SCH_1):GND
CW68    GND VSS<325> @BASEBOARD_FAB2_LIB.BASEBOARD_FAB2(SCH_1):GND
CW74    GND VSS<324> @BASEBOARD_FAB2_LIB.BASEBOARD_FAB2(SCH_1):GND
CW78    GND VSS<323> @BASEBOARD_FAB2_LIB.BASEBOARD_FAB2(SCH_1):GND
CW82    GND VSS<322> @BASEBOARD_FAB2_LIB.BASEBOARD_FAB2(SCH_1):GND
 CY1    GND VSS<321> @BASEBOARD_FAB2_LIB.BASEBOARD_FAB2(SCH_1):GND
 CY9    GND VSS<320> @BASEBOARD_FAB2_LIB.BASEBOARD_FAB2(SCH_1):GND
CY13    GND VSS<319> @BASEBOARD_FAB2_LIB.BASEBOARD_FAB2(SCH_1):GND
CY15    GND VSS<318> @BASEBOARD_FAB2_LIB.BASEBOARD_FAB2(SCH_1):GND
CY21    GND VSS<317> @BASEBOARD_FAB2_LIB.BASEBOARD_FAB2(SCH_1):GND
CY41    GND VSS<316> @BASEBOARD_FAB2_LIB.BASEBOARD_FAB2(SCH_1):GND
CY45    GND VSS<315> @BASEBOARD_FAB2_LIB.BASEBOARD_FAB2(SCH_1):GND
CY51    GND VSS<314> @BASEBOARD_FAB2_LIB.BASEBOARD_FAB2(SCH_1):GND
CY59    GND VSS<313> @BASEBOARD_FAB2_LIB.BASEBOARD_FAB2(SCH_1):GND
CY61    GND VSS<312> @BASEBOARD_FAB2_LIB.BASEBOARD_FAB2(SCH_1):GND
CY65    GND VSS<311> @BASEBOARD_FAB2_LIB.BASEBOARD_FAB2(SCH_1):GND
CY69    GND VSS<310> @BASEBOARD_FAB2_LIB.BASEBOARD_FAB2(SCH_1):GND
CY75    GND VSS<309> @BASEBOARD_FAB2_LIB.BASEBOARD_FAB2(SCH_1):GND
CY77    GND VSS<308> @BASEBOARD_FAB2_LIB.BASEBOARD_FAB2(SCH_1):GND
CY83    GND VSS<307> @BASEBOARD_FAB2_LIB.BASEBOARD_FAB2(SCH_1):GND
CY85    GND VSS<306> @BASEBOARD_FAB2_LIB.BASEBOARD_FAB2(SCH_1):GND
 DA6    GND VSS<305> @BASEBOARD_FAB2_LIB.BASEBOARD_FAB2(SCH_1):GND
 H53    GND VSS<304> @BASEBOARD_FAB2_LIB.BASEBOARD_FAB2(SCH_1):GND
DA18    GND VSS<303> @BASEBOARD_FAB2_LIB.BASEBOARD_FAB2(SCH_1):GND
DA26    GND VSS<302> @BASEBOARD_FAB2_LIB.BASEBOARD_FAB2(SCH_1):GND
DA28    GND VSS<301> @BASEBOARD_FAB2_LIB.BASEBOARD_FAB2(SCH_1):GND
DA30    GND VSS<300> @BASEBOARD_FAB2_LIB.BASEBOARD_FAB2(SCH_1):GND
DA32    GND VSS<299> @BASEBOARD_FAB2_LIB.BASEBOARD_FAB2(SCH_1):GND
DA34    GND VSS<298> @BASEBOARD_FAB2_LIB.BASEBOARD_FAB2(SCH_1):GND
DA36    GND VSS<297> @BASEBOARD_FAB2_LIB.BASEBOARD_FAB2(SCH_1):GND
DA38    GND VSS<296> @BASEBOARD_FAB2_LIB.BASEBOARD_FAB2(SCH_1):GND
DA44    GND VSS<295> @BASEBOARD_FAB2_LIB.BASEBOARD_FAB2(SCH_1):GND
DA46    GND VSS<294> @BASEBOARD_FAB2_LIB.BASEBOARD_FAB2(SCH_1):GND

SKX_EXT_B_BGA1-IC,TBD  I19  U2D1
DA48    GND VSS<293> @BASEBOARD_FAB2_LIB.BASEBOARD_FAB2(SCH_1):GND
DA50    GND VSS<292> @BASEBOARD_FAB2_LIB.BASEBOARD_FAB2(SCH_1):GND
DA64    GND VSS<291> @BASEBOARD_FAB2_LIB.BASEBOARD_FAB2(SCH_1):GND
DA70    GND VSS<290> @BASEBOARD_FAB2_LIB.BASEBOARD_FAB2(SCH_1):GND
DA74    GND VSS<289> @BASEBOARD_FAB2_LIB.BASEBOARD_FAB2(SCH_1):GND
DA76    GND VSS<288> @BASEBOARD_FAB2_LIB.BASEBOARD_FAB2(SCH_1):GND
DA78    GND VSS<287> @BASEBOARD_FAB2_LIB.BASEBOARD_FAB2(SCH_1):GND
DA80    GND VSS<286> @BASEBOARD_FAB2_LIB.BASEBOARD_FAB2(SCH_1):GND
 DB3    GND VSS<285> @BASEBOARD_FAB2_LIB.BASEBOARD_FAB2(SCH_1):GND
DB13    GND VSS<284> @BASEBOARD_FAB2_LIB.BASEBOARD_FAB2(SCH_1):GND
DB17    GND VSS<283> @BASEBOARD_FAB2_LIB.BASEBOARD_FAB2(SCH_1):GND
DB23    GND VSS<282> @BASEBOARD_FAB2_LIB.BASEBOARD_FAB2(SCH_1):GND
DB25    GND VSS<281> @BASEBOARD_FAB2_LIB.BASEBOARD_FAB2(SCH_1):GND
DB39    GND VSS<280> @BASEBOARD_FAB2_LIB.BASEBOARD_FAB2(SCH_1):GND
DB41    GND VSS<279> @BASEBOARD_FAB2_LIB.BASEBOARD_FAB2(SCH_1):GND
DB47    GND VSS<278> @BASEBOARD_FAB2_LIB.BASEBOARD_FAB2(SCH_1):GND
DB49    GND VSS<277> @BASEBOARD_FAB2_LIB.BASEBOARD_FAB2(SCH_1):GND
DB73    GND VSS<276> @BASEBOARD_FAB2_LIB.BASEBOARD_FAB2(SCH_1):GND
DB77    GND VSS<275> @BASEBOARD_FAB2_LIB.BASEBOARD_FAB2(SCH_1):GND
DB83    GND VSS<274> @BASEBOARD_FAB2_LIB.BASEBOARD_FAB2(SCH_1):GND
DB85    GND VSS<273> @BASEBOARD_FAB2_LIB.BASEBOARD_FAB2(SCH_1):GND
DC14    GND VSS<272> @BASEBOARD_FAB2_LIB.BASEBOARD_FAB2(SCH_1):GND
DC24    GND VSS<271> @BASEBOARD_FAB2_LIB.BASEBOARD_FAB2(SCH_1):GND
DC26    GND VSS<270> @BASEBOARD_FAB2_LIB.BASEBOARD_FAB2(SCH_1):GND
DC32    GND VSS<269> @BASEBOARD_FAB2_LIB.BASEBOARD_FAB2(SCH_1):GND
DC38    GND VSS<268> @BASEBOARD_FAB2_LIB.BASEBOARD_FAB2(SCH_1):GND
DC42    GND VSS<267> @BASEBOARD_FAB2_LIB.BASEBOARD_FAB2(SCH_1):GND
DC64    GND VSS<266> @BASEBOARD_FAB2_LIB.BASEBOARD_FAB2(SCH_1):GND
DC66    GND VSS<265> @BASEBOARD_FAB2_LIB.BASEBOARD_FAB2(SCH_1):GND
DC68    GND VSS<264> @BASEBOARD_FAB2_LIB.BASEBOARD_FAB2(SCH_1):GND
DC70    GND VSS<263> @BASEBOARD_FAB2_LIB.BASEBOARD_FAB2(SCH_1):GND
DC78    GND VSS<262> @BASEBOARD_FAB2_LIB.BASEBOARD_FAB2(SCH_1):GND
DC84    GND VSS<261> @BASEBOARD_FAB2_LIB.BASEBOARD_FAB2(SCH_1):GND
DC86    GND VSS<260> @BASEBOARD_FAB2_LIB.BASEBOARD_FAB2(SCH_1):GND
DD11    GND VSS<259> @BASEBOARD_FAB2_LIB.BASEBOARD_FAB2(SCH_1):GND
DD23    GND VSS<258> @BASEBOARD_FAB2_LIB.BASEBOARD_FAB2(SCH_1):GND
DD27    GND VSS<257> @BASEBOARD_FAB2_LIB.BASEBOARD_FAB2(SCH_1):GND
DD31    GND VSS<256> @BASEBOARD_FAB2_LIB.BASEBOARD_FAB2(SCH_1):GND
DD33    GND VSS<255> @BASEBOARD_FAB2_LIB.BASEBOARD_FAB2(SCH_1):GND
DD37    GND VSS<254> @BASEBOARD_FAB2_LIB.BASEBOARD_FAB2(SCH_1):GND
DD71    GND VSS<253> @BASEBOARD_FAB2_LIB.BASEBOARD_FAB2(SCH_1):GND
DD73    GND VSS<252> @BASEBOARD_FAB2_LIB.BASEBOARD_FAB2(SCH_1):GND
DD75    GND VSS<251> @BASEBOARD_FAB2_LIB.BASEBOARD_FAB2(SCH_1):GND
DD81    GND VSS<250> @BASEBOARD_FAB2_LIB.BASEBOARD_FAB2(SCH_1):GND
DD83    GND VSS<249> @BASEBOARD_FAB2_LIB.BASEBOARD_FAB2(SCH_1):GND
 DE6    GND VSS<248> @BASEBOARD_FAB2_LIB.BASEBOARD_FAB2(SCH_1):GND
 DE8    GND VSS<247> @BASEBOARD_FAB2_LIB.BASEBOARD_FAB2(SCH_1):GND
DE18    GND VSS<246> @BASEBOARD_FAB2_LIB.BASEBOARD_FAB2(SCH_1):GND
DE20    GND VSS<245> @BASEBOARD_FAB2_LIB.BASEBOARD_FAB2(SCH_1):GND
DE24    GND VSS<244> @BASEBOARD_FAB2_LIB.BASEBOARD_FAB2(SCH_1):GND
DE28    GND VSS<243> @BASEBOARD_FAB2_LIB.BASEBOARD_FAB2(SCH_1):GND
DE30    GND VSS<242> @BASEBOARD_FAB2_LIB.BASEBOARD_FAB2(SCH_1):GND
DE34    GND VSS<241> @BASEBOARD_FAB2_LIB.BASEBOARD_FAB2(SCH_1):GND
DE36    GND VSS<240> @BASEBOARD_FAB2_LIB.BASEBOARD_FAB2(SCH_1):GND
DE64    GND VSS<239> @BASEBOARD_FAB2_LIB.BASEBOARD_FAB2(SCH_1):GND
DE70    GND VSS<238> @BASEBOARD_FAB2_LIB.BASEBOARD_FAB2(SCH_1):GND
DE72    GND VSS<237> @BASEBOARD_FAB2_LIB.BASEBOARD_FAB2(SCH_1):GND
DE78    GND VSS<236> @BASEBOARD_FAB2_LIB.BASEBOARD_FAB2(SCH_1):GND
 DF5    GND VSS<235> @BASEBOARD_FAB2_LIB.BASEBOARD_FAB2(SCH_1):GND
 DF7    GND VSS<234> @BASEBOARD_FAB2_LIB.BASEBOARD_FAB2(SCH_1):GND
 H51    GND VSS<233> @BASEBOARD_FAB2_LIB.BASEBOARD_FAB2(SCH_1):GND
DF19    GND VSS<232> @BASEBOARD_FAB2_LIB.BASEBOARD_FAB2(SCH_1):GND
DF29    GND VSS<231> @BASEBOARD_FAB2_LIB.BASEBOARD_FAB2(SCH_1):GND
DF35    GND VSS<230> @BASEBOARD_FAB2_LIB.BASEBOARD_FAB2(SCH_1):GND
DF37    GND VSS<229> @BASEBOARD_FAB2_LIB.BASEBOARD_FAB2(SCH_1):GND
DF39    GND VSS<228> @BASEBOARD_FAB2_LIB.BASEBOARD_FAB2(SCH_1):GND
DF41    GND VSS<227> @BASEBOARD_FAB2_LIB.BASEBOARD_FAB2(SCH_1):GND
DF65    GND VSS<226> @BASEBOARD_FAB2_LIB.BASEBOARD_FAB2(SCH_1):GND
DF69    GND VSS<225> @BASEBOARD_FAB2_LIB.BASEBOARD_FAB2(SCH_1):GND
DF73    GND VSS<224> @BASEBOARD_FAB2_LIB.BASEBOARD_FAB2(SCH_1):GND
DF79    GND VSS<223> @BASEBOARD_FAB2_LIB.BASEBOARD_FAB2(SCH_1):GND
DF83    GND VSS<222> @BASEBOARD_FAB2_LIB.BASEBOARD_FAB2(SCH_1):GND
DF85    GND VSS<221> @BASEBOARD_FAB2_LIB.BASEBOARD_FAB2(SCH_1):GND
 DG2    GND VSS<220> @BASEBOARD_FAB2_LIB.BASEBOARD_FAB2(SCH_1):GND
 H49    GND VSS<219> @BASEBOARD_FAB2_LIB.BASEBOARD_FAB2(SCH_1):GND
DG14    GND VSS<218> @BASEBOARD_FAB2_LIB.BASEBOARD_FAB2(SCH_1):GND
DG16    GND VSS<217> @BASEBOARD_FAB2_LIB.BASEBOARD_FAB2(SCH_1):GND
DG24    GND VSS<216> @BASEBOARD_FAB2_LIB.BASEBOARD_FAB2(SCH_1):GND
DG66    GND VSS<215> @BASEBOARD_FAB2_LIB.BASEBOARD_FAB2(SCH_1):GND
DG68    GND VSS<214> @BASEBOARD_FAB2_LIB.BASEBOARD_FAB2(SCH_1):GND
DG76    GND VSS<213> @BASEBOARD_FAB2_LIB.BASEBOARD_FAB2(SCH_1):GND
DG78    GND VSS<212> @BASEBOARD_FAB2_LIB.BASEBOARD_FAB2(SCH_1):GND
DG80    GND VSS<211> @BASEBOARD_FAB2_LIB.BASEBOARD_FAB2(SCH_1):GND
DG82    GND VSS<210> @BASEBOARD_FAB2_LIB.BASEBOARD_FAB2(SCH_1):GND
DH13    GND VSS<209> @BASEBOARD_FAB2_LIB.BASEBOARD_FAB2(SCH_1):GND
DH15    GND VSS<208> @BASEBOARD_FAB2_LIB.BASEBOARD_FAB2(SCH_1):GND
DH23    GND VSS<207> @BASEBOARD_FAB2_LIB.BASEBOARD_FAB2(SCH_1):GND
DH25    GND VSS<206> @BASEBOARD_FAB2_LIB.BASEBOARD_FAB2(SCH_1):GND
DH27    GND VSS<205> @BASEBOARD_FAB2_LIB.BASEBOARD_FAB2(SCH_1):GND
DH29    GND VSS<204> @BASEBOARD_FAB2_LIB.BASEBOARD_FAB2(SCH_1):GND
DH31    GND VSS<203> @BASEBOARD_FAB2_LIB.BASEBOARD_FAB2(SCH_1):GND
DH33    GND VSS<202> @BASEBOARD_FAB2_LIB.BASEBOARD_FAB2(SCH_1):GND
DH35    GND VSS<201> @BASEBOARD_FAB2_LIB.BASEBOARD_FAB2(SCH_1):GND
DH37    GND VSS<200> @BASEBOARD_FAB2_LIB.BASEBOARD_FAB2(SCH_1):GND
DH41    GND VSS<199> @BASEBOARD_FAB2_LIB.BASEBOARD_FAB2(SCH_1):GND
DH67    GND VSS<198> @BASEBOARD_FAB2_LIB.BASEBOARD_FAB2(SCH_1):GND
DH71    GND VSS<197> @BASEBOARD_FAB2_LIB.BASEBOARD_FAB2(SCH_1):GND
DH73    GND VSS<196> @BASEBOARD_FAB2_LIB.BASEBOARD_FAB2(SCH_1):GND
DH79    GND VSS<195> @BASEBOARD_FAB2_LIB.BASEBOARD_FAB2(SCH_1):GND
DH81    GND VSS<194> @BASEBOARD_FAB2_LIB.BASEBOARD_FAB2(SCH_1):GND
DH83    GND VSS<193> @BASEBOARD_FAB2_LIB.BASEBOARD_FAB2(SCH_1):GND
 DJ2    GND VSS<192> @BASEBOARD_FAB2_LIB.BASEBOARD_FAB2(SCH_1):GND
DJ10    GND VSS<191> @BASEBOARD_FAB2_LIB.BASEBOARD_FAB2(SCH_1):GND
 H47    GND VSS<190> @BASEBOARD_FAB2_LIB.BASEBOARD_FAB2(SCH_1):GND
DJ22    GND VSS<189> @BASEBOARD_FAB2_LIB.BASEBOARD_FAB2(SCH_1):GND
DJ38    GND VSS<188> @BASEBOARD_FAB2_LIB.BASEBOARD_FAB2(SCH_1):GND
DJ42    GND VSS<187> @BASEBOARD_FAB2_LIB.BASEBOARD_FAB2(SCH_1):GND
DJ68    GND VSS<186> @BASEBOARD_FAB2_LIB.BASEBOARD_FAB2(SCH_1):GND
DJ74    GND VSS<185> @BASEBOARD_FAB2_LIB.BASEBOARD_FAB2(SCH_1):GND
DJ78    GND VSS<184> @BASEBOARD_FAB2_LIB.BASEBOARD_FAB2(SCH_1):GND
DJ82    GND VSS<183> @BASEBOARD_FAB2_LIB.BASEBOARD_FAB2(SCH_1):GND
DJ84    GND VSS<182> @BASEBOARD_FAB2_LIB.BASEBOARD_FAB2(SCH_1):GND
 DK7    GND VSS<181> @BASEBOARD_FAB2_LIB.BASEBOARD_FAB2(SCH_1):GND
DK23    GND VSS<180> @BASEBOARD_FAB2_LIB.BASEBOARD_FAB2(SCH_1):GND
DK29    GND VSS<179> @BASEBOARD_FAB2_LIB.BASEBOARD_FAB2(SCH_1):GND
DK35    GND VSS<178> @BASEBOARD_FAB2_LIB.BASEBOARD_FAB2(SCH_1):GND
DK39    GND VSS<177> @BASEBOARD_FAB2_LIB.BASEBOARD_FAB2(SCH_1):GND
DK41    GND VSS<176> @BASEBOARD_FAB2_LIB.BASEBOARD_FAB2(SCH_1):GND
DK73    GND VSS<175> @BASEBOARD_FAB2_LIB.BASEBOARD_FAB2(SCH_1):GND
DK75    GND VSS<174> @BASEBOARD_FAB2_LIB.BASEBOARD_FAB2(SCH_1):GND
DK77    GND VSS<173> @BASEBOARD_FAB2_LIB.BASEBOARD_FAB2(SCH_1):GND
DK83    GND VSS<172> @BASEBOARD_FAB2_LIB.BASEBOARD_FAB2(SCH_1):GND
DK85    GND VSS<171> @BASEBOARD_FAB2_LIB.BASEBOARD_FAB2(SCH_1):GND
DL16    GND VSS<170> @BASEBOARD_FAB2_LIB.BASEBOARD_FAB2(SCH_1):GND
DL18    GND VSS<169> @BASEBOARD_FAB2_LIB.BASEBOARD_FAB2(SCH_1):GND
 DL4    GND VSS<168> @BASEBOARD_FAB2_LIB.BASEBOARD_FAB2(SCH_1):GND
DL22    GND VSS<167> @BASEBOARD_FAB2_LIB.BASEBOARD_FAB2(SCH_1):GND
DL24    GND VSS<166> @BASEBOARD_FAB2_LIB.BASEBOARD_FAB2(SCH_1):GND
DL28    GND VSS<165> @BASEBOARD_FAB2_LIB.BASEBOARD_FAB2(SCH_1):GND
DL30    GND VSS<164> @BASEBOARD_FAB2_LIB.BASEBOARD_FAB2(SCH_1):GND
DL34    GND VSS<163> @BASEBOARD_FAB2_LIB.BASEBOARD_FAB2(SCH_1):GND
DL36    GND VSS<162> @BASEBOARD_FAB2_LIB.BASEBOARD_FAB2(SCH_1):GND
DL40    GND VSS<161> @BASEBOARD_FAB2_LIB.BASEBOARD_FAB2(SCH_1):GND
DL68    GND VSS<160> @BASEBOARD_FAB2_LIB.BASEBOARD_FAB2(SCH_1):GND
DL70    GND VSS<159> @BASEBOARD_FAB2_LIB.BASEBOARD_FAB2(SCH_1):GND
DL74    GND VSS<158> @BASEBOARD_FAB2_LIB.BASEBOARD_FAB2(SCH_1):GND
DL76    GND VSS<157> @BASEBOARD_FAB2_LIB.BASEBOARD_FAB2(SCH_1):GND
DL78    GND VSS<156> @BASEBOARD_FAB2_LIB.BASEBOARD_FAB2(SCH_1):GND
DL80    GND VSS<155> @BASEBOARD_FAB2_LIB.BASEBOARD_FAB2(SCH_1):GND
DM15    GND VSS<154> @BASEBOARD_FAB2_LIB.BASEBOARD_FAB2(SCH_1):GND
 H45    GND VSS<153> @BASEBOARD_FAB2_LIB.BASEBOARD_FAB2(SCH_1):GND
DM25    GND VSS<152> @BASEBOARD_FAB2_LIB.BASEBOARD_FAB2(SCH_1):GND
DM27    GND VSS<151> @BASEBOARD_FAB2_LIB.BASEBOARD_FAB2(SCH_1):GND
DM31    GND VSS<150> @BASEBOARD_FAB2_LIB.BASEBOARD_FAB2(SCH_1):GND
DM33    GND VSS<149> @BASEBOARD_FAB2_LIB.BASEBOARD_FAB2(SCH_1):GND
DM37    GND VSS<148> @BASEBOARD_FAB2_LIB.BASEBOARD_FAB2(SCH_1):GND
DM39    GND VSS<147> @BASEBOARD_FAB2_LIB.BASEBOARD_FAB2(SCH_1):GND
DM65    GND VSS<146> @BASEBOARD_FAB2_LIB.BASEBOARD_FAB2(SCH_1):GND
DM73    GND VSS<145> @BASEBOARD_FAB2_LIB.BASEBOARD_FAB2(SCH_1):GND
DM77    GND VSS<144> @BASEBOARD_FAB2_LIB.BASEBOARD_FAB2(SCH_1):GND
DM83    GND VSS<143> @BASEBOARD_FAB2_LIB.BASEBOARD_FAB2(SCH_1):GND
 DN2    GND VSS<142> @BASEBOARD_FAB2_LIB.BASEBOARD_FAB2(SCH_1):GND
BH17    GND VSS<141> @BASEBOARD_FAB2_LIB.BASEBOARD_FAB2(SCH_1):GND
DN12    GND VSS<140> @BASEBOARD_FAB2_LIB.BASEBOARD_FAB2(SCH_1):GND
DN22    GND VSS<139> @BASEBOARD_FAB2_LIB.BASEBOARD_FAB2(SCH_1):GND
DN26    GND VSS<138> @BASEBOARD_FAB2_LIB.BASEBOARD_FAB2(SCH_1):GND
DN32    GND VSS<137> @BASEBOARD_FAB2_LIB.BASEBOARD_FAB2(SCH_1):GND
DN38    GND VSS<136> @BASEBOARD_FAB2_LIB.BASEBOARD_FAB2(SCH_1):GND
DN68    GND VSS<135> @BASEBOARD_FAB2_LIB.BASEBOARD_FAB2(SCH_1):GND
DN72    GND VSS<134> @BASEBOARD_FAB2_LIB.BASEBOARD_FAB2(SCH_1):GND

SKX_EXT_B_BGA1-IC,TBD  I20  U2D1
DN78    GND VSS<133> @BASEBOARD_FAB2_LIB.BASEBOARD_FAB2(SCH_1):GND
DP67    GND VSS<132> @BASEBOARD_FAB2_LIB.BASEBOARD_FAB2(SCH_1):GND
DP69    GND VSS<131> @BASEBOARD_FAB2_LIB.BASEBOARD_FAB2(SCH_1):GND
DP71    GND VSS<130> @BASEBOARD_FAB2_LIB.BASEBOARD_FAB2(SCH_1):GND
DP81    GND VSS<129> @BASEBOARD_FAB2_LIB.BASEBOARD_FAB2(SCH_1):GND
DP83    GND VSS<128> @BASEBOARD_FAB2_LIB.BASEBOARD_FAB2(SCH_1):GND
BR26    GND VSS<127> @BASEBOARD_FAB2_LIB.BASEBOARD_FAB2(SCH_1):GND
 DR6    GND VSS<126> @BASEBOARD_FAB2_LIB.BASEBOARD_FAB2(SCH_1):GND
CA20    GND VSS<125> @BASEBOARD_FAB2_LIB.BASEBOARD_FAB2(SCH_1):GND
CL22    GND VSS<124> @BASEBOARD_FAB2_LIB.BASEBOARD_FAB2(SCH_1):GND
DR20    GND VSS<123> @BASEBOARD_FAB2_LIB.BASEBOARD_FAB2(SCH_1):GND
DR22    GND VSS<122> @BASEBOARD_FAB2_LIB.BASEBOARD_FAB2(SCH_1):GND
DR24    GND VSS<121> @BASEBOARD_FAB2_LIB.BASEBOARD_FAB2(SCH_1):GND
DR26    GND VSS<120> @BASEBOARD_FAB2_LIB.BASEBOARD_FAB2(SCH_1):GND
DR28    GND VSS<119> @BASEBOARD_FAB2_LIB.BASEBOARD_FAB2(SCH_1):GND
DR30    GND VSS<118> @BASEBOARD_FAB2_LIB.BASEBOARD_FAB2(SCH_1):GND
DR32    GND VSS<117> @BASEBOARD_FAB2_LIB.BASEBOARD_FAB2(SCH_1):GND
DR34    GND VSS<116> @BASEBOARD_FAB2_LIB.BASEBOARD_FAB2(SCH_1):GND
DR36    GND VSS<115> @BASEBOARD_FAB2_LIB.BASEBOARD_FAB2(SCH_1):GND
DR38    GND VSS<114> @BASEBOARD_FAB2_LIB.BASEBOARD_FAB2(SCH_1):GND
DR40    GND VSS<113> @BASEBOARD_FAB2_LIB.BASEBOARD_FAB2(SCH_1):GND
DR42    GND VSS<112> @BASEBOARD_FAB2_LIB.BASEBOARD_FAB2(SCH_1):GND
DR66    GND VSS<111> @BASEBOARD_FAB2_LIB.BASEBOARD_FAB2(SCH_1):GND
DR68    GND VSS<110> @BASEBOARD_FAB2_LIB.BASEBOARD_FAB2(SCH_1):GND
DR70    GND VSS<109> @BASEBOARD_FAB2_LIB.BASEBOARD_FAB2(SCH_1):GND
DR72    GND VSS<108> @BASEBOARD_FAB2_LIB.BASEBOARD_FAB2(SCH_1):GND
DR74    GND VSS<107> @BASEBOARD_FAB2_LIB.BASEBOARD_FAB2(SCH_1):GND
DR76    GND VSS<106> @BASEBOARD_FAB2_LIB.BASEBOARD_FAB2(SCH_1):GND
DR78    GND VSS<105> @BASEBOARD_FAB2_LIB.BASEBOARD_FAB2(SCH_1):GND
 DT3    GND VSS<104> @BASEBOARD_FAB2_LIB.BASEBOARD_FAB2(SCH_1):GND
DT17    GND VSS<103> @BASEBOARD_FAB2_LIB.BASEBOARD_FAB2(SCH_1):GND
DH21    GND VSS<102> @BASEBOARD_FAB2_LIB.BASEBOARD_FAB2(SCH_1):GND
DT65    GND VSS<101> @BASEBOARD_FAB2_LIB.BASEBOARD_FAB2(SCH_1):GND
DT69    GND VSS<100> @BASEBOARD_FAB2_LIB.BASEBOARD_FAB2(SCH_1):GND
DT79    GND VSS<99> @BASEBOARD_FAB2_LIB.BASEBOARD_FAB2(SCH_1):GND
DT83    GND VSS<98> @BASEBOARD_FAB2_LIB.BASEBOARD_FAB2(SCH_1):GND
DT85    GND VSS<97> @BASEBOARD_FAB2_LIB.BASEBOARD_FAB2(SCH_1):GND
DU10    GND VSS<96> @BASEBOARD_FAB2_LIB.BASEBOARD_FAB2(SCH_1):GND
DU14    GND VSS<95> @BASEBOARD_FAB2_LIB.BASEBOARD_FAB2(SCH_1):GND
CN14    GND VSS<94> @BASEBOARD_FAB2_LIB.BASEBOARD_FAB2(SCH_1):GND
DU22    GND VSS<93> @BASEBOARD_FAB2_LIB.BASEBOARD_FAB2(SCH_1):GND
DU26    GND VSS<92> @BASEBOARD_FAB2_LIB.BASEBOARD_FAB2(SCH_1):GND
DU32    GND VSS<91> @BASEBOARD_FAB2_LIB.BASEBOARD_FAB2(SCH_1):GND
DU38    GND VSS<90> @BASEBOARD_FAB2_LIB.BASEBOARD_FAB2(SCH_1):GND
DU70    GND VSS<89> @BASEBOARD_FAB2_LIB.BASEBOARD_FAB2(SCH_1):GND
DU72    GND VSS<88> @BASEBOARD_FAB2_LIB.BASEBOARD_FAB2(SCH_1):GND
DU78    GND VSS<87> @BASEBOARD_FAB2_LIB.BASEBOARD_FAB2(SCH_1):GND
DU80    GND VSS<86> @BASEBOARD_FAB2_LIB.BASEBOARD_FAB2(SCH_1):GND
DU82    GND VSS<85> @BASEBOARD_FAB2_LIB.BASEBOARD_FAB2(SCH_1):GND
DU84    GND VSS<84> @BASEBOARD_FAB2_LIB.BASEBOARD_FAB2(SCH_1):GND
DV21    GND VSS<83> @BASEBOARD_FAB2_LIB.BASEBOARD_FAB2(SCH_1):GND
DV25    GND VSS<82> @BASEBOARD_FAB2_LIB.BASEBOARD_FAB2(SCH_1):GND
DV27    GND VSS<81> @BASEBOARD_FAB2_LIB.BASEBOARD_FAB2(SCH_1):GND
DV31    GND VSS<80> @BASEBOARD_FAB2_LIB.BASEBOARD_FAB2(SCH_1):GND
DV33    GND VSS<79> @BASEBOARD_FAB2_LIB.BASEBOARD_FAB2(SCH_1):GND
DV37    GND VSS<78> @BASEBOARD_FAB2_LIB.BASEBOARD_FAB2(SCH_1):GND
DV39    GND VSS<77> @BASEBOARD_FAB2_LIB.BASEBOARD_FAB2(SCH_1):GND
DV73    GND VSS<76> @BASEBOARD_FAB2_LIB.BASEBOARD_FAB2(SCH_1):GND
DV77    GND VSS<75> @BASEBOARD_FAB2_LIB.BASEBOARD_FAB2(SCH_1):GND
DV81    GND VSS<74> @BASEBOARD_FAB2_LIB.BASEBOARD_FAB2(SCH_1):GND
DW12    GND VSS<73> @BASEBOARD_FAB2_LIB.BASEBOARD_FAB2(SCH_1):GND
DW20    GND VSS<72> @BASEBOARD_FAB2_LIB.BASEBOARD_FAB2(SCH_1):GND
DW24    GND VSS<71> @BASEBOARD_FAB2_LIB.BASEBOARD_FAB2(SCH_1):GND
DW28    GND VSS<70> @BASEBOARD_FAB2_LIB.BASEBOARD_FAB2(SCH_1):GND
DW30    GND VSS<69> @BASEBOARD_FAB2_LIB.BASEBOARD_FAB2(SCH_1):GND
DW34    GND VSS<68> @BASEBOARD_FAB2_LIB.BASEBOARD_FAB2(SCH_1):GND
DW36    GND VSS<67> @BASEBOARD_FAB2_LIB.BASEBOARD_FAB2(SCH_1):GND
DW40    GND VSS<66> @BASEBOARD_FAB2_LIB.BASEBOARD_FAB2(SCH_1):GND
DW64    GND VSS<65> @BASEBOARD_FAB2_LIB.BASEBOARD_FAB2(SCH_1):GND
DW66    GND VSS<64> @BASEBOARD_FAB2_LIB.BASEBOARD_FAB2(SCH_1):GND
DW68    GND VSS<63> @BASEBOARD_FAB2_LIB.BASEBOARD_FAB2(SCH_1):GND
DW70    GND VSS<62> @BASEBOARD_FAB2_LIB.BASEBOARD_FAB2(SCH_1):GND
DW72    GND VSS<61> @BASEBOARD_FAB2_LIB.BASEBOARD_FAB2(SCH_1):GND
DW74    GND VSS<60> @BASEBOARD_FAB2_LIB.BASEBOARD_FAB2(SCH_1):GND
DW76    GND VSS<59> @BASEBOARD_FAB2_LIB.BASEBOARD_FAB2(SCH_1):GND
 DW8    GND VSS<58> @BASEBOARD_FAB2_LIB.BASEBOARD_FAB2(SCH_1):GND
DW82    GND VSS<57> @BASEBOARD_FAB2_LIB.BASEBOARD_FAB2(SCH_1):GND
DW84    GND VSS<56> @BASEBOARD_FAB2_LIB.BASEBOARD_FAB2(SCH_1):GND
 DY5    GND VSS<55> @BASEBOARD_FAB2_LIB.BASEBOARD_FAB2(SCH_1):GND
DY19    GND VSS<54> @BASEBOARD_FAB2_LIB.BASEBOARD_FAB2(SCH_1):GND
DY23    GND VSS<53> @BASEBOARD_FAB2_LIB.BASEBOARD_FAB2(SCH_1):GND
DY29    GND VSS<52> @BASEBOARD_FAB2_LIB.BASEBOARD_FAB2(SCH_1):GND
DY35    GND VSS<51> @BASEBOARD_FAB2_LIB.BASEBOARD_FAB2(SCH_1):GND
DY41    GND VSS<50> @BASEBOARD_FAB2_LIB.BASEBOARD_FAB2(SCH_1):GND
DY71    GND VSS<49> @BASEBOARD_FAB2_LIB.BASEBOARD_FAB2(SCH_1):GND
DY75    GND VSS<48> @BASEBOARD_FAB2_LIB.BASEBOARD_FAB2(SCH_1):GND
 EA6    GND VSS<47> @BASEBOARD_FAB2_LIB.BASEBOARD_FAB2(SCH_1):GND
 J16    GND VSS<46> @BASEBOARD_FAB2_LIB.BASEBOARD_FAB2(SCH_1):GND
EA16    GND VSS<45> @BASEBOARD_FAB2_LIB.BASEBOARD_FAB2(SCH_1):GND
EA20    GND VSS<44> @BASEBOARD_FAB2_LIB.BASEBOARD_FAB2(SCH_1):GND
EA22    GND VSS<43> @BASEBOARD_FAB2_LIB.BASEBOARD_FAB2(SCH_1):GND
EA42    GND VSS<42> @BASEBOARD_FAB2_LIB.BASEBOARD_FAB2(SCH_1):GND
EA64    GND VSS<41> @BASEBOARD_FAB2_LIB.BASEBOARD_FAB2(SCH_1):GND
EA70    GND VSS<40> @BASEBOARD_FAB2_LIB.BASEBOARD_FAB2(SCH_1):GND
EA76    GND VSS<39> @BASEBOARD_FAB2_LIB.BASEBOARD_FAB2(SCH_1):GND
EA78    GND VSS<38> @BASEBOARD_FAB2_LIB.BASEBOARD_FAB2(SCH_1):GND
EA80    GND VSS<37> @BASEBOARD_FAB2_LIB.BASEBOARD_FAB2(SCH_1):GND
EA82    GND VSS<36> @BASEBOARD_FAB2_LIB.BASEBOARD_FAB2(SCH_1):GND
EB13    GND VSS<35> @BASEBOARD_FAB2_LIB.BASEBOARD_FAB2(SCH_1):GND
BR18    GND VSS<34> @BASEBOARD_FAB2_LIB.BASEBOARD_FAB2(SCH_1):GND
EB23    GND VSS<33> @BASEBOARD_FAB2_LIB.BASEBOARD_FAB2(SCH_1):GND
EB25    GND VSS<32> @BASEBOARD_FAB2_LIB.BASEBOARD_FAB2(SCH_1):GND
EB27    GND VSS<31> @BASEBOARD_FAB2_LIB.BASEBOARD_FAB2(SCH_1):GND
EB29    GND VSS<30> @BASEBOARD_FAB2_LIB.BASEBOARD_FAB2(SCH_1):GND
EB31    GND VSS<29> @BASEBOARD_FAB2_LIB.BASEBOARD_FAB2(SCH_1):GND
EB33    GND VSS<28> @BASEBOARD_FAB2_LIB.BASEBOARD_FAB2(SCH_1):GND
EB35    GND VSS<27> @BASEBOARD_FAB2_LIB.BASEBOARD_FAB2(SCH_1):GND
EB37    GND VSS<26> @BASEBOARD_FAB2_LIB.BASEBOARD_FAB2(SCH_1):GND
EB39    GND VSS<25> @BASEBOARD_FAB2_LIB.BASEBOARD_FAB2(SCH_1):GND
EB41    GND VSS<24> @BASEBOARD_FAB2_LIB.BASEBOARD_FAB2(SCH_1):GND
EB65    GND VSS<23> @BASEBOARD_FAB2_LIB.BASEBOARD_FAB2(SCH_1):GND
EB69    GND VSS<22> @BASEBOARD_FAB2_LIB.BASEBOARD_FAB2(SCH_1):GND
EC10    GND VSS<21> @BASEBOARD_FAB2_LIB.BASEBOARD_FAB2(SCH_1):GND
EC70    GND VSS<20> @BASEBOARD_FAB2_LIB.BASEBOARD_FAB2(SCH_1):GND
EC72    GND VSS<19> @BASEBOARD_FAB2_LIB.BASEBOARD_FAB2(SCH_1):GND
EC74    GND VSS<18> @BASEBOARD_FAB2_LIB.BASEBOARD_FAB2(SCH_1):GND
EC76    GND VSS<17> @BASEBOARD_FAB2_LIB.BASEBOARD_FAB2(SCH_1):GND
ED11    GND VSS<16> @BASEBOARD_FAB2_LIB.BASEBOARD_FAB2(SCH_1):GND
ED15    GND VSS<15> @BASEBOARD_FAB2_LIB.BASEBOARD_FAB2(SCH_1):GND
ED23    GND VSS<14> @BASEBOARD_FAB2_LIB.BASEBOARD_FAB2(SCH_1):GND
ED29    GND VSS<13> @BASEBOARD_FAB2_LIB.BASEBOARD_FAB2(SCH_1):GND
ED35    GND VSS<12> @BASEBOARD_FAB2_LIB.BASEBOARD_FAB2(SCH_1):GND
ED77    GND VSS<11> @BASEBOARD_FAB2_LIB.BASEBOARD_FAB2(SCH_1):GND
EE24    GND VSS<10> @BASEBOARD_FAB2_LIB.BASEBOARD_FAB2(SCH_1):GND
EE28    GND VSS<9> @BASEBOARD_FAB2_LIB.BASEBOARD_FAB2(SCH_1):GND
EE30    GND VSS<8> @BASEBOARD_FAB2_LIB.BASEBOARD_FAB2(SCH_1):GND
EE34    GND VSS<7> @BASEBOARD_FAB2_LIB.BASEBOARD_FAB2(SCH_1):GND
EE36    GND VSS<6> @BASEBOARD_FAB2_LIB.BASEBOARD_FAB2(SCH_1):GND
EE70    GND VSS<5> @BASEBOARD_FAB2_LIB.BASEBOARD_FAB2(SCH_1):GND
EE76    GND VSS<4> @BASEBOARD_FAB2_LIB.BASEBOARD_FAB2(SCH_1):GND
EE78    GND VSS<3> @BASEBOARD_FAB2_LIB.BASEBOARD_FAB2(SCH_1):GND
EF71    GND VSS<2> @BASEBOARD_FAB2_LIB.BASEBOARD_FAB2(SCH_1):GND
EF75    GND VSS<1> @BASEBOARD_FAB2_LIB.BASEBOARD_FAB2(SCH_1):GND
EF79    GND VSS<0> @BASEBOARD_FAB2_LIB.BASEBOARD_FAB2(SCH_1):GND


DRAWING: @BASEBOARD_FAB2_LIB.BASEBOARD_FAB2(SCH_1):PAGE76 

CAP_A_0603V-22.0UF,4V,20%,X6S,A  I1  C3D21
   1 PVCCMCP_CPU1      A @BASEBOARD_FAB2_LIB.BASEBOARD_FAB2(SCH_1):PVCCMCP_CPU1
   2    GND      B @BASEBOARD_FAB2_LIB.BASEBOARD_FAB2(SCH_1):GND

CAP_A_0603V-22.0UF,4V,20%,X6S,A  I3  C3D5
   1 PVCCMCP_CPU1      A @BASEBOARD_FAB2_LIB.BASEBOARD_FAB2(SCH_1):PVCCMCP_CPU1
   2    GND      B @BASEBOARD_FAB2_LIB.BASEBOARD_FAB2(SCH_1):GND

CAP_A_0603V-22.0UF,4V,20%,X6S,A  I4  C3D12
   1 PVCCMCP_CPU1      A @BASEBOARD_FAB2_LIB.BASEBOARD_FAB2(SCH_1):PVCCMCP_CPU1
   2    GND      B @BASEBOARD_FAB2_LIB.BASEBOARD_FAB2(SCH_1):GND

CAP_A_0603V-22.0UF,4V,20%,X6S,A  I5  C3D4
   1 PVCCMCP_CPU1      A @BASEBOARD_FAB2_LIB.BASEBOARD_FAB2(SCH_1):PVCCMCP_CPU1
   2    GND      B @BASEBOARD_FAB2_LIB.BASEBOARD_FAB2(SCH_1):GND

CAP_A_0603V-22.0UF,4V,20%,X6S,A  I7  C3D11
   1 PVCCMCP_CPU1      A @BASEBOARD_FAB2_LIB.BASEBOARD_FAB2(SCH_1):PVCCMCP_CPU1
   2    GND      B @BASEBOARD_FAB2_LIB.BASEBOARD_FAB2(SCH_1):GND

CAP_A_0603V-22.0UF,4V,20%,X6S,A  I8  C3D13
   1 PVCCMCP_CPU1      A @BASEBOARD_FAB2_LIB.BASEBOARD_FAB2(SCH_1):PVCCMCP_CPU1
   2    GND      B @BASEBOARD_FAB2_LIB.BASEBOARD_FAB2(SCH_1):GND

CAP_A_0603V-22.0UF,4V,20%,X6S,A  I10  C2D40
   1 PVCCMCP_CPU1      A @BASEBOARD_FAB2_LIB.BASEBOARD_FAB2(SCH_1):PVCCMCP_CPU1
   2    GND      B @BASEBOARD_FAB2_LIB.BASEBOARD_FAB2(SCH_1):GND

CAP_A_0603V-22.0UF,4V,20%,X6S,A  I15  C3D9
   1 PVCCIO_CPU1      A @BASEBOARD_FAB2_LIB.BASEBOARD_FAB2(SCH_1):PVCCIO_CPU1
   2    GND      B @BASEBOARD_FAB2_LIB.BASEBOARD_FAB2(SCH_1):GND

CAP_A_0603V-22.0UF,4V,20%,X6S,A  I18  C3D8
   1 PVCCIO_CPU1      A @BASEBOARD_FAB2_LIB.BASEBOARD_FAB2(SCH_1):PVCCIO_CPU1
   2    GND      B @BASEBOARD_FAB2_LIB.BASEBOARD_FAB2(SCH_1):GND

CAP_0805-47UF,4V,20%,X6S,C9533A  I29  C7P17
   1 PVCCIO_CPU1      A @BASEBOARD_FAB2_LIB.BASEBOARD_FAB2(SCH_1):PVCCIO_CPU1
   2    GND      B @BASEBOARD_FAB2_LIB.BASEBOARD_FAB2(SCH_1):GND

CAP_0603LF-10UF,4V,20%,X6S,E15A  I33  C2D8
   1 PVSA_CPU1      A @BASEBOARD_FAB2_LIB.BASEBOARD_FAB2(SCH_1):PVSA_CPU1
   2    GND      B @BASEBOARD_FAB2_LIB.BASEBOARD_FAB2(SCH_1):GND

CAP_0603LF-10UF,4V,20%,X6S,E15A  I37  C2D10
   1 PVSA_CPU1      A @BASEBOARD_FAB2_LIB.BASEBOARD_FAB2(SCH_1):PVSA_CPU1
   2    GND      B @BASEBOARD_FAB2_LIB.BASEBOARD_FAB2(SCH_1):GND

CAP_0603LF-10UF,4V,20%,X6S,E15A  I42  C2D11
   1 PVSA_CPU1      A @BASEBOARD_FAB2_LIB.BASEBOARD_FAB2(SCH_1):PVSA_CPU1
   2    GND      B @BASEBOARD_FAB2_LIB.BASEBOARD_FAB2(SCH_1):GND

CAP_0603LF-10UF,4V,20%,X6S,E15A  I43  C2D9
   1 PVSA_CPU1      A @BASEBOARD_FAB2_LIB.BASEBOARD_FAB2(SCH_1):PVSA_CPU1
   2    GND      B @BASEBOARD_FAB2_LIB.BASEBOARD_FAB2(SCH_1):GND

CAP_0805-47UF,4V,20%,X6S,C9533A  I51  C7P18
   1 PVCCIO_CPU1      A @BASEBOARD_FAB2_LIB.BASEBOARD_FAB2(SCH_1):PVCCIO_CPU1
   2    GND      B @BASEBOARD_FAB2_LIB.BASEBOARD_FAB2(SCH_1):GND

CAP_0805-47UF,4V,20%,X6S,C9533A  I52  C7P3
   1 PVCCIO_CPU1      A @BASEBOARD_FAB2_LIB.BASEBOARD_FAB2(SCH_1):PVCCIO_CPU1
   2    GND      B @BASEBOARD_FAB2_LIB.BASEBOARD_FAB2(SCH_1):GND

CAP_A_0603V-22.0UF,4V,20%,X6S,A  I59  C2D12
   1 PVCCIN_CPU1      A @BASEBOARD_FAB2_LIB.BASEBOARD_FAB2(SCH_1):PVCCIN_CPU1
   2    GND      B @BASEBOARD_FAB2_LIB.BASEBOARD_FAB2(SCH_1):GND

CAP_A_0603V-22.0UF,4V,20%,X6S,A  I61  C2D22
   1 PVCCIN_CPU1      A @BASEBOARD_FAB2_LIB.BASEBOARD_FAB2(SCH_1):PVCCIN_CPU1
   2    GND      B @BASEBOARD_FAB2_LIB.BASEBOARD_FAB2(SCH_1):GND

CAP_A_0603V-22.0UF,4V,20%,X6S,A  I63  C2D31
   1 PVCCIN_CPU1      A @BASEBOARD_FAB2_LIB.BASEBOARD_FAB2(SCH_1):PVCCIN_CPU1
   2    GND      B @BASEBOARD_FAB2_LIB.BASEBOARD_FAB2(SCH_1):GND

CAP_A_0603V-22.0UF,4V,20%,X6S,A  I65  C2D21
   1 PVCCIN_CPU1      A @BASEBOARD_FAB2_LIB.BASEBOARD_FAB2(SCH_1):PVCCIN_CPU1
   2    GND      B @BASEBOARD_FAB2_LIB.BASEBOARD_FAB2(SCH_1):GND

CAP_A_0603V-22.0UF,4V,20%,X6S,A  I66  C2D27
   1 PVCCIN_CPU1      A @BASEBOARD_FAB2_LIB.BASEBOARD_FAB2(SCH_1):PVCCIN_CPU1
   2    GND      B @BASEBOARD_FAB2_LIB.BASEBOARD_FAB2(SCH_1):GND

CAP_A_0603V-22.0UF,4V,20%,X6S,A  I69  C3D2
   1 PVCCIN_CPU1      A @BASEBOARD_FAB2_LIB.BASEBOARD_FAB2(SCH_1):PVCCIN_CPU1
   2    GND      B @BASEBOARD_FAB2_LIB.BASEBOARD_FAB2(SCH_1):GND

CAP_A_0603V-22.0UF,4V,20%,X6S,A  I70  C2D36
   1 PVCCIN_CPU1      A @BASEBOARD_FAB2_LIB.BASEBOARD_FAB2(SCH_1):PVCCIN_CPU1
   2    GND      B @BASEBOARD_FAB2_LIB.BASEBOARD_FAB2(SCH_1):GND

CAP_A_0603V-22.0UF,4V,20%,X6S,A  I73  C2D13
   1 PVCCIN_CPU1      A @BASEBOARD_FAB2_LIB.BASEBOARD_FAB2(SCH_1):PVCCIN_CPU1
   2    GND      B @BASEBOARD_FAB2_LIB.BASEBOARD_FAB2(SCH_1):GND

CAP_A_0603V-22.0UF,4V,20%,X6S,A  I75  C2D19
   1 PVCCIN_CPU1      A @BASEBOARD_FAB2_LIB.BASEBOARD_FAB2(SCH_1):PVCCIN_CPU1
   2    GND      B @BASEBOARD_FAB2_LIB.BASEBOARD_FAB2(SCH_1):GND

CAP_A_0603V-22.0UF,4V,20%,X6S,A  I76  C2D14
   1 PVCCIN_CPU1      A @BASEBOARD_FAB2_LIB.BASEBOARD_FAB2(SCH_1):PVCCIN_CPU1
   2    GND      B @BASEBOARD_FAB2_LIB.BASEBOARD_FAB2(SCH_1):GND

CAP_A_0603V-22.0UF,4V,20%,X6S,A  I79  C2D20
   1 PVCCIN_CPU1      A @BASEBOARD_FAB2_LIB.BASEBOARD_FAB2(SCH_1):PVCCIN_CPU1
   2    GND      B @BASEBOARD_FAB2_LIB.BASEBOARD_FAB2(SCH_1):GND

CAP_A_0603V-22.0UF,4V,20%,X6S,A  I80  C2D24
   1 PVCCIN_CPU1      A @BASEBOARD_FAB2_LIB.BASEBOARD_FAB2(SCH_1):PVCCIN_CPU1
   2    GND      B @BASEBOARD_FAB2_LIB.BASEBOARD_FAB2(SCH_1):GND

CAP_A_0603V-22.0UF,4V,20%,X6S,A  I82  C2D25
   1 PVCCIN_CPU1      A @BASEBOARD_FAB2_LIB.BASEBOARD_FAB2(SCH_1):PVCCIN_CPU1
   2    GND      B @BASEBOARD_FAB2_LIB.BASEBOARD_FAB2(SCH_1):GND

CAP_A_0603V-22.0UF,4V,20%,X6S,A  I83  C2D30
   1 PVCCIN_CPU1      A @BASEBOARD_FAB2_LIB.BASEBOARD_FAB2(SCH_1):PVCCIN_CPU1
   2    GND      B @BASEBOARD_FAB2_LIB.BASEBOARD_FAB2(SCH_1):GND

CAP_A_0603V-22.0UF,4V,20%,X6S,A  I85  C2D33
   1 PVCCIN_CPU1      A @BASEBOARD_FAB2_LIB.BASEBOARD_FAB2(SCH_1):PVCCIN_CPU1
   2    GND      B @BASEBOARD_FAB2_LIB.BASEBOARD_FAB2(SCH_1):GND

CAP_0805-47UF,4V,20%,X6S,C9533A  I89  C8P20
   1 PVCCIN_CPU1      A @BASEBOARD_FAB2_LIB.BASEBOARD_FAB2(SCH_1):PVCCIN_CPU1
   2    GND      B @BASEBOARD_FAB2_LIB.BASEBOARD_FAB2(SCH_1):GND

CAP_A_0603V-22.0UF,4V,20%,X6S,A  I90  C2D32
   1 PVCCIN_CPU1      A @BASEBOARD_FAB2_LIB.BASEBOARD_FAB2(SCH_1):PVCCIN_CPU1
   2    GND      B @BASEBOARD_FAB2_LIB.BASEBOARD_FAB2(SCH_1):GND

CAP_0805-47UF,4V,20%,X6S,C9533A  I92  C8P18
   1 PVCCIN_CPU1      A @BASEBOARD_FAB2_LIB.BASEBOARD_FAB2(SCH_1):PVCCIN_CPU1
   2    GND      B @BASEBOARD_FAB2_LIB.BASEBOARD_FAB2(SCH_1):GND

CAP_0805-47UF,4V,20%,X6S,C9533A  I103  C8P19
   1 PVCCIN_CPU1      A @BASEBOARD_FAB2_LIB.BASEBOARD_FAB2(SCH_1):PVCCIN_CPU1
   2    GND      B @BASEBOARD_FAB2_LIB.BASEBOARD_FAB2(SCH_1):GND

CAP_0805-47UF,4V,20%,X6S,C9533A  I107  C8P12
   1 PVCCIN_CPU1      A @BASEBOARD_FAB2_LIB.BASEBOARD_FAB2(SCH_1):PVCCIN_CPU1
   2    GND      B @BASEBOARD_FAB2_LIB.BASEBOARD_FAB2(SCH_1):GND

CAP_A_0603V-22.0UF,4V,20%,X6S,A  I108  C2D26
   1 PVCCIN_CPU1      A @BASEBOARD_FAB2_LIB.BASEBOARD_FAB2(SCH_1):PVCCIN_CPU1
   2    GND      B @BASEBOARD_FAB2_LIB.BASEBOARD_FAB2(SCH_1):GND

CAP_A_0603V-22.0UF,4V,20%,X6S,A  I112  C2D23
   1 PVCCIN_CPU1      A @BASEBOARD_FAB2_LIB.BASEBOARD_FAB2(SCH_1):PVCCIN_CPU1
   2    GND      B @BASEBOARD_FAB2_LIB.BASEBOARD_FAB2(SCH_1):GND

CAP_A_0603V-22.0UF,4V,20%,X6S,A  I114  C2D17
   1 PVCCIN_CPU1      A @BASEBOARD_FAB2_LIB.BASEBOARD_FAB2(SCH_1):PVCCIN_CPU1
   2    GND      B @BASEBOARD_FAB2_LIB.BASEBOARD_FAB2(SCH_1):GND

CAP_0805-47UF,4V,20%,X6S,C9533A  I118  C8P26
   1 PVCCIN_CPU1      A @BASEBOARD_FAB2_LIB.BASEBOARD_FAB2(SCH_1):PVCCIN_CPU1
   2    GND      B @BASEBOARD_FAB2_LIB.BASEBOARD_FAB2(SCH_1):GND

CAP_A_0603V-22.0UF,4V,20%,X6S,A  I119  C2D37
   1 PVCCIN_CPU1      A @BASEBOARD_FAB2_LIB.BASEBOARD_FAB2(SCH_1):PVCCIN_CPU1
   2    GND      B @BASEBOARD_FAB2_LIB.BASEBOARD_FAB2(SCH_1):GND

CAP_A_0603V-22.0UF,4V,20%,X6S,A  I122  C2D34
   1 PVCCIN_CPU1      A @BASEBOARD_FAB2_LIB.BASEBOARD_FAB2(SCH_1):PVCCIN_CPU1
   2    GND      B @BASEBOARD_FAB2_LIB.BASEBOARD_FAB2(SCH_1):GND

CAP_A_0603V-22.0UF,4V,20%,X6S,A  I124  C2D16
   1 PVCCIN_CPU1      A @BASEBOARD_FAB2_LIB.BASEBOARD_FAB2(SCH_1):PVCCIN_CPU1
   2    GND      B @BASEBOARD_FAB2_LIB.BASEBOARD_FAB2(SCH_1):GND

CAP_0805-47UF,4V,20%,X6S,C9533A  I125  C8P29
   1 PVCCIN_CPU1      A @BASEBOARD_FAB2_LIB.BASEBOARD_FAB2(SCH_1):PVCCIN_CPU1
   2    GND      B @BASEBOARD_FAB2_LIB.BASEBOARD_FAB2(SCH_1):GND

CAP_0805-47UF,4V,20%,X6S,C9533A  I127  C8P10
   1 PVCCIN_CPU1      A @BASEBOARD_FAB2_LIB.BASEBOARD_FAB2(SCH_1):PVCCIN_CPU1
   2    GND      B @BASEBOARD_FAB2_LIB.BASEBOARD_FAB2(SCH_1):GND

CAP_0805-47UF,4V,20%,X6S,C9533A  I129  C8P16
   1 PVCCIN_CPU1      A @BASEBOARD_FAB2_LIB.BASEBOARD_FAB2(SCH_1):PVCCIN_CPU1
   2    GND      B @BASEBOARD_FAB2_LIB.BASEBOARD_FAB2(SCH_1):GND

CAP_0805-47UF,4V,20%,X6S,C9533A  I132  C8P13
   1 PVCCIN_CPU1      A @BASEBOARD_FAB2_LIB.BASEBOARD_FAB2(SCH_1):PVCCIN_CPU1
   2    GND      B @BASEBOARD_FAB2_LIB.BASEBOARD_FAB2(SCH_1):GND

CAP_0805-47UF,4V,20%,X6S,C9533A  I137  C8P28
   1 PVCCIN_CPU1      A @BASEBOARD_FAB2_LIB.BASEBOARD_FAB2(SCH_1):PVCCIN_CPU1
   2    GND      B @BASEBOARD_FAB2_LIB.BASEBOARD_FAB2(SCH_1):GND

CAP_0805-47UF,4V,20%,X6S,C9533A  I139  C8P11
   1 PVCCIN_CPU1      A @BASEBOARD_FAB2_LIB.BASEBOARD_FAB2(SCH_1):PVCCIN_CPU1
   2    GND      B @BASEBOARD_FAB2_LIB.BASEBOARD_FAB2(SCH_1):GND

CAP_A_0603V-22.0UF,4V,20%,X6S,A  I159  C2D15
   1 PVCCIN_CPU1      A @BASEBOARD_FAB2_LIB.BASEBOARD_FAB2(SCH_1):PVCCIN_CPU1
   2    GND      B @BASEBOARD_FAB2_LIB.BASEBOARD_FAB2(SCH_1):GND

CAP_A_0603V-22.0UF,4V,20%,X6S,A  I160  C2D38
   1 PVCCIN_CPU1      A @BASEBOARD_FAB2_LIB.BASEBOARD_FAB2(SCH_1):PVCCIN_CPU1
   2    GND      B @BASEBOARD_FAB2_LIB.BASEBOARD_FAB2(SCH_1):GND

CAP_A_0603V-22.0UF,4V,20%,X6S,A  I161  C2D35
   1 PVCCIN_CPU1      A @BASEBOARD_FAB2_LIB.BASEBOARD_FAB2(SCH_1):PVCCIN_CPU1
   2    GND      B @BASEBOARD_FAB2_LIB.BASEBOARD_FAB2(SCH_1):GND

CAP_A_0603V-22.0UF,4V,20%,X6S,A  I164  C3D7
   1 PVCCMCP_CPU1      A @BASEBOARD_FAB2_LIB.BASEBOARD_FAB2(SCH_1):PVCCMCP_CPU1
   2    GND      B @BASEBOARD_FAB2_LIB.BASEBOARD_FAB2(SCH_1):GND

CAP_A_0603V-22.0UF,4V,20%,X6S,A  I165  C2D39
   1 PVCCMCP_CPU1      A @BASEBOARD_FAB2_LIB.BASEBOARD_FAB2(SCH_1):PVCCMCP_CPU1
   2    GND      B @BASEBOARD_FAB2_LIB.BASEBOARD_FAB2(SCH_1):GND

CAP_A_0603V-22.0UF,4V,20%,X6S,A  I166  C3D17
   1 PVCCMCP_CPU1      A @BASEBOARD_FAB2_LIB.BASEBOARD_FAB2(SCH_1):PVCCMCP_CPU1
   2    GND      B @BASEBOARD_FAB2_LIB.BASEBOARD_FAB2(SCH_1):GND

CAP_A_0603V-22.0UF,4V,20%,X6S,A  I169  C3D18
   1 PVCCMCP_CPU1      A @BASEBOARD_FAB2_LIB.BASEBOARD_FAB2(SCH_1):PVCCMCP_CPU1
   2    GND      B @BASEBOARD_FAB2_LIB.BASEBOARD_FAB2(SCH_1):GND

CAP_A_0603V-22.0UF,4V,20%,X6S,A  I170  C3D6
   1 PVCCMCP_CPU1      A @BASEBOARD_FAB2_LIB.BASEBOARD_FAB2(SCH_1):PVCCMCP_CPU1
   2    GND      B @BASEBOARD_FAB2_LIB.BASEBOARD_FAB2(SCH_1):GND

CAP_A_0603V-22.0UF,4V,20%,X6S,A  I171  C3D14
   1 PVCCMCP_CPU1      A @BASEBOARD_FAB2_LIB.BASEBOARD_FAB2(SCH_1):PVCCMCP_CPU1
   2    GND      B @BASEBOARD_FAB2_LIB.BASEBOARD_FAB2(SCH_1):GND

CAP_A_0603V-22.0UF,4V,20%,X6S,A  I172  C3D23
   1 PVCCIO_CPU1      A @BASEBOARD_FAB2_LIB.BASEBOARD_FAB2(SCH_1):PVCCIO_CPU1
   2    GND      B @BASEBOARD_FAB2_LIB.BASEBOARD_FAB2(SCH_1):GND

CAP_A_0603V-22.0UF,4V,20%,X6S,A  I174  C3D15
   1 PVCCIO_CPU1      A @BASEBOARD_FAB2_LIB.BASEBOARD_FAB2(SCH_1):PVCCIO_CPU1
   2    GND      B @BASEBOARD_FAB2_LIB.BASEBOARD_FAB2(SCH_1):GND

CAP_A_0603V-22.0UF,4V,20%,X6S,A  I175  C3D24
   1 PVCCIO_CPU1      A @BASEBOARD_FAB2_LIB.BASEBOARD_FAB2(SCH_1):PVCCIO_CPU1
   2    GND      B @BASEBOARD_FAB2_LIB.BASEBOARD_FAB2(SCH_1):GND

CAP_A_0603V-22.0UF,4V,20%,X6S,A  I176  C3D16
   1 PVCCIO_CPU1      A @BASEBOARD_FAB2_LIB.BASEBOARD_FAB2(SCH_1):PVCCIO_CPU1
   2    GND      B @BASEBOARD_FAB2_LIB.BASEBOARD_FAB2(SCH_1):GND

CAP_A_0603V-22.0UF,4V,20%,X6S,A  I179  C7P12
   1 PVCCIO_CPU1      A @BASEBOARD_FAB2_LIB.BASEBOARD_FAB2(SCH_1):PVCCIO_CPU1
   2    GND      B @BASEBOARD_FAB2_LIB.BASEBOARD_FAB2(SCH_1):GND

CAP_A_0603V-22.0UF,4V,20%,X6S,A  I196  C3D10
   1 PVCCMCP_CPU1      A @BASEBOARD_FAB2_LIB.BASEBOARD_FAB2(SCH_1):PVCCMCP_CPU1
   2    GND      B @BASEBOARD_FAB2_LIB.BASEBOARD_FAB2(SCH_1):GND

CAP_A_0603V-22.0UF,4V,20%,X6S,A  I197  C2D18
   1 PVCCMCP_CPU1      A @BASEBOARD_FAB2_LIB.BASEBOARD_FAB2(SCH_1):PVCCMCP_CPU1
   2    GND      B @BASEBOARD_FAB2_LIB.BASEBOARD_FAB2(SCH_1):GND

CAP_A_0603V-22.0UF,4V,20%,X6S,A  I198  C2D28
   1 PVCCMCP_CPU1      A @BASEBOARD_FAB2_LIB.BASEBOARD_FAB2(SCH_1):PVCCMCP_CPU1
   2    GND      B @BASEBOARD_FAB2_LIB.BASEBOARD_FAB2(SCH_1):GND

CAP_A_0603V-22.0UF,4V,20%,X6S,A  I199  C2D29
   1 PVCCMCP_CPU1      A @BASEBOARD_FAB2_LIB.BASEBOARD_FAB2(SCH_1):PVCCMCP_CPU1
   2    GND      B @BASEBOARD_FAB2_LIB.BASEBOARD_FAB2(SCH_1):GND

CAP_A_0603V-22.0UF,4V,20%,X6S,A  I206  C7P16
   1 PVCCIO_CPU1      A @BASEBOARD_FAB2_LIB.BASEBOARD_FAB2(SCH_1):PVCCIO_CPU1
   2    GND      B @BASEBOARD_FAB2_LIB.BASEBOARD_FAB2(SCH_1):GND

CAP_A_0603V-22.0UF,4V,20%,X6S,A  I207  C3D20
   1 PVCCMCP_CPU1      A @BASEBOARD_FAB2_LIB.BASEBOARD_FAB2(SCH_1):PVCCMCP_CPU1
   2    GND      B @BASEBOARD_FAB2_LIB.BASEBOARD_FAB2(SCH_1):GND

CAP_A_0603V-22.0UF,4V,20%,X6S,A  I208  C3D19
   1 PVCCMCP_CPU1      A @BASEBOARD_FAB2_LIB.BASEBOARD_FAB2(SCH_1):PVCCMCP_CPU1
   2    GND      B @BASEBOARD_FAB2_LIB.BASEBOARD_FAB2(SCH_1):GND

CAP_0805-47UF,4V,20%,X6S,C9533A  I215  C7P19
   1 PVCCIN_CPU1      A @BASEBOARD_FAB2_LIB.BASEBOARD_FAB2(SCH_1):PVCCIN_CPU1
   2    GND      B @BASEBOARD_FAB2_LIB.BASEBOARD_FAB2(SCH_1):GND

CAP_0805-47UF,4V,20%,X6S,C9533A  I217  C8P24
   1 PVCCIN_CPU1      A @BASEBOARD_FAB2_LIB.BASEBOARD_FAB2(SCH_1):PVCCIN_CPU1
   2    GND      B @BASEBOARD_FAB2_LIB.BASEBOARD_FAB2(SCH_1):GND

CAP_0805-100UF,4V,20%,X5R,6024A  I245  C8W4
   1 PVCCIN_CPU1      A @BASEBOARD_FAB2_LIB.BASEBOARD_FAB2(SCH_1):PVCCIN_CPU1
   2    GND      B @BASEBOARD_FAB2_LIB.BASEBOARD_FAB2(SCH_1):GND

CAP_0805LF-22UF,4V,20%,X6S,C95A  I246  C8P5
   1 PVSA_CPU1      A @BASEBOARD_FAB2_LIB.BASEBOARD_FAB2(SCH_1):PVSA_CPU1
   2    GND      B @BASEBOARD_FAB2_LIB.BASEBOARD_FAB2(SCH_1):GND

CAP_0805LF-22UF,4V,20%,X6S,C95A  I247  C8P6
   1 PVSA_CPU1      A @BASEBOARD_FAB2_LIB.BASEBOARD_FAB2(SCH_1):PVSA_CPU1
   2    GND      B @BASEBOARD_FAB2_LIB.BASEBOARD_FAB2(SCH_1):GND

CAP_0805LF-22UF,4V,20%,X6S,C95A  I248  C8P7
   1 PVSA_CPU1      A @BASEBOARD_FAB2_LIB.BASEBOARD_FAB2(SCH_1):PVSA_CPU1
   2    GND      B @BASEBOARD_FAB2_LIB.BASEBOARD_FAB2(SCH_1):GND

CAP_0805-47UF,4V,20%,X6S,C9533A  I249  C8P21
   1 PVCCIN_CPU1      A @BASEBOARD_FAB2_LIB.BASEBOARD_FAB2(SCH_1):PVCCIN_CPU1
   2    GND      B @BASEBOARD_FAB2_LIB.BASEBOARD_FAB2(SCH_1):GND

CAP_0805-47UF,4V,20%,X6S,C9533A  I250  C8P27
   1 PVCCIN_CPU1      A @BASEBOARD_FAB2_LIB.BASEBOARD_FAB2(SCH_1):PVCCIN_CPU1
   2    GND      B @BASEBOARD_FAB2_LIB.BASEBOARD_FAB2(SCH_1):GND

CAP_0805-47UF,4V,20%,X6S,C9533A  I251  C8P25
   1 PVCCIN_CPU1      A @BASEBOARD_FAB2_LIB.BASEBOARD_FAB2(SCH_1):PVCCIN_CPU1
   2    GND      B @BASEBOARD_FAB2_LIB.BASEBOARD_FAB2(SCH_1):GND

CAP_0805-47UF,4V,20%,X6S,C9533A  I252  C8P17
   1 PVCCIN_CPU1      A @BASEBOARD_FAB2_LIB.BASEBOARD_FAB2(SCH_1):PVCCIN_CPU1
   2    GND      B @BASEBOARD_FAB2_LIB.BASEBOARD_FAB2(SCH_1):GND

CAP_A_0603V-22.0UF,4V,20%,X6S,A  I254  C3W4
   1 PVCCMCP_CPU1      A @BASEBOARD_FAB2_LIB.BASEBOARD_FAB2(SCH_1):PVCCMCP_CPU1
   2    GND      B @BASEBOARD_FAB2_LIB.BASEBOARD_FAB2(SCH_1):GND

CAP_A_0603V-22.0UF,4V,20%,X6S,A  I256  C3W3
   1 PVCCMCP_CPU1      A @BASEBOARD_FAB2_LIB.BASEBOARD_FAB2(SCH_1):PVCCMCP_CPU1
   2    GND      B @BASEBOARD_FAB2_LIB.BASEBOARD_FAB2(SCH_1):GND

CAP_0805-100UF,4V,20%,X5R,6024A  I258  C7P9
   1 PVCCMCP_CPU1      A @BASEBOARD_FAB2_LIB.BASEBOARD_FAB2(SCH_1):PVCCMCP_CPU1
   2    GND      B @BASEBOARD_FAB2_LIB.BASEBOARD_FAB2(SCH_1):GND

CAP_0805-100UF,4V,20%,X5R,6024A  I259  C7P5
   1 PVCCMCP_CPU1      A @BASEBOARD_FAB2_LIB.BASEBOARD_FAB2(SCH_1):PVCCMCP_CPU1
   2    GND      B @BASEBOARD_FAB2_LIB.BASEBOARD_FAB2(SCH_1):GND

CAP_0805-100UF,4V,20%,X5R,6024A  I260  C8P23
   1 PVCCMCP_CPU1      A @BASEBOARD_FAB2_LIB.BASEBOARD_FAB2(SCH_1):PVCCMCP_CPU1
   2    GND      B @BASEBOARD_FAB2_LIB.BASEBOARD_FAB2(SCH_1):GND

CAP_0805-100UF,4V,20%,X5R,6024A  I261  C7P14
   1 PVCCMCP_CPU1      A @BASEBOARD_FAB2_LIB.BASEBOARD_FAB2(SCH_1):PVCCMCP_CPU1
   2    GND      B @BASEBOARD_FAB2_LIB.BASEBOARD_FAB2(SCH_1):GND

CAP_0805-100UF,4V,20%,X5R,6024A  I262  C7P11
   1 PVCCMCP_CPU1      A @BASEBOARD_FAB2_LIB.BASEBOARD_FAB2(SCH_1):PVCCMCP_CPU1
   2    GND      B @BASEBOARD_FAB2_LIB.BASEBOARD_FAB2(SCH_1):GND

CAP_0805-100UF,4V,20%,X5R,6024A  I263  C7P15
   1 PVCCMCP_CPU1      A @BASEBOARD_FAB2_LIB.BASEBOARD_FAB2(SCH_1):PVCCMCP_CPU1
   2    GND      B @BASEBOARD_FAB2_LIB.BASEBOARD_FAB2(SCH_1):GND

CAP_0805-100UF,4V,20%,X5R,6024A  I264  C8P22
   1 PVCCMCP_CPU1      A @BASEBOARD_FAB2_LIB.BASEBOARD_FAB2(SCH_1):PVCCMCP_CPU1
   2    GND      B @BASEBOARD_FAB2_LIB.BASEBOARD_FAB2(SCH_1):GND

CAP_0805-100UF,4V,20%,X5R,6024A  I265  C7P8
   1 PVCCMCP_CPU1      A @BASEBOARD_FAB2_LIB.BASEBOARD_FAB2(SCH_1):PVCCMCP_CPU1
   2    GND      B @BASEBOARD_FAB2_LIB.BASEBOARD_FAB2(SCH_1):GND

CAP_0805-100UF,4V,20%,X5R,6024A  I266  C7P10
   1 PVCCMCP_CPU1      A @BASEBOARD_FAB2_LIB.BASEBOARD_FAB2(SCH_1):PVCCMCP_CPU1
   2    GND      B @BASEBOARD_FAB2_LIB.BASEBOARD_FAB2(SCH_1):GND

CAP_0805-100UF,4V,20%,X5R,6024A  I267  C7P7
   1 PVCCMCP_CPU1      A @BASEBOARD_FAB2_LIB.BASEBOARD_FAB2(SCH_1):PVCCMCP_CPU1
   2    GND      B @BASEBOARD_FAB2_LIB.BASEBOARD_FAB2(SCH_1):GND

CAP_0805-100UF,4V,20%,X5R,6024A  I268  C7P6
   1 PVCCMCP_CPU1      A @BASEBOARD_FAB2_LIB.BASEBOARD_FAB2(SCH_1):PVCCMCP_CPU1
   2    GND      B @BASEBOARD_FAB2_LIB.BASEBOARD_FAB2(SCH_1):GND

CAP_0805-100UF,4V,20%,X5R,6024A  I269  C7P13
   1 PVCCMCP_CPU1      A @BASEBOARD_FAB2_LIB.BASEBOARD_FAB2(SCH_1):PVCCMCP_CPU1
   2    GND      B @BASEBOARD_FAB2_LIB.BASEBOARD_FAB2(SCH_1):GND

CAP_0805-100UF,4V,20%,X5R,6024A  I270  C8P15
   1 PVCCMCP_CPU1      A @BASEBOARD_FAB2_LIB.BASEBOARD_FAB2(SCH_1):PVCCMCP_CPU1
   2    GND      B @BASEBOARD_FAB2_LIB.BASEBOARD_FAB2(SCH_1):GND

CAP_0805-100UF,4V,20%,X5R,6024A  I271  C7P4
   1 PVCCMCP_CPU1      A @BASEBOARD_FAB2_LIB.BASEBOARD_FAB2(SCH_1):PVCCMCP_CPU1
   2    GND      B @BASEBOARD_FAB2_LIB.BASEBOARD_FAB2(SCH_1):GND

CAP_0805-100UF,4V,20%,X5R,6024A  I272  C8P14
   1 PVCCMCP_CPU1      A @BASEBOARD_FAB2_LIB.BASEBOARD_FAB2(SCH_1):PVCCMCP_CPU1
   2    GND      B @BASEBOARD_FAB2_LIB.BASEBOARD_FAB2(SCH_1):GND

CAP_0805-100UF,4V,20%,X5R,6024A  I273  C8P9
   1 PVCCMCP_CPU1      A @BASEBOARD_FAB2_LIB.BASEBOARD_FAB2(SCH_1):PVCCMCP_CPU1
   2    GND      B @BASEBOARD_FAB2_LIB.BASEBOARD_FAB2(SCH_1):GND

CAP_0805-100UF,4V,20%,X5R,6024A  I274  C8P8
   1 PVCCMCP_CPU1      A @BASEBOARD_FAB2_LIB.BASEBOARD_FAB2(SCH_1):PVCCMCP_CPU1
   2    GND      B @BASEBOARD_FAB2_LIB.BASEBOARD_FAB2(SCH_1):GND


DRAWING: @BASEBOARD_FAB2_LIB.BASEBOARD_FAB2(SCH_1):PAGE77 

SCONN288_H44441004_PIP-SCONN,HA  I43  J1G1
   2    GND VSS<93> @BASEBOARD_FAB2_LIB.BASEBOARD_FAB2(SCH_1):GND
   4    GND VSS<92> @BASEBOARD_FAB2_LIB.BASEBOARD_FAB2(SCH_1):GND
   6    GND VSS<91> @BASEBOARD_FAB2_LIB.BASEBOARD_FAB2(SCH_1):GND
   9    GND VSS<90> @BASEBOARD_FAB2_LIB.BASEBOARD_FAB2(SCH_1):GND
  11    GND VSS<89> @BASEBOARD_FAB2_LIB.BASEBOARD_FAB2(SCH_1):GND
  13    GND VSS<88> @BASEBOARD_FAB2_LIB.BASEBOARD_FAB2(SCH_1):GND
  15    GND VSS<87> @BASEBOARD_FAB2_LIB.BASEBOARD_FAB2(SCH_1):GND
  17    GND VSS<86> @BASEBOARD_FAB2_LIB.BASEBOARD_FAB2(SCH_1):GND
  20    GND VSS<85> @BASEBOARD_FAB2_LIB.BASEBOARD_FAB2(SCH_1):GND
  22    GND VSS<84> @BASEBOARD_FAB2_LIB.BASEBOARD_FAB2(SCH_1):GND
  24    GND VSS<83> @BASEBOARD_FAB2_LIB.BASEBOARD_FAB2(SCH_1):GND
  26    GND VSS<82> @BASEBOARD_FAB2_LIB.BASEBOARD_FAB2(SCH_1):GND
  28    GND VSS<81> @BASEBOARD_FAB2_LIB.BASEBOARD_FAB2(SCH_1):GND
  31    GND VSS<80> @BASEBOARD_FAB2_LIB.BASEBOARD_FAB2(SCH_1):GND
  33    GND VSS<79> @BASEBOARD_FAB2_LIB.BASEBOARD_FAB2(SCH_1):GND
  35    GND VSS<78> @BASEBOARD_FAB2_LIB.BASEBOARD_FAB2(SCH_1):GND
  37    GND VSS<77> @BASEBOARD_FAB2_LIB.BASEBOARD_FAB2(SCH_1):GND
  39    GND VSS<76> @BASEBOARD_FAB2_LIB.BASEBOARD_FAB2(SCH_1):GND
  42    GND VSS<75> @BASEBOARD_FAB2_LIB.BASEBOARD_FAB2(SCH_1):GND
  44    GND VSS<74> @BASEBOARD_FAB2_LIB.BASEBOARD_FAB2(SCH_1):GND
  46    GND VSS<73> @BASEBOARD_FAB2_LIB.BASEBOARD_FAB2(SCH_1):GND
  48    GND VSS<72> @BASEBOARD_FAB2_LIB.BASEBOARD_FAB2(SCH_1):GND
  50    GND VSS<71> @BASEBOARD_FAB2_LIB.BASEBOARD_FAB2(SCH_1):GND
  53    GND VSS<70> @BASEBOARD_FAB2_LIB.BASEBOARD_FAB2(SCH_1):GND
  55    GND VSS<69> @BASEBOARD_FAB2_LIB.BASEBOARD_FAB2(SCH_1):GND
  57    GND VSS<68> @BASEBOARD_FAB2_LIB.BASEBOARD_FAB2(SCH_1):GND
  94    GND VSS<67> @BASEBOARD_FAB2_LIB.BASEBOARD_FAB2(SCH_1):GND
  96    GND VSS<66> @BASEBOARD_FAB2_LIB.BASEBOARD_FAB2(SCH_1):GND
  98    GND VSS<65> @BASEBOARD_FAB2_LIB.BASEBOARD_FAB2(SCH_1):GND
 101    GND VSS<64> @BASEBOARD_FAB2_LIB.BASEBOARD_FAB2(SCH_1):GND
 103    GND VSS<63> @BASEBOARD_FAB2_LIB.BASEBOARD_FAB2(SCH_1):GND
 105    GND VSS<62> @BASEBOARD_FAB2_LIB.BASEBOARD_FAB2(SCH_1):GND
 107    GND VSS<61> @BASEBOARD_FAB2_LIB.BASEBOARD_FAB2(SCH_1):GND
 109    GND VSS<60> @BASEBOARD_FAB2_LIB.BASEBOARD_FAB2(SCH_1):GND
 112    GND VSS<59> @BASEBOARD_FAB2_LIB.BASEBOARD_FAB2(SCH_1):GND
 114    GND VSS<58> @BASEBOARD_FAB2_LIB.BASEBOARD_FAB2(SCH_1):GND
 116    GND VSS<57> @BASEBOARD_FAB2_LIB.BASEBOARD_FAB2(SCH_1):GND
 118    GND VSS<56> @BASEBOARD_FAB2_LIB.BASEBOARD_FAB2(SCH_1):GND
 120    GND VSS<55> @BASEBOARD_FAB2_LIB.BASEBOARD_FAB2(SCH_1):GND
 123    GND VSS<54> @BASEBOARD_FAB2_LIB.BASEBOARD_FAB2(SCH_1):GND
 125    GND VSS<53> @BASEBOARD_FAB2_LIB.BASEBOARD_FAB2(SCH_1):GND
 127    GND VSS<52> @BASEBOARD_FAB2_LIB.BASEBOARD_FAB2(SCH_1):GND
 129    GND VSS<51> @BASEBOARD_FAB2_LIB.BASEBOARD_FAB2(SCH_1):GND
 131    GND VSS<50> @BASEBOARD_FAB2_LIB.BASEBOARD_FAB2(SCH_1):GND
 134    GND VSS<49> @BASEBOARD_FAB2_LIB.BASEBOARD_FAB2(SCH_1):GND
 136    GND VSS<48> @BASEBOARD_FAB2_LIB.BASEBOARD_FAB2(SCH_1):GND
 138    GND VSS<47> @BASEBOARD_FAB2_LIB.BASEBOARD_FAB2(SCH_1):GND
 147    GND VSS<46> @BASEBOARD_FAB2_LIB.BASEBOARD_FAB2(SCH_1):GND
 149    GND VSS<45> @BASEBOARD_FAB2_LIB.BASEBOARD_FAB2(SCH_1):GND
 151    GND VSS<44> @BASEBOARD_FAB2_LIB.BASEBOARD_FAB2(SCH_1):GND
 154    GND VSS<43> @BASEBOARD_FAB2_LIB.BASEBOARD_FAB2(SCH_1):GND
 156    GND VSS<42> @BASEBOARD_FAB2_LIB.BASEBOARD_FAB2(SCH_1):GND
 158    GND VSS<41> @BASEBOARD_FAB2_LIB.BASEBOARD_FAB2(SCH_1):GND
 160    GND VSS<40> @BASEBOARD_FAB2_LIB.BASEBOARD_FAB2(SCH_1):GND
 162    GND VSS<39> @BASEBOARD_FAB2_LIB.BASEBOARD_FAB2(SCH_1):GND
 165    GND VSS<38> @BASEBOARD_FAB2_LIB.BASEBOARD_FAB2(SCH_1):GND
 167    GND VSS<37> @BASEBOARD_FAB2_LIB.BASEBOARD_FAB2(SCH_1):GND
 169    GND VSS<36> @BASEBOARD_FAB2_LIB.BASEBOARD_FAB2(SCH_1):GND
 171    GND VSS<35> @BASEBOARD_FAB2_LIB.BASEBOARD_FAB2(SCH_1):GND
 173    GND VSS<34> @BASEBOARD_FAB2_LIB.BASEBOARD_FAB2(SCH_1):GND
 176    GND VSS<33> @BASEBOARD_FAB2_LIB.BASEBOARD_FAB2(SCH_1):GND
 178    GND VSS<32> @BASEBOARD_FAB2_LIB.BASEBOARD_FAB2(SCH_1):GND
 180    GND VSS<31> @BASEBOARD_FAB2_LIB.BASEBOARD_FAB2(SCH_1):GND
 182    GND VSS<30> @BASEBOARD_FAB2_LIB.BASEBOARD_FAB2(SCH_1):GND
 184    GND VSS<29> @BASEBOARD_FAB2_LIB.BASEBOARD_FAB2(SCH_1):GND
 187    GND VSS<28> @BASEBOARD_FAB2_LIB.BASEBOARD_FAB2(SCH_1):GND
 189    GND VSS<27> @BASEBOARD_FAB2_LIB.BASEBOARD_FAB2(SCH_1):GND
 191    GND VSS<26> @BASEBOARD_FAB2_LIB.BASEBOARD_FAB2(SCH_1):GND
 193    GND VSS<25> @BASEBOARD_FAB2_LIB.BASEBOARD_FAB2(SCH_1):GND
 195    GND VSS<24> @BASEBOARD_FAB2_LIB.BASEBOARD_FAB2(SCH_1):GND
 198    GND VSS<23> @BASEBOARD_FAB2_LIB.BASEBOARD_FAB2(SCH_1):GND
 200    GND VSS<22> @BASEBOARD_FAB2_LIB.BASEBOARD_FAB2(SCH_1):GND
 202    GND VSS<21> @BASEBOARD_FAB2_LIB.BASEBOARD_FAB2(SCH_1):GND
 239    GND VSS<20> @BASEBOARD_FAB2_LIB.BASEBOARD_FAB2(SCH_1):GND
 241    GND VSS<19> @BASEBOARD_FAB2_LIB.BASEBOARD_FAB2(SCH_1):GND
 243    GND VSS<18> @BASEBOARD_FAB2_LIB.BASEBOARD_FAB2(SCH_1):GND
 246    GND VSS<17> @BASEBOARD_FAB2_LIB.BASEBOARD_FAB2(SCH_1):GND
 248    GND VSS<16> @BASEBOARD_FAB2_LIB.BASEBOARD_FAB2(SCH_1):GND
 250    GND VSS<15> @BASEBOARD_FAB2_LIB.BASEBOARD_FAB2(SCH_1):GND
 252    GND VSS<14> @BASEBOARD_FAB2_LIB.BASEBOARD_FAB2(SCH_1):GND
 254    GND VSS<13> @BASEBOARD_FAB2_LIB.BASEBOARD_FAB2(SCH_1):GND
 257    GND VSS<12> @BASEBOARD_FAB2_LIB.BASEBOARD_FAB2(SCH_1):GND
 259    GND VSS<11> @BASEBOARD_FAB2_LIB.BASEBOARD_FAB2(SCH_1):GND
 261    GND VSS<10> @BASEBOARD_FAB2_LIB.BASEBOARD_FAB2(SCH_1):GND
 263    GND VSS<9> @BASEBOARD_FAB2_LIB.BASEBOARD_FAB2(SCH_1):GND
 265    GND VSS<8> @BASEBOARD_FAB2_LIB.BASEBOARD_FAB2(SCH_1):GND
 268    GND VSS<7> @BASEBOARD_FAB2_LIB.BASEBOARD_FAB2(SCH_1):GND
 270    GND VSS<6> @BASEBOARD_FAB2_LIB.BASEBOARD_FAB2(SCH_1):GND
 272    GND VSS<5> @BASEBOARD_FAB2_LIB.BASEBOARD_FAB2(SCH_1):GND
 274    GND VSS<4> @BASEBOARD_FAB2_LIB.BASEBOARD_FAB2(SCH_1):GND
 276    GND VSS<3> @BASEBOARD_FAB2_LIB.BASEBOARD_FAB2(SCH_1):GND
 279    GND VSS<2> @BASEBOARD_FAB2_LIB.BASEBOARD_FAB2(SCH_1):GND
 281    GND VSS<1> @BASEBOARD_FAB2_LIB.BASEBOARD_FAB2(SCH_1):GND
 283    GND VSS<0> @BASEBOARD_FAB2_LIB.BASEBOARD_FAB2(SCH_1):GND

SCONN288_H44441004_PIP-SCONN,HA  I66  J1G1
 152 M_G_DQS_DN<0>  DQS0N @BASEBOARD_FAB2_LIB.BASEBOARD_FAB2(SCH_1):M_G_DQS_DN(0)
 153 M_G_DQS_DP<0>  DQS0P @BASEBOARD_FAB2_LIB.BASEBOARD_FAB2(SCH_1):M_G_DQS_DP(0)
  19 M_G_DQS_DN<10> DQS10N @BASEBOARD_FAB2_LIB.BASEBOARD_FAB2(SCH_1):M_G_DQS_DN(10)
  18 M_G_DQS_DP<10> DQS10P @BASEBOARD_FAB2_LIB.BASEBOARD_FAB2(SCH_1):M_G_DQS_DP(10)
  30 M_G_DQS_DN<11> DQS11N @BASEBOARD_FAB2_LIB.BASEBOARD_FAB2(SCH_1):M_G_DQS_DN(11)
  29 M_G_DQS_DP<11> DQS11P @BASEBOARD_FAB2_LIB.BASEBOARD_FAB2(SCH_1):M_G_DQS_DP(11)
  41 M_G_DQS_DN<12> DQS12N @BASEBOARD_FAB2_LIB.BASEBOARD_FAB2(SCH_1):M_G_DQS_DN(12)
  40 M_G_DQS_DP<12> DQS12P @BASEBOARD_FAB2_LIB.BASEBOARD_FAB2(SCH_1):M_G_DQS_DP(12)
 100 M_G_DQS_DN<13> DQS13N @BASEBOARD_FAB2_LIB.BASEBOARD_FAB2(SCH_1):M_G_DQS_DN(13)
  99 M_G_DQS_DP<13> DQS13P @BASEBOARD_FAB2_LIB.BASEBOARD_FAB2(SCH_1):M_G_DQS_DP(13)
 111 M_G_DQS_DN<14> DQS14N @BASEBOARD_FAB2_LIB.BASEBOARD_FAB2(SCH_1):M_G_DQS_DN(14)
 110 M_G_DQS_DP<14> DQS14P @BASEBOARD_FAB2_LIB.BASEBOARD_FAB2(SCH_1):M_G_DQS_DP(14)
 122 M_G_DQS_DN<15> DQS15N @BASEBOARD_FAB2_LIB.BASEBOARD_FAB2(SCH_1):M_G_DQS_DN(15)
 121 M_G_DQS_DP<15> DQS15P @BASEBOARD_FAB2_LIB.BASEBOARD_FAB2(SCH_1):M_G_DQS_DP(15)
 133 M_G_DQS_DN<16> DQS16N @BASEBOARD_FAB2_LIB.BASEBOARD_FAB2(SCH_1):M_G_DQS_DN(16)
 132 M_G_DQS_DP<16> DQS16P @BASEBOARD_FAB2_LIB.BASEBOARD_FAB2(SCH_1):M_G_DQS_DP(16)
  52 M_G_DQS_DN<17> DQS17N @BASEBOARD_FAB2_LIB.BASEBOARD_FAB2(SCH_1):M_G_DQS_DN(17)
  51 M_G_DQS_DP<17> DQS17P @BASEBOARD_FAB2_LIB.BASEBOARD_FAB2(SCH_1):M_G_DQS_DP(17)
 163 M_G_DQS_DN<1>  DQS1N @BASEBOARD_FAB2_LIB.BASEBOARD_FAB2(SCH_1):M_G_DQS_DN(1)
 164 M_G_DQS_DP<1>  DQS1P @BASEBOARD_FAB2_LIB.BASEBOARD_FAB2(SCH_1):M_G_DQS_DP(1)
 174 M_G_DQS_DN<2>  DQS2N @BASEBOARD_FAB2_LIB.BASEBOARD_FAB2(SCH_1):M_G_DQS_DN(2)
 175 M_G_DQS_DP<2>  DQS2P @BASEBOARD_FAB2_LIB.BASEBOARD_FAB2(SCH_1):M_G_DQS_DP(2)
 185 M_G_DQS_DN<3>  DQS3N @BASEBOARD_FAB2_LIB.BASEBOARD_FAB2(SCH_1):M_G_DQS_DN(3)
 186 M_G_DQS_DP<3>  DQS3P @BASEBOARD_FAB2_LIB.BASEBOARD_FAB2(SCH_1):M_G_DQS_DP(3)
 244 M_G_DQS_DN<4>  DQS4N @BASEBOARD_FAB2_LIB.BASEBOARD_FAB2(SCH_1):M_G_DQS_DN(4)
 245 M_G_DQS_DP<4>  DQS4P @BASEBOARD_FAB2_LIB.BASEBOARD_FAB2(SCH_1):M_G_DQS_DP(4)
 255 M_G_DQS_DN<5>  DQS5N @BASEBOARD_FAB2_LIB.BASEBOARD_FAB2(SCH_1):M_G_DQS_DN(5)
 256 M_G_DQS_DP<5>  DQS5P @BASEBOARD_FAB2_LIB.BASEBOARD_FAB2(SCH_1):M_G_DQS_DP(5)
 266 M_G_DQS_DN<6>  DQS6N @BASEBOARD_FAB2_LIB.BASEBOARD_FAB2(SCH_1):M_G_DQS_DN(6)
 267 M_G_DQS_DP<6>  DQS6P @BASEBOARD_FAB2_LIB.BASEBOARD_FAB2(SCH_1):M_G_DQS_DP(6)
 277 M_G_DQS_DN<7>  DQS7N @BASEBOARD_FAB2_LIB.BASEBOARD_FAB2(SCH_1):M_G_DQS_DN(7)
 278 M_G_DQS_DP<7>  DQS7P @BASEBOARD_FAB2_LIB.BASEBOARD_FAB2(SCH_1):M_G_DQS_DP(7)
 196 M_G_DQS_DN<8>  DQS8N @BASEBOARD_FAB2_LIB.BASEBOARD_FAB2(SCH_1):M_G_DQS_DN(8)
 197 M_G_DQS_DP<8>  DQS8P @BASEBOARD_FAB2_LIB.BASEBOARD_FAB2(SCH_1):M_G_DQS_DP(8)
   8 M_G_DQS_DN<9>  DQS9N @BASEBOARD_FAB2_LIB.BASEBOARD_FAB2(SCH_1):M_G_DQS_DN(9)
   7 M_G_DQS_DP<9>  DQS9P @BASEBOARD_FAB2_LIB.BASEBOARD_FAB2(SCH_1):M_G_DQS_DP(9)

SCONN288_H44441004_PIP-SCONN,HA  I111  J1G1
  79 M_G_MA<0>     A0 @BASEBOARD_FAB2_LIB.BASEBOARD_FAB2(SCH_1):M_G_MA(0)
  72 M_G_MA<1>     A1 @BASEBOARD_FAB2_LIB.BASEBOARD_FAB2(SCH_1):M_G_MA(1)
 225 M_G_MA<10>    A10 @BASEBOARD_FAB2_LIB.BASEBOARD_FAB2(SCH_1):M_G_MA(10)
 210 M_G_MA<11>    A11 @BASEBOARD_FAB2_LIB.BASEBOARD_FAB2(SCH_1):M_G_MA(11)
  65 M_G_MA<12>    A12 @BASEBOARD_FAB2_LIB.BASEBOARD_FAB2(SCH_1):M_G_MA(12)
 232 M_G_MA<13>    A13 @BASEBOARD_FAB2_LIB.BASEBOARD_FAB2(SCH_1):M_G_MA(13)
 228 M_G_MA<14> A14_WE_N @BASEBOARD_FAB2_LIB.BASEBOARD_FAB2(SCH_1):M_G_MA(14)
  86 M_G_MA<15> A15_CAS_N @BASEBOARD_FAB2_LIB.BASEBOARD_FAB2(SCH_1):M_G_MA(15)
  82 M_G_MA<16> A16_RAS_N @BASEBOARD_FAB2_LIB.BASEBOARD_FAB2(SCH_1):M_G_MA(16)
 234 M_G_MA<17>    A17 @BASEBOARD_FAB2_LIB.BASEBOARD_FAB2(SCH_1):M_G_MA(17)
 216 M_G_MA<2>     A2 @BASEBOARD_FAB2_LIB.BASEBOARD_FAB2(SCH_1):M_G_MA(2)
  71 M_G_MA<3>     A3 @BASEBOARD_FAB2_LIB.BASEBOARD_FAB2(SCH_1):M_G_MA(3)
 214 M_G_MA<4>     A4 @BASEBOARD_FAB2_LIB.BASEBOARD_FAB2(SCH_1):M_G_MA(4)
 213 M_G_MA<5>     A5 @BASEBOARD_FAB2_LIB.BASEBOARD_FAB2(SCH_1):M_G_MA(5)
  69 M_G_MA<6>     A6 @BASEBOARD_FAB2_LIB.BASEBOARD_FAB2(SCH_1):M_G_MA(6)
 211 M_G_MA<7>     A7 @BASEBOARD_FAB2_LIB.BASEBOARD_FAB2(SCH_1):M_G_MA(7)
  68 M_G_MA<8>     A8 @BASEBOARD_FAB2_LIB.BASEBOARD_FAB2(SCH_1):M_G_MA(8)
  66 M_G_MA<9>     A9 @BASEBOARD_FAB2_LIB.BASEBOARD_FAB2(SCH_1):M_G_MA(9)
  62 M_G_ACT_N  ACT_N @BASEBOARD_FAB2_LIB.BASEBOARD_FAB2(SCH_1):M_G_ACT_N
 208 M_G_ALERT_N ALERT_N @BASEBOARD_FAB2_LIB.BASEBOARD_FAB2(SCH_1):M_G_ALERT_N
 224 M_G_BA<1>  BA<1> @BASEBOARD_FAB2_LIB.BASEBOARD_FAB2(SCH_1):M_G_BA(1)
  81 M_G_BA<0>  BA<0> @BASEBOARD_FAB2_LIB.BASEBOARD_FAB2(SCH_1):M_G_BA(0)
 207 M_G_BG<1>  BG<1> @BASEBOARD_FAB2_LIB.BASEBOARD_FAB2(SCH_1):M_G_BG(1)
  63 M_G_BG<0>  BG<0> @BASEBOARD_FAB2_LIB.BASEBOARD_FAB2(SCH_1):M_G_BG(0)
 235 M_G_C<2>   C<2> @BASEBOARD_FAB2_LIB.BASEBOARD_FAB2(SCH_1):M_G_C(2)
 199 M_G_ECC<6>  CB<7> @BASEBOARD_FAB2_LIB.BASEBOARD_FAB2(SCH_1):M_G_ECC(6)
  54 M_G_ECC<7>  CB<6> @BASEBOARD_FAB2_LIB.BASEBOARD_FAB2(SCH_1):M_G_ECC(7)
 192 M_G_ECC<4>  CB<5> @BASEBOARD_FAB2_LIB.BASEBOARD_FAB2(SCH_1):M_G_ECC(4)
  47 M_G_ECC<5>  CB<4> @BASEBOARD_FAB2_LIB.BASEBOARD_FAB2(SCH_1):M_G_ECC(5)
 201 M_G_ECC<2>  CB<3> @BASEBOARD_FAB2_LIB.BASEBOARD_FAB2(SCH_1):M_G_ECC(2)
  56 M_G_ECC<3>  CB<2> @BASEBOARD_FAB2_LIB.BASEBOARD_FAB2(SCH_1):M_G_ECC(3)
 194 M_G_ECC<0>  CB<1> @BASEBOARD_FAB2_LIB.BASEBOARD_FAB2(SCH_1):M_G_ECC(0)
  49 M_G_ECC<1>  CB<0> @BASEBOARD_FAB2_LIB.BASEBOARD_FAB2(SCH_1):M_G_ECC(1)
  75 M_G_CLK_DN<0>   CK0N @BASEBOARD_FAB2_LIB.BASEBOARD_FAB2(SCH_1):M_G_CLK_DN(0)
  74 M_G_CLK_DP<0>   CK0P @BASEBOARD_FAB2_LIB.BASEBOARD_FAB2(SCH_1):M_G_CLK_DP(0)
 219 M_G_CLK_DN<1>   CK1N @BASEBOARD_FAB2_LIB.BASEBOARD_FAB2(SCH_1):M_G_CLK_DN(1)
 218 M_G_CLK_DP<1>   CK1P @BASEBOARD_FAB2_LIB.BASEBOARD_FAB2(SCH_1):M_G_CLK_DP(1)
 203 M_G_CKE<1> CKE<1> @BASEBOARD_FAB2_LIB.BASEBOARD_FAB2(SCH_1):M_G_CKE(1)
  60 M_G_CKE<0> CKE<0> @BASEBOARD_FAB2_LIB.BASEBOARD_FAB2(SCH_1):M_G_CKE(0)
 280 M_G_DQ<62> DQ<63> @BASEBOARD_FAB2_LIB.BASEBOARD_FAB2(SCH_1):M_G_DQ(62)
 135 M_G_DQ<63> DQ<62> @BASEBOARD_FAB2_LIB.BASEBOARD_FAB2(SCH_1):M_G_DQ(63)
 273 M_G_DQ<60> DQ<61> @BASEBOARD_FAB2_LIB.BASEBOARD_FAB2(SCH_1):M_G_DQ(60)
 128 M_G_DQ<61> DQ<60> @BASEBOARD_FAB2_LIB.BASEBOARD_FAB2(SCH_1):M_G_DQ(61)
 282 M_G_DQ<58> DQ<59> @BASEBOARD_FAB2_LIB.BASEBOARD_FAB2(SCH_1):M_G_DQ(58)
 137 M_G_DQ<59> DQ<58> @BASEBOARD_FAB2_LIB.BASEBOARD_FAB2(SCH_1):M_G_DQ(59)
 275 M_G_DQ<56> DQ<57> @BASEBOARD_FAB2_LIB.BASEBOARD_FAB2(SCH_1):M_G_DQ(56)
 130 M_G_DQ<57> DQ<56> @BASEBOARD_FAB2_LIB.BASEBOARD_FAB2(SCH_1):M_G_DQ(57)
 269 M_G_DQ<54> DQ<55> @BASEBOARD_FAB2_LIB.BASEBOARD_FAB2(SCH_1):M_G_DQ(54)
 124 M_G_DQ<55> DQ<54> @BASEBOARD_FAB2_LIB.BASEBOARD_FAB2(SCH_1):M_G_DQ(55)
 262 M_G_DQ<52> DQ<53> @BASEBOARD_FAB2_LIB.BASEBOARD_FAB2(SCH_1):M_G_DQ(52)
 117 M_G_DQ<53> DQ<52> @BASEBOARD_FAB2_LIB.BASEBOARD_FAB2(SCH_1):M_G_DQ(53)
 271 M_G_DQ<50> DQ<51> @BASEBOARD_FAB2_LIB.BASEBOARD_FAB2(SCH_1):M_G_DQ(50)
 126 M_G_DQ<51> DQ<50> @BASEBOARD_FAB2_LIB.BASEBOARD_FAB2(SCH_1):M_G_DQ(51)
 264 M_G_DQ<48> DQ<49> @BASEBOARD_FAB2_LIB.BASEBOARD_FAB2(SCH_1):M_G_DQ(48)
 119 M_G_DQ<49> DQ<48> @BASEBOARD_FAB2_LIB.BASEBOARD_FAB2(SCH_1):M_G_DQ(49)
 258 M_G_DQ<46> DQ<47> @BASEBOARD_FAB2_LIB.BASEBOARD_FAB2(SCH_1):M_G_DQ(46)
 113 M_G_DQ<47> DQ<46> @BASEBOARD_FAB2_LIB.BASEBOARD_FAB2(SCH_1):M_G_DQ(47)
 251 M_G_DQ<44> DQ<45> @BASEBOARD_FAB2_LIB.BASEBOARD_FAB2(SCH_1):M_G_DQ(44)
 106 M_G_DQ<45> DQ<44> @BASEBOARD_FAB2_LIB.BASEBOARD_FAB2(SCH_1):M_G_DQ(45)
 260 M_G_DQ<42> DQ<43> @BASEBOARD_FAB2_LIB.BASEBOARD_FAB2(SCH_1):M_G_DQ(42)
 115 M_G_DQ<43> DQ<42> @BASEBOARD_FAB2_LIB.BASEBOARD_FAB2(SCH_1):M_G_DQ(43)
 253 M_G_DQ<40> DQ<41> @BASEBOARD_FAB2_LIB.BASEBOARD_FAB2(SCH_1):M_G_DQ(40)
 108 M_G_DQ<41> DQ<40> @BASEBOARD_FAB2_LIB.BASEBOARD_FAB2(SCH_1):M_G_DQ(41)
 247 M_G_DQ<38> DQ<39> @BASEBOARD_FAB2_LIB.BASEBOARD_FAB2(SCH_1):M_G_DQ(38)
 102 M_G_DQ<39> DQ<38> @BASEBOARD_FAB2_LIB.BASEBOARD_FAB2(SCH_1):M_G_DQ(39)
 240 M_G_DQ<36> DQ<37> @BASEBOARD_FAB2_LIB.BASEBOARD_FAB2(SCH_1):M_G_DQ(36)
  95 M_G_DQ<37> DQ<36> @BASEBOARD_FAB2_LIB.BASEBOARD_FAB2(SCH_1):M_G_DQ(37)
 249 M_G_DQ<34> DQ<35> @BASEBOARD_FAB2_LIB.BASEBOARD_FAB2(SCH_1):M_G_DQ(34)
 104 M_G_DQ<35> DQ<34> @BASEBOARD_FAB2_LIB.BASEBOARD_FAB2(SCH_1):M_G_DQ(35)
 242 M_G_DQ<32> DQ<33> @BASEBOARD_FAB2_LIB.BASEBOARD_FAB2(SCH_1):M_G_DQ(32)
  97 M_G_DQ<33> DQ<32> @BASEBOARD_FAB2_LIB.BASEBOARD_FAB2(SCH_1):M_G_DQ(33)
 188 M_G_DQ<30> DQ<31> @BASEBOARD_FAB2_LIB.BASEBOARD_FAB2(SCH_1):M_G_DQ(30)
  43 M_G_DQ<31> DQ<30> @BASEBOARD_FAB2_LIB.BASEBOARD_FAB2(SCH_1):M_G_DQ(31)
 181 M_G_DQ<28> DQ<29> @BASEBOARD_FAB2_LIB.BASEBOARD_FAB2(SCH_1):M_G_DQ(28)
  36 M_G_DQ<29> DQ<28> @BASEBOARD_FAB2_LIB.BASEBOARD_FAB2(SCH_1):M_G_DQ(29)
 190 M_G_DQ<26> DQ<27> @BASEBOARD_FAB2_LIB.BASEBOARD_FAB2(SCH_1):M_G_DQ(26)
  45 M_G_DQ<27> DQ<26> @BASEBOARD_FAB2_LIB.BASEBOARD_FAB2(SCH_1):M_G_DQ(27)
 183 M_G_DQ<24> DQ<25> @BASEBOARD_FAB2_LIB.BASEBOARD_FAB2(SCH_1):M_G_DQ(24)
  38 M_G_DQ<25> DQ<24> @BASEBOARD_FAB2_LIB.BASEBOARD_FAB2(SCH_1):M_G_DQ(25)
 177 M_G_DQ<22> DQ<23> @BASEBOARD_FAB2_LIB.BASEBOARD_FAB2(SCH_1):M_G_DQ(22)
  32 M_G_DQ<23> DQ<22> @BASEBOARD_FAB2_LIB.BASEBOARD_FAB2(SCH_1):M_G_DQ(23)
 170 M_G_DQ<20> DQ<21> @BASEBOARD_FAB2_LIB.BASEBOARD_FAB2(SCH_1):M_G_DQ(20)
  25 M_G_DQ<21> DQ<20> @BASEBOARD_FAB2_LIB.BASEBOARD_FAB2(SCH_1):M_G_DQ(21)
 179 M_G_DQ<18> DQ<19> @BASEBOARD_FAB2_LIB.BASEBOARD_FAB2(SCH_1):M_G_DQ(18)
  34 M_G_DQ<19> DQ<18> @BASEBOARD_FAB2_LIB.BASEBOARD_FAB2(SCH_1):M_G_DQ(19)
 172 M_G_DQ<16> DQ<17> @BASEBOARD_FAB2_LIB.BASEBOARD_FAB2(SCH_1):M_G_DQ(16)
  27 M_G_DQ<17> DQ<16> @BASEBOARD_FAB2_LIB.BASEBOARD_FAB2(SCH_1):M_G_DQ(17)
 166 M_G_DQ<14> DQ<15> @BASEBOARD_FAB2_LIB.BASEBOARD_FAB2(SCH_1):M_G_DQ(14)
  21 M_G_DQ<15> DQ<14> @BASEBOARD_FAB2_LIB.BASEBOARD_FAB2(SCH_1):M_G_DQ(15)
 159 M_G_DQ<12> DQ<13> @BASEBOARD_FAB2_LIB.BASEBOARD_FAB2(SCH_1):M_G_DQ(12)
  14 M_G_DQ<13> DQ<12> @BASEBOARD_FAB2_LIB.BASEBOARD_FAB2(SCH_1):M_G_DQ(13)
 168 M_G_DQ<10> DQ<11> @BASEBOARD_FAB2_LIB.BASEBOARD_FAB2(SCH_1):M_G_DQ(10)
  23 M_G_DQ<11> DQ<10> @BASEBOARD_FAB2_LIB.BASEBOARD_FAB2(SCH_1):M_G_DQ(11)
 161 M_G_DQ<8>  DQ<9> @BASEBOARD_FAB2_LIB.BASEBOARD_FAB2(SCH_1):M_G_DQ(8)
  16 M_G_DQ<9>  DQ<8> @BASEBOARD_FAB2_LIB.BASEBOARD_FAB2(SCH_1):M_G_DQ(9)
 155 M_G_DQ<6>  DQ<7> @BASEBOARD_FAB2_LIB.BASEBOARD_FAB2(SCH_1):M_G_DQ(6)
  10 M_G_DQ<7>  DQ<6> @BASEBOARD_FAB2_LIB.BASEBOARD_FAB2(SCH_1):M_G_DQ(7)
 148 M_G_DQ<4>  DQ<5> @BASEBOARD_FAB2_LIB.BASEBOARD_FAB2(SCH_1):M_G_DQ(4)
   3 M_G_DQ<5>  DQ<4> @BASEBOARD_FAB2_LIB.BASEBOARD_FAB2(SCH_1):M_G_DQ(5)
 157 M_G_DQ<2>  DQ<3> @BASEBOARD_FAB2_LIB.BASEBOARD_FAB2(SCH_1):M_G_DQ(2)
  12 M_G_DQ<3>  DQ<2> @BASEBOARD_FAB2_LIB.BASEBOARD_FAB2(SCH_1):M_G_DQ(3)
 150 M_G_DQ<0>  DQ<1> @BASEBOARD_FAB2_LIB.BASEBOARD_FAB2(SCH_1):M_G_DQ(0)
   5 M_G_DQ<1>  DQ<0> @BASEBOARD_FAB2_LIB.BASEBOARD_FAB2(SCH_1):M_G_DQ(1)
  78 FM_DIMM_EVENT_COD_N EVENT_N @BASEBOARD_FAB2_LIB.BASEBOARD_FAB2(SCH_1):FM_DIMM_EVENT_COD_N
  91 M_G_ODT<1> ODT<1> @BASEBOARD_FAB2_LIB.BASEBOARD_FAB2(SCH_1):M_G_ODT(1)
  87 M_G_ODT<0> ODT<0> @BASEBOARD_FAB2_LIB.BASEBOARD_FAB2(SCH_1):M_G_ODT(0)
 222 M_G_PAR    PAR @BASEBOARD_FAB2_LIB.BASEBOARD_FAB2(SCH_1):M_G_PAR
  58 M_GHJ_RST_N RESET_N @BASEBOARD_FAB2_LIB.BASEBOARD_FAB2(SCH_1):M_GHJ_RST_N
 144 TP_CH_G_DIMM_G0_RFU_2 RFU<2> @BASEBOARD_FAB2_LIB.BASEBOARD_FAB2(SCH_1):TP_CH_G_DIMM_G0_RFU_2
 227 TP_CH_G_DIMM_G0_RFU_1 RFU<1> @BASEBOARD_FAB2_LIB.BASEBOARD_FAB2(SCH_1):TP_CH_G_DIMM_G0_RFU_1
 205 TP_CH_G_DIMM_G0_RFU_0 RFU<0> @BASEBOARD_FAB2_LIB.BASEBOARD_FAB2(SCH_1):TP_CH_G_DIMM_G0_RFU_0
  84 M_G_CS_N<0>   S0_N @BASEBOARD_FAB2_LIB.BASEBOARD_FAB2(SCH_1):M_G_CS_N(0)
  89 M_G_CS_N<1>   S1_N @BASEBOARD_FAB2_LIB.BASEBOARD_FAB2(SCH_1):M_G_CS_N(1)
  93 M_G_CS_N<2> S2_N_C<0> @BASEBOARD_FAB2_LIB.BASEBOARD_FAB2(SCH_1):M_G_CS_N(2)
 237 M_G_CS_N<3> S3_N_C<1> @BASEBOARD_FAB2_LIB.BASEBOARD_FAB2(SCH_1):M_G_CS_N(3)
 238    GND  SA<2> @BASEBOARD_FAB2_LIB.BASEBOARD_FAB2(SCH_1):GND
 140    GND  SA<1> @BASEBOARD_FAB2_LIB.BASEBOARD_FAB2(SCH_1):GND
 139    GND  SA<0> @BASEBOARD_FAB2_LIB.BASEBOARD_FAB2(SCH_1):GND
 230 FM_ADR_COMPLETE_GHJ_N SAVE_N_NC @BASEBOARD_FAB2_LIB.BASEBOARD_FAB2(SCH_1):FM_ADR_COMPLETE_GHJ_N
 141 SMB_DDR_GHJ_VPP_SCL    SCL @BASEBOARD_FAB2_LIB.BASEBOARD_FAB2(SCH_1):SMB_DDR_GHJ_VPP_SCL
 285 SMB_DDR_GHJ_VPP_SDA    SDA @BASEBOARD_FAB2_LIB.BASEBOARD_FAB2(SCH_1):SMB_DDR_GHJ_VPP_SDA
 284 PVPP_GHJ VDDSPD @BASEBOARD_FAB2_LIB.BASEBOARD_FAB2(SCH_1):PVPP_GHJ
 146 M_G_VREF VREFCA @BASEBOARD_FAB2_LIB.BASEBOARD_FAB2(SCH_1):M_G_VREF

SCONN288_H44441004_PIP-SCONN,HA  I171  J1G1
   1 P12V_NVDIMM_GHJ 12V<1> @BASEBOARD_FAB2_LIB.BASEBOARD_FAB2(SCH_1):P12V_NVDIMM_GHJ
 145 P12V_NVDIMM_GHJ 12V<0> @BASEBOARD_FAB2_LIB.BASEBOARD_FAB2(SCH_1):P12V_NVDIMM_GHJ
  59 PVDDQ_GHJ VDD<25> @BASEBOARD_FAB2_LIB.BASEBOARD_FAB2(SCH_1):PVDDQ_GHJ
  61 PVDDQ_GHJ VDD<24> @BASEBOARD_FAB2_LIB.BASEBOARD_FAB2(SCH_1):PVDDQ_GHJ
  64 PVDDQ_GHJ VDD<23> @BASEBOARD_FAB2_LIB.BASEBOARD_FAB2(SCH_1):PVDDQ_GHJ
  67 PVDDQ_GHJ VDD<22> @BASEBOARD_FAB2_LIB.BASEBOARD_FAB2(SCH_1):PVDDQ_GHJ
  70 PVDDQ_GHJ VDD<21> @BASEBOARD_FAB2_LIB.BASEBOARD_FAB2(SCH_1):PVDDQ_GHJ
  73 PVDDQ_GHJ VDD<20> @BASEBOARD_FAB2_LIB.BASEBOARD_FAB2(SCH_1):PVDDQ_GHJ
  76 PVDDQ_GHJ VDD<19> @BASEBOARD_FAB2_LIB.BASEBOARD_FAB2(SCH_1):PVDDQ_GHJ
  80 PVDDQ_GHJ VDD<18> @BASEBOARD_FAB2_LIB.BASEBOARD_FAB2(SCH_1):PVDDQ_GHJ
  83 PVDDQ_GHJ VDD<17> @BASEBOARD_FAB2_LIB.BASEBOARD_FAB2(SCH_1):PVDDQ_GHJ
  85 PVDDQ_GHJ VDD<16> @BASEBOARD_FAB2_LIB.BASEBOARD_FAB2(SCH_1):PVDDQ_GHJ
  88 PVDDQ_GHJ VDD<15> @BASEBOARD_FAB2_LIB.BASEBOARD_FAB2(SCH_1):PVDDQ_GHJ
  90 PVDDQ_GHJ VDD<14> @BASEBOARD_FAB2_LIB.BASEBOARD_FAB2(SCH_1):PVDDQ_GHJ
  92 PVDDQ_GHJ VDD<13> @BASEBOARD_FAB2_LIB.BASEBOARD_FAB2(SCH_1):PVDDQ_GHJ
 204 PVDDQ_GHJ VDD<12> @BASEBOARD_FAB2_LIB.BASEBOARD_FAB2(SCH_1):PVDDQ_GHJ
 206 PVDDQ_GHJ VDD<11> @BASEBOARD_FAB2_LIB.BASEBOARD_FAB2(SCH_1):PVDDQ_GHJ
 209 PVDDQ_GHJ VDD<10> @BASEBOARD_FAB2_LIB.BASEBOARD_FAB2(SCH_1):PVDDQ_GHJ
 212 PVDDQ_GHJ VDD<9> @BASEBOARD_FAB2_LIB.BASEBOARD_FAB2(SCH_1):PVDDQ_GHJ
 215 PVDDQ_GHJ VDD<8> @BASEBOARD_FAB2_LIB.BASEBOARD_FAB2(SCH_1):PVDDQ_GHJ
 217 PVDDQ_GHJ VDD<7> @BASEBOARD_FAB2_LIB.BASEBOARD_FAB2(SCH_1):PVDDQ_GHJ
 220 PVDDQ_GHJ VDD<6> @BASEBOARD_FAB2_LIB.BASEBOARD_FAB2(SCH_1):PVDDQ_GHJ
 223 PVDDQ_GHJ VDD<5> @BASEBOARD_FAB2_LIB.BASEBOARD_FAB2(SCH_1):PVDDQ_GHJ
 226 PVDDQ_GHJ VDD<4> @BASEBOARD_FAB2_LIB.BASEBOARD_FAB2(SCH_1):PVDDQ_GHJ
 229 PVDDQ_GHJ VDD<3> @BASEBOARD_FAB2_LIB.BASEBOARD_FAB2(SCH_1):PVDDQ_GHJ
 231 PVDDQ_GHJ VDD<2> @BASEBOARD_FAB2_LIB.BASEBOARD_FAB2(SCH_1):PVDDQ_GHJ
 233 PVDDQ_GHJ VDD<1> @BASEBOARD_FAB2_LIB.BASEBOARD_FAB2(SCH_1):PVDDQ_GHJ
 236 PVDDQ_GHJ VDD<0> @BASEBOARD_FAB2_LIB.BASEBOARD_FAB2(SCH_1):PVDDQ_GHJ
 142 PVPP_GHJ VPP<4> @BASEBOARD_FAB2_LIB.BASEBOARD_FAB2(SCH_1):PVPP_GHJ
 143 PVPP_GHJ VPP<3> @BASEBOARD_FAB2_LIB.BASEBOARD_FAB2(SCH_1):PVPP_GHJ
 288 PVPP_GHJ VPP<2> @BASEBOARD_FAB2_LIB.BASEBOARD_FAB2(SCH_1):PVPP_GHJ
 286 PVPP_GHJ VPP<1> @BASEBOARD_FAB2_LIB.BASEBOARD_FAB2(SCH_1):PVPP_GHJ
 287 PVPP_GHJ VPP<0> @BASEBOARD_FAB2_LIB.BASEBOARD_FAB2(SCH_1):PVPP_GHJ
  77 PVTT_GHJ VTT<1> @BASEBOARD_FAB2_LIB.BASEBOARD_FAB2(SCH_1):PVTT_GHJ
 221 PVTT_GHJ VTT<0> @BASEBOARD_FAB2_LIB.BASEBOARD_FAB2(SCH_1):PVTT_GHJ

CAP_A_0402V-0.01UF,25V,10%,X7RA  I181  C1F22
   1 M_G_VREF      A @BASEBOARD_FAB2_LIB.BASEBOARD_FAB2(SCH_1):M_G_VREF
   2    GND      B @BASEBOARD_FAB2_LIB.BASEBOARD_FAB2(SCH_1):GND


DRAWING: @BASEBOARD_FAB2_LIB.BASEBOARD_FAB2(SCH_1):PAGE78 

CAP_A_0402V-0.01UF,25V,10%,X7RA  I2  C9T7
   1 M_G_VREF      A @BASEBOARD_FAB2_LIB.BASEBOARD_FAB2(SCH_1):M_G_VREF
   2    GND      B @BASEBOARD_FAB2_LIB.BASEBOARD_FAB2(SCH_1):GND

SCONN288_H44441003_PIP-SCONN,HA  I13  J9T1
  79 M_G_MA<0>     A0 @BASEBOARD_FAB2_LIB.BASEBOARD_FAB2(SCH_1):M_G_MA(0)
  72 M_G_MA<1>     A1 @BASEBOARD_FAB2_LIB.BASEBOARD_FAB2(SCH_1):M_G_MA(1)
 225 M_G_MA<10>    A10 @BASEBOARD_FAB2_LIB.BASEBOARD_FAB2(SCH_1):M_G_MA(10)
 210 M_G_MA<11>    A11 @BASEBOARD_FAB2_LIB.BASEBOARD_FAB2(SCH_1):M_G_MA(11)
  65 M_G_MA<12>    A12 @BASEBOARD_FAB2_LIB.BASEBOARD_FAB2(SCH_1):M_G_MA(12)
 232 M_G_MA<13>    A13 @BASEBOARD_FAB2_LIB.BASEBOARD_FAB2(SCH_1):M_G_MA(13)
 228 M_G_MA<14> A14_WE_N @BASEBOARD_FAB2_LIB.BASEBOARD_FAB2(SCH_1):M_G_MA(14)
  86 M_G_MA<15> A15_CAS_N @BASEBOARD_FAB2_LIB.BASEBOARD_FAB2(SCH_1):M_G_MA(15)
  82 M_G_MA<16> A16_RAS_N @BASEBOARD_FAB2_LIB.BASEBOARD_FAB2(SCH_1):M_G_MA(16)
 234 M_G_MA<17>    A17 @BASEBOARD_FAB2_LIB.BASEBOARD_FAB2(SCH_1):M_G_MA(17)
 216 M_G_MA<2>     A2 @BASEBOARD_FAB2_LIB.BASEBOARD_FAB2(SCH_1):M_G_MA(2)
  71 M_G_MA<3>     A3 @BASEBOARD_FAB2_LIB.BASEBOARD_FAB2(SCH_1):M_G_MA(3)
 214 M_G_MA<4>     A4 @BASEBOARD_FAB2_LIB.BASEBOARD_FAB2(SCH_1):M_G_MA(4)
 213 M_G_MA<5>     A5 @BASEBOARD_FAB2_LIB.BASEBOARD_FAB2(SCH_1):M_G_MA(5)
  69 M_G_MA<6>     A6 @BASEBOARD_FAB2_LIB.BASEBOARD_FAB2(SCH_1):M_G_MA(6)
 211 M_G_MA<7>     A7 @BASEBOARD_FAB2_LIB.BASEBOARD_FAB2(SCH_1):M_G_MA(7)
  68 M_G_MA<8>     A8 @BASEBOARD_FAB2_LIB.BASEBOARD_FAB2(SCH_1):M_G_MA(8)
  66 M_G_MA<9>     A9 @BASEBOARD_FAB2_LIB.BASEBOARD_FAB2(SCH_1):M_G_MA(9)
  62 M_G_ACT_N  ACT_N @BASEBOARD_FAB2_LIB.BASEBOARD_FAB2(SCH_1):M_G_ACT_N
 208 M_G_ALERT_N ALERT_N @BASEBOARD_FAB2_LIB.BASEBOARD_FAB2(SCH_1):M_G_ALERT_N
 224 M_G_BA<1>  BA<1> @BASEBOARD_FAB2_LIB.BASEBOARD_FAB2(SCH_1):M_G_BA(1)
  81 M_G_BA<0>  BA<0> @BASEBOARD_FAB2_LIB.BASEBOARD_FAB2(SCH_1):M_G_BA(0)
 207 M_G_BG<1>  BG<1> @BASEBOARD_FAB2_LIB.BASEBOARD_FAB2(SCH_1):M_G_BG(1)
  63 M_G_BG<0>  BG<0> @BASEBOARD_FAB2_LIB.BASEBOARD_FAB2(SCH_1):M_G_BG(0)
 235 M_G_C<2>   C<2> @BASEBOARD_FAB2_LIB.BASEBOARD_FAB2(SCH_1):M_G_C(2)
 199 M_G_ECC<7>  CB<7> @BASEBOARD_FAB2_LIB.BASEBOARD_FAB2(SCH_1):M_G_ECC(7)
  54 M_G_ECC<6>  CB<6> @BASEBOARD_FAB2_LIB.BASEBOARD_FAB2(SCH_1):M_G_ECC(6)
 192 M_G_ECC<5>  CB<5> @BASEBOARD_FAB2_LIB.BASEBOARD_FAB2(SCH_1):M_G_ECC(5)
  47 M_G_ECC<4>  CB<4> @BASEBOARD_FAB2_LIB.BASEBOARD_FAB2(SCH_1):M_G_ECC(4)
 201 M_G_ECC<3>  CB<3> @BASEBOARD_FAB2_LIB.BASEBOARD_FAB2(SCH_1):M_G_ECC(3)
  56 M_G_ECC<2>  CB<2> @BASEBOARD_FAB2_LIB.BASEBOARD_FAB2(SCH_1):M_G_ECC(2)
 194 M_G_ECC<1>  CB<1> @BASEBOARD_FAB2_LIB.BASEBOARD_FAB2(SCH_1):M_G_ECC(1)
  49 M_G_ECC<0>  CB<0> @BASEBOARD_FAB2_LIB.BASEBOARD_FAB2(SCH_1):M_G_ECC(0)
  75 M_G_CLK_DN<2>   CK0N @BASEBOARD_FAB2_LIB.BASEBOARD_FAB2(SCH_1):M_G_CLK_DN(2)
  74 M_G_CLK_DP<2>   CK0P @BASEBOARD_FAB2_LIB.BASEBOARD_FAB2(SCH_1):M_G_CLK_DP(2)
 219 M_G_CLK_DN<3>   CK1N @BASEBOARD_FAB2_LIB.BASEBOARD_FAB2(SCH_1):M_G_CLK_DN(3)
 218 M_G_CLK_DP<3>   CK1P @BASEBOARD_FAB2_LIB.BASEBOARD_FAB2(SCH_1):M_G_CLK_DP(3)
 203 M_G_CKE<3> CKE<1> @BASEBOARD_FAB2_LIB.BASEBOARD_FAB2(SCH_1):M_G_CKE(3)
  60 M_G_CKE<2> CKE<0> @BASEBOARD_FAB2_LIB.BASEBOARD_FAB2(SCH_1):M_G_CKE(2)
 280 M_G_DQ<63> DQ<63> @BASEBOARD_FAB2_LIB.BASEBOARD_FAB2(SCH_1):M_G_DQ(63)
 135 M_G_DQ<62> DQ<62> @BASEBOARD_FAB2_LIB.BASEBOARD_FAB2(SCH_1):M_G_DQ(62)
 273 M_G_DQ<61> DQ<61> @BASEBOARD_FAB2_LIB.BASEBOARD_FAB2(SCH_1):M_G_DQ(61)
 128 M_G_DQ<60> DQ<60> @BASEBOARD_FAB2_LIB.BASEBOARD_FAB2(SCH_1):M_G_DQ(60)
 282 M_G_DQ<59> DQ<59> @BASEBOARD_FAB2_LIB.BASEBOARD_FAB2(SCH_1):M_G_DQ(59)
 137 M_G_DQ<58> DQ<58> @BASEBOARD_FAB2_LIB.BASEBOARD_FAB2(SCH_1):M_G_DQ(58)
 275 M_G_DQ<57> DQ<57> @BASEBOARD_FAB2_LIB.BASEBOARD_FAB2(SCH_1):M_G_DQ(57)
 130 M_G_DQ<56> DQ<56> @BASEBOARD_FAB2_LIB.BASEBOARD_FAB2(SCH_1):M_G_DQ(56)
 269 M_G_DQ<55> DQ<55> @BASEBOARD_FAB2_LIB.BASEBOARD_FAB2(SCH_1):M_G_DQ(55)
 124 M_G_DQ<54> DQ<54> @BASEBOARD_FAB2_LIB.BASEBOARD_FAB2(SCH_1):M_G_DQ(54)
 262 M_G_DQ<53> DQ<53> @BASEBOARD_FAB2_LIB.BASEBOARD_FAB2(SCH_1):M_G_DQ(53)
 117 M_G_DQ<52> DQ<52> @BASEBOARD_FAB2_LIB.BASEBOARD_FAB2(SCH_1):M_G_DQ(52)
 271 M_G_DQ<51> DQ<51> @BASEBOARD_FAB2_LIB.BASEBOARD_FAB2(SCH_1):M_G_DQ(51)
 126 M_G_DQ<50> DQ<50> @BASEBOARD_FAB2_LIB.BASEBOARD_FAB2(SCH_1):M_G_DQ(50)
 264 M_G_DQ<49> DQ<49> @BASEBOARD_FAB2_LIB.BASEBOARD_FAB2(SCH_1):M_G_DQ(49)
 119 M_G_DQ<48> DQ<48> @BASEBOARD_FAB2_LIB.BASEBOARD_FAB2(SCH_1):M_G_DQ(48)
 258 M_G_DQ<47> DQ<47> @BASEBOARD_FAB2_LIB.BASEBOARD_FAB2(SCH_1):M_G_DQ(47)
 113 M_G_DQ<46> DQ<46> @BASEBOARD_FAB2_LIB.BASEBOARD_FAB2(SCH_1):M_G_DQ(46)
 251 M_G_DQ<45> DQ<45> @BASEBOARD_FAB2_LIB.BASEBOARD_FAB2(SCH_1):M_G_DQ(45)
 106 M_G_DQ<44> DQ<44> @BASEBOARD_FAB2_LIB.BASEBOARD_FAB2(SCH_1):M_G_DQ(44)
 260 M_G_DQ<43> DQ<43> @BASEBOARD_FAB2_LIB.BASEBOARD_FAB2(SCH_1):M_G_DQ(43)
 115 M_G_DQ<42> DQ<42> @BASEBOARD_FAB2_LIB.BASEBOARD_FAB2(SCH_1):M_G_DQ(42)
 253 M_G_DQ<41> DQ<41> @BASEBOARD_FAB2_LIB.BASEBOARD_FAB2(SCH_1):M_G_DQ(41)
 108 M_G_DQ<40> DQ<40> @BASEBOARD_FAB2_LIB.BASEBOARD_FAB2(SCH_1):M_G_DQ(40)
 247 M_G_DQ<39> DQ<39> @BASEBOARD_FAB2_LIB.BASEBOARD_FAB2(SCH_1):M_G_DQ(39)
 102 M_G_DQ<38> DQ<38> @BASEBOARD_FAB2_LIB.BASEBOARD_FAB2(SCH_1):M_G_DQ(38)
 240 M_G_DQ<37> DQ<37> @BASEBOARD_FAB2_LIB.BASEBOARD_FAB2(SCH_1):M_G_DQ(37)
  95 M_G_DQ<36> DQ<36> @BASEBOARD_FAB2_LIB.BASEBOARD_FAB2(SCH_1):M_G_DQ(36)
 249 M_G_DQ<35> DQ<35> @BASEBOARD_FAB2_LIB.BASEBOARD_FAB2(SCH_1):M_G_DQ(35)
 104 M_G_DQ<34> DQ<34> @BASEBOARD_FAB2_LIB.BASEBOARD_FAB2(SCH_1):M_G_DQ(34)
 242 M_G_DQ<33> DQ<33> @BASEBOARD_FAB2_LIB.BASEBOARD_FAB2(SCH_1):M_G_DQ(33)
  97 M_G_DQ<32> DQ<32> @BASEBOARD_FAB2_LIB.BASEBOARD_FAB2(SCH_1):M_G_DQ(32)
 188 M_G_DQ<31> DQ<31> @BASEBOARD_FAB2_LIB.BASEBOARD_FAB2(SCH_1):M_G_DQ(31)
  43 M_G_DQ<30> DQ<30> @BASEBOARD_FAB2_LIB.BASEBOARD_FAB2(SCH_1):M_G_DQ(30)
 181 M_G_DQ<29> DQ<29> @BASEBOARD_FAB2_LIB.BASEBOARD_FAB2(SCH_1):M_G_DQ(29)
  36 M_G_DQ<28> DQ<28> @BASEBOARD_FAB2_LIB.BASEBOARD_FAB2(SCH_1):M_G_DQ(28)
 190 M_G_DQ<27> DQ<27> @BASEBOARD_FAB2_LIB.BASEBOARD_FAB2(SCH_1):M_G_DQ(27)
  45 M_G_DQ<26> DQ<26> @BASEBOARD_FAB2_LIB.BASEBOARD_FAB2(SCH_1):M_G_DQ(26)
 183 M_G_DQ<25> DQ<25> @BASEBOARD_FAB2_LIB.BASEBOARD_FAB2(SCH_1):M_G_DQ(25)
  38 M_G_DQ<24> DQ<24> @BASEBOARD_FAB2_LIB.BASEBOARD_FAB2(SCH_1):M_G_DQ(24)
 177 M_G_DQ<23> DQ<23> @BASEBOARD_FAB2_LIB.BASEBOARD_FAB2(SCH_1):M_G_DQ(23)
  32 M_G_DQ<22> DQ<22> @BASEBOARD_FAB2_LIB.BASEBOARD_FAB2(SCH_1):M_G_DQ(22)
 170 M_G_DQ<21> DQ<21> @BASEBOARD_FAB2_LIB.BASEBOARD_FAB2(SCH_1):M_G_DQ(21)
  25 M_G_DQ<20> DQ<20> @BASEBOARD_FAB2_LIB.BASEBOARD_FAB2(SCH_1):M_G_DQ(20)
 179 M_G_DQ<19> DQ<19> @BASEBOARD_FAB2_LIB.BASEBOARD_FAB2(SCH_1):M_G_DQ(19)
  34 M_G_DQ<18> DQ<18> @BASEBOARD_FAB2_LIB.BASEBOARD_FAB2(SCH_1):M_G_DQ(18)
 172 M_G_DQ<17> DQ<17> @BASEBOARD_FAB2_LIB.BASEBOARD_FAB2(SCH_1):M_G_DQ(17)
  27 M_G_DQ<16> DQ<16> @BASEBOARD_FAB2_LIB.BASEBOARD_FAB2(SCH_1):M_G_DQ(16)
 166 M_G_DQ<15> DQ<15> @BASEBOARD_FAB2_LIB.BASEBOARD_FAB2(SCH_1):M_G_DQ(15)
  21 M_G_DQ<14> DQ<14> @BASEBOARD_FAB2_LIB.BASEBOARD_FAB2(SCH_1):M_G_DQ(14)
 159 M_G_DQ<13> DQ<13> @BASEBOARD_FAB2_LIB.BASEBOARD_FAB2(SCH_1):M_G_DQ(13)
  14 M_G_DQ<12> DQ<12> @BASEBOARD_FAB2_LIB.BASEBOARD_FAB2(SCH_1):M_G_DQ(12)
 168 M_G_DQ<11> DQ<11> @BASEBOARD_FAB2_LIB.BASEBOARD_FAB2(SCH_1):M_G_DQ(11)
  23 M_G_DQ<10> DQ<10> @BASEBOARD_FAB2_LIB.BASEBOARD_FAB2(SCH_1):M_G_DQ(10)
 161 M_G_DQ<9>  DQ<9> @BASEBOARD_FAB2_LIB.BASEBOARD_FAB2(SCH_1):M_G_DQ(9)
  16 M_G_DQ<8>  DQ<8> @BASEBOARD_FAB2_LIB.BASEBOARD_FAB2(SCH_1):M_G_DQ(8)
 155 M_G_DQ<7>  DQ<7> @BASEBOARD_FAB2_LIB.BASEBOARD_FAB2(SCH_1):M_G_DQ(7)
  10 M_G_DQ<6>  DQ<6> @BASEBOARD_FAB2_LIB.BASEBOARD_FAB2(SCH_1):M_G_DQ(6)
 148 M_G_DQ<5>  DQ<5> @BASEBOARD_FAB2_LIB.BASEBOARD_FAB2(SCH_1):M_G_DQ(5)
   3 M_G_DQ<4>  DQ<4> @BASEBOARD_FAB2_LIB.BASEBOARD_FAB2(SCH_1):M_G_DQ(4)
 157 M_G_DQ<3>  DQ<3> @BASEBOARD_FAB2_LIB.BASEBOARD_FAB2(SCH_1):M_G_DQ(3)
  12 M_G_DQ<2>  DQ<2> @BASEBOARD_FAB2_LIB.BASEBOARD_FAB2(SCH_1):M_G_DQ(2)
 150 M_G_DQ<1>  DQ<1> @BASEBOARD_FAB2_LIB.BASEBOARD_FAB2(SCH_1):M_G_DQ(1)
   5 M_G_DQ<0>  DQ<0> @BASEBOARD_FAB2_LIB.BASEBOARD_FAB2(SCH_1):M_G_DQ(0)
  78 FM_DIMM_EVENT_COD_N EVENT_N @BASEBOARD_FAB2_LIB.BASEBOARD_FAB2(SCH_1):FM_DIMM_EVENT_COD_N
  91 M_G_ODT<3> ODT<1> @BASEBOARD_FAB2_LIB.BASEBOARD_FAB2(SCH_1):M_G_ODT(3)
  87 M_G_ODT<2> ODT<0> @BASEBOARD_FAB2_LIB.BASEBOARD_FAB2(SCH_1):M_G_ODT(2)
 222 M_G_PAR    PAR @BASEBOARD_FAB2_LIB.BASEBOARD_FAB2(SCH_1):M_G_PAR
  58 M_GHJ_RST_N RESET_N @BASEBOARD_FAB2_LIB.BASEBOARD_FAB2(SCH_1):M_GHJ_RST_N
 144 TP_CH_G_DIMM0_RFU_2 RFU<2> @BASEBOARD_FAB2_LIB.BASEBOARD_FAB2(SCH_1):TP_CH_G_DIMM0_RFU_2
 227 TP_CH_G_DIMM0_RFU_1 RFU<1> @BASEBOARD_FAB2_LIB.BASEBOARD_FAB2(SCH_1):TP_CH_G_DIMM0_RFU_1
 205 TP_CH_G_DIMM0_RFU_0 RFU<0> @BASEBOARD_FAB2_LIB.BASEBOARD_FAB2(SCH_1):TP_CH_G_DIMM0_RFU_0
  84 M_G_CS_N<4>   S0_N @BASEBOARD_FAB2_LIB.BASEBOARD_FAB2(SCH_1):M_G_CS_N(4)
  89 M_G_CS_N<5>   S1_N @BASEBOARD_FAB2_LIB.BASEBOARD_FAB2(SCH_1):M_G_CS_N(5)
  93 M_G_CS_N<6> S2_N_C<0> @BASEBOARD_FAB2_LIB.BASEBOARD_FAB2(SCH_1):M_G_CS_N(6)
 237 M_G_CS_N<7> S3_N_C<1> @BASEBOARD_FAB2_LIB.BASEBOARD_FAB2(SCH_1):M_G_CS_N(7)
 238    GND  SA<2> @BASEBOARD_FAB2_LIB.BASEBOARD_FAB2(SCH_1):GND
 140    GND  SA<1> @BASEBOARD_FAB2_LIB.BASEBOARD_FAB2(SCH_1):GND
 139 PVPP_GHJ  SA<0> @BASEBOARD_FAB2_LIB.BASEBOARD_FAB2(SCH_1):PVPP_GHJ
 230 FM_ADR_COMPLETE_GHJ_N SAVE_N_NC @BASEBOARD_FAB2_LIB.BASEBOARD_FAB2(SCH_1):FM_ADR_COMPLETE_GHJ_N
 141 SMB_DDR_GHJ_VPP_SCL    SCL @BASEBOARD_FAB2_LIB.BASEBOARD_FAB2(SCH_1):SMB_DDR_GHJ_VPP_SCL
 285 SMB_DDR_GHJ_VPP_SDA    SDA @BASEBOARD_FAB2_LIB.BASEBOARD_FAB2(SCH_1):SMB_DDR_GHJ_VPP_SDA
 284 PVPP_GHJ VDDSPD @BASEBOARD_FAB2_LIB.BASEBOARD_FAB2(SCH_1):PVPP_GHJ
 146 M_G_VREF VREFCA @BASEBOARD_FAB2_LIB.BASEBOARD_FAB2(SCH_1):M_G_VREF

SCONN288_H44441003_PIP-SCONN,HA  I75  J9T1
   1 P12V_NVDIMM_GHJ 12V<1> @BASEBOARD_FAB2_LIB.BASEBOARD_FAB2(SCH_1):P12V_NVDIMM_GHJ
 145 P12V_NVDIMM_GHJ 12V<0> @BASEBOARD_FAB2_LIB.BASEBOARD_FAB2(SCH_1):P12V_NVDIMM_GHJ
  59 PVDDQ_GHJ VDD<25> @BASEBOARD_FAB2_LIB.BASEBOARD_FAB2(SCH_1):PVDDQ_GHJ
  61 PVDDQ_GHJ VDD<24> @BASEBOARD_FAB2_LIB.BASEBOARD_FAB2(SCH_1):PVDDQ_GHJ
  64 PVDDQ_GHJ VDD<23> @BASEBOARD_FAB2_LIB.BASEBOARD_FAB2(SCH_1):PVDDQ_GHJ
  67 PVDDQ_GHJ VDD<22> @BASEBOARD_FAB2_LIB.BASEBOARD_FAB2(SCH_1):PVDDQ_GHJ
  70 PVDDQ_GHJ VDD<21> @BASEBOARD_FAB2_LIB.BASEBOARD_FAB2(SCH_1):PVDDQ_GHJ
  73 PVDDQ_GHJ VDD<20> @BASEBOARD_FAB2_LIB.BASEBOARD_FAB2(SCH_1):PVDDQ_GHJ
  76 PVDDQ_GHJ VDD<19> @BASEBOARD_FAB2_LIB.BASEBOARD_FAB2(SCH_1):PVDDQ_GHJ
  80 PVDDQ_GHJ VDD<18> @BASEBOARD_FAB2_LIB.BASEBOARD_FAB2(SCH_1):PVDDQ_GHJ
  83 PVDDQ_GHJ VDD<17> @BASEBOARD_FAB2_LIB.BASEBOARD_FAB2(SCH_1):PVDDQ_GHJ
  85 PVDDQ_GHJ VDD<16> @BASEBOARD_FAB2_LIB.BASEBOARD_FAB2(SCH_1):PVDDQ_GHJ
  88 PVDDQ_GHJ VDD<15> @BASEBOARD_FAB2_LIB.BASEBOARD_FAB2(SCH_1):PVDDQ_GHJ
  90 PVDDQ_GHJ VDD<14> @BASEBOARD_FAB2_LIB.BASEBOARD_FAB2(SCH_1):PVDDQ_GHJ
  92 PVDDQ_GHJ VDD<13> @BASEBOARD_FAB2_LIB.BASEBOARD_FAB2(SCH_1):PVDDQ_GHJ
 204 PVDDQ_GHJ VDD<12> @BASEBOARD_FAB2_LIB.BASEBOARD_FAB2(SCH_1):PVDDQ_GHJ
 206 PVDDQ_GHJ VDD<11> @BASEBOARD_FAB2_LIB.BASEBOARD_FAB2(SCH_1):PVDDQ_GHJ
 209 PVDDQ_GHJ VDD<10> @BASEBOARD_FAB2_LIB.BASEBOARD_FAB2(SCH_1):PVDDQ_GHJ
 212 PVDDQ_GHJ VDD<9> @BASEBOARD_FAB2_LIB.BASEBOARD_FAB2(SCH_1):PVDDQ_GHJ
 215 PVDDQ_GHJ VDD<8> @BASEBOARD_FAB2_LIB.BASEBOARD_FAB2(SCH_1):PVDDQ_GHJ
 217 PVDDQ_GHJ VDD<7> @BASEBOARD_FAB2_LIB.BASEBOARD_FAB2(SCH_1):PVDDQ_GHJ
 220 PVDDQ_GHJ VDD<6> @BASEBOARD_FAB2_LIB.BASEBOARD_FAB2(SCH_1):PVDDQ_GHJ
 223 PVDDQ_GHJ VDD<5> @BASEBOARD_FAB2_LIB.BASEBOARD_FAB2(SCH_1):PVDDQ_GHJ
 226 PVDDQ_GHJ VDD<4> @BASEBOARD_FAB2_LIB.BASEBOARD_FAB2(SCH_1):PVDDQ_GHJ
 229 PVDDQ_GHJ VDD<3> @BASEBOARD_FAB2_LIB.BASEBOARD_FAB2(SCH_1):PVDDQ_GHJ
 231 PVDDQ_GHJ VDD<2> @BASEBOARD_FAB2_LIB.BASEBOARD_FAB2(SCH_1):PVDDQ_GHJ
 233 PVDDQ_GHJ VDD<1> @BASEBOARD_FAB2_LIB.BASEBOARD_FAB2(SCH_1):PVDDQ_GHJ
 236 PVDDQ_GHJ VDD<0> @BASEBOARD_FAB2_LIB.BASEBOARD_FAB2(SCH_1):PVDDQ_GHJ
 142 PVPP_GHJ VPP<4> @BASEBOARD_FAB2_LIB.BASEBOARD_FAB2(SCH_1):PVPP_GHJ
 143 PVPP_GHJ VPP<3> @BASEBOARD_FAB2_LIB.BASEBOARD_FAB2(SCH_1):PVPP_GHJ
 288 PVPP_GHJ VPP<2> @BASEBOARD_FAB2_LIB.BASEBOARD_FAB2(SCH_1):PVPP_GHJ
 286 PVPP_GHJ VPP<1> @BASEBOARD_FAB2_LIB.BASEBOARD_FAB2(SCH_1):PVPP_GHJ
 287 PVPP_GHJ VPP<0> @BASEBOARD_FAB2_LIB.BASEBOARD_FAB2(SCH_1):PVPP_GHJ
  77 PVTT_GHJ VTT<1> @BASEBOARD_FAB2_LIB.BASEBOARD_FAB2(SCH_1):PVTT_GHJ
 221 PVTT_GHJ VTT<0> @BASEBOARD_FAB2_LIB.BASEBOARD_FAB2(SCH_1):PVTT_GHJ

SCONN288_H44441003_PIP-SCONN,HA  I120  J9T1
 152 M_G_DQS_DN<0>  DQS0N @BASEBOARD_FAB2_LIB.BASEBOARD_FAB2(SCH_1):M_G_DQS_DN(0)
 153 M_G_DQS_DP<0>  DQS0P @BASEBOARD_FAB2_LIB.BASEBOARD_FAB2(SCH_1):M_G_DQS_DP(0)
  19 M_G_DQS_DN<10> DQS10N @BASEBOARD_FAB2_LIB.BASEBOARD_FAB2(SCH_1):M_G_DQS_DN(10)
  18 M_G_DQS_DP<10> DQS10P @BASEBOARD_FAB2_LIB.BASEBOARD_FAB2(SCH_1):M_G_DQS_DP(10)
  30 M_G_DQS_DN<11> DQS11N @BASEBOARD_FAB2_LIB.BASEBOARD_FAB2(SCH_1):M_G_DQS_DN(11)
  29 M_G_DQS_DP<11> DQS11P @BASEBOARD_FAB2_LIB.BASEBOARD_FAB2(SCH_1):M_G_DQS_DP(11)
  41 M_G_DQS_DN<12> DQS12N @BASEBOARD_FAB2_LIB.BASEBOARD_FAB2(SCH_1):M_G_DQS_DN(12)
  40 M_G_DQS_DP<12> DQS12P @BASEBOARD_FAB2_LIB.BASEBOARD_FAB2(SCH_1):M_G_DQS_DP(12)
 100 M_G_DQS_DN<13> DQS13N @BASEBOARD_FAB2_LIB.BASEBOARD_FAB2(SCH_1):M_G_DQS_DN(13)
  99 M_G_DQS_DP<13> DQS13P @BASEBOARD_FAB2_LIB.BASEBOARD_FAB2(SCH_1):M_G_DQS_DP(13)
 111 M_G_DQS_DN<14> DQS14N @BASEBOARD_FAB2_LIB.BASEBOARD_FAB2(SCH_1):M_G_DQS_DN(14)
 110 M_G_DQS_DP<14> DQS14P @BASEBOARD_FAB2_LIB.BASEBOARD_FAB2(SCH_1):M_G_DQS_DP(14)
 122 M_G_DQS_DN<15> DQS15N @BASEBOARD_FAB2_LIB.BASEBOARD_FAB2(SCH_1):M_G_DQS_DN(15)
 121 M_G_DQS_DP<15> DQS15P @BASEBOARD_FAB2_LIB.BASEBOARD_FAB2(SCH_1):M_G_DQS_DP(15)
 133 M_G_DQS_DN<16> DQS16N @BASEBOARD_FAB2_LIB.BASEBOARD_FAB2(SCH_1):M_G_DQS_DN(16)
 132 M_G_DQS_DP<16> DQS16P @BASEBOARD_FAB2_LIB.BASEBOARD_FAB2(SCH_1):M_G_DQS_DP(16)
  52 M_G_DQS_DN<17> DQS17N @BASEBOARD_FAB2_LIB.BASEBOARD_FAB2(SCH_1):M_G_DQS_DN(17)
  51 M_G_DQS_DP<17> DQS17P @BASEBOARD_FAB2_LIB.BASEBOARD_FAB2(SCH_1):M_G_DQS_DP(17)
 163 M_G_DQS_DN<1>  DQS1N @BASEBOARD_FAB2_LIB.BASEBOARD_FAB2(SCH_1):M_G_DQS_DN(1)
 164 M_G_DQS_DP<1>  DQS1P @BASEBOARD_FAB2_LIB.BASEBOARD_FAB2(SCH_1):M_G_DQS_DP(1)
 174 M_G_DQS_DN<2>  DQS2N @BASEBOARD_FAB2_LIB.BASEBOARD_FAB2(SCH_1):M_G_DQS_DN(2)
 175 M_G_DQS_DP<2>  DQS2P @BASEBOARD_FAB2_LIB.BASEBOARD_FAB2(SCH_1):M_G_DQS_DP(2)
 185 M_G_DQS_DN<3>  DQS3N @BASEBOARD_FAB2_LIB.BASEBOARD_FAB2(SCH_1):M_G_DQS_DN(3)
 186 M_G_DQS_DP<3>  DQS3P @BASEBOARD_FAB2_LIB.BASEBOARD_FAB2(SCH_1):M_G_DQS_DP(3)
 244 M_G_DQS_DN<4>  DQS4N @BASEBOARD_FAB2_LIB.BASEBOARD_FAB2(SCH_1):M_G_DQS_DN(4)
 245 M_G_DQS_DP<4>  DQS4P @BASEBOARD_FAB2_LIB.BASEBOARD_FAB2(SCH_1):M_G_DQS_DP(4)
 255 M_G_DQS_DN<5>  DQS5N @BASEBOARD_FAB2_LIB.BASEBOARD_FAB2(SCH_1):M_G_DQS_DN(5)
 256 M_G_DQS_DP<5>  DQS5P @BASEBOARD_FAB2_LIB.BASEBOARD_FAB2(SCH_1):M_G_DQS_DP(5)
 266 M_G_DQS_DN<6>  DQS6N @BASEBOARD_FAB2_LIB.BASEBOARD_FAB2(SCH_1):M_G_DQS_DN(6)
 267 M_G_DQS_DP<6>  DQS6P @BASEBOARD_FAB2_LIB.BASEBOARD_FAB2(SCH_1):M_G_DQS_DP(6)
 277 M_G_DQS_DN<7>  DQS7N @BASEBOARD_FAB2_LIB.BASEBOARD_FAB2(SCH_1):M_G_DQS_DN(7)
 278 M_G_DQS_DP<7>  DQS7P @BASEBOARD_FAB2_LIB.BASEBOARD_FAB2(SCH_1):M_G_DQS_DP(7)
 196 M_G_DQS_DN<8>  DQS8N @BASEBOARD_FAB2_LIB.BASEBOARD_FAB2(SCH_1):M_G_DQS_DN(8)
 197 M_G_DQS_DP<8>  DQS8P @BASEBOARD_FAB2_LIB.BASEBOARD_FAB2(SCH_1):M_G_DQS_DP(8)
   8 M_G_DQS_DN<9>  DQS9N @BASEBOARD_FAB2_LIB.BASEBOARD_FAB2(SCH_1):M_G_DQS_DN(9)
   7 M_G_DQS_DP<9>  DQS9P @BASEBOARD_FAB2_LIB.BASEBOARD_FAB2(SCH_1):M_G_DQS_DP(9)

SCONN288_H44441003_PIP-SCONN,HA  I144  J9T1
   2    GND VSS<93> @BASEBOARD_FAB2_LIB.BASEBOARD_FAB2(SCH_1):GND
   4    GND VSS<92> @BASEBOARD_FAB2_LIB.BASEBOARD_FAB2(SCH_1):GND
   6    GND VSS<91> @BASEBOARD_FAB2_LIB.BASEBOARD_FAB2(SCH_1):GND
   9    GND VSS<90> @BASEBOARD_FAB2_LIB.BASEBOARD_FAB2(SCH_1):GND
  11    GND VSS<89> @BASEBOARD_FAB2_LIB.BASEBOARD_FAB2(SCH_1):GND
  13    GND VSS<88> @BASEBOARD_FAB2_LIB.BASEBOARD_FAB2(SCH_1):GND
  15    GND VSS<87> @BASEBOARD_FAB2_LIB.BASEBOARD_FAB2(SCH_1):GND
  17    GND VSS<86> @BASEBOARD_FAB2_LIB.BASEBOARD_FAB2(SCH_1):GND
  20    GND VSS<85> @BASEBOARD_FAB2_LIB.BASEBOARD_FAB2(SCH_1):GND
  22    GND VSS<84> @BASEBOARD_FAB2_LIB.BASEBOARD_FAB2(SCH_1):GND
  24    GND VSS<83> @BASEBOARD_FAB2_LIB.BASEBOARD_FAB2(SCH_1):GND
  26    GND VSS<82> @BASEBOARD_FAB2_LIB.BASEBOARD_FAB2(SCH_1):GND
  28    GND VSS<81> @BASEBOARD_FAB2_LIB.BASEBOARD_FAB2(SCH_1):GND
  31    GND VSS<80> @BASEBOARD_FAB2_LIB.BASEBOARD_FAB2(SCH_1):GND
  33    GND VSS<79> @BASEBOARD_FAB2_LIB.BASEBOARD_FAB2(SCH_1):GND
  35    GND VSS<78> @BASEBOARD_FAB2_LIB.BASEBOARD_FAB2(SCH_1):GND
  37    GND VSS<77> @BASEBOARD_FAB2_LIB.BASEBOARD_FAB2(SCH_1):GND
  39    GND VSS<76> @BASEBOARD_FAB2_LIB.BASEBOARD_FAB2(SCH_1):GND
  42    GND VSS<75> @BASEBOARD_FAB2_LIB.BASEBOARD_FAB2(SCH_1):GND
  44    GND VSS<74> @BASEBOARD_FAB2_LIB.BASEBOARD_FAB2(SCH_1):GND
  46    GND VSS<73> @BASEBOARD_FAB2_LIB.BASEBOARD_FAB2(SCH_1):GND
  48    GND VSS<72> @BASEBOARD_FAB2_LIB.BASEBOARD_FAB2(SCH_1):GND
  50    GND VSS<71> @BASEBOARD_FAB2_LIB.BASEBOARD_FAB2(SCH_1):GND
  53    GND VSS<70> @BASEBOARD_FAB2_LIB.BASEBOARD_FAB2(SCH_1):GND
  55    GND VSS<69> @BASEBOARD_FAB2_LIB.BASEBOARD_FAB2(SCH_1):GND
  57    GND VSS<68> @BASEBOARD_FAB2_LIB.BASEBOARD_FAB2(SCH_1):GND
  94    GND VSS<67> @BASEBOARD_FAB2_LIB.BASEBOARD_FAB2(SCH_1):GND
  96    GND VSS<66> @BASEBOARD_FAB2_LIB.BASEBOARD_FAB2(SCH_1):GND
  98    GND VSS<65> @BASEBOARD_FAB2_LIB.BASEBOARD_FAB2(SCH_1):GND
 101    GND VSS<64> @BASEBOARD_FAB2_LIB.BASEBOARD_FAB2(SCH_1):GND
 103    GND VSS<63> @BASEBOARD_FAB2_LIB.BASEBOARD_FAB2(SCH_1):GND
 105    GND VSS<62> @BASEBOARD_FAB2_LIB.BASEBOARD_FAB2(SCH_1):GND
 107    GND VSS<61> @BASEBOARD_FAB2_LIB.BASEBOARD_FAB2(SCH_1):GND
 109    GND VSS<60> @BASEBOARD_FAB2_LIB.BASEBOARD_FAB2(SCH_1):GND
 112    GND VSS<59> @BASEBOARD_FAB2_LIB.BASEBOARD_FAB2(SCH_1):GND
 114    GND VSS<58> @BASEBOARD_FAB2_LIB.BASEBOARD_FAB2(SCH_1):GND
 116    GND VSS<57> @BASEBOARD_FAB2_LIB.BASEBOARD_FAB2(SCH_1):GND
 118    GND VSS<56> @BASEBOARD_FAB2_LIB.BASEBOARD_FAB2(SCH_1):GND
 120    GND VSS<55> @BASEBOARD_FAB2_LIB.BASEBOARD_FAB2(SCH_1):GND
 123    GND VSS<54> @BASEBOARD_FAB2_LIB.BASEBOARD_FAB2(SCH_1):GND
 125    GND VSS<53> @BASEBOARD_FAB2_LIB.BASEBOARD_FAB2(SCH_1):GND
 127    GND VSS<52> @BASEBOARD_FAB2_LIB.BASEBOARD_FAB2(SCH_1):GND
 129    GND VSS<51> @BASEBOARD_FAB2_LIB.BASEBOARD_FAB2(SCH_1):GND
 131    GND VSS<50> @BASEBOARD_FAB2_LIB.BASEBOARD_FAB2(SCH_1):GND
 134    GND VSS<49> @BASEBOARD_FAB2_LIB.BASEBOARD_FAB2(SCH_1):GND
 136    GND VSS<48> @BASEBOARD_FAB2_LIB.BASEBOARD_FAB2(SCH_1):GND
 138    GND VSS<47> @BASEBOARD_FAB2_LIB.BASEBOARD_FAB2(SCH_1):GND
 147    GND VSS<46> @BASEBOARD_FAB2_LIB.BASEBOARD_FAB2(SCH_1):GND
 149    GND VSS<45> @BASEBOARD_FAB2_LIB.BASEBOARD_FAB2(SCH_1):GND
 151    GND VSS<44> @BASEBOARD_FAB2_LIB.BASEBOARD_FAB2(SCH_1):GND
 154    GND VSS<43> @BASEBOARD_FAB2_LIB.BASEBOARD_FAB2(SCH_1):GND
 156    GND VSS<42> @BASEBOARD_FAB2_LIB.BASEBOARD_FAB2(SCH_1):GND
 158    GND VSS<41> @BASEBOARD_FAB2_LIB.BASEBOARD_FAB2(SCH_1):GND
 160    GND VSS<40> @BASEBOARD_FAB2_LIB.BASEBOARD_FAB2(SCH_1):GND
 162    GND VSS<39> @BASEBOARD_FAB2_LIB.BASEBOARD_FAB2(SCH_1):GND
 165    GND VSS<38> @BASEBOARD_FAB2_LIB.BASEBOARD_FAB2(SCH_1):GND
 167    GND VSS<37> @BASEBOARD_FAB2_LIB.BASEBOARD_FAB2(SCH_1):GND
 169    GND VSS<36> @BASEBOARD_FAB2_LIB.BASEBOARD_FAB2(SCH_1):GND
 171    GND VSS<35> @BASEBOARD_FAB2_LIB.BASEBOARD_FAB2(SCH_1):GND
 173    GND VSS<34> @BASEBOARD_FAB2_LIB.BASEBOARD_FAB2(SCH_1):GND
 176    GND VSS<33> @BASEBOARD_FAB2_LIB.BASEBOARD_FAB2(SCH_1):GND
 178    GND VSS<32> @BASEBOARD_FAB2_LIB.BASEBOARD_FAB2(SCH_1):GND
 180    GND VSS<31> @BASEBOARD_FAB2_LIB.BASEBOARD_FAB2(SCH_1):GND
 182    GND VSS<30> @BASEBOARD_FAB2_LIB.BASEBOARD_FAB2(SCH_1):GND
 184    GND VSS<29> @BASEBOARD_FAB2_LIB.BASEBOARD_FAB2(SCH_1):GND
 187    GND VSS<28> @BASEBOARD_FAB2_LIB.BASEBOARD_FAB2(SCH_1):GND
 189    GND VSS<27> @BASEBOARD_FAB2_LIB.BASEBOARD_FAB2(SCH_1):GND
 191    GND VSS<26> @BASEBOARD_FAB2_LIB.BASEBOARD_FAB2(SCH_1):GND
 193    GND VSS<25> @BASEBOARD_FAB2_LIB.BASEBOARD_FAB2(SCH_1):GND
 195    GND VSS<24> @BASEBOARD_FAB2_LIB.BASEBOARD_FAB2(SCH_1):GND
 198    GND VSS<23> @BASEBOARD_FAB2_LIB.BASEBOARD_FAB2(SCH_1):GND
 200    GND VSS<22> @BASEBOARD_FAB2_LIB.BASEBOARD_FAB2(SCH_1):GND
 202    GND VSS<21> @BASEBOARD_FAB2_LIB.BASEBOARD_FAB2(SCH_1):GND
 239    GND VSS<20> @BASEBOARD_FAB2_LIB.BASEBOARD_FAB2(SCH_1):GND
 241    GND VSS<19> @BASEBOARD_FAB2_LIB.BASEBOARD_FAB2(SCH_1):GND
 243    GND VSS<18> @BASEBOARD_FAB2_LIB.BASEBOARD_FAB2(SCH_1):GND
 246    GND VSS<17> @BASEBOARD_FAB2_LIB.BASEBOARD_FAB2(SCH_1):GND
 248    GND VSS<16> @BASEBOARD_FAB2_LIB.BASEBOARD_FAB2(SCH_1):GND
 250    GND VSS<15> @BASEBOARD_FAB2_LIB.BASEBOARD_FAB2(SCH_1):GND
 252    GND VSS<14> @BASEBOARD_FAB2_LIB.BASEBOARD_FAB2(SCH_1):GND
 254    GND VSS<13> @BASEBOARD_FAB2_LIB.BASEBOARD_FAB2(SCH_1):GND
 257    GND VSS<12> @BASEBOARD_FAB2_LIB.BASEBOARD_FAB2(SCH_1):GND
 259    GND VSS<11> @BASEBOARD_FAB2_LIB.BASEBOARD_FAB2(SCH_1):GND
 261    GND VSS<10> @BASEBOARD_FAB2_LIB.BASEBOARD_FAB2(SCH_1):GND
 263    GND VSS<9> @BASEBOARD_FAB2_LIB.BASEBOARD_FAB2(SCH_1):GND
 265    GND VSS<8> @BASEBOARD_FAB2_LIB.BASEBOARD_FAB2(SCH_1):GND
 268    GND VSS<7> @BASEBOARD_FAB2_LIB.BASEBOARD_FAB2(SCH_1):GND
 270    GND VSS<6> @BASEBOARD_FAB2_LIB.BASEBOARD_FAB2(SCH_1):GND
 272    GND VSS<5> @BASEBOARD_FAB2_LIB.BASEBOARD_FAB2(SCH_1):GND
 274    GND VSS<4> @BASEBOARD_FAB2_LIB.BASEBOARD_FAB2(SCH_1):GND
 276    GND VSS<3> @BASEBOARD_FAB2_LIB.BASEBOARD_FAB2(SCH_1):GND
 279    GND VSS<2> @BASEBOARD_FAB2_LIB.BASEBOARD_FAB2(SCH_1):GND
 281    GND VSS<1> @BASEBOARD_FAB2_LIB.BASEBOARD_FAB2(SCH_1):GND
 283    GND VSS<0> @BASEBOARD_FAB2_LIB.BASEBOARD_FAB2(SCH_1):GND


DRAWING: @BASEBOARD_FAB2_LIB.BASEBOARD_FAB2(SCH_1):PAGE79 

SCONN288_H44441004_PIP-SCONN,HA  I43  J1G2
   2    GND VSS<93> @BASEBOARD_FAB2_LIB.BASEBOARD_FAB2(SCH_1):GND
   4    GND VSS<92> @BASEBOARD_FAB2_LIB.BASEBOARD_FAB2(SCH_1):GND
   6    GND VSS<91> @BASEBOARD_FAB2_LIB.BASEBOARD_FAB2(SCH_1):GND
   9    GND VSS<90> @BASEBOARD_FAB2_LIB.BASEBOARD_FAB2(SCH_1):GND
  11    GND VSS<89> @BASEBOARD_FAB2_LIB.BASEBOARD_FAB2(SCH_1):GND
  13    GND VSS<88> @BASEBOARD_FAB2_LIB.BASEBOARD_FAB2(SCH_1):GND
  15    GND VSS<87> @BASEBOARD_FAB2_LIB.BASEBOARD_FAB2(SCH_1):GND
  17    GND VSS<86> @BASEBOARD_FAB2_LIB.BASEBOARD_FAB2(SCH_1):GND
  20    GND VSS<85> @BASEBOARD_FAB2_LIB.BASEBOARD_FAB2(SCH_1):GND
  22    GND VSS<84> @BASEBOARD_FAB2_LIB.BASEBOARD_FAB2(SCH_1):GND
  24    GND VSS<83> @BASEBOARD_FAB2_LIB.BASEBOARD_FAB2(SCH_1):GND
  26    GND VSS<82> @BASEBOARD_FAB2_LIB.BASEBOARD_FAB2(SCH_1):GND
  28    GND VSS<81> @BASEBOARD_FAB2_LIB.BASEBOARD_FAB2(SCH_1):GND
  31    GND VSS<80> @BASEBOARD_FAB2_LIB.BASEBOARD_FAB2(SCH_1):GND
  33    GND VSS<79> @BASEBOARD_FAB2_LIB.BASEBOARD_FAB2(SCH_1):GND
  35    GND VSS<78> @BASEBOARD_FAB2_LIB.BASEBOARD_FAB2(SCH_1):GND
  37    GND VSS<77> @BASEBOARD_FAB2_LIB.BASEBOARD_FAB2(SCH_1):GND
  39    GND VSS<76> @BASEBOARD_FAB2_LIB.BASEBOARD_FAB2(SCH_1):GND
  42    GND VSS<75> @BASEBOARD_FAB2_LIB.BASEBOARD_FAB2(SCH_1):GND
  44    GND VSS<74> @BASEBOARD_FAB2_LIB.BASEBOARD_FAB2(SCH_1):GND
  46    GND VSS<73> @BASEBOARD_FAB2_LIB.BASEBOARD_FAB2(SCH_1):GND
  48    GND VSS<72> @BASEBOARD_FAB2_LIB.BASEBOARD_FAB2(SCH_1):GND
  50    GND VSS<71> @BASEBOARD_FAB2_LIB.BASEBOARD_FAB2(SCH_1):GND
  53    GND VSS<70> @BASEBOARD_FAB2_LIB.BASEBOARD_FAB2(SCH_1):GND
  55    GND VSS<69> @BASEBOARD_FAB2_LIB.BASEBOARD_FAB2(SCH_1):GND
  57    GND VSS<68> @BASEBOARD_FAB2_LIB.BASEBOARD_FAB2(SCH_1):GND
  94    GND VSS<67> @BASEBOARD_FAB2_LIB.BASEBOARD_FAB2(SCH_1):GND
  96    GND VSS<66> @BASEBOARD_FAB2_LIB.BASEBOARD_FAB2(SCH_1):GND
  98    GND VSS<65> @BASEBOARD_FAB2_LIB.BASEBOARD_FAB2(SCH_1):GND
 101    GND VSS<64> @BASEBOARD_FAB2_LIB.BASEBOARD_FAB2(SCH_1):GND
 103    GND VSS<63> @BASEBOARD_FAB2_LIB.BASEBOARD_FAB2(SCH_1):GND
 105    GND VSS<62> @BASEBOARD_FAB2_LIB.BASEBOARD_FAB2(SCH_1):GND
 107    GND VSS<61> @BASEBOARD_FAB2_LIB.BASEBOARD_FAB2(SCH_1):GND
 109    GND VSS<60> @BASEBOARD_FAB2_LIB.BASEBOARD_FAB2(SCH_1):GND
 112    GND VSS<59> @BASEBOARD_FAB2_LIB.BASEBOARD_FAB2(SCH_1):GND
 114    GND VSS<58> @BASEBOARD_FAB2_LIB.BASEBOARD_FAB2(SCH_1):GND
 116    GND VSS<57> @BASEBOARD_FAB2_LIB.BASEBOARD_FAB2(SCH_1):GND
 118    GND VSS<56> @BASEBOARD_FAB2_LIB.BASEBOARD_FAB2(SCH_1):GND
 120    GND VSS<55> @BASEBOARD_FAB2_LIB.BASEBOARD_FAB2(SCH_1):GND
 123    GND VSS<54> @BASEBOARD_FAB2_LIB.BASEBOARD_FAB2(SCH_1):GND
 125    GND VSS<53> @BASEBOARD_FAB2_LIB.BASEBOARD_FAB2(SCH_1):GND
 127    GND VSS<52> @BASEBOARD_FAB2_LIB.BASEBOARD_FAB2(SCH_1):GND
 129    GND VSS<51> @BASEBOARD_FAB2_LIB.BASEBOARD_FAB2(SCH_1):GND
 131    GND VSS<50> @BASEBOARD_FAB2_LIB.BASEBOARD_FAB2(SCH_1):GND
 134    GND VSS<49> @BASEBOARD_FAB2_LIB.BASEBOARD_FAB2(SCH_1):GND
 136    GND VSS<48> @BASEBOARD_FAB2_LIB.BASEBOARD_FAB2(SCH_1):GND
 138    GND VSS<47> @BASEBOARD_FAB2_LIB.BASEBOARD_FAB2(SCH_1):GND
 147    GND VSS<46> @BASEBOARD_FAB2_LIB.BASEBOARD_FAB2(SCH_1):GND
 149    GND VSS<45> @BASEBOARD_FAB2_LIB.BASEBOARD_FAB2(SCH_1):GND
 151    GND VSS<44> @BASEBOARD_FAB2_LIB.BASEBOARD_FAB2(SCH_1):GND
 154    GND VSS<43> @BASEBOARD_FAB2_LIB.BASEBOARD_FAB2(SCH_1):GND
 156    GND VSS<42> @BASEBOARD_FAB2_LIB.BASEBOARD_FAB2(SCH_1):GND
 158    GND VSS<41> @BASEBOARD_FAB2_LIB.BASEBOARD_FAB2(SCH_1):GND
 160    GND VSS<40> @BASEBOARD_FAB2_LIB.BASEBOARD_FAB2(SCH_1):GND
 162    GND VSS<39> @BASEBOARD_FAB2_LIB.BASEBOARD_FAB2(SCH_1):GND
 165    GND VSS<38> @BASEBOARD_FAB2_LIB.BASEBOARD_FAB2(SCH_1):GND
 167    GND VSS<37> @BASEBOARD_FAB2_LIB.BASEBOARD_FAB2(SCH_1):GND
 169    GND VSS<36> @BASEBOARD_FAB2_LIB.BASEBOARD_FAB2(SCH_1):GND
 171    GND VSS<35> @BASEBOARD_FAB2_LIB.BASEBOARD_FAB2(SCH_1):GND
 173    GND VSS<34> @BASEBOARD_FAB2_LIB.BASEBOARD_FAB2(SCH_1):GND
 176    GND VSS<33> @BASEBOARD_FAB2_LIB.BASEBOARD_FAB2(SCH_1):GND
 178    GND VSS<32> @BASEBOARD_FAB2_LIB.BASEBOARD_FAB2(SCH_1):GND
 180    GND VSS<31> @BASEBOARD_FAB2_LIB.BASEBOARD_FAB2(SCH_1):GND
 182    GND VSS<30> @BASEBOARD_FAB2_LIB.BASEBOARD_FAB2(SCH_1):GND
 184    GND VSS<29> @BASEBOARD_FAB2_LIB.BASEBOARD_FAB2(SCH_1):GND
 187    GND VSS<28> @BASEBOARD_FAB2_LIB.BASEBOARD_FAB2(SCH_1):GND
 189    GND VSS<27> @BASEBOARD_FAB2_LIB.BASEBOARD_FAB2(SCH_1):GND
 191    GND VSS<26> @BASEBOARD_FAB2_LIB.BASEBOARD_FAB2(SCH_1):GND
 193    GND VSS<25> @BASEBOARD_FAB2_LIB.BASEBOARD_FAB2(SCH_1):GND
 195    GND VSS<24> @BASEBOARD_FAB2_LIB.BASEBOARD_FAB2(SCH_1):GND
 198    GND VSS<23> @BASEBOARD_FAB2_LIB.BASEBOARD_FAB2(SCH_1):GND
 200    GND VSS<22> @BASEBOARD_FAB2_LIB.BASEBOARD_FAB2(SCH_1):GND
 202    GND VSS<21> @BASEBOARD_FAB2_LIB.BASEBOARD_FAB2(SCH_1):GND
 239    GND VSS<20> @BASEBOARD_FAB2_LIB.BASEBOARD_FAB2(SCH_1):GND
 241    GND VSS<19> @BASEBOARD_FAB2_LIB.BASEBOARD_FAB2(SCH_1):GND
 243    GND VSS<18> @BASEBOARD_FAB2_LIB.BASEBOARD_FAB2(SCH_1):GND
 246    GND VSS<17> @BASEBOARD_FAB2_LIB.BASEBOARD_FAB2(SCH_1):GND
 248    GND VSS<16> @BASEBOARD_FAB2_LIB.BASEBOARD_FAB2(SCH_1):GND
 250    GND VSS<15> @BASEBOARD_FAB2_LIB.BASEBOARD_FAB2(SCH_1):GND
 252    GND VSS<14> @BASEBOARD_FAB2_LIB.BASEBOARD_FAB2(SCH_1):GND
 254    GND VSS<13> @BASEBOARD_FAB2_LIB.BASEBOARD_FAB2(SCH_1):GND
 257    GND VSS<12> @BASEBOARD_FAB2_LIB.BASEBOARD_FAB2(SCH_1):GND
 259    GND VSS<11> @BASEBOARD_FAB2_LIB.BASEBOARD_FAB2(SCH_1):GND
 261    GND VSS<10> @BASEBOARD_FAB2_LIB.BASEBOARD_FAB2(SCH_1):GND
 263    GND VSS<9> @BASEBOARD_FAB2_LIB.BASEBOARD_FAB2(SCH_1):GND
 265    GND VSS<8> @BASEBOARD_FAB2_LIB.BASEBOARD_FAB2(SCH_1):GND
 268    GND VSS<7> @BASEBOARD_FAB2_LIB.BASEBOARD_FAB2(SCH_1):GND
 270    GND VSS<6> @BASEBOARD_FAB2_LIB.BASEBOARD_FAB2(SCH_1):GND
 272    GND VSS<5> @BASEBOARD_FAB2_LIB.BASEBOARD_FAB2(SCH_1):GND
 274    GND VSS<4> @BASEBOARD_FAB2_LIB.BASEBOARD_FAB2(SCH_1):GND
 276    GND VSS<3> @BASEBOARD_FAB2_LIB.BASEBOARD_FAB2(SCH_1):GND
 279    GND VSS<2> @BASEBOARD_FAB2_LIB.BASEBOARD_FAB2(SCH_1):GND
 281    GND VSS<1> @BASEBOARD_FAB2_LIB.BASEBOARD_FAB2(SCH_1):GND
 283    GND VSS<0> @BASEBOARD_FAB2_LIB.BASEBOARD_FAB2(SCH_1):GND

SCONN288_H44441004_PIP-SCONN,HA  I64  J1G2
 152 M_H_DQS_DN<0>  DQS0N @BASEBOARD_FAB2_LIB.BASEBOARD_FAB2(SCH_1):M_H_DQS_DN(0)
 153 M_H_DQS_DP<0>  DQS0P @BASEBOARD_FAB2_LIB.BASEBOARD_FAB2(SCH_1):M_H_DQS_DP(0)
  19 M_H_DQS_DN<10> DQS10N @BASEBOARD_FAB2_LIB.BASEBOARD_FAB2(SCH_1):M_H_DQS_DN(10)
  18 M_H_DQS_DP<10> DQS10P @BASEBOARD_FAB2_LIB.BASEBOARD_FAB2(SCH_1):M_H_DQS_DP(10)
  30 M_H_DQS_DN<11> DQS11N @BASEBOARD_FAB2_LIB.BASEBOARD_FAB2(SCH_1):M_H_DQS_DN(11)
  29 M_H_DQS_DP<11> DQS11P @BASEBOARD_FAB2_LIB.BASEBOARD_FAB2(SCH_1):M_H_DQS_DP(11)
  41 M_H_DQS_DN<12> DQS12N @BASEBOARD_FAB2_LIB.BASEBOARD_FAB2(SCH_1):M_H_DQS_DN(12)
  40 M_H_DQS_DP<12> DQS12P @BASEBOARD_FAB2_LIB.BASEBOARD_FAB2(SCH_1):M_H_DQS_DP(12)
 100 M_H_DQS_DN<13> DQS13N @BASEBOARD_FAB2_LIB.BASEBOARD_FAB2(SCH_1):M_H_DQS_DN(13)
  99 M_H_DQS_DP<13> DQS13P @BASEBOARD_FAB2_LIB.BASEBOARD_FAB2(SCH_1):M_H_DQS_DP(13)
 111 M_H_DQS_DN<14> DQS14N @BASEBOARD_FAB2_LIB.BASEBOARD_FAB2(SCH_1):M_H_DQS_DN(14)
 110 M_H_DQS_DP<14> DQS14P @BASEBOARD_FAB2_LIB.BASEBOARD_FAB2(SCH_1):M_H_DQS_DP(14)
 122 M_H_DQS_DN<15> DQS15N @BASEBOARD_FAB2_LIB.BASEBOARD_FAB2(SCH_1):M_H_DQS_DN(15)
 121 M_H_DQS_DP<15> DQS15P @BASEBOARD_FAB2_LIB.BASEBOARD_FAB2(SCH_1):M_H_DQS_DP(15)
 133 M_H_DQS_DN<16> DQS16N @BASEBOARD_FAB2_LIB.BASEBOARD_FAB2(SCH_1):M_H_DQS_DN(16)
 132 M_H_DQS_DP<16> DQS16P @BASEBOARD_FAB2_LIB.BASEBOARD_FAB2(SCH_1):M_H_DQS_DP(16)
  52 M_H_DQS_DN<17> DQS17N @BASEBOARD_FAB2_LIB.BASEBOARD_FAB2(SCH_1):M_H_DQS_DN(17)
  51 M_H_DQS_DP<17> DQS17P @BASEBOARD_FAB2_LIB.BASEBOARD_FAB2(SCH_1):M_H_DQS_DP(17)
 163 M_H_DQS_DN<1>  DQS1N @BASEBOARD_FAB2_LIB.BASEBOARD_FAB2(SCH_1):M_H_DQS_DN(1)
 164 M_H_DQS_DP<1>  DQS1P @BASEBOARD_FAB2_LIB.BASEBOARD_FAB2(SCH_1):M_H_DQS_DP(1)
 174 M_H_DQS_DN<2>  DQS2N @BASEBOARD_FAB2_LIB.BASEBOARD_FAB2(SCH_1):M_H_DQS_DN(2)
 175 M_H_DQS_DP<2>  DQS2P @BASEBOARD_FAB2_LIB.BASEBOARD_FAB2(SCH_1):M_H_DQS_DP(2)
 185 M_H_DQS_DN<3>  DQS3N @BASEBOARD_FAB2_LIB.BASEBOARD_FAB2(SCH_1):M_H_DQS_DN(3)
 186 M_H_DQS_DP<3>  DQS3P @BASEBOARD_FAB2_LIB.BASEBOARD_FAB2(SCH_1):M_H_DQS_DP(3)
 244 M_H_DQS_DN<4>  DQS4N @BASEBOARD_FAB2_LIB.BASEBOARD_FAB2(SCH_1):M_H_DQS_DN(4)
 245 M_H_DQS_DP<4>  DQS4P @BASEBOARD_FAB2_LIB.BASEBOARD_FAB2(SCH_1):M_H_DQS_DP(4)
 255 M_H_DQS_DN<5>  DQS5N @BASEBOARD_FAB2_LIB.BASEBOARD_FAB2(SCH_1):M_H_DQS_DN(5)
 256 M_H_DQS_DP<5>  DQS5P @BASEBOARD_FAB2_LIB.BASEBOARD_FAB2(SCH_1):M_H_DQS_DP(5)
 266 M_H_DQS_DN<6>  DQS6N @BASEBOARD_FAB2_LIB.BASEBOARD_FAB2(SCH_1):M_H_DQS_DN(6)
 267 M_H_DQS_DP<6>  DQS6P @BASEBOARD_FAB2_LIB.BASEBOARD_FAB2(SCH_1):M_H_DQS_DP(6)
 277 M_H_DQS_DN<7>  DQS7N @BASEBOARD_FAB2_LIB.BASEBOARD_FAB2(SCH_1):M_H_DQS_DN(7)
 278 M_H_DQS_DP<7>  DQS7P @BASEBOARD_FAB2_LIB.BASEBOARD_FAB2(SCH_1):M_H_DQS_DP(7)
 196 M_H_DQS_DN<8>  DQS8N @BASEBOARD_FAB2_LIB.BASEBOARD_FAB2(SCH_1):M_H_DQS_DN(8)
 197 M_H_DQS_DP<8>  DQS8P @BASEBOARD_FAB2_LIB.BASEBOARD_FAB2(SCH_1):M_H_DQS_DP(8)
   8 M_H_DQS_DN<9>  DQS9N @BASEBOARD_FAB2_LIB.BASEBOARD_FAB2(SCH_1):M_H_DQS_DN(9)
   7 M_H_DQS_DP<9>  DQS9P @BASEBOARD_FAB2_LIB.BASEBOARD_FAB2(SCH_1):M_H_DQS_DP(9)

SCONN288_H44441004_PIP-SCONN,HA  I111  J1G2
  79 M_H_MA<0>     A0 @BASEBOARD_FAB2_LIB.BASEBOARD_FAB2(SCH_1):M_H_MA(0)
  72 M_H_MA<1>     A1 @BASEBOARD_FAB2_LIB.BASEBOARD_FAB2(SCH_1):M_H_MA(1)
 225 M_H_MA<10>    A10 @BASEBOARD_FAB2_LIB.BASEBOARD_FAB2(SCH_1):M_H_MA(10)
 210 M_H_MA<11>    A11 @BASEBOARD_FAB2_LIB.BASEBOARD_FAB2(SCH_1):M_H_MA(11)
  65 M_H_MA<12>    A12 @BASEBOARD_FAB2_LIB.BASEBOARD_FAB2(SCH_1):M_H_MA(12)
 232 M_H_MA<13>    A13 @BASEBOARD_FAB2_LIB.BASEBOARD_FAB2(SCH_1):M_H_MA(13)
 228 M_H_MA<14> A14_WE_N @BASEBOARD_FAB2_LIB.BASEBOARD_FAB2(SCH_1):M_H_MA(14)
  86 M_H_MA<15> A15_CAS_N @BASEBOARD_FAB2_LIB.BASEBOARD_FAB2(SCH_1):M_H_MA(15)
  82 M_H_MA<16> A16_RAS_N @BASEBOARD_FAB2_LIB.BASEBOARD_FAB2(SCH_1):M_H_MA(16)
 234 M_H_MA<17>    A17 @BASEBOARD_FAB2_LIB.BASEBOARD_FAB2(SCH_1):M_H_MA(17)
 216 M_H_MA<2>     A2 @BASEBOARD_FAB2_LIB.BASEBOARD_FAB2(SCH_1):M_H_MA(2)
  71 M_H_MA<3>     A3 @BASEBOARD_FAB2_LIB.BASEBOARD_FAB2(SCH_1):M_H_MA(3)
 214 M_H_MA<4>     A4 @BASEBOARD_FAB2_LIB.BASEBOARD_FAB2(SCH_1):M_H_MA(4)
 213 M_H_MA<5>     A5 @BASEBOARD_FAB2_LIB.BASEBOARD_FAB2(SCH_1):M_H_MA(5)
  69 M_H_MA<6>     A6 @BASEBOARD_FAB2_LIB.BASEBOARD_FAB2(SCH_1):M_H_MA(6)
 211 M_H_MA<7>     A7 @BASEBOARD_FAB2_LIB.BASEBOARD_FAB2(SCH_1):M_H_MA(7)
  68 M_H_MA<8>     A8 @BASEBOARD_FAB2_LIB.BASEBOARD_FAB2(SCH_1):M_H_MA(8)
  66 M_H_MA<9>     A9 @BASEBOARD_FAB2_LIB.BASEBOARD_FAB2(SCH_1):M_H_MA(9)
  62 M_H_ACT_N  ACT_N @BASEBOARD_FAB2_LIB.BASEBOARD_FAB2(SCH_1):M_H_ACT_N
 208 M_H_ALERT_N ALERT_N @BASEBOARD_FAB2_LIB.BASEBOARD_FAB2(SCH_1):M_H_ALERT_N
 224 M_H_BA<1>  BA<1> @BASEBOARD_FAB2_LIB.BASEBOARD_FAB2(SCH_1):M_H_BA(1)
  81 M_H_BA<0>  BA<0> @BASEBOARD_FAB2_LIB.BASEBOARD_FAB2(SCH_1):M_H_BA(0)
 207 M_H_BG<1>  BG<1> @BASEBOARD_FAB2_LIB.BASEBOARD_FAB2(SCH_1):M_H_BG(1)
  63 M_H_BG<0>  BG<0> @BASEBOARD_FAB2_LIB.BASEBOARD_FAB2(SCH_1):M_H_BG(0)
 235 M_H_C<2>   C<2> @BASEBOARD_FAB2_LIB.BASEBOARD_FAB2(SCH_1):M_H_C(2)
 199 M_H_ECC<6>  CB<7> @BASEBOARD_FAB2_LIB.BASEBOARD_FAB2(SCH_1):M_H_ECC(6)
  54 M_H_ECC<7>  CB<6> @BASEBOARD_FAB2_LIB.BASEBOARD_FAB2(SCH_1):M_H_ECC(7)
 192 M_H_ECC<4>  CB<5> @BASEBOARD_FAB2_LIB.BASEBOARD_FAB2(SCH_1):M_H_ECC(4)
  47 M_H_ECC<5>  CB<4> @BASEBOARD_FAB2_LIB.BASEBOARD_FAB2(SCH_1):M_H_ECC(5)
 201 M_H_ECC<2>  CB<3> @BASEBOARD_FAB2_LIB.BASEBOARD_FAB2(SCH_1):M_H_ECC(2)
  56 M_H_ECC<3>  CB<2> @BASEBOARD_FAB2_LIB.BASEBOARD_FAB2(SCH_1):M_H_ECC(3)
 194 M_H_ECC<0>  CB<1> @BASEBOARD_FAB2_LIB.BASEBOARD_FAB2(SCH_1):M_H_ECC(0)
  49 M_H_ECC<1>  CB<0> @BASEBOARD_FAB2_LIB.BASEBOARD_FAB2(SCH_1):M_H_ECC(1)
  75 M_H_CLK_DN<0>   CK0N @BASEBOARD_FAB2_LIB.BASEBOARD_FAB2(SCH_1):M_H_CLK_DN(0)
  74 M_H_CLK_DP<0>   CK0P @BASEBOARD_FAB2_LIB.BASEBOARD_FAB2(SCH_1):M_H_CLK_DP(0)
 219 M_H_CLK_DN<1>   CK1N @BASEBOARD_FAB2_LIB.BASEBOARD_FAB2(SCH_1):M_H_CLK_DN(1)
 218 M_H_CLK_DP<1>   CK1P @BASEBOARD_FAB2_LIB.BASEBOARD_FAB2(SCH_1):M_H_CLK_DP(1)
 203 M_H_CKE<1> CKE<1> @BASEBOARD_FAB2_LIB.BASEBOARD_FAB2(SCH_1):M_H_CKE(1)
  60 M_H_CKE<0> CKE<0> @BASEBOARD_FAB2_LIB.BASEBOARD_FAB2(SCH_1):M_H_CKE(0)
 280 M_H_DQ<62> DQ<63> @BASEBOARD_FAB2_LIB.BASEBOARD_FAB2(SCH_1):M_H_DQ(62)
 135 M_H_DQ<63> DQ<62> @BASEBOARD_FAB2_LIB.BASEBOARD_FAB2(SCH_1):M_H_DQ(63)
 273 M_H_DQ<60> DQ<61> @BASEBOARD_FAB2_LIB.BASEBOARD_FAB2(SCH_1):M_H_DQ(60)
 128 M_H_DQ<61> DQ<60> @BASEBOARD_FAB2_LIB.BASEBOARD_FAB2(SCH_1):M_H_DQ(61)
 282 M_H_DQ<58> DQ<59> @BASEBOARD_FAB2_LIB.BASEBOARD_FAB2(SCH_1):M_H_DQ(58)
 137 M_H_DQ<59> DQ<58> @BASEBOARD_FAB2_LIB.BASEBOARD_FAB2(SCH_1):M_H_DQ(59)
 275 M_H_DQ<56> DQ<57> @BASEBOARD_FAB2_LIB.BASEBOARD_FAB2(SCH_1):M_H_DQ(56)
 130 M_H_DQ<57> DQ<56> @BASEBOARD_FAB2_LIB.BASEBOARD_FAB2(SCH_1):M_H_DQ(57)
 269 M_H_DQ<54> DQ<55> @BASEBOARD_FAB2_LIB.BASEBOARD_FAB2(SCH_1):M_H_DQ(54)
 124 M_H_DQ<55> DQ<54> @BASEBOARD_FAB2_LIB.BASEBOARD_FAB2(SCH_1):M_H_DQ(55)
 262 M_H_DQ<52> DQ<53> @BASEBOARD_FAB2_LIB.BASEBOARD_FAB2(SCH_1):M_H_DQ(52)
 117 M_H_DQ<53> DQ<52> @BASEBOARD_FAB2_LIB.BASEBOARD_FAB2(SCH_1):M_H_DQ(53)
 271 M_H_DQ<50> DQ<51> @BASEBOARD_FAB2_LIB.BASEBOARD_FAB2(SCH_1):M_H_DQ(50)
 126 M_H_DQ<51> DQ<50> @BASEBOARD_FAB2_LIB.BASEBOARD_FAB2(SCH_1):M_H_DQ(51)
 264 M_H_DQ<48> DQ<49> @BASEBOARD_FAB2_LIB.BASEBOARD_FAB2(SCH_1):M_H_DQ(48)
 119 M_H_DQ<49> DQ<48> @BASEBOARD_FAB2_LIB.BASEBOARD_FAB2(SCH_1):M_H_DQ(49)
 258 M_H_DQ<46> DQ<47> @BASEBOARD_FAB2_LIB.BASEBOARD_FAB2(SCH_1):M_H_DQ(46)
 113 M_H_DQ<47> DQ<46> @BASEBOARD_FAB2_LIB.BASEBOARD_FAB2(SCH_1):M_H_DQ(47)
 251 M_H_DQ<44> DQ<45> @BASEBOARD_FAB2_LIB.BASEBOARD_FAB2(SCH_1):M_H_DQ(44)
 106 M_H_DQ<45> DQ<44> @BASEBOARD_FAB2_LIB.BASEBOARD_FAB2(SCH_1):M_H_DQ(45)
 260 M_H_DQ<42> DQ<43> @BASEBOARD_FAB2_LIB.BASEBOARD_FAB2(SCH_1):M_H_DQ(42)
 115 M_H_DQ<43> DQ<42> @BASEBOARD_FAB2_LIB.BASEBOARD_FAB2(SCH_1):M_H_DQ(43)
 253 M_H_DQ<40> DQ<41> @BASEBOARD_FAB2_LIB.BASEBOARD_FAB2(SCH_1):M_H_DQ(40)
 108 M_H_DQ<41> DQ<40> @BASEBOARD_FAB2_LIB.BASEBOARD_FAB2(SCH_1):M_H_DQ(41)
 247 M_H_DQ<38> DQ<39> @BASEBOARD_FAB2_LIB.BASEBOARD_FAB2(SCH_1):M_H_DQ(38)
 102 M_H_DQ<39> DQ<38> @BASEBOARD_FAB2_LIB.BASEBOARD_FAB2(SCH_1):M_H_DQ(39)
 240 M_H_DQ<36> DQ<37> @BASEBOARD_FAB2_LIB.BASEBOARD_FAB2(SCH_1):M_H_DQ(36)
  95 M_H_DQ<37> DQ<36> @BASEBOARD_FAB2_LIB.BASEBOARD_FAB2(SCH_1):M_H_DQ(37)
 249 M_H_DQ<34> DQ<35> @BASEBOARD_FAB2_LIB.BASEBOARD_FAB2(SCH_1):M_H_DQ(34)
 104 M_H_DQ<35> DQ<34> @BASEBOARD_FAB2_LIB.BASEBOARD_FAB2(SCH_1):M_H_DQ(35)
 242 M_H_DQ<32> DQ<33> @BASEBOARD_FAB2_LIB.BASEBOARD_FAB2(SCH_1):M_H_DQ(32)
  97 M_H_DQ<33> DQ<32> @BASEBOARD_FAB2_LIB.BASEBOARD_FAB2(SCH_1):M_H_DQ(33)
 188 M_H_DQ<30> DQ<31> @BASEBOARD_FAB2_LIB.BASEBOARD_FAB2(SCH_1):M_H_DQ(30)
  43 M_H_DQ<31> DQ<30> @BASEBOARD_FAB2_LIB.BASEBOARD_FAB2(SCH_1):M_H_DQ(31)
 181 M_H_DQ<28> DQ<29> @BASEBOARD_FAB2_LIB.BASEBOARD_FAB2(SCH_1):M_H_DQ(28)
  36 M_H_DQ<29> DQ<28> @BASEBOARD_FAB2_LIB.BASEBOARD_FAB2(SCH_1):M_H_DQ(29)
 190 M_H_DQ<26> DQ<27> @BASEBOARD_FAB2_LIB.BASEBOARD_FAB2(SCH_1):M_H_DQ(26)
  45 M_H_DQ<27> DQ<26> @BASEBOARD_FAB2_LIB.BASEBOARD_FAB2(SCH_1):M_H_DQ(27)
 183 M_H_DQ<24> DQ<25> @BASEBOARD_FAB2_LIB.BASEBOARD_FAB2(SCH_1):M_H_DQ(24)
  38 M_H_DQ<25> DQ<24> @BASEBOARD_FAB2_LIB.BASEBOARD_FAB2(SCH_1):M_H_DQ(25)
 177 M_H_DQ<22> DQ<23> @BASEBOARD_FAB2_LIB.BASEBOARD_FAB2(SCH_1):M_H_DQ(22)
  32 M_H_DQ<23> DQ<22> @BASEBOARD_FAB2_LIB.BASEBOARD_FAB2(SCH_1):M_H_DQ(23)
 170 M_H_DQ<20> DQ<21> @BASEBOARD_FAB2_LIB.BASEBOARD_FAB2(SCH_1):M_H_DQ(20)
  25 M_H_DQ<21> DQ<20> @BASEBOARD_FAB2_LIB.BASEBOARD_FAB2(SCH_1):M_H_DQ(21)
 179 M_H_DQ<18> DQ<19> @BASEBOARD_FAB2_LIB.BASEBOARD_FAB2(SCH_1):M_H_DQ(18)
  34 M_H_DQ<19> DQ<18> @BASEBOARD_FAB2_LIB.BASEBOARD_FAB2(SCH_1):M_H_DQ(19)
 172 M_H_DQ<16> DQ<17> @BASEBOARD_FAB2_LIB.BASEBOARD_FAB2(SCH_1):M_H_DQ(16)
  27 M_H_DQ<17> DQ<16> @BASEBOARD_FAB2_LIB.BASEBOARD_FAB2(SCH_1):M_H_DQ(17)
 166 M_H_DQ<14> DQ<15> @BASEBOARD_FAB2_LIB.BASEBOARD_FAB2(SCH_1):M_H_DQ(14)
  21 M_H_DQ<15> DQ<14> @BASEBOARD_FAB2_LIB.BASEBOARD_FAB2(SCH_1):M_H_DQ(15)
 159 M_H_DQ<12> DQ<13> @BASEBOARD_FAB2_LIB.BASEBOARD_FAB2(SCH_1):M_H_DQ(12)
  14 M_H_DQ<13> DQ<12> @BASEBOARD_FAB2_LIB.BASEBOARD_FAB2(SCH_1):M_H_DQ(13)
 168 M_H_DQ<10> DQ<11> @BASEBOARD_FAB2_LIB.BASEBOARD_FAB2(SCH_1):M_H_DQ(10)
  23 M_H_DQ<11> DQ<10> @BASEBOARD_FAB2_LIB.BASEBOARD_FAB2(SCH_1):M_H_DQ(11)
 161 M_H_DQ<8>  DQ<9> @BASEBOARD_FAB2_LIB.BASEBOARD_FAB2(SCH_1):M_H_DQ(8)
  16 M_H_DQ<9>  DQ<8> @BASEBOARD_FAB2_LIB.BASEBOARD_FAB2(SCH_1):M_H_DQ(9)
 155 M_H_DQ<6>  DQ<7> @BASEBOARD_FAB2_LIB.BASEBOARD_FAB2(SCH_1):M_H_DQ(6)
  10 M_H_DQ<7>  DQ<6> @BASEBOARD_FAB2_LIB.BASEBOARD_FAB2(SCH_1):M_H_DQ(7)
 148 M_H_DQ<4>  DQ<5> @BASEBOARD_FAB2_LIB.BASEBOARD_FAB2(SCH_1):M_H_DQ(4)
   3 M_H_DQ<5>  DQ<4> @BASEBOARD_FAB2_LIB.BASEBOARD_FAB2(SCH_1):M_H_DQ(5)
 157 M_H_DQ<2>  DQ<3> @BASEBOARD_FAB2_LIB.BASEBOARD_FAB2(SCH_1):M_H_DQ(2)
  12 M_H_DQ<3>  DQ<2> @BASEBOARD_FAB2_LIB.BASEBOARD_FAB2(SCH_1):M_H_DQ(3)
 150 M_H_DQ<0>  DQ<1> @BASEBOARD_FAB2_LIB.BASEBOARD_FAB2(SCH_1):M_H_DQ(0)
   5 M_H_DQ<1>  DQ<0> @BASEBOARD_FAB2_LIB.BASEBOARD_FAB2(SCH_1):M_H_DQ(1)
  78 FM_DIMM_EVENT_COD_N EVENT_N @BASEBOARD_FAB2_LIB.BASEBOARD_FAB2(SCH_1):FM_DIMM_EVENT_COD_N
  91 M_H_ODT<1> ODT<1> @BASEBOARD_FAB2_LIB.BASEBOARD_FAB2(SCH_1):M_H_ODT(1)
  87 M_H_ODT<0> ODT<0> @BASEBOARD_FAB2_LIB.BASEBOARD_FAB2(SCH_1):M_H_ODT(0)
 222 M_H_PAR    PAR @BASEBOARD_FAB2_LIB.BASEBOARD_FAB2(SCH_1):M_H_PAR
  58 M_GHJ_RST_N RESET_N @BASEBOARD_FAB2_LIB.BASEBOARD_FAB2(SCH_1):M_GHJ_RST_N
 144 TP_CH_H_DIMM_H0_RFU_2 RFU<2> @BASEBOARD_FAB2_LIB.BASEBOARD_FAB2(SCH_1):TP_CH_H_DIMM_H0_RFU_2
 227 TP_CH_H_DIMM_H0_RFU_1 RFU<1> @BASEBOARD_FAB2_LIB.BASEBOARD_FAB2(SCH_1):TP_CH_H_DIMM_H0_RFU_1
 205 TP_CH_H_DIMM_H0_RFU_0 RFU<0> @BASEBOARD_FAB2_LIB.BASEBOARD_FAB2(SCH_1):TP_CH_H_DIMM_H0_RFU_0
  84 M_H_CS_N<0>   S0_N @BASEBOARD_FAB2_LIB.BASEBOARD_FAB2(SCH_1):M_H_CS_N(0)
  89 M_H_CS_N<1>   S1_N @BASEBOARD_FAB2_LIB.BASEBOARD_FAB2(SCH_1):M_H_CS_N(1)
  93 M_H_CS_N<2> S2_N_C<0> @BASEBOARD_FAB2_LIB.BASEBOARD_FAB2(SCH_1):M_H_CS_N(2)
 237 M_H_CS_N<3> S3_N_C<1> @BASEBOARD_FAB2_LIB.BASEBOARD_FAB2(SCH_1):M_H_CS_N(3)
 238    GND  SA<2> @BASEBOARD_FAB2_LIB.BASEBOARD_FAB2(SCH_1):GND
 140 PVPP_GHJ  SA<1> @BASEBOARD_FAB2_LIB.BASEBOARD_FAB2(SCH_1):PVPP_GHJ
 139    GND  SA<0> @BASEBOARD_FAB2_LIB.BASEBOARD_FAB2(SCH_1):GND
 230 FM_ADR_COMPLETE_GHJ_N SAVE_N_NC @BASEBOARD_FAB2_LIB.BASEBOARD_FAB2(SCH_1):FM_ADR_COMPLETE_GHJ_N
 141 SMB_DDR_GHJ_VPP_SCL    SCL @BASEBOARD_FAB2_LIB.BASEBOARD_FAB2(SCH_1):SMB_DDR_GHJ_VPP_SCL
 285 SMB_DDR_GHJ_VPP_SDA    SDA @BASEBOARD_FAB2_LIB.BASEBOARD_FAB2(SCH_1):SMB_DDR_GHJ_VPP_SDA
 284 PVPP_GHJ VDDSPD @BASEBOARD_FAB2_LIB.BASEBOARD_FAB2(SCH_1):PVPP_GHJ
 146 M_H_VREF VREFCA @BASEBOARD_FAB2_LIB.BASEBOARD_FAB2(SCH_1):M_H_VREF

SCONN288_H44441004_PIP-SCONN,HA  I169  J1G2
   1 P12V_NVDIMM_GHJ 12V<1> @BASEBOARD_FAB2_LIB.BASEBOARD_FAB2(SCH_1):P12V_NVDIMM_GHJ
 145 P12V_NVDIMM_GHJ 12V<0> @BASEBOARD_FAB2_LIB.BASEBOARD_FAB2(SCH_1):P12V_NVDIMM_GHJ
  59 PVDDQ_GHJ VDD<25> @BASEBOARD_FAB2_LIB.BASEBOARD_FAB2(SCH_1):PVDDQ_GHJ
  61 PVDDQ_GHJ VDD<24> @BASEBOARD_FAB2_LIB.BASEBOARD_FAB2(SCH_1):PVDDQ_GHJ
  64 PVDDQ_GHJ VDD<23> @BASEBOARD_FAB2_LIB.BASEBOARD_FAB2(SCH_1):PVDDQ_GHJ
  67 PVDDQ_GHJ VDD<22> @BASEBOARD_FAB2_LIB.BASEBOARD_FAB2(SCH_1):PVDDQ_GHJ
  70 PVDDQ_GHJ VDD<21> @BASEBOARD_FAB2_LIB.BASEBOARD_FAB2(SCH_1):PVDDQ_GHJ
  73 PVDDQ_GHJ VDD<20> @BASEBOARD_FAB2_LIB.BASEBOARD_FAB2(SCH_1):PVDDQ_GHJ
  76 PVDDQ_GHJ VDD<19> @BASEBOARD_FAB2_LIB.BASEBOARD_FAB2(SCH_1):PVDDQ_GHJ
  80 PVDDQ_GHJ VDD<18> @BASEBOARD_FAB2_LIB.BASEBOARD_FAB2(SCH_1):PVDDQ_GHJ
  83 PVDDQ_GHJ VDD<17> @BASEBOARD_FAB2_LIB.BASEBOARD_FAB2(SCH_1):PVDDQ_GHJ
  85 PVDDQ_GHJ VDD<16> @BASEBOARD_FAB2_LIB.BASEBOARD_FAB2(SCH_1):PVDDQ_GHJ
  88 PVDDQ_GHJ VDD<15> @BASEBOARD_FAB2_LIB.BASEBOARD_FAB2(SCH_1):PVDDQ_GHJ
  90 PVDDQ_GHJ VDD<14> @BASEBOARD_FAB2_LIB.BASEBOARD_FAB2(SCH_1):PVDDQ_GHJ
  92 PVDDQ_GHJ VDD<13> @BASEBOARD_FAB2_LIB.BASEBOARD_FAB2(SCH_1):PVDDQ_GHJ
 204 PVDDQ_GHJ VDD<12> @BASEBOARD_FAB2_LIB.BASEBOARD_FAB2(SCH_1):PVDDQ_GHJ
 206 PVDDQ_GHJ VDD<11> @BASEBOARD_FAB2_LIB.BASEBOARD_FAB2(SCH_1):PVDDQ_GHJ
 209 PVDDQ_GHJ VDD<10> @BASEBOARD_FAB2_LIB.BASEBOARD_FAB2(SCH_1):PVDDQ_GHJ
 212 PVDDQ_GHJ VDD<9> @BASEBOARD_FAB2_LIB.BASEBOARD_FAB2(SCH_1):PVDDQ_GHJ
 215 PVDDQ_GHJ VDD<8> @BASEBOARD_FAB2_LIB.BASEBOARD_FAB2(SCH_1):PVDDQ_GHJ
 217 PVDDQ_GHJ VDD<7> @BASEBOARD_FAB2_LIB.BASEBOARD_FAB2(SCH_1):PVDDQ_GHJ
 220 PVDDQ_GHJ VDD<6> @BASEBOARD_FAB2_LIB.BASEBOARD_FAB2(SCH_1):PVDDQ_GHJ
 223 PVDDQ_GHJ VDD<5> @BASEBOARD_FAB2_LIB.BASEBOARD_FAB2(SCH_1):PVDDQ_GHJ
 226 PVDDQ_GHJ VDD<4> @BASEBOARD_FAB2_LIB.BASEBOARD_FAB2(SCH_1):PVDDQ_GHJ
 229 PVDDQ_GHJ VDD<3> @BASEBOARD_FAB2_LIB.BASEBOARD_FAB2(SCH_1):PVDDQ_GHJ
 231 PVDDQ_GHJ VDD<2> @BASEBOARD_FAB2_LIB.BASEBOARD_FAB2(SCH_1):PVDDQ_GHJ
 233 PVDDQ_GHJ VDD<1> @BASEBOARD_FAB2_LIB.BASEBOARD_FAB2(SCH_1):PVDDQ_GHJ
 236 PVDDQ_GHJ VDD<0> @BASEBOARD_FAB2_LIB.BASEBOARD_FAB2(SCH_1):PVDDQ_GHJ
 142 PVPP_GHJ VPP<4> @BASEBOARD_FAB2_LIB.BASEBOARD_FAB2(SCH_1):PVPP_GHJ
 143 PVPP_GHJ VPP<3> @BASEBOARD_FAB2_LIB.BASEBOARD_FAB2(SCH_1):PVPP_GHJ
 288 PVPP_GHJ VPP<2> @BASEBOARD_FAB2_LIB.BASEBOARD_FAB2(SCH_1):PVPP_GHJ
 286 PVPP_GHJ VPP<1> @BASEBOARD_FAB2_LIB.BASEBOARD_FAB2(SCH_1):PVPP_GHJ
 287 PVPP_GHJ VPP<0> @BASEBOARD_FAB2_LIB.BASEBOARD_FAB2(SCH_1):PVPP_GHJ
  77 PVTT_GHJ VTT<1> @BASEBOARD_FAB2_LIB.BASEBOARD_FAB2(SCH_1):PVTT_GHJ
 221 PVTT_GHJ VTT<0> @BASEBOARD_FAB2_LIB.BASEBOARD_FAB2(SCH_1):PVTT_GHJ

CAP_A_0402V-0.01UF,25V,10%,X7RA  I178  C9U7
   1 M_H_VREF      A @BASEBOARD_FAB2_LIB.BASEBOARD_FAB2(SCH_1):M_H_VREF
   2    GND      B @BASEBOARD_FAB2_LIB.BASEBOARD_FAB2(SCH_1):GND


DRAWING: @BASEBOARD_FAB2_LIB.BASEBOARD_FAB2(SCH_1):PAGE80 

CAP_A_0402V-0.01UF,25V,10%,X7RA  I3  C1G10
   1 M_H_VREF      A @BASEBOARD_FAB2_LIB.BASEBOARD_FAB2(SCH_1):M_H_VREF
   2    GND      B @BASEBOARD_FAB2_LIB.BASEBOARD_FAB2(SCH_1):GND

SCONN288_H44441003_PIP-SCONN,HA  I24  J9U1
  79 M_H_MA<0>     A0 @BASEBOARD_FAB2_LIB.BASEBOARD_FAB2(SCH_1):M_H_MA(0)
  72 M_H_MA<1>     A1 @BASEBOARD_FAB2_LIB.BASEBOARD_FAB2(SCH_1):M_H_MA(1)
 225 M_H_MA<10>    A10 @BASEBOARD_FAB2_LIB.BASEBOARD_FAB2(SCH_1):M_H_MA(10)
 210 M_H_MA<11>    A11 @BASEBOARD_FAB2_LIB.BASEBOARD_FAB2(SCH_1):M_H_MA(11)
  65 M_H_MA<12>    A12 @BASEBOARD_FAB2_LIB.BASEBOARD_FAB2(SCH_1):M_H_MA(12)
 232 M_H_MA<13>    A13 @BASEBOARD_FAB2_LIB.BASEBOARD_FAB2(SCH_1):M_H_MA(13)
 228 M_H_MA<14> A14_WE_N @BASEBOARD_FAB2_LIB.BASEBOARD_FAB2(SCH_1):M_H_MA(14)
  86 M_H_MA<15> A15_CAS_N @BASEBOARD_FAB2_LIB.BASEBOARD_FAB2(SCH_1):M_H_MA(15)
  82 M_H_MA<16> A16_RAS_N @BASEBOARD_FAB2_LIB.BASEBOARD_FAB2(SCH_1):M_H_MA(16)
 234 M_H_MA<17>    A17 @BASEBOARD_FAB2_LIB.BASEBOARD_FAB2(SCH_1):M_H_MA(17)
 216 M_H_MA<2>     A2 @BASEBOARD_FAB2_LIB.BASEBOARD_FAB2(SCH_1):M_H_MA(2)
  71 M_H_MA<3>     A3 @BASEBOARD_FAB2_LIB.BASEBOARD_FAB2(SCH_1):M_H_MA(3)
 214 M_H_MA<4>     A4 @BASEBOARD_FAB2_LIB.BASEBOARD_FAB2(SCH_1):M_H_MA(4)
 213 M_H_MA<5>     A5 @BASEBOARD_FAB2_LIB.BASEBOARD_FAB2(SCH_1):M_H_MA(5)
  69 M_H_MA<6>     A6 @BASEBOARD_FAB2_LIB.BASEBOARD_FAB2(SCH_1):M_H_MA(6)
 211 M_H_MA<7>     A7 @BASEBOARD_FAB2_LIB.BASEBOARD_FAB2(SCH_1):M_H_MA(7)
  68 M_H_MA<8>     A8 @BASEBOARD_FAB2_LIB.BASEBOARD_FAB2(SCH_1):M_H_MA(8)
  66 M_H_MA<9>     A9 @BASEBOARD_FAB2_LIB.BASEBOARD_FAB2(SCH_1):M_H_MA(9)
  62 M_H_ACT_N  ACT_N @BASEBOARD_FAB2_LIB.BASEBOARD_FAB2(SCH_1):M_H_ACT_N
 208 M_H_ALERT_N ALERT_N @BASEBOARD_FAB2_LIB.BASEBOARD_FAB2(SCH_1):M_H_ALERT_N
 224 M_H_BA<1>  BA<1> @BASEBOARD_FAB2_LIB.BASEBOARD_FAB2(SCH_1):M_H_BA(1)
  81 M_H_BA<0>  BA<0> @BASEBOARD_FAB2_LIB.BASEBOARD_FAB2(SCH_1):M_H_BA(0)
 207 M_H_BG<1>  BG<1> @BASEBOARD_FAB2_LIB.BASEBOARD_FAB2(SCH_1):M_H_BG(1)
  63 M_H_BG<0>  BG<0> @BASEBOARD_FAB2_LIB.BASEBOARD_FAB2(SCH_1):M_H_BG(0)
 235 M_H_C<2>   C<2> @BASEBOARD_FAB2_LIB.BASEBOARD_FAB2(SCH_1):M_H_C(2)
 199 M_H_ECC<7>  CB<7> @BASEBOARD_FAB2_LIB.BASEBOARD_FAB2(SCH_1):M_H_ECC(7)
  54 M_H_ECC<6>  CB<6> @BASEBOARD_FAB2_LIB.BASEBOARD_FAB2(SCH_1):M_H_ECC(6)
 192 M_H_ECC<5>  CB<5> @BASEBOARD_FAB2_LIB.BASEBOARD_FAB2(SCH_1):M_H_ECC(5)
  47 M_H_ECC<4>  CB<4> @BASEBOARD_FAB2_LIB.BASEBOARD_FAB2(SCH_1):M_H_ECC(4)
 201 M_H_ECC<3>  CB<3> @BASEBOARD_FAB2_LIB.BASEBOARD_FAB2(SCH_1):M_H_ECC(3)
  56 M_H_ECC<2>  CB<2> @BASEBOARD_FAB2_LIB.BASEBOARD_FAB2(SCH_1):M_H_ECC(2)
 194 M_H_ECC<1>  CB<1> @BASEBOARD_FAB2_LIB.BASEBOARD_FAB2(SCH_1):M_H_ECC(1)
  49 M_H_ECC<0>  CB<0> @BASEBOARD_FAB2_LIB.BASEBOARD_FAB2(SCH_1):M_H_ECC(0)
  75 M_H_CLK_DN<2>   CK0N @BASEBOARD_FAB2_LIB.BASEBOARD_FAB2(SCH_1):M_H_CLK_DN(2)
  74 M_H_CLK_DP<2>   CK0P @BASEBOARD_FAB2_LIB.BASEBOARD_FAB2(SCH_1):M_H_CLK_DP(2)
 219 M_H_CLK_DN<3>   CK1N @BASEBOARD_FAB2_LIB.BASEBOARD_FAB2(SCH_1):M_H_CLK_DN(3)
 218 M_H_CLK_DP<3>   CK1P @BASEBOARD_FAB2_LIB.BASEBOARD_FAB2(SCH_1):M_H_CLK_DP(3)
 203 M_H_CKE<3> CKE<1> @BASEBOARD_FAB2_LIB.BASEBOARD_FAB2(SCH_1):M_H_CKE(3)
  60 M_H_CKE<2> CKE<0> @BASEBOARD_FAB2_LIB.BASEBOARD_FAB2(SCH_1):M_H_CKE(2)
 280 M_H_DQ<63> DQ<63> @BASEBOARD_FAB2_LIB.BASEBOARD_FAB2(SCH_1):M_H_DQ(63)
 135 M_H_DQ<62> DQ<62> @BASEBOARD_FAB2_LIB.BASEBOARD_FAB2(SCH_1):M_H_DQ(62)
 273 M_H_DQ<61> DQ<61> @BASEBOARD_FAB2_LIB.BASEBOARD_FAB2(SCH_1):M_H_DQ(61)
 128 M_H_DQ<60> DQ<60> @BASEBOARD_FAB2_LIB.BASEBOARD_FAB2(SCH_1):M_H_DQ(60)
 282 M_H_DQ<59> DQ<59> @BASEBOARD_FAB2_LIB.BASEBOARD_FAB2(SCH_1):M_H_DQ(59)
 137 M_H_DQ<58> DQ<58> @BASEBOARD_FAB2_LIB.BASEBOARD_FAB2(SCH_1):M_H_DQ(58)
 275 M_H_DQ<57> DQ<57> @BASEBOARD_FAB2_LIB.BASEBOARD_FAB2(SCH_1):M_H_DQ(57)
 130 M_H_DQ<56> DQ<56> @BASEBOARD_FAB2_LIB.BASEBOARD_FAB2(SCH_1):M_H_DQ(56)
 269 M_H_DQ<55> DQ<55> @BASEBOARD_FAB2_LIB.BASEBOARD_FAB2(SCH_1):M_H_DQ(55)
 124 M_H_DQ<54> DQ<54> @BASEBOARD_FAB2_LIB.BASEBOARD_FAB2(SCH_1):M_H_DQ(54)
 262 M_H_DQ<53> DQ<53> @BASEBOARD_FAB2_LIB.BASEBOARD_FAB2(SCH_1):M_H_DQ(53)
 117 M_H_DQ<52> DQ<52> @BASEBOARD_FAB2_LIB.BASEBOARD_FAB2(SCH_1):M_H_DQ(52)
 271 M_H_DQ<51> DQ<51> @BASEBOARD_FAB2_LIB.BASEBOARD_FAB2(SCH_1):M_H_DQ(51)
 126 M_H_DQ<50> DQ<50> @BASEBOARD_FAB2_LIB.BASEBOARD_FAB2(SCH_1):M_H_DQ(50)
 264 M_H_DQ<49> DQ<49> @BASEBOARD_FAB2_LIB.BASEBOARD_FAB2(SCH_1):M_H_DQ(49)
 119 M_H_DQ<48> DQ<48> @BASEBOARD_FAB2_LIB.BASEBOARD_FAB2(SCH_1):M_H_DQ(48)
 258 M_H_DQ<47> DQ<47> @BASEBOARD_FAB2_LIB.BASEBOARD_FAB2(SCH_1):M_H_DQ(47)
 113 M_H_DQ<46> DQ<46> @BASEBOARD_FAB2_LIB.BASEBOARD_FAB2(SCH_1):M_H_DQ(46)
 251 M_H_DQ<45> DQ<45> @BASEBOARD_FAB2_LIB.BASEBOARD_FAB2(SCH_1):M_H_DQ(45)
 106 M_H_DQ<44> DQ<44> @BASEBOARD_FAB2_LIB.BASEBOARD_FAB2(SCH_1):M_H_DQ(44)
 260 M_H_DQ<43> DQ<43> @BASEBOARD_FAB2_LIB.BASEBOARD_FAB2(SCH_1):M_H_DQ(43)
 115 M_H_DQ<42> DQ<42> @BASEBOARD_FAB2_LIB.BASEBOARD_FAB2(SCH_1):M_H_DQ(42)
 253 M_H_DQ<41> DQ<41> @BASEBOARD_FAB2_LIB.BASEBOARD_FAB2(SCH_1):M_H_DQ(41)
 108 M_H_DQ<40> DQ<40> @BASEBOARD_FAB2_LIB.BASEBOARD_FAB2(SCH_1):M_H_DQ(40)
 247 M_H_DQ<39> DQ<39> @BASEBOARD_FAB2_LIB.BASEBOARD_FAB2(SCH_1):M_H_DQ(39)
 102 M_H_DQ<38> DQ<38> @BASEBOARD_FAB2_LIB.BASEBOARD_FAB2(SCH_1):M_H_DQ(38)
 240 M_H_DQ<37> DQ<37> @BASEBOARD_FAB2_LIB.BASEBOARD_FAB2(SCH_1):M_H_DQ(37)
  95 M_H_DQ<36> DQ<36> @BASEBOARD_FAB2_LIB.BASEBOARD_FAB2(SCH_1):M_H_DQ(36)
 249 M_H_DQ<35> DQ<35> @BASEBOARD_FAB2_LIB.BASEBOARD_FAB2(SCH_1):M_H_DQ(35)
 104 M_H_DQ<34> DQ<34> @BASEBOARD_FAB2_LIB.BASEBOARD_FAB2(SCH_1):M_H_DQ(34)
 242 M_H_DQ<33> DQ<33> @BASEBOARD_FAB2_LIB.BASEBOARD_FAB2(SCH_1):M_H_DQ(33)
  97 M_H_DQ<32> DQ<32> @BASEBOARD_FAB2_LIB.BASEBOARD_FAB2(SCH_1):M_H_DQ(32)
 188 M_H_DQ<31> DQ<31> @BASEBOARD_FAB2_LIB.BASEBOARD_FAB2(SCH_1):M_H_DQ(31)
  43 M_H_DQ<30> DQ<30> @BASEBOARD_FAB2_LIB.BASEBOARD_FAB2(SCH_1):M_H_DQ(30)
 181 M_H_DQ<29> DQ<29> @BASEBOARD_FAB2_LIB.BASEBOARD_FAB2(SCH_1):M_H_DQ(29)
  36 M_H_DQ<28> DQ<28> @BASEBOARD_FAB2_LIB.BASEBOARD_FAB2(SCH_1):M_H_DQ(28)
 190 M_H_DQ<27> DQ<27> @BASEBOARD_FAB2_LIB.BASEBOARD_FAB2(SCH_1):M_H_DQ(27)
  45 M_H_DQ<26> DQ<26> @BASEBOARD_FAB2_LIB.BASEBOARD_FAB2(SCH_1):M_H_DQ(26)
 183 M_H_DQ<25> DQ<25> @BASEBOARD_FAB2_LIB.BASEBOARD_FAB2(SCH_1):M_H_DQ(25)
  38 M_H_DQ<24> DQ<24> @BASEBOARD_FAB2_LIB.BASEBOARD_FAB2(SCH_1):M_H_DQ(24)
 177 M_H_DQ<23> DQ<23> @BASEBOARD_FAB2_LIB.BASEBOARD_FAB2(SCH_1):M_H_DQ(23)
  32 M_H_DQ<22> DQ<22> @BASEBOARD_FAB2_LIB.BASEBOARD_FAB2(SCH_1):M_H_DQ(22)
 170 M_H_DQ<21> DQ<21> @BASEBOARD_FAB2_LIB.BASEBOARD_FAB2(SCH_1):M_H_DQ(21)
  25 M_H_DQ<20> DQ<20> @BASEBOARD_FAB2_LIB.BASEBOARD_FAB2(SCH_1):M_H_DQ(20)
 179 M_H_DQ<19> DQ<19> @BASEBOARD_FAB2_LIB.BASEBOARD_FAB2(SCH_1):M_H_DQ(19)
  34 M_H_DQ<18> DQ<18> @BASEBOARD_FAB2_LIB.BASEBOARD_FAB2(SCH_1):M_H_DQ(18)
 172 M_H_DQ<17> DQ<17> @BASEBOARD_FAB2_LIB.BASEBOARD_FAB2(SCH_1):M_H_DQ(17)
  27 M_H_DQ<16> DQ<16> @BASEBOARD_FAB2_LIB.BASEBOARD_FAB2(SCH_1):M_H_DQ(16)
 166 M_H_DQ<15> DQ<15> @BASEBOARD_FAB2_LIB.BASEBOARD_FAB2(SCH_1):M_H_DQ(15)
  21 M_H_DQ<14> DQ<14> @BASEBOARD_FAB2_LIB.BASEBOARD_FAB2(SCH_1):M_H_DQ(14)
 159 M_H_DQ<13> DQ<13> @BASEBOARD_FAB2_LIB.BASEBOARD_FAB2(SCH_1):M_H_DQ(13)
  14 M_H_DQ<12> DQ<12> @BASEBOARD_FAB2_LIB.BASEBOARD_FAB2(SCH_1):M_H_DQ(12)
 168 M_H_DQ<11> DQ<11> @BASEBOARD_FAB2_LIB.BASEBOARD_FAB2(SCH_1):M_H_DQ(11)
  23 M_H_DQ<10> DQ<10> @BASEBOARD_FAB2_LIB.BASEBOARD_FAB2(SCH_1):M_H_DQ(10)
 161 M_H_DQ<9>  DQ<9> @BASEBOARD_FAB2_LIB.BASEBOARD_FAB2(SCH_1):M_H_DQ(9)
  16 M_H_DQ<8>  DQ<8> @BASEBOARD_FAB2_LIB.BASEBOARD_FAB2(SCH_1):M_H_DQ(8)
 155 M_H_DQ<7>  DQ<7> @BASEBOARD_FAB2_LIB.BASEBOARD_FAB2(SCH_1):M_H_DQ(7)
  10 M_H_DQ<6>  DQ<6> @BASEBOARD_FAB2_LIB.BASEBOARD_FAB2(SCH_1):M_H_DQ(6)
 148 M_H_DQ<5>  DQ<5> @BASEBOARD_FAB2_LIB.BASEBOARD_FAB2(SCH_1):M_H_DQ(5)
   3 M_H_DQ<4>  DQ<4> @BASEBOARD_FAB2_LIB.BASEBOARD_FAB2(SCH_1):M_H_DQ(4)
 157 M_H_DQ<3>  DQ<3> @BASEBOARD_FAB2_LIB.BASEBOARD_FAB2(SCH_1):M_H_DQ(3)
  12 M_H_DQ<2>  DQ<2> @BASEBOARD_FAB2_LIB.BASEBOARD_FAB2(SCH_1):M_H_DQ(2)
 150 M_H_DQ<1>  DQ<1> @BASEBOARD_FAB2_LIB.BASEBOARD_FAB2(SCH_1):M_H_DQ(1)
   5 M_H_DQ<0>  DQ<0> @BASEBOARD_FAB2_LIB.BASEBOARD_FAB2(SCH_1):M_H_DQ(0)
  78 FM_DIMM_EVENT_COD_N EVENT_N @BASEBOARD_FAB2_LIB.BASEBOARD_FAB2(SCH_1):FM_DIMM_EVENT_COD_N
  91 M_H_ODT<3> ODT<1> @BASEBOARD_FAB2_LIB.BASEBOARD_FAB2(SCH_1):M_H_ODT(3)
  87 M_H_ODT<2> ODT<0> @BASEBOARD_FAB2_LIB.BASEBOARD_FAB2(SCH_1):M_H_ODT(2)
 222 M_H_PAR    PAR @BASEBOARD_FAB2_LIB.BASEBOARD_FAB2(SCH_1):M_H_PAR
  58 M_GHJ_RST_N RESET_N @BASEBOARD_FAB2_LIB.BASEBOARD_FAB2(SCH_1):M_GHJ_RST_N
 144 TP_CH_H_DIMM0_RFU_2 RFU<2> @BASEBOARD_FAB2_LIB.BASEBOARD_FAB2(SCH_1):TP_CH_H_DIMM0_RFU_2
 227 TP_CH_H_DIMM0_RFU_1 RFU<1> @BASEBOARD_FAB2_LIB.BASEBOARD_FAB2(SCH_1):TP_CH_H_DIMM0_RFU_1
 205 TP_CH_H_DIMM0_RFU_0 RFU<0> @BASEBOARD_FAB2_LIB.BASEBOARD_FAB2(SCH_1):TP_CH_H_DIMM0_RFU_0
  84 M_H_CS_N<4>   S0_N @BASEBOARD_FAB2_LIB.BASEBOARD_FAB2(SCH_1):M_H_CS_N(4)
  89 M_H_CS_N<5>   S1_N @BASEBOARD_FAB2_LIB.BASEBOARD_FAB2(SCH_1):M_H_CS_N(5)
  93 M_H_CS_N<6> S2_N_C<0> @BASEBOARD_FAB2_LIB.BASEBOARD_FAB2(SCH_1):M_H_CS_N(6)
 237 M_H_CS_N<7> S3_N_C<1> @BASEBOARD_FAB2_LIB.BASEBOARD_FAB2(SCH_1):M_H_CS_N(7)
 238    GND  SA<2> @BASEBOARD_FAB2_LIB.BASEBOARD_FAB2(SCH_1):GND
 140 PVPP_GHJ  SA<1> @BASEBOARD_FAB2_LIB.BASEBOARD_FAB2(SCH_1):PVPP_GHJ
 139 PVPP_GHJ  SA<0> @BASEBOARD_FAB2_LIB.BASEBOARD_FAB2(SCH_1):PVPP_GHJ
 230 FM_ADR_COMPLETE_GHJ_N SAVE_N_NC @BASEBOARD_FAB2_LIB.BASEBOARD_FAB2(SCH_1):FM_ADR_COMPLETE_GHJ_N
 141 SMB_DDR_GHJ_VPP_SCL    SCL @BASEBOARD_FAB2_LIB.BASEBOARD_FAB2(SCH_1):SMB_DDR_GHJ_VPP_SCL
 285 SMB_DDR_GHJ_VPP_SDA    SDA @BASEBOARD_FAB2_LIB.BASEBOARD_FAB2(SCH_1):SMB_DDR_GHJ_VPP_SDA
 284 PVPP_GHJ VDDSPD @BASEBOARD_FAB2_LIB.BASEBOARD_FAB2(SCH_1):PVPP_GHJ
 146 M_H_VREF VREFCA @BASEBOARD_FAB2_LIB.BASEBOARD_FAB2(SCH_1):M_H_VREF

SCONN288_H44441003_PIP-SCONN,HA  I56  J9U1
   1 P12V_NVDIMM_GHJ 12V<1> @BASEBOARD_FAB2_LIB.BASEBOARD_FAB2(SCH_1):P12V_NVDIMM_GHJ
 145 P12V_NVDIMM_GHJ 12V<0> @BASEBOARD_FAB2_LIB.BASEBOARD_FAB2(SCH_1):P12V_NVDIMM_GHJ
  59 PVDDQ_GHJ VDD<25> @BASEBOARD_FAB2_LIB.BASEBOARD_FAB2(SCH_1):PVDDQ_GHJ
  61 PVDDQ_GHJ VDD<24> @BASEBOARD_FAB2_LIB.BASEBOARD_FAB2(SCH_1):PVDDQ_GHJ
  64 PVDDQ_GHJ VDD<23> @BASEBOARD_FAB2_LIB.BASEBOARD_FAB2(SCH_1):PVDDQ_GHJ
  67 PVDDQ_GHJ VDD<22> @BASEBOARD_FAB2_LIB.BASEBOARD_FAB2(SCH_1):PVDDQ_GHJ
  70 PVDDQ_GHJ VDD<21> @BASEBOARD_FAB2_LIB.BASEBOARD_FAB2(SCH_1):PVDDQ_GHJ
  73 PVDDQ_GHJ VDD<20> @BASEBOARD_FAB2_LIB.BASEBOARD_FAB2(SCH_1):PVDDQ_GHJ
  76 PVDDQ_GHJ VDD<19> @BASEBOARD_FAB2_LIB.BASEBOARD_FAB2(SCH_1):PVDDQ_GHJ
  80 PVDDQ_GHJ VDD<18> @BASEBOARD_FAB2_LIB.BASEBOARD_FAB2(SCH_1):PVDDQ_GHJ
  83 PVDDQ_GHJ VDD<17> @BASEBOARD_FAB2_LIB.BASEBOARD_FAB2(SCH_1):PVDDQ_GHJ
  85 PVDDQ_GHJ VDD<16> @BASEBOARD_FAB2_LIB.BASEBOARD_FAB2(SCH_1):PVDDQ_GHJ
  88 PVDDQ_GHJ VDD<15> @BASEBOARD_FAB2_LIB.BASEBOARD_FAB2(SCH_1):PVDDQ_GHJ
  90 PVDDQ_GHJ VDD<14> @BASEBOARD_FAB2_LIB.BASEBOARD_FAB2(SCH_1):PVDDQ_GHJ
  92 PVDDQ_GHJ VDD<13> @BASEBOARD_FAB2_LIB.BASEBOARD_FAB2(SCH_1):PVDDQ_GHJ
 204 PVDDQ_GHJ VDD<12> @BASEBOARD_FAB2_LIB.BASEBOARD_FAB2(SCH_1):PVDDQ_GHJ
 206 PVDDQ_GHJ VDD<11> @BASEBOARD_FAB2_LIB.BASEBOARD_FAB2(SCH_1):PVDDQ_GHJ
 209 PVDDQ_GHJ VDD<10> @BASEBOARD_FAB2_LIB.BASEBOARD_FAB2(SCH_1):PVDDQ_GHJ
 212 PVDDQ_GHJ VDD<9> @BASEBOARD_FAB2_LIB.BASEBOARD_FAB2(SCH_1):PVDDQ_GHJ
 215 PVDDQ_GHJ VDD<8> @BASEBOARD_FAB2_LIB.BASEBOARD_FAB2(SCH_1):PVDDQ_GHJ
 217 PVDDQ_GHJ VDD<7> @BASEBOARD_FAB2_LIB.BASEBOARD_FAB2(SCH_1):PVDDQ_GHJ
 220 PVDDQ_GHJ VDD<6> @BASEBOARD_FAB2_LIB.BASEBOARD_FAB2(SCH_1):PVDDQ_GHJ
 223 PVDDQ_GHJ VDD<5> @BASEBOARD_FAB2_LIB.BASEBOARD_FAB2(SCH_1):PVDDQ_GHJ
 226 PVDDQ_GHJ VDD<4> @BASEBOARD_FAB2_LIB.BASEBOARD_FAB2(SCH_1):PVDDQ_GHJ
 229 PVDDQ_GHJ VDD<3> @BASEBOARD_FAB2_LIB.BASEBOARD_FAB2(SCH_1):PVDDQ_GHJ
 231 PVDDQ_GHJ VDD<2> @BASEBOARD_FAB2_LIB.BASEBOARD_FAB2(SCH_1):PVDDQ_GHJ
 233 PVDDQ_GHJ VDD<1> @BASEBOARD_FAB2_LIB.BASEBOARD_FAB2(SCH_1):PVDDQ_GHJ
 236 PVDDQ_GHJ VDD<0> @BASEBOARD_FAB2_LIB.BASEBOARD_FAB2(SCH_1):PVDDQ_GHJ
 142 PVPP_GHJ VPP<4> @BASEBOARD_FAB2_LIB.BASEBOARD_FAB2(SCH_1):PVPP_GHJ
 143 PVPP_GHJ VPP<3> @BASEBOARD_FAB2_LIB.BASEBOARD_FAB2(SCH_1):PVPP_GHJ
 288 PVPP_GHJ VPP<2> @BASEBOARD_FAB2_LIB.BASEBOARD_FAB2(SCH_1):PVPP_GHJ
 286 PVPP_GHJ VPP<1> @BASEBOARD_FAB2_LIB.BASEBOARD_FAB2(SCH_1):PVPP_GHJ
 287 PVPP_GHJ VPP<0> @BASEBOARD_FAB2_LIB.BASEBOARD_FAB2(SCH_1):PVPP_GHJ
  77 PVTT_GHJ VTT<1> @BASEBOARD_FAB2_LIB.BASEBOARD_FAB2(SCH_1):PVTT_GHJ
 221 PVTT_GHJ VTT<0> @BASEBOARD_FAB2_LIB.BASEBOARD_FAB2(SCH_1):PVTT_GHJ

SCONN288_H44441003_PIP-SCONN,HA  I101  J9U1
 152 M_H_DQS_DN<0>  DQS0N @BASEBOARD_FAB2_LIB.BASEBOARD_FAB2(SCH_1):M_H_DQS_DN(0)
 153 M_H_DQS_DP<0>  DQS0P @BASEBOARD_FAB2_LIB.BASEBOARD_FAB2(SCH_1):M_H_DQS_DP(0)
  19 M_H_DQS_DN<10> DQS10N @BASEBOARD_FAB2_LIB.BASEBOARD_FAB2(SCH_1):M_H_DQS_DN(10)
  18 M_H_DQS_DP<10> DQS10P @BASEBOARD_FAB2_LIB.BASEBOARD_FAB2(SCH_1):M_H_DQS_DP(10)
  30 M_H_DQS_DN<11> DQS11N @BASEBOARD_FAB2_LIB.BASEBOARD_FAB2(SCH_1):M_H_DQS_DN(11)
  29 M_H_DQS_DP<11> DQS11P @BASEBOARD_FAB2_LIB.BASEBOARD_FAB2(SCH_1):M_H_DQS_DP(11)
  41 M_H_DQS_DN<12> DQS12N @BASEBOARD_FAB2_LIB.BASEBOARD_FAB2(SCH_1):M_H_DQS_DN(12)
  40 M_H_DQS_DP<12> DQS12P @BASEBOARD_FAB2_LIB.BASEBOARD_FAB2(SCH_1):M_H_DQS_DP(12)
 100 M_H_DQS_DN<13> DQS13N @BASEBOARD_FAB2_LIB.BASEBOARD_FAB2(SCH_1):M_H_DQS_DN(13)
  99 M_H_DQS_DP<13> DQS13P @BASEBOARD_FAB2_LIB.BASEBOARD_FAB2(SCH_1):M_H_DQS_DP(13)
 111 M_H_DQS_DN<14> DQS14N @BASEBOARD_FAB2_LIB.BASEBOARD_FAB2(SCH_1):M_H_DQS_DN(14)
 110 M_H_DQS_DP<14> DQS14P @BASEBOARD_FAB2_LIB.BASEBOARD_FAB2(SCH_1):M_H_DQS_DP(14)
 122 M_H_DQS_DN<15> DQS15N @BASEBOARD_FAB2_LIB.BASEBOARD_FAB2(SCH_1):M_H_DQS_DN(15)
 121 M_H_DQS_DP<15> DQS15P @BASEBOARD_FAB2_LIB.BASEBOARD_FAB2(SCH_1):M_H_DQS_DP(15)
 133 M_H_DQS_DN<16> DQS16N @BASEBOARD_FAB2_LIB.BASEBOARD_FAB2(SCH_1):M_H_DQS_DN(16)
 132 M_H_DQS_DP<16> DQS16P @BASEBOARD_FAB2_LIB.BASEBOARD_FAB2(SCH_1):M_H_DQS_DP(16)
  52 M_H_DQS_DN<17> DQS17N @BASEBOARD_FAB2_LIB.BASEBOARD_FAB2(SCH_1):M_H_DQS_DN(17)
  51 M_H_DQS_DP<17> DQS17P @BASEBOARD_FAB2_LIB.BASEBOARD_FAB2(SCH_1):M_H_DQS_DP(17)
 163 M_H_DQS_DN<1>  DQS1N @BASEBOARD_FAB2_LIB.BASEBOARD_FAB2(SCH_1):M_H_DQS_DN(1)
 164 M_H_DQS_DP<1>  DQS1P @BASEBOARD_FAB2_LIB.BASEBOARD_FAB2(SCH_1):M_H_DQS_DP(1)
 174 M_H_DQS_DN<2>  DQS2N @BASEBOARD_FAB2_LIB.BASEBOARD_FAB2(SCH_1):M_H_DQS_DN(2)
 175 M_H_DQS_DP<2>  DQS2P @BASEBOARD_FAB2_LIB.BASEBOARD_FAB2(SCH_1):M_H_DQS_DP(2)
 185 M_H_DQS_DN<3>  DQS3N @BASEBOARD_FAB2_LIB.BASEBOARD_FAB2(SCH_1):M_H_DQS_DN(3)
 186 M_H_DQS_DP<3>  DQS3P @BASEBOARD_FAB2_LIB.BASEBOARD_FAB2(SCH_1):M_H_DQS_DP(3)
 244 M_H_DQS_DN<4>  DQS4N @BASEBOARD_FAB2_LIB.BASEBOARD_FAB2(SCH_1):M_H_DQS_DN(4)
 245 M_H_DQS_DP<4>  DQS4P @BASEBOARD_FAB2_LIB.BASEBOARD_FAB2(SCH_1):M_H_DQS_DP(4)
 255 M_H_DQS_DN<5>  DQS5N @BASEBOARD_FAB2_LIB.BASEBOARD_FAB2(SCH_1):M_H_DQS_DN(5)
 256 M_H_DQS_DP<5>  DQS5P @BASEBOARD_FAB2_LIB.BASEBOARD_FAB2(SCH_1):M_H_DQS_DP(5)
 266 M_H_DQS_DN<6>  DQS6N @BASEBOARD_FAB2_LIB.BASEBOARD_FAB2(SCH_1):M_H_DQS_DN(6)
 267 M_H_DQS_DP<6>  DQS6P @BASEBOARD_FAB2_LIB.BASEBOARD_FAB2(SCH_1):M_H_DQS_DP(6)
 277 M_H_DQS_DN<7>  DQS7N @BASEBOARD_FAB2_LIB.BASEBOARD_FAB2(SCH_1):M_H_DQS_DN(7)
 278 M_H_DQS_DP<7>  DQS7P @BASEBOARD_FAB2_LIB.BASEBOARD_FAB2(SCH_1):M_H_DQS_DP(7)
 196 M_H_DQS_DN<8>  DQS8N @BASEBOARD_FAB2_LIB.BASEBOARD_FAB2(SCH_1):M_H_DQS_DN(8)
 197 M_H_DQS_DP<8>  DQS8P @BASEBOARD_FAB2_LIB.BASEBOARD_FAB2(SCH_1):M_H_DQS_DP(8)
   8 M_H_DQS_DN<9>  DQS9N @BASEBOARD_FAB2_LIB.BASEBOARD_FAB2(SCH_1):M_H_DQS_DN(9)
   7 M_H_DQS_DP<9>  DQS9P @BASEBOARD_FAB2_LIB.BASEBOARD_FAB2(SCH_1):M_H_DQS_DP(9)

SCONN288_H44441003_PIP-SCONN,HA  I138  J9U1
   2    GND VSS<93> @BASEBOARD_FAB2_LIB.BASEBOARD_FAB2(SCH_1):GND
   4    GND VSS<92> @BASEBOARD_FAB2_LIB.BASEBOARD_FAB2(SCH_1):GND
   6    GND VSS<91> @BASEBOARD_FAB2_LIB.BASEBOARD_FAB2(SCH_1):GND
   9    GND VSS<90> @BASEBOARD_FAB2_LIB.BASEBOARD_FAB2(SCH_1):GND
  11    GND VSS<89> @BASEBOARD_FAB2_LIB.BASEBOARD_FAB2(SCH_1):GND
  13    GND VSS<88> @BASEBOARD_FAB2_LIB.BASEBOARD_FAB2(SCH_1):GND
  15    GND VSS<87> @BASEBOARD_FAB2_LIB.BASEBOARD_FAB2(SCH_1):GND
  17    GND VSS<86> @BASEBOARD_FAB2_LIB.BASEBOARD_FAB2(SCH_1):GND
  20    GND VSS<85> @BASEBOARD_FAB2_LIB.BASEBOARD_FAB2(SCH_1):GND
  22    GND VSS<84> @BASEBOARD_FAB2_LIB.BASEBOARD_FAB2(SCH_1):GND
  24    GND VSS<83> @BASEBOARD_FAB2_LIB.BASEBOARD_FAB2(SCH_1):GND
  26    GND VSS<82> @BASEBOARD_FAB2_LIB.BASEBOARD_FAB2(SCH_1):GND
  28    GND VSS<81> @BASEBOARD_FAB2_LIB.BASEBOARD_FAB2(SCH_1):GND
  31    GND VSS<80> @BASEBOARD_FAB2_LIB.BASEBOARD_FAB2(SCH_1):GND
  33    GND VSS<79> @BASEBOARD_FAB2_LIB.BASEBOARD_FAB2(SCH_1):GND
  35    GND VSS<78> @BASEBOARD_FAB2_LIB.BASEBOARD_FAB2(SCH_1):GND
  37    GND VSS<77> @BASEBOARD_FAB2_LIB.BASEBOARD_FAB2(SCH_1):GND
  39    GND VSS<76> @BASEBOARD_FAB2_LIB.BASEBOARD_FAB2(SCH_1):GND
  42    GND VSS<75> @BASEBOARD_FAB2_LIB.BASEBOARD_FAB2(SCH_1):GND
  44    GND VSS<74> @BASEBOARD_FAB2_LIB.BASEBOARD_FAB2(SCH_1):GND
  46    GND VSS<73> @BASEBOARD_FAB2_LIB.BASEBOARD_FAB2(SCH_1):GND
  48    GND VSS<72> @BASEBOARD_FAB2_LIB.BASEBOARD_FAB2(SCH_1):GND
  50    GND VSS<71> @BASEBOARD_FAB2_LIB.BASEBOARD_FAB2(SCH_1):GND
  53    GND VSS<70> @BASEBOARD_FAB2_LIB.BASEBOARD_FAB2(SCH_1):GND
  55    GND VSS<69> @BASEBOARD_FAB2_LIB.BASEBOARD_FAB2(SCH_1):GND
  57    GND VSS<68> @BASEBOARD_FAB2_LIB.BASEBOARD_FAB2(SCH_1):GND
  94    GND VSS<67> @BASEBOARD_FAB2_LIB.BASEBOARD_FAB2(SCH_1):GND
  96    GND VSS<66> @BASEBOARD_FAB2_LIB.BASEBOARD_FAB2(SCH_1):GND
  98    GND VSS<65> @BASEBOARD_FAB2_LIB.BASEBOARD_FAB2(SCH_1):GND
 101    GND VSS<64> @BASEBOARD_FAB2_LIB.BASEBOARD_FAB2(SCH_1):GND
 103    GND VSS<63> @BASEBOARD_FAB2_LIB.BASEBOARD_FAB2(SCH_1):GND
 105    GND VSS<62> @BASEBOARD_FAB2_LIB.BASEBOARD_FAB2(SCH_1):GND
 107    GND VSS<61> @BASEBOARD_FAB2_LIB.BASEBOARD_FAB2(SCH_1):GND
 109    GND VSS<60> @BASEBOARD_FAB2_LIB.BASEBOARD_FAB2(SCH_1):GND
 112    GND VSS<59> @BASEBOARD_FAB2_LIB.BASEBOARD_FAB2(SCH_1):GND
 114    GND VSS<58> @BASEBOARD_FAB2_LIB.BASEBOARD_FAB2(SCH_1):GND
 116    GND VSS<57> @BASEBOARD_FAB2_LIB.BASEBOARD_FAB2(SCH_1):GND
 118    GND VSS<56> @BASEBOARD_FAB2_LIB.BASEBOARD_FAB2(SCH_1):GND
 120    GND VSS<55> @BASEBOARD_FAB2_LIB.BASEBOARD_FAB2(SCH_1):GND
 123    GND VSS<54> @BASEBOARD_FAB2_LIB.BASEBOARD_FAB2(SCH_1):GND
 125    GND VSS<53> @BASEBOARD_FAB2_LIB.BASEBOARD_FAB2(SCH_1):GND
 127    GND VSS<52> @BASEBOARD_FAB2_LIB.BASEBOARD_FAB2(SCH_1):GND
 129    GND VSS<51> @BASEBOARD_FAB2_LIB.BASEBOARD_FAB2(SCH_1):GND
 131    GND VSS<50> @BASEBOARD_FAB2_LIB.BASEBOARD_FAB2(SCH_1):GND
 134    GND VSS<49> @BASEBOARD_FAB2_LIB.BASEBOARD_FAB2(SCH_1):GND
 136    GND VSS<48> @BASEBOARD_FAB2_LIB.BASEBOARD_FAB2(SCH_1):GND
 138    GND VSS<47> @BASEBOARD_FAB2_LIB.BASEBOARD_FAB2(SCH_1):GND
 147    GND VSS<46> @BASEBOARD_FAB2_LIB.BASEBOARD_FAB2(SCH_1):GND
 149    GND VSS<45> @BASEBOARD_FAB2_LIB.BASEBOARD_FAB2(SCH_1):GND
 151    GND VSS<44> @BASEBOARD_FAB2_LIB.BASEBOARD_FAB2(SCH_1):GND
 154    GND VSS<43> @BASEBOARD_FAB2_LIB.BASEBOARD_FAB2(SCH_1):GND
 156    GND VSS<42> @BASEBOARD_FAB2_LIB.BASEBOARD_FAB2(SCH_1):GND
 158    GND VSS<41> @BASEBOARD_FAB2_LIB.BASEBOARD_FAB2(SCH_1):GND
 160    GND VSS<40> @BASEBOARD_FAB2_LIB.BASEBOARD_FAB2(SCH_1):GND
 162    GND VSS<39> @BASEBOARD_FAB2_LIB.BASEBOARD_FAB2(SCH_1):GND
 165    GND VSS<38> @BASEBOARD_FAB2_LIB.BASEBOARD_FAB2(SCH_1):GND
 167    GND VSS<37> @BASEBOARD_FAB2_LIB.BASEBOARD_FAB2(SCH_1):GND
 169    GND VSS<36> @BASEBOARD_FAB2_LIB.BASEBOARD_FAB2(SCH_1):GND
 171    GND VSS<35> @BASEBOARD_FAB2_LIB.BASEBOARD_FAB2(SCH_1):GND
 173    GND VSS<34> @BASEBOARD_FAB2_LIB.BASEBOARD_FAB2(SCH_1):GND
 176    GND VSS<33> @BASEBOARD_FAB2_LIB.BASEBOARD_FAB2(SCH_1):GND
 178    GND VSS<32> @BASEBOARD_FAB2_LIB.BASEBOARD_FAB2(SCH_1):GND
 180    GND VSS<31> @BASEBOARD_FAB2_LIB.BASEBOARD_FAB2(SCH_1):GND
 182    GND VSS<30> @BASEBOARD_FAB2_LIB.BASEBOARD_FAB2(SCH_1):GND
 184    GND VSS<29> @BASEBOARD_FAB2_LIB.BASEBOARD_FAB2(SCH_1):GND
 187    GND VSS<28> @BASEBOARD_FAB2_LIB.BASEBOARD_FAB2(SCH_1):GND
 189    GND VSS<27> @BASEBOARD_FAB2_LIB.BASEBOARD_FAB2(SCH_1):GND
 191    GND VSS<26> @BASEBOARD_FAB2_LIB.BASEBOARD_FAB2(SCH_1):GND
 193    GND VSS<25> @BASEBOARD_FAB2_LIB.BASEBOARD_FAB2(SCH_1):GND
 195    GND VSS<24> @BASEBOARD_FAB2_LIB.BASEBOARD_FAB2(SCH_1):GND
 198    GND VSS<23> @BASEBOARD_FAB2_LIB.BASEBOARD_FAB2(SCH_1):GND
 200    GND VSS<22> @BASEBOARD_FAB2_LIB.BASEBOARD_FAB2(SCH_1):GND
 202    GND VSS<21> @BASEBOARD_FAB2_LIB.BASEBOARD_FAB2(SCH_1):GND
 239    GND VSS<20> @BASEBOARD_FAB2_LIB.BASEBOARD_FAB2(SCH_1):GND
 241    GND VSS<19> @BASEBOARD_FAB2_LIB.BASEBOARD_FAB2(SCH_1):GND
 243    GND VSS<18> @BASEBOARD_FAB2_LIB.BASEBOARD_FAB2(SCH_1):GND
 246    GND VSS<17> @BASEBOARD_FAB2_LIB.BASEBOARD_FAB2(SCH_1):GND
 248    GND VSS<16> @BASEBOARD_FAB2_LIB.BASEBOARD_FAB2(SCH_1):GND
 250    GND VSS<15> @BASEBOARD_FAB2_LIB.BASEBOARD_FAB2(SCH_1):GND
 252    GND VSS<14> @BASEBOARD_FAB2_LIB.BASEBOARD_FAB2(SCH_1):GND
 254    GND VSS<13> @BASEBOARD_FAB2_LIB.BASEBOARD_FAB2(SCH_1):GND
 257    GND VSS<12> @BASEBOARD_FAB2_LIB.BASEBOARD_FAB2(SCH_1):GND
 259    GND VSS<11> @BASEBOARD_FAB2_LIB.BASEBOARD_FAB2(SCH_1):GND
 261    GND VSS<10> @BASEBOARD_FAB2_LIB.BASEBOARD_FAB2(SCH_1):GND
 263    GND VSS<9> @BASEBOARD_FAB2_LIB.BASEBOARD_FAB2(SCH_1):GND
 265    GND VSS<8> @BASEBOARD_FAB2_LIB.BASEBOARD_FAB2(SCH_1):GND
 268    GND VSS<7> @BASEBOARD_FAB2_LIB.BASEBOARD_FAB2(SCH_1):GND
 270    GND VSS<6> @BASEBOARD_FAB2_LIB.BASEBOARD_FAB2(SCH_1):GND
 272    GND VSS<5> @BASEBOARD_FAB2_LIB.BASEBOARD_FAB2(SCH_1):GND
 274    GND VSS<4> @BASEBOARD_FAB2_LIB.BASEBOARD_FAB2(SCH_1):GND
 276    GND VSS<3> @BASEBOARD_FAB2_LIB.BASEBOARD_FAB2(SCH_1):GND
 279    GND VSS<2> @BASEBOARD_FAB2_LIB.BASEBOARD_FAB2(SCH_1):GND
 281    GND VSS<1> @BASEBOARD_FAB2_LIB.BASEBOARD_FAB2(SCH_1):GND
 283    GND VSS<0> @BASEBOARD_FAB2_LIB.BASEBOARD_FAB2(SCH_1):GND


DRAWING: @BASEBOARD_FAB2_LIB.BASEBOARD_FAB2(SCH_1):PAGE81 

SCONN288_H44441004_PIP-SCONN,HA  I67  J1G3
 152 M_J_DQS_DN<0>  DQS0N @BASEBOARD_FAB2_LIB.BASEBOARD_FAB2(SCH_1):M_J_DQS_DN(0)
 153 M_J_DQS_DP<0>  DQS0P @BASEBOARD_FAB2_LIB.BASEBOARD_FAB2(SCH_1):M_J_DQS_DP(0)
  19 M_J_DQS_DN<10> DQS10N @BASEBOARD_FAB2_LIB.BASEBOARD_FAB2(SCH_1):M_J_DQS_DN(10)
  18 M_J_DQS_DP<10> DQS10P @BASEBOARD_FAB2_LIB.BASEBOARD_FAB2(SCH_1):M_J_DQS_DP(10)
  30 M_J_DQS_DN<11> DQS11N @BASEBOARD_FAB2_LIB.BASEBOARD_FAB2(SCH_1):M_J_DQS_DN(11)
  29 M_J_DQS_DP<11> DQS11P @BASEBOARD_FAB2_LIB.BASEBOARD_FAB2(SCH_1):M_J_DQS_DP(11)
  41 M_J_DQS_DN<12> DQS12N @BASEBOARD_FAB2_LIB.BASEBOARD_FAB2(SCH_1):M_J_DQS_DN(12)
  40 M_J_DQS_DP<12> DQS12P @BASEBOARD_FAB2_LIB.BASEBOARD_FAB2(SCH_1):M_J_DQS_DP(12)
 100 M_J_DQS_DN<13> DQS13N @BASEBOARD_FAB2_LIB.BASEBOARD_FAB2(SCH_1):M_J_DQS_DN(13)
  99 M_J_DQS_DP<13> DQS13P @BASEBOARD_FAB2_LIB.BASEBOARD_FAB2(SCH_1):M_J_DQS_DP(13)
 111 M_J_DQS_DN<14> DQS14N @BASEBOARD_FAB2_LIB.BASEBOARD_FAB2(SCH_1):M_J_DQS_DN(14)
 110 M_J_DQS_DP<14> DQS14P @BASEBOARD_FAB2_LIB.BASEBOARD_FAB2(SCH_1):M_J_DQS_DP(14)
 122 M_J_DQS_DN<15> DQS15N @BASEBOARD_FAB2_LIB.BASEBOARD_FAB2(SCH_1):M_J_DQS_DN(15)
 121 M_J_DQS_DP<15> DQS15P @BASEBOARD_FAB2_LIB.BASEBOARD_FAB2(SCH_1):M_J_DQS_DP(15)
 133 M_J_DQS_DN<16> DQS16N @BASEBOARD_FAB2_LIB.BASEBOARD_FAB2(SCH_1):M_J_DQS_DN(16)
 132 M_J_DQS_DP<16> DQS16P @BASEBOARD_FAB2_LIB.BASEBOARD_FAB2(SCH_1):M_J_DQS_DP(16)
  52 M_J_DQS_DN<17> DQS17N @BASEBOARD_FAB2_LIB.BASEBOARD_FAB2(SCH_1):M_J_DQS_DN(17)
  51 M_J_DQS_DP<17> DQS17P @BASEBOARD_FAB2_LIB.BASEBOARD_FAB2(SCH_1):M_J_DQS_DP(17)
 163 M_J_DQS_DN<1>  DQS1N @BASEBOARD_FAB2_LIB.BASEBOARD_FAB2(SCH_1):M_J_DQS_DN(1)
 164 M_J_DQS_DP<1>  DQS1P @BASEBOARD_FAB2_LIB.BASEBOARD_FAB2(SCH_1):M_J_DQS_DP(1)
 174 M_J_DQS_DN<2>  DQS2N @BASEBOARD_FAB2_LIB.BASEBOARD_FAB2(SCH_1):M_J_DQS_DN(2)
 175 M_J_DQS_DP<2>  DQS2P @BASEBOARD_FAB2_LIB.BASEBOARD_FAB2(SCH_1):M_J_DQS_DP(2)
 185 M_J_DQS_DN<3>  DQS3N @BASEBOARD_FAB2_LIB.BASEBOARD_FAB2(SCH_1):M_J_DQS_DN(3)
 186 M_J_DQS_DP<3>  DQS3P @BASEBOARD_FAB2_LIB.BASEBOARD_FAB2(SCH_1):M_J_DQS_DP(3)
 244 M_J_DQS_DN<4>  DQS4N @BASEBOARD_FAB2_LIB.BASEBOARD_FAB2(SCH_1):M_J_DQS_DN(4)
 245 M_J_DQS_DP<4>  DQS4P @BASEBOARD_FAB2_LIB.BASEBOARD_FAB2(SCH_1):M_J_DQS_DP(4)
 255 M_J_DQS_DN<5>  DQS5N @BASEBOARD_FAB2_LIB.BASEBOARD_FAB2(SCH_1):M_J_DQS_DN(5)
 256 M_J_DQS_DP<5>  DQS5P @BASEBOARD_FAB2_LIB.BASEBOARD_FAB2(SCH_1):M_J_DQS_DP(5)
 266 M_J_DQS_DN<6>  DQS6N @BASEBOARD_FAB2_LIB.BASEBOARD_FAB2(SCH_1):M_J_DQS_DN(6)
 267 M_J_DQS_DP<6>  DQS6P @BASEBOARD_FAB2_LIB.BASEBOARD_FAB2(SCH_1):M_J_DQS_DP(6)
 277 M_J_DQS_DN<7>  DQS7N @BASEBOARD_FAB2_LIB.BASEBOARD_FAB2(SCH_1):M_J_DQS_DN(7)
 278 M_J_DQS_DP<7>  DQS7P @BASEBOARD_FAB2_LIB.BASEBOARD_FAB2(SCH_1):M_J_DQS_DP(7)
 196 M_J_DQS_DN<8>  DQS8N @BASEBOARD_FAB2_LIB.BASEBOARD_FAB2(SCH_1):M_J_DQS_DN(8)
 197 M_J_DQS_DP<8>  DQS8P @BASEBOARD_FAB2_LIB.BASEBOARD_FAB2(SCH_1):M_J_DQS_DP(8)
   8 M_J_DQS_DN<9>  DQS9N @BASEBOARD_FAB2_LIB.BASEBOARD_FAB2(SCH_1):M_J_DQS_DN(9)
   7 M_J_DQS_DP<9>  DQS9P @BASEBOARD_FAB2_LIB.BASEBOARD_FAB2(SCH_1):M_J_DQS_DP(9)

SCONN288_H44441004_PIP-SCONN,HA  I169  J1G3
   1 P12V_NVDIMM_GHJ 12V<1> @BASEBOARD_FAB2_LIB.BASEBOARD_FAB2(SCH_1):P12V_NVDIMM_GHJ
 145 P12V_NVDIMM_GHJ 12V<0> @BASEBOARD_FAB2_LIB.BASEBOARD_FAB2(SCH_1):P12V_NVDIMM_GHJ
  59 PVDDQ_GHJ VDD<25> @BASEBOARD_FAB2_LIB.BASEBOARD_FAB2(SCH_1):PVDDQ_GHJ
  61 PVDDQ_GHJ VDD<24> @BASEBOARD_FAB2_LIB.BASEBOARD_FAB2(SCH_1):PVDDQ_GHJ
  64 PVDDQ_GHJ VDD<23> @BASEBOARD_FAB2_LIB.BASEBOARD_FAB2(SCH_1):PVDDQ_GHJ
  67 PVDDQ_GHJ VDD<22> @BASEBOARD_FAB2_LIB.BASEBOARD_FAB2(SCH_1):PVDDQ_GHJ
  70 PVDDQ_GHJ VDD<21> @BASEBOARD_FAB2_LIB.BASEBOARD_FAB2(SCH_1):PVDDQ_GHJ
  73 PVDDQ_GHJ VDD<20> @BASEBOARD_FAB2_LIB.BASEBOARD_FAB2(SCH_1):PVDDQ_GHJ
  76 PVDDQ_GHJ VDD<19> @BASEBOARD_FAB2_LIB.BASEBOARD_FAB2(SCH_1):PVDDQ_GHJ
  80 PVDDQ_GHJ VDD<18> @BASEBOARD_FAB2_LIB.BASEBOARD_FAB2(SCH_1):PVDDQ_GHJ
  83 PVDDQ_GHJ VDD<17> @BASEBOARD_FAB2_LIB.BASEBOARD_FAB2(SCH_1):PVDDQ_GHJ
  85 PVDDQ_GHJ VDD<16> @BASEBOARD_FAB2_LIB.BASEBOARD_FAB2(SCH_1):PVDDQ_GHJ
  88 PVDDQ_GHJ VDD<15> @BASEBOARD_FAB2_LIB.BASEBOARD_FAB2(SCH_1):PVDDQ_GHJ
  90 PVDDQ_GHJ VDD<14> @BASEBOARD_FAB2_LIB.BASEBOARD_FAB2(SCH_1):PVDDQ_GHJ
  92 PVDDQ_GHJ VDD<13> @BASEBOARD_FAB2_LIB.BASEBOARD_FAB2(SCH_1):PVDDQ_GHJ
 204 PVDDQ_GHJ VDD<12> @BASEBOARD_FAB2_LIB.BASEBOARD_FAB2(SCH_1):PVDDQ_GHJ
 206 PVDDQ_GHJ VDD<11> @BASEBOARD_FAB2_LIB.BASEBOARD_FAB2(SCH_1):PVDDQ_GHJ
 209 PVDDQ_GHJ VDD<10> @BASEBOARD_FAB2_LIB.BASEBOARD_FAB2(SCH_1):PVDDQ_GHJ
 212 PVDDQ_GHJ VDD<9> @BASEBOARD_FAB2_LIB.BASEBOARD_FAB2(SCH_1):PVDDQ_GHJ
 215 PVDDQ_GHJ VDD<8> @BASEBOARD_FAB2_LIB.BASEBOARD_FAB2(SCH_1):PVDDQ_GHJ
 217 PVDDQ_GHJ VDD<7> @BASEBOARD_FAB2_LIB.BASEBOARD_FAB2(SCH_1):PVDDQ_GHJ
 220 PVDDQ_GHJ VDD<6> @BASEBOARD_FAB2_LIB.BASEBOARD_FAB2(SCH_1):PVDDQ_GHJ
 223 PVDDQ_GHJ VDD<5> @BASEBOARD_FAB2_LIB.BASEBOARD_FAB2(SCH_1):PVDDQ_GHJ
 226 PVDDQ_GHJ VDD<4> @BASEBOARD_FAB2_LIB.BASEBOARD_FAB2(SCH_1):PVDDQ_GHJ
 229 PVDDQ_GHJ VDD<3> @BASEBOARD_FAB2_LIB.BASEBOARD_FAB2(SCH_1):PVDDQ_GHJ
 231 PVDDQ_GHJ VDD<2> @BASEBOARD_FAB2_LIB.BASEBOARD_FAB2(SCH_1):PVDDQ_GHJ
 233 PVDDQ_GHJ VDD<1> @BASEBOARD_FAB2_LIB.BASEBOARD_FAB2(SCH_1):PVDDQ_GHJ
 236 PVDDQ_GHJ VDD<0> @BASEBOARD_FAB2_LIB.BASEBOARD_FAB2(SCH_1):PVDDQ_GHJ
 142 PVPP_GHJ VPP<4> @BASEBOARD_FAB2_LIB.BASEBOARD_FAB2(SCH_1):PVPP_GHJ
 143 PVPP_GHJ VPP<3> @BASEBOARD_FAB2_LIB.BASEBOARD_FAB2(SCH_1):PVPP_GHJ
 288 PVPP_GHJ VPP<2> @BASEBOARD_FAB2_LIB.BASEBOARD_FAB2(SCH_1):PVPP_GHJ
 286 PVPP_GHJ VPP<1> @BASEBOARD_FAB2_LIB.BASEBOARD_FAB2(SCH_1):PVPP_GHJ
 287 PVPP_GHJ VPP<0> @BASEBOARD_FAB2_LIB.BASEBOARD_FAB2(SCH_1):PVPP_GHJ
  77 PVTT_GHJ VTT<1> @BASEBOARD_FAB2_LIB.BASEBOARD_FAB2(SCH_1):PVTT_GHJ
 221 PVTT_GHJ VTT<0> @BASEBOARD_FAB2_LIB.BASEBOARD_FAB2(SCH_1):PVTT_GHJ

CAP_A_0402V-0.01UF,25V,10%,X7RA  I178  C9U10
   1 M_J_VREF      A @BASEBOARD_FAB2_LIB.BASEBOARD_FAB2(SCH_1):M_J_VREF
   2    GND      B @BASEBOARD_FAB2_LIB.BASEBOARD_FAB2(SCH_1):GND

SCONN288_H44441004_PIP-SCONN,HA  I185  J1G3
   2    GND VSS<93> @BASEBOARD_FAB2_LIB.BASEBOARD_FAB2(SCH_1):GND
   4    GND VSS<92> @BASEBOARD_FAB2_LIB.BASEBOARD_FAB2(SCH_1):GND
   6    GND VSS<91> @BASEBOARD_FAB2_LIB.BASEBOARD_FAB2(SCH_1):GND
   9    GND VSS<90> @BASEBOARD_FAB2_LIB.BASEBOARD_FAB2(SCH_1):GND
  11    GND VSS<89> @BASEBOARD_FAB2_LIB.BASEBOARD_FAB2(SCH_1):GND
  13    GND VSS<88> @BASEBOARD_FAB2_LIB.BASEBOARD_FAB2(SCH_1):GND
  15    GND VSS<87> @BASEBOARD_FAB2_LIB.BASEBOARD_FAB2(SCH_1):GND
  17    GND VSS<86> @BASEBOARD_FAB2_LIB.BASEBOARD_FAB2(SCH_1):GND
  20    GND VSS<85> @BASEBOARD_FAB2_LIB.BASEBOARD_FAB2(SCH_1):GND
  22    GND VSS<84> @BASEBOARD_FAB2_LIB.BASEBOARD_FAB2(SCH_1):GND
  24    GND VSS<83> @BASEBOARD_FAB2_LIB.BASEBOARD_FAB2(SCH_1):GND
  26    GND VSS<82> @BASEBOARD_FAB2_LIB.BASEBOARD_FAB2(SCH_1):GND
  28    GND VSS<81> @BASEBOARD_FAB2_LIB.BASEBOARD_FAB2(SCH_1):GND
  31    GND VSS<80> @BASEBOARD_FAB2_LIB.BASEBOARD_FAB2(SCH_1):GND
  33    GND VSS<79> @BASEBOARD_FAB2_LIB.BASEBOARD_FAB2(SCH_1):GND
  35    GND VSS<78> @BASEBOARD_FAB2_LIB.BASEBOARD_FAB2(SCH_1):GND
  37    GND VSS<77> @BASEBOARD_FAB2_LIB.BASEBOARD_FAB2(SCH_1):GND
  39    GND VSS<76> @BASEBOARD_FAB2_LIB.BASEBOARD_FAB2(SCH_1):GND
  42    GND VSS<75> @BASEBOARD_FAB2_LIB.BASEBOARD_FAB2(SCH_1):GND
  44    GND VSS<74> @BASEBOARD_FAB2_LIB.BASEBOARD_FAB2(SCH_1):GND
  46    GND VSS<73> @BASEBOARD_FAB2_LIB.BASEBOARD_FAB2(SCH_1):GND
  48    GND VSS<72> @BASEBOARD_FAB2_LIB.BASEBOARD_FAB2(SCH_1):GND
  50    GND VSS<71> @BASEBOARD_FAB2_LIB.BASEBOARD_FAB2(SCH_1):GND
  53    GND VSS<70> @BASEBOARD_FAB2_LIB.BASEBOARD_FAB2(SCH_1):GND
  55    GND VSS<69> @BASEBOARD_FAB2_LIB.BASEBOARD_FAB2(SCH_1):GND
  57    GND VSS<68> @BASEBOARD_FAB2_LIB.BASEBOARD_FAB2(SCH_1):GND
  94    GND VSS<67> @BASEBOARD_FAB2_LIB.BASEBOARD_FAB2(SCH_1):GND
  96    GND VSS<66> @BASEBOARD_FAB2_LIB.BASEBOARD_FAB2(SCH_1):GND
  98    GND VSS<65> @BASEBOARD_FAB2_LIB.BASEBOARD_FAB2(SCH_1):GND
 101    GND VSS<64> @BASEBOARD_FAB2_LIB.BASEBOARD_FAB2(SCH_1):GND
 103    GND VSS<63> @BASEBOARD_FAB2_LIB.BASEBOARD_FAB2(SCH_1):GND
 105    GND VSS<62> @BASEBOARD_FAB2_LIB.BASEBOARD_FAB2(SCH_1):GND
 107    GND VSS<61> @BASEBOARD_FAB2_LIB.BASEBOARD_FAB2(SCH_1):GND
 109    GND VSS<60> @BASEBOARD_FAB2_LIB.BASEBOARD_FAB2(SCH_1):GND
 112    GND VSS<59> @BASEBOARD_FAB2_LIB.BASEBOARD_FAB2(SCH_1):GND
 114    GND VSS<58> @BASEBOARD_FAB2_LIB.BASEBOARD_FAB2(SCH_1):GND
 116    GND VSS<57> @BASEBOARD_FAB2_LIB.BASEBOARD_FAB2(SCH_1):GND
 118    GND VSS<56> @BASEBOARD_FAB2_LIB.BASEBOARD_FAB2(SCH_1):GND
 120    GND VSS<55> @BASEBOARD_FAB2_LIB.BASEBOARD_FAB2(SCH_1):GND
 123    GND VSS<54> @BASEBOARD_FAB2_LIB.BASEBOARD_FAB2(SCH_1):GND
 125    GND VSS<53> @BASEBOARD_FAB2_LIB.BASEBOARD_FAB2(SCH_1):GND
 127    GND VSS<52> @BASEBOARD_FAB2_LIB.BASEBOARD_FAB2(SCH_1):GND
 129    GND VSS<51> @BASEBOARD_FAB2_LIB.BASEBOARD_FAB2(SCH_1):GND
 131    GND VSS<50> @BASEBOARD_FAB2_LIB.BASEBOARD_FAB2(SCH_1):GND
 134    GND VSS<49> @BASEBOARD_FAB2_LIB.BASEBOARD_FAB2(SCH_1):GND
 136    GND VSS<48> @BASEBOARD_FAB2_LIB.BASEBOARD_FAB2(SCH_1):GND
 138    GND VSS<47> @BASEBOARD_FAB2_LIB.BASEBOARD_FAB2(SCH_1):GND
 147    GND VSS<46> @BASEBOARD_FAB2_LIB.BASEBOARD_FAB2(SCH_1):GND
 149    GND VSS<45> @BASEBOARD_FAB2_LIB.BASEBOARD_FAB2(SCH_1):GND
 151    GND VSS<44> @BASEBOARD_FAB2_LIB.BASEBOARD_FAB2(SCH_1):GND
 154    GND VSS<43> @BASEBOARD_FAB2_LIB.BASEBOARD_FAB2(SCH_1):GND
 156    GND VSS<42> @BASEBOARD_FAB2_LIB.BASEBOARD_FAB2(SCH_1):GND
 158    GND VSS<41> @BASEBOARD_FAB2_LIB.BASEBOARD_FAB2(SCH_1):GND
 160    GND VSS<40> @BASEBOARD_FAB2_LIB.BASEBOARD_FAB2(SCH_1):GND
 162    GND VSS<39> @BASEBOARD_FAB2_LIB.BASEBOARD_FAB2(SCH_1):GND
 165    GND VSS<38> @BASEBOARD_FAB2_LIB.BASEBOARD_FAB2(SCH_1):GND
 167    GND VSS<37> @BASEBOARD_FAB2_LIB.BASEBOARD_FAB2(SCH_1):GND
 169    GND VSS<36> @BASEBOARD_FAB2_LIB.BASEBOARD_FAB2(SCH_1):GND
 171    GND VSS<35> @BASEBOARD_FAB2_LIB.BASEBOARD_FAB2(SCH_1):GND
 173    GND VSS<34> @BASEBOARD_FAB2_LIB.BASEBOARD_FAB2(SCH_1):GND
 176    GND VSS<33> @BASEBOARD_FAB2_LIB.BASEBOARD_FAB2(SCH_1):GND
 178    GND VSS<32> @BASEBOARD_FAB2_LIB.BASEBOARD_FAB2(SCH_1):GND
 180    GND VSS<31> @BASEBOARD_FAB2_LIB.BASEBOARD_FAB2(SCH_1):GND
 182    GND VSS<30> @BASEBOARD_FAB2_LIB.BASEBOARD_FAB2(SCH_1):GND
 184    GND VSS<29> @BASEBOARD_FAB2_LIB.BASEBOARD_FAB2(SCH_1):GND
 187    GND VSS<28> @BASEBOARD_FAB2_LIB.BASEBOARD_FAB2(SCH_1):GND
 189    GND VSS<27> @BASEBOARD_FAB2_LIB.BASEBOARD_FAB2(SCH_1):GND
 191    GND VSS<26> @BASEBOARD_FAB2_LIB.BASEBOARD_FAB2(SCH_1):GND
 193    GND VSS<25> @BASEBOARD_FAB2_LIB.BASEBOARD_FAB2(SCH_1):GND
 195    GND VSS<24> @BASEBOARD_FAB2_LIB.BASEBOARD_FAB2(SCH_1):GND
 198    GND VSS<23> @BASEBOARD_FAB2_LIB.BASEBOARD_FAB2(SCH_1):GND
 200    GND VSS<22> @BASEBOARD_FAB2_LIB.BASEBOARD_FAB2(SCH_1):GND
 202    GND VSS<21> @BASEBOARD_FAB2_LIB.BASEBOARD_FAB2(SCH_1):GND
 239    GND VSS<20> @BASEBOARD_FAB2_LIB.BASEBOARD_FAB2(SCH_1):GND
 241    GND VSS<19> @BASEBOARD_FAB2_LIB.BASEBOARD_FAB2(SCH_1):GND
 243    GND VSS<18> @BASEBOARD_FAB2_LIB.BASEBOARD_FAB2(SCH_1):GND
 246    GND VSS<17> @BASEBOARD_FAB2_LIB.BASEBOARD_FAB2(SCH_1):GND
 248    GND VSS<16> @BASEBOARD_FAB2_LIB.BASEBOARD_FAB2(SCH_1):GND
 250    GND VSS<15> @BASEBOARD_FAB2_LIB.BASEBOARD_FAB2(SCH_1):GND
 252    GND VSS<14> @BASEBOARD_FAB2_LIB.BASEBOARD_FAB2(SCH_1):GND
 254    GND VSS<13> @BASEBOARD_FAB2_LIB.BASEBOARD_FAB2(SCH_1):GND
 257    GND VSS<12> @BASEBOARD_FAB2_LIB.BASEBOARD_FAB2(SCH_1):GND
 259    GND VSS<11> @BASEBOARD_FAB2_LIB.BASEBOARD_FAB2(SCH_1):GND
 261    GND VSS<10> @BASEBOARD_FAB2_LIB.BASEBOARD_FAB2(SCH_1):GND
 263    GND VSS<9> @BASEBOARD_FAB2_LIB.BASEBOARD_FAB2(SCH_1):GND
 265    GND VSS<8> @BASEBOARD_FAB2_LIB.BASEBOARD_FAB2(SCH_1):GND
 268    GND VSS<7> @BASEBOARD_FAB2_LIB.BASEBOARD_FAB2(SCH_1):GND
 270    GND VSS<6> @BASEBOARD_FAB2_LIB.BASEBOARD_FAB2(SCH_1):GND
 272    GND VSS<5> @BASEBOARD_FAB2_LIB.BASEBOARD_FAB2(SCH_1):GND
 274    GND VSS<4> @BASEBOARD_FAB2_LIB.BASEBOARD_FAB2(SCH_1):GND
 276    GND VSS<3> @BASEBOARD_FAB2_LIB.BASEBOARD_FAB2(SCH_1):GND
 279    GND VSS<2> @BASEBOARD_FAB2_LIB.BASEBOARD_FAB2(SCH_1):GND
 281    GND VSS<1> @BASEBOARD_FAB2_LIB.BASEBOARD_FAB2(SCH_1):GND
 283    GND VSS<0> @BASEBOARD_FAB2_LIB.BASEBOARD_FAB2(SCH_1):GND

SCONN288_H44441004_PIP-SCONN,HA  I186  J1G3
  79 M_J_MA<0>     A0 @BASEBOARD_FAB2_LIB.BASEBOARD_FAB2(SCH_1):M_J_MA(0)
  72 M_J_MA<1>     A1 @BASEBOARD_FAB2_LIB.BASEBOARD_FAB2(SCH_1):M_J_MA(1)
 225 M_J_MA<10>    A10 @BASEBOARD_FAB2_LIB.BASEBOARD_FAB2(SCH_1):M_J_MA(10)
 210 M_J_MA<11>    A11 @BASEBOARD_FAB2_LIB.BASEBOARD_FAB2(SCH_1):M_J_MA(11)
  65 M_J_MA<12>    A12 @BASEBOARD_FAB2_LIB.BASEBOARD_FAB2(SCH_1):M_J_MA(12)
 232 M_J_MA<13>    A13 @BASEBOARD_FAB2_LIB.BASEBOARD_FAB2(SCH_1):M_J_MA(13)
 228 M_J_MA<14> A14_WE_N @BASEBOARD_FAB2_LIB.BASEBOARD_FAB2(SCH_1):M_J_MA(14)
  86 M_J_MA<15> A15_CAS_N @BASEBOARD_FAB2_LIB.BASEBOARD_FAB2(SCH_1):M_J_MA(15)
  82 M_J_MA<16> A16_RAS_N @BASEBOARD_FAB2_LIB.BASEBOARD_FAB2(SCH_1):M_J_MA(16)
 234 M_J_MA<17>    A17 @BASEBOARD_FAB2_LIB.BASEBOARD_FAB2(SCH_1):M_J_MA(17)
 216 M_J_MA<2>     A2 @BASEBOARD_FAB2_LIB.BASEBOARD_FAB2(SCH_1):M_J_MA(2)
  71 M_J_MA<3>     A3 @BASEBOARD_FAB2_LIB.BASEBOARD_FAB2(SCH_1):M_J_MA(3)
 214 M_J_MA<4>     A4 @BASEBOARD_FAB2_LIB.BASEBOARD_FAB2(SCH_1):M_J_MA(4)
 213 M_J_MA<5>     A5 @BASEBOARD_FAB2_LIB.BASEBOARD_FAB2(SCH_1):M_J_MA(5)
  69 M_J_MA<6>     A6 @BASEBOARD_FAB2_LIB.BASEBOARD_FAB2(SCH_1):M_J_MA(6)
 211 M_J_MA<7>     A7 @BASEBOARD_FAB2_LIB.BASEBOARD_FAB2(SCH_1):M_J_MA(7)
  68 M_J_MA<8>     A8 @BASEBOARD_FAB2_LIB.BASEBOARD_FAB2(SCH_1):M_J_MA(8)
  66 M_J_MA<9>     A9 @BASEBOARD_FAB2_LIB.BASEBOARD_FAB2(SCH_1):M_J_MA(9)
  62 M_J_ACT_N  ACT_N @BASEBOARD_FAB2_LIB.BASEBOARD_FAB2(SCH_1):M_J_ACT_N
 208 M_J_ALERT_N ALERT_N @BASEBOARD_FAB2_LIB.BASEBOARD_FAB2(SCH_1):M_J_ALERT_N
 224 M_J_BA<1>  BA<1> @BASEBOARD_FAB2_LIB.BASEBOARD_FAB2(SCH_1):M_J_BA(1)
  81 M_J_BA<0>  BA<0> @BASEBOARD_FAB2_LIB.BASEBOARD_FAB2(SCH_1):M_J_BA(0)
 207 M_J_BG<1>  BG<1> @BASEBOARD_FAB2_LIB.BASEBOARD_FAB2(SCH_1):M_J_BG(1)
  63 M_J_BG<0>  BG<0> @BASEBOARD_FAB2_LIB.BASEBOARD_FAB2(SCH_1):M_J_BG(0)
 235 M_J_C<2>   C<2> @BASEBOARD_FAB2_LIB.BASEBOARD_FAB2(SCH_1):M_J_C(2)
 199 M_J_ECC<6>  CB<7> @BASEBOARD_FAB2_LIB.BASEBOARD_FAB2(SCH_1):M_J_ECC(6)
  54 M_J_ECC<7>  CB<6> @BASEBOARD_FAB2_LIB.BASEBOARD_FAB2(SCH_1):M_J_ECC(7)
 192 M_J_ECC<4>  CB<5> @BASEBOARD_FAB2_LIB.BASEBOARD_FAB2(SCH_1):M_J_ECC(4)
  47 M_J_ECC<5>  CB<4> @BASEBOARD_FAB2_LIB.BASEBOARD_FAB2(SCH_1):M_J_ECC(5)
 201 M_J_ECC<2>  CB<3> @BASEBOARD_FAB2_LIB.BASEBOARD_FAB2(SCH_1):M_J_ECC(2)
  56 M_J_ECC<3>  CB<2> @BASEBOARD_FAB2_LIB.BASEBOARD_FAB2(SCH_1):M_J_ECC(3)
 194 M_J_ECC<0>  CB<1> @BASEBOARD_FAB2_LIB.BASEBOARD_FAB2(SCH_1):M_J_ECC(0)
  49 M_J_ECC<1>  CB<0> @BASEBOARD_FAB2_LIB.BASEBOARD_FAB2(SCH_1):M_J_ECC(1)
  75 M_J_CLK_DN<0>   CK0N @BASEBOARD_FAB2_LIB.BASEBOARD_FAB2(SCH_1):M_J_CLK_DN(0)
  74 M_J_CLK_DP<0>   CK0P @BASEBOARD_FAB2_LIB.BASEBOARD_FAB2(SCH_1):M_J_CLK_DP(0)
 219 M_J_CLK_DN<1>   CK1N @BASEBOARD_FAB2_LIB.BASEBOARD_FAB2(SCH_1):M_J_CLK_DN(1)
 218 M_J_CLK_DP<1>   CK1P @BASEBOARD_FAB2_LIB.BASEBOARD_FAB2(SCH_1):M_J_CLK_DP(1)
 203 M_J_CKE<1> CKE<1> @BASEBOARD_FAB2_LIB.BASEBOARD_FAB2(SCH_1):M_J_CKE(1)
  60 M_J_CKE<0> CKE<0> @BASEBOARD_FAB2_LIB.BASEBOARD_FAB2(SCH_1):M_J_CKE(0)
 280 M_J_DQ<62> DQ<63> @BASEBOARD_FAB2_LIB.BASEBOARD_FAB2(SCH_1):M_J_DQ(62)
 135 M_J_DQ<63> DQ<62> @BASEBOARD_FAB2_LIB.BASEBOARD_FAB2(SCH_1):M_J_DQ(63)
 273 M_J_DQ<60> DQ<61> @BASEBOARD_FAB2_LIB.BASEBOARD_FAB2(SCH_1):M_J_DQ(60)
 128 M_J_DQ<61> DQ<60> @BASEBOARD_FAB2_LIB.BASEBOARD_FAB2(SCH_1):M_J_DQ(61)
 282 M_J_DQ<58> DQ<59> @BASEBOARD_FAB2_LIB.BASEBOARD_FAB2(SCH_1):M_J_DQ(58)
 137 M_J_DQ<59> DQ<58> @BASEBOARD_FAB2_LIB.BASEBOARD_FAB2(SCH_1):M_J_DQ(59)
 275 M_J_DQ<56> DQ<57> @BASEBOARD_FAB2_LIB.BASEBOARD_FAB2(SCH_1):M_J_DQ(56)
 130 M_J_DQ<57> DQ<56> @BASEBOARD_FAB2_LIB.BASEBOARD_FAB2(SCH_1):M_J_DQ(57)
 269 M_J_DQ<54> DQ<55> @BASEBOARD_FAB2_LIB.BASEBOARD_FAB2(SCH_1):M_J_DQ(54)
 124 M_J_DQ<55> DQ<54> @BASEBOARD_FAB2_LIB.BASEBOARD_FAB2(SCH_1):M_J_DQ(55)
 262 M_J_DQ<52> DQ<53> @BASEBOARD_FAB2_LIB.BASEBOARD_FAB2(SCH_1):M_J_DQ(52)
 117 M_J_DQ<53> DQ<52> @BASEBOARD_FAB2_LIB.BASEBOARD_FAB2(SCH_1):M_J_DQ(53)
 271 M_J_DQ<50> DQ<51> @BASEBOARD_FAB2_LIB.BASEBOARD_FAB2(SCH_1):M_J_DQ(50)
 126 M_J_DQ<51> DQ<50> @BASEBOARD_FAB2_LIB.BASEBOARD_FAB2(SCH_1):M_J_DQ(51)
 264 M_J_DQ<48> DQ<49> @BASEBOARD_FAB2_LIB.BASEBOARD_FAB2(SCH_1):M_J_DQ(48)
 119 M_J_DQ<49> DQ<48> @BASEBOARD_FAB2_LIB.BASEBOARD_FAB2(SCH_1):M_J_DQ(49)
 258 M_J_DQ<46> DQ<47> @BASEBOARD_FAB2_LIB.BASEBOARD_FAB2(SCH_1):M_J_DQ(46)
 113 M_J_DQ<47> DQ<46> @BASEBOARD_FAB2_LIB.BASEBOARD_FAB2(SCH_1):M_J_DQ(47)
 251 M_J_DQ<44> DQ<45> @BASEBOARD_FAB2_LIB.BASEBOARD_FAB2(SCH_1):M_J_DQ(44)
 106 M_J_DQ<45> DQ<44> @BASEBOARD_FAB2_LIB.BASEBOARD_FAB2(SCH_1):M_J_DQ(45)
 260 M_J_DQ<42> DQ<43> @BASEBOARD_FAB2_LIB.BASEBOARD_FAB2(SCH_1):M_J_DQ(42)
 115 M_J_DQ<43> DQ<42> @BASEBOARD_FAB2_LIB.BASEBOARD_FAB2(SCH_1):M_J_DQ(43)
 253 M_J_DQ<40> DQ<41> @BASEBOARD_FAB2_LIB.BASEBOARD_FAB2(SCH_1):M_J_DQ(40)
 108 M_J_DQ<41> DQ<40> @BASEBOARD_FAB2_LIB.BASEBOARD_FAB2(SCH_1):M_J_DQ(41)
 247 M_J_DQ<38> DQ<39> @BASEBOARD_FAB2_LIB.BASEBOARD_FAB2(SCH_1):M_J_DQ(38)
 102 M_J_DQ<39> DQ<38> @BASEBOARD_FAB2_LIB.BASEBOARD_FAB2(SCH_1):M_J_DQ(39)
 240 M_J_DQ<36> DQ<37> @BASEBOARD_FAB2_LIB.BASEBOARD_FAB2(SCH_1):M_J_DQ(36)
  95 M_J_DQ<37> DQ<36> @BASEBOARD_FAB2_LIB.BASEBOARD_FAB2(SCH_1):M_J_DQ(37)
 249 M_J_DQ<34> DQ<35> @BASEBOARD_FAB2_LIB.BASEBOARD_FAB2(SCH_1):M_J_DQ(34)
 104 M_J_DQ<35> DQ<34> @BASEBOARD_FAB2_LIB.BASEBOARD_FAB2(SCH_1):M_J_DQ(35)
 242 M_J_DQ<32> DQ<33> @BASEBOARD_FAB2_LIB.BASEBOARD_FAB2(SCH_1):M_J_DQ(32)
  97 M_J_DQ<33> DQ<32> @BASEBOARD_FAB2_LIB.BASEBOARD_FAB2(SCH_1):M_J_DQ(33)
 188 M_J_DQ<30> DQ<31> @BASEBOARD_FAB2_LIB.BASEBOARD_FAB2(SCH_1):M_J_DQ(30)
  43 M_J_DQ<31> DQ<30> @BASEBOARD_FAB2_LIB.BASEBOARD_FAB2(SCH_1):M_J_DQ(31)
 181 M_J_DQ<28> DQ<29> @BASEBOARD_FAB2_LIB.BASEBOARD_FAB2(SCH_1):M_J_DQ(28)
  36 M_J_DQ<29> DQ<28> @BASEBOARD_FAB2_LIB.BASEBOARD_FAB2(SCH_1):M_J_DQ(29)
 190 M_J_DQ<26> DQ<27> @BASEBOARD_FAB2_LIB.BASEBOARD_FAB2(SCH_1):M_J_DQ(26)
  45 M_J_DQ<27> DQ<26> @BASEBOARD_FAB2_LIB.BASEBOARD_FAB2(SCH_1):M_J_DQ(27)
 183 M_J_DQ<24> DQ<25> @BASEBOARD_FAB2_LIB.BASEBOARD_FAB2(SCH_1):M_J_DQ(24)
  38 M_J_DQ<25> DQ<24> @BASEBOARD_FAB2_LIB.BASEBOARD_FAB2(SCH_1):M_J_DQ(25)
 177 M_J_DQ<22> DQ<23> @BASEBOARD_FAB2_LIB.BASEBOARD_FAB2(SCH_1):M_J_DQ(22)
  32 M_J_DQ<23> DQ<22> @BASEBOARD_FAB2_LIB.BASEBOARD_FAB2(SCH_1):M_J_DQ(23)
 170 M_J_DQ<20> DQ<21> @BASEBOARD_FAB2_LIB.BASEBOARD_FAB2(SCH_1):M_J_DQ(20)
  25 M_J_DQ<21> DQ<20> @BASEBOARD_FAB2_LIB.BASEBOARD_FAB2(SCH_1):M_J_DQ(21)
 179 M_J_DQ<18> DQ<19> @BASEBOARD_FAB2_LIB.BASEBOARD_FAB2(SCH_1):M_J_DQ(18)
  34 M_J_DQ<19> DQ<18> @BASEBOARD_FAB2_LIB.BASEBOARD_FAB2(SCH_1):M_J_DQ(19)
 172 M_J_DQ<16> DQ<17> @BASEBOARD_FAB2_LIB.BASEBOARD_FAB2(SCH_1):M_J_DQ(16)
  27 M_J_DQ<17> DQ<16> @BASEBOARD_FAB2_LIB.BASEBOARD_FAB2(SCH_1):M_J_DQ(17)
 166 M_J_DQ<14> DQ<15> @BASEBOARD_FAB2_LIB.BASEBOARD_FAB2(SCH_1):M_J_DQ(14)
  21 M_J_DQ<15> DQ<14> @BASEBOARD_FAB2_LIB.BASEBOARD_FAB2(SCH_1):M_J_DQ(15)
 159 M_J_DQ<12> DQ<13> @BASEBOARD_FAB2_LIB.BASEBOARD_FAB2(SCH_1):M_J_DQ(12)
  14 M_J_DQ<13> DQ<12> @BASEBOARD_FAB2_LIB.BASEBOARD_FAB2(SCH_1):M_J_DQ(13)
 168 M_J_DQ<10> DQ<11> @BASEBOARD_FAB2_LIB.BASEBOARD_FAB2(SCH_1):M_J_DQ(10)
  23 M_J_DQ<11> DQ<10> @BASEBOARD_FAB2_LIB.BASEBOARD_FAB2(SCH_1):M_J_DQ(11)
 161 M_J_DQ<8>  DQ<9> @BASEBOARD_FAB2_LIB.BASEBOARD_FAB2(SCH_1):M_J_DQ(8)
  16 M_J_DQ<9>  DQ<8> @BASEBOARD_FAB2_LIB.BASEBOARD_FAB2(SCH_1):M_J_DQ(9)
 155 M_J_DQ<6>  DQ<7> @BASEBOARD_FAB2_LIB.BASEBOARD_FAB2(SCH_1):M_J_DQ(6)
  10 M_J_DQ<7>  DQ<6> @BASEBOARD_FAB2_LIB.BASEBOARD_FAB2(SCH_1):M_J_DQ(7)
 148 M_J_DQ<4>  DQ<5> @BASEBOARD_FAB2_LIB.BASEBOARD_FAB2(SCH_1):M_J_DQ(4)
   3 M_J_DQ<5>  DQ<4> @BASEBOARD_FAB2_LIB.BASEBOARD_FAB2(SCH_1):M_J_DQ(5)
 157 M_J_DQ<2>  DQ<3> @BASEBOARD_FAB2_LIB.BASEBOARD_FAB2(SCH_1):M_J_DQ(2)
  12 M_J_DQ<3>  DQ<2> @BASEBOARD_FAB2_LIB.BASEBOARD_FAB2(SCH_1):M_J_DQ(3)
 150 M_J_DQ<0>  DQ<1> @BASEBOARD_FAB2_LIB.BASEBOARD_FAB2(SCH_1):M_J_DQ(0)
   5 M_J_DQ<1>  DQ<0> @BASEBOARD_FAB2_LIB.BASEBOARD_FAB2(SCH_1):M_J_DQ(1)
  78 FM_DIMM_EVENT_COD_N EVENT_N @BASEBOARD_FAB2_LIB.BASEBOARD_FAB2(SCH_1):FM_DIMM_EVENT_COD_N
  91 M_J_ODT<1> ODT<1> @BASEBOARD_FAB2_LIB.BASEBOARD_FAB2(SCH_1):M_J_ODT(1)
  87 M_J_ODT<0> ODT<0> @BASEBOARD_FAB2_LIB.BASEBOARD_FAB2(SCH_1):M_J_ODT(0)
 222 M_J_PAR    PAR @BASEBOARD_FAB2_LIB.BASEBOARD_FAB2(SCH_1):M_J_PAR
  58 M_GHJ_RST_N RESET_N @BASEBOARD_FAB2_LIB.BASEBOARD_FAB2(SCH_1):M_GHJ_RST_N
 144 TP_CH_J_DIMM_J0_RFU_2 RFU<2> @BASEBOARD_FAB2_LIB.BASEBOARD_FAB2(SCH_1):TP_CH_J_DIMM_J0_RFU_2
 227 TP_CH_J_DIMM_J0_RFU_1 RFU<1> @BASEBOARD_FAB2_LIB.BASEBOARD_FAB2(SCH_1):TP_CH_J_DIMM_J0_RFU_1
 205 TP_CH_J_DIMM_J0_RFU_0 RFU<0> @BASEBOARD_FAB2_LIB.BASEBOARD_FAB2(SCH_1):TP_CH_J_DIMM_J0_RFU_0
  84 M_J_CS_N<0>   S0_N @BASEBOARD_FAB2_LIB.BASEBOARD_FAB2(SCH_1):M_J_CS_N(0)
  89 M_J_CS_N<1>   S1_N @BASEBOARD_FAB2_LIB.BASEBOARD_FAB2(SCH_1):M_J_CS_N(1)
  93 M_J_CS_N<2> S2_N_C<0> @BASEBOARD_FAB2_LIB.BASEBOARD_FAB2(SCH_1):M_J_CS_N(2)
 237 M_J_CS_N<3> S3_N_C<1> @BASEBOARD_FAB2_LIB.BASEBOARD_FAB2(SCH_1):M_J_CS_N(3)
 238 PVPP_GHJ  SA<2> @BASEBOARD_FAB2_LIB.BASEBOARD_FAB2(SCH_1):PVPP_GHJ
 140    GND  SA<1> @BASEBOARD_FAB2_LIB.BASEBOARD_FAB2(SCH_1):GND
 139    GND  SA<0> @BASEBOARD_FAB2_LIB.BASEBOARD_FAB2(SCH_1):GND
 230 FM_ADR_COMPLETE_GHJ_N SAVE_N_NC @BASEBOARD_FAB2_LIB.BASEBOARD_FAB2(SCH_1):FM_ADR_COMPLETE_GHJ_N
 141 SMB_DDR_GHJ_VPP_SCL    SCL @BASEBOARD_FAB2_LIB.BASEBOARD_FAB2(SCH_1):SMB_DDR_GHJ_VPP_SCL
 285 SMB_DDR_GHJ_VPP_SDA    SDA @BASEBOARD_FAB2_LIB.BASEBOARD_FAB2(SCH_1):SMB_DDR_GHJ_VPP_SDA
 284 PVPP_GHJ VDDSPD @BASEBOARD_FAB2_LIB.BASEBOARD_FAB2(SCH_1):PVPP_GHJ
 146 M_J_VREF VREFCA @BASEBOARD_FAB2_LIB.BASEBOARD_FAB2(SCH_1):M_J_VREF


DRAWING: @BASEBOARD_FAB2_LIB.BASEBOARD_FAB2(SCH_1):PAGE82 

SCONN288_H44441003_PIP-SCONN,HA  I64  J9U2
 152 M_J_DQS_DN<0>  DQS0N @BASEBOARD_FAB2_LIB.BASEBOARD_FAB2(SCH_1):M_J_DQS_DN(0)
 153 M_J_DQS_DP<0>  DQS0P @BASEBOARD_FAB2_LIB.BASEBOARD_FAB2(SCH_1):M_J_DQS_DP(0)
  19 M_J_DQS_DN<10> DQS10N @BASEBOARD_FAB2_LIB.BASEBOARD_FAB2(SCH_1):M_J_DQS_DN(10)
  18 M_J_DQS_DP<10> DQS10P @BASEBOARD_FAB2_LIB.BASEBOARD_FAB2(SCH_1):M_J_DQS_DP(10)
  30 M_J_DQS_DN<11> DQS11N @BASEBOARD_FAB2_LIB.BASEBOARD_FAB2(SCH_1):M_J_DQS_DN(11)
  29 M_J_DQS_DP<11> DQS11P @BASEBOARD_FAB2_LIB.BASEBOARD_FAB2(SCH_1):M_J_DQS_DP(11)
  41 M_J_DQS_DN<12> DQS12N @BASEBOARD_FAB2_LIB.BASEBOARD_FAB2(SCH_1):M_J_DQS_DN(12)
  40 M_J_DQS_DP<12> DQS12P @BASEBOARD_FAB2_LIB.BASEBOARD_FAB2(SCH_1):M_J_DQS_DP(12)
 100 M_J_DQS_DN<13> DQS13N @BASEBOARD_FAB2_LIB.BASEBOARD_FAB2(SCH_1):M_J_DQS_DN(13)
  99 M_J_DQS_DP<13> DQS13P @BASEBOARD_FAB2_LIB.BASEBOARD_FAB2(SCH_1):M_J_DQS_DP(13)
 111 M_J_DQS_DN<14> DQS14N @BASEBOARD_FAB2_LIB.BASEBOARD_FAB2(SCH_1):M_J_DQS_DN(14)
 110 M_J_DQS_DP<14> DQS14P @BASEBOARD_FAB2_LIB.BASEBOARD_FAB2(SCH_1):M_J_DQS_DP(14)
 122 M_J_DQS_DN<15> DQS15N @BASEBOARD_FAB2_LIB.BASEBOARD_FAB2(SCH_1):M_J_DQS_DN(15)
 121 M_J_DQS_DP<15> DQS15P @BASEBOARD_FAB2_LIB.BASEBOARD_FAB2(SCH_1):M_J_DQS_DP(15)
 133 M_J_DQS_DN<16> DQS16N @BASEBOARD_FAB2_LIB.BASEBOARD_FAB2(SCH_1):M_J_DQS_DN(16)
 132 M_J_DQS_DP<16> DQS16P @BASEBOARD_FAB2_LIB.BASEBOARD_FAB2(SCH_1):M_J_DQS_DP(16)
  52 M_J_DQS_DN<17> DQS17N @BASEBOARD_FAB2_LIB.BASEBOARD_FAB2(SCH_1):M_J_DQS_DN(17)
  51 M_J_DQS_DP<17> DQS17P @BASEBOARD_FAB2_LIB.BASEBOARD_FAB2(SCH_1):M_J_DQS_DP(17)
 163 M_J_DQS_DN<1>  DQS1N @BASEBOARD_FAB2_LIB.BASEBOARD_FAB2(SCH_1):M_J_DQS_DN(1)
 164 M_J_DQS_DP<1>  DQS1P @BASEBOARD_FAB2_LIB.BASEBOARD_FAB2(SCH_1):M_J_DQS_DP(1)
 174 M_J_DQS_DN<2>  DQS2N @BASEBOARD_FAB2_LIB.BASEBOARD_FAB2(SCH_1):M_J_DQS_DN(2)
 175 M_J_DQS_DP<2>  DQS2P @BASEBOARD_FAB2_LIB.BASEBOARD_FAB2(SCH_1):M_J_DQS_DP(2)
 185 M_J_DQS_DN<3>  DQS3N @BASEBOARD_FAB2_LIB.BASEBOARD_FAB2(SCH_1):M_J_DQS_DN(3)
 186 M_J_DQS_DP<3>  DQS3P @BASEBOARD_FAB2_LIB.BASEBOARD_FAB2(SCH_1):M_J_DQS_DP(3)
 244 M_J_DQS_DN<4>  DQS4N @BASEBOARD_FAB2_LIB.BASEBOARD_FAB2(SCH_1):M_J_DQS_DN(4)
 245 M_J_DQS_DP<4>  DQS4P @BASEBOARD_FAB2_LIB.BASEBOARD_FAB2(SCH_1):M_J_DQS_DP(4)
 255 M_J_DQS_DN<5>  DQS5N @BASEBOARD_FAB2_LIB.BASEBOARD_FAB2(SCH_1):M_J_DQS_DN(5)
 256 M_J_DQS_DP<5>  DQS5P @BASEBOARD_FAB2_LIB.BASEBOARD_FAB2(SCH_1):M_J_DQS_DP(5)
 266 M_J_DQS_DN<6>  DQS6N @BASEBOARD_FAB2_LIB.BASEBOARD_FAB2(SCH_1):M_J_DQS_DN(6)
 267 M_J_DQS_DP<6>  DQS6P @BASEBOARD_FAB2_LIB.BASEBOARD_FAB2(SCH_1):M_J_DQS_DP(6)
 277 M_J_DQS_DN<7>  DQS7N @BASEBOARD_FAB2_LIB.BASEBOARD_FAB2(SCH_1):M_J_DQS_DN(7)
 278 M_J_DQS_DP<7>  DQS7P @BASEBOARD_FAB2_LIB.BASEBOARD_FAB2(SCH_1):M_J_DQS_DP(7)
 196 M_J_DQS_DN<8>  DQS8N @BASEBOARD_FAB2_LIB.BASEBOARD_FAB2(SCH_1):M_J_DQS_DN(8)
 197 M_J_DQS_DP<8>  DQS8P @BASEBOARD_FAB2_LIB.BASEBOARD_FAB2(SCH_1):M_J_DQS_DP(8)
   8 M_J_DQS_DN<9>  DQS9N @BASEBOARD_FAB2_LIB.BASEBOARD_FAB2(SCH_1):M_J_DQS_DN(9)
   7 M_J_DQS_DP<9>  DQS9P @BASEBOARD_FAB2_LIB.BASEBOARD_FAB2(SCH_1):M_J_DQS_DP(9)

SCONN288_H44441003_PIP-SCONN,HA  I171  J9U2
   1 P12V_NVDIMM_GHJ 12V<1> @BASEBOARD_FAB2_LIB.BASEBOARD_FAB2(SCH_1):P12V_NVDIMM_GHJ
 145 P12V_NVDIMM_GHJ 12V<0> @BASEBOARD_FAB2_LIB.BASEBOARD_FAB2(SCH_1):P12V_NVDIMM_GHJ
  59 PVDDQ_GHJ VDD<25> @BASEBOARD_FAB2_LIB.BASEBOARD_FAB2(SCH_1):PVDDQ_GHJ
  61 PVDDQ_GHJ VDD<24> @BASEBOARD_FAB2_LIB.BASEBOARD_FAB2(SCH_1):PVDDQ_GHJ
  64 PVDDQ_GHJ VDD<23> @BASEBOARD_FAB2_LIB.BASEBOARD_FAB2(SCH_1):PVDDQ_GHJ
  67 PVDDQ_GHJ VDD<22> @BASEBOARD_FAB2_LIB.BASEBOARD_FAB2(SCH_1):PVDDQ_GHJ
  70 PVDDQ_GHJ VDD<21> @BASEBOARD_FAB2_LIB.BASEBOARD_FAB2(SCH_1):PVDDQ_GHJ
  73 PVDDQ_GHJ VDD<20> @BASEBOARD_FAB2_LIB.BASEBOARD_FAB2(SCH_1):PVDDQ_GHJ
  76 PVDDQ_GHJ VDD<19> @BASEBOARD_FAB2_LIB.BASEBOARD_FAB2(SCH_1):PVDDQ_GHJ
  80 PVDDQ_GHJ VDD<18> @BASEBOARD_FAB2_LIB.BASEBOARD_FAB2(SCH_1):PVDDQ_GHJ
  83 PVDDQ_GHJ VDD<17> @BASEBOARD_FAB2_LIB.BASEBOARD_FAB2(SCH_1):PVDDQ_GHJ
  85 PVDDQ_GHJ VDD<16> @BASEBOARD_FAB2_LIB.BASEBOARD_FAB2(SCH_1):PVDDQ_GHJ
  88 PVDDQ_GHJ VDD<15> @BASEBOARD_FAB2_LIB.BASEBOARD_FAB2(SCH_1):PVDDQ_GHJ
  90 PVDDQ_GHJ VDD<14> @BASEBOARD_FAB2_LIB.BASEBOARD_FAB2(SCH_1):PVDDQ_GHJ
  92 PVDDQ_GHJ VDD<13> @BASEBOARD_FAB2_LIB.BASEBOARD_FAB2(SCH_1):PVDDQ_GHJ
 204 PVDDQ_GHJ VDD<12> @BASEBOARD_FAB2_LIB.BASEBOARD_FAB2(SCH_1):PVDDQ_GHJ
 206 PVDDQ_GHJ VDD<11> @BASEBOARD_FAB2_LIB.BASEBOARD_FAB2(SCH_1):PVDDQ_GHJ
 209 PVDDQ_GHJ VDD<10> @BASEBOARD_FAB2_LIB.BASEBOARD_FAB2(SCH_1):PVDDQ_GHJ
 212 PVDDQ_GHJ VDD<9> @BASEBOARD_FAB2_LIB.BASEBOARD_FAB2(SCH_1):PVDDQ_GHJ
 215 PVDDQ_GHJ VDD<8> @BASEBOARD_FAB2_LIB.BASEBOARD_FAB2(SCH_1):PVDDQ_GHJ
 217 PVDDQ_GHJ VDD<7> @BASEBOARD_FAB2_LIB.BASEBOARD_FAB2(SCH_1):PVDDQ_GHJ
 220 PVDDQ_GHJ VDD<6> @BASEBOARD_FAB2_LIB.BASEBOARD_FAB2(SCH_1):PVDDQ_GHJ
 223 PVDDQ_GHJ VDD<5> @BASEBOARD_FAB2_LIB.BASEBOARD_FAB2(SCH_1):PVDDQ_GHJ
 226 PVDDQ_GHJ VDD<4> @BASEBOARD_FAB2_LIB.BASEBOARD_FAB2(SCH_1):PVDDQ_GHJ
 229 PVDDQ_GHJ VDD<3> @BASEBOARD_FAB2_LIB.BASEBOARD_FAB2(SCH_1):PVDDQ_GHJ
 231 PVDDQ_GHJ VDD<2> @BASEBOARD_FAB2_LIB.BASEBOARD_FAB2(SCH_1):PVDDQ_GHJ
 233 PVDDQ_GHJ VDD<1> @BASEBOARD_FAB2_LIB.BASEBOARD_FAB2(SCH_1):PVDDQ_GHJ
 236 PVDDQ_GHJ VDD<0> @BASEBOARD_FAB2_LIB.BASEBOARD_FAB2(SCH_1):PVDDQ_GHJ
 142 PVPP_GHJ VPP<4> @BASEBOARD_FAB2_LIB.BASEBOARD_FAB2(SCH_1):PVPP_GHJ
 143 PVPP_GHJ VPP<3> @BASEBOARD_FAB2_LIB.BASEBOARD_FAB2(SCH_1):PVPP_GHJ
 288 PVPP_GHJ VPP<2> @BASEBOARD_FAB2_LIB.BASEBOARD_FAB2(SCH_1):PVPP_GHJ
 286 PVPP_GHJ VPP<1> @BASEBOARD_FAB2_LIB.BASEBOARD_FAB2(SCH_1):PVPP_GHJ
 287 PVPP_GHJ VPP<0> @BASEBOARD_FAB2_LIB.BASEBOARD_FAB2(SCH_1):PVPP_GHJ
  77 PVTT_GHJ VTT<1> @BASEBOARD_FAB2_LIB.BASEBOARD_FAB2(SCH_1):PVTT_GHJ
 221 PVTT_GHJ VTT<0> @BASEBOARD_FAB2_LIB.BASEBOARD_FAB2(SCH_1):PVTT_GHJ

CAP_A_0402V-0.01UF,25V,10%,X7RA  I180  C1G19
   1 M_J_VREF      A @BASEBOARD_FAB2_LIB.BASEBOARD_FAB2(SCH_1):M_J_VREF
   2    GND      B @BASEBOARD_FAB2_LIB.BASEBOARD_FAB2(SCH_1):GND

SCONN288_H44441003_PIP-SCONN,HA  I187  J9U2
  79 M_J_MA<0>     A0 @BASEBOARD_FAB2_LIB.BASEBOARD_FAB2(SCH_1):M_J_MA(0)
  72 M_J_MA<1>     A1 @BASEBOARD_FAB2_LIB.BASEBOARD_FAB2(SCH_1):M_J_MA(1)
 225 M_J_MA<10>    A10 @BASEBOARD_FAB2_LIB.BASEBOARD_FAB2(SCH_1):M_J_MA(10)
 210 M_J_MA<11>    A11 @BASEBOARD_FAB2_LIB.BASEBOARD_FAB2(SCH_1):M_J_MA(11)
  65 M_J_MA<12>    A12 @BASEBOARD_FAB2_LIB.BASEBOARD_FAB2(SCH_1):M_J_MA(12)
 232 M_J_MA<13>    A13 @BASEBOARD_FAB2_LIB.BASEBOARD_FAB2(SCH_1):M_J_MA(13)
 228 M_J_MA<14> A14_WE_N @BASEBOARD_FAB2_LIB.BASEBOARD_FAB2(SCH_1):M_J_MA(14)
  86 M_J_MA<15> A15_CAS_N @BASEBOARD_FAB2_LIB.BASEBOARD_FAB2(SCH_1):M_J_MA(15)
  82 M_J_MA<16> A16_RAS_N @BASEBOARD_FAB2_LIB.BASEBOARD_FAB2(SCH_1):M_J_MA(16)
 234 M_J_MA<17>    A17 @BASEBOARD_FAB2_LIB.BASEBOARD_FAB2(SCH_1):M_J_MA(17)
 216 M_J_MA<2>     A2 @BASEBOARD_FAB2_LIB.BASEBOARD_FAB2(SCH_1):M_J_MA(2)
  71 M_J_MA<3>     A3 @BASEBOARD_FAB2_LIB.BASEBOARD_FAB2(SCH_1):M_J_MA(3)
 214 M_J_MA<4>     A4 @BASEBOARD_FAB2_LIB.BASEBOARD_FAB2(SCH_1):M_J_MA(4)
 213 M_J_MA<5>     A5 @BASEBOARD_FAB2_LIB.BASEBOARD_FAB2(SCH_1):M_J_MA(5)
  69 M_J_MA<6>     A6 @BASEBOARD_FAB2_LIB.BASEBOARD_FAB2(SCH_1):M_J_MA(6)
 211 M_J_MA<7>     A7 @BASEBOARD_FAB2_LIB.BASEBOARD_FAB2(SCH_1):M_J_MA(7)
  68 M_J_MA<8>     A8 @BASEBOARD_FAB2_LIB.BASEBOARD_FAB2(SCH_1):M_J_MA(8)
  66 M_J_MA<9>     A9 @BASEBOARD_FAB2_LIB.BASEBOARD_FAB2(SCH_1):M_J_MA(9)
  62 M_J_ACT_N  ACT_N @BASEBOARD_FAB2_LIB.BASEBOARD_FAB2(SCH_1):M_J_ACT_N
 208 M_J_ALERT_N ALERT_N @BASEBOARD_FAB2_LIB.BASEBOARD_FAB2(SCH_1):M_J_ALERT_N
 224 M_J_BA<1>  BA<1> @BASEBOARD_FAB2_LIB.BASEBOARD_FAB2(SCH_1):M_J_BA(1)
  81 M_J_BA<0>  BA<0> @BASEBOARD_FAB2_LIB.BASEBOARD_FAB2(SCH_1):M_J_BA(0)
 207 M_J_BG<1>  BG<1> @BASEBOARD_FAB2_LIB.BASEBOARD_FAB2(SCH_1):M_J_BG(1)
  63 M_J_BG<0>  BG<0> @BASEBOARD_FAB2_LIB.BASEBOARD_FAB2(SCH_1):M_J_BG(0)
 235 M_J_C<2>   C<2> @BASEBOARD_FAB2_LIB.BASEBOARD_FAB2(SCH_1):M_J_C(2)
 199 M_J_ECC<7>  CB<7> @BASEBOARD_FAB2_LIB.BASEBOARD_FAB2(SCH_1):M_J_ECC(7)
  54 M_J_ECC<6>  CB<6> @BASEBOARD_FAB2_LIB.BASEBOARD_FAB2(SCH_1):M_J_ECC(6)
 192 M_J_ECC<5>  CB<5> @BASEBOARD_FAB2_LIB.BASEBOARD_FAB2(SCH_1):M_J_ECC(5)
  47 M_J_ECC<4>  CB<4> @BASEBOARD_FAB2_LIB.BASEBOARD_FAB2(SCH_1):M_J_ECC(4)
 201 M_J_ECC<3>  CB<3> @BASEBOARD_FAB2_LIB.BASEBOARD_FAB2(SCH_1):M_J_ECC(3)
  56 M_J_ECC<2>  CB<2> @BASEBOARD_FAB2_LIB.BASEBOARD_FAB2(SCH_1):M_J_ECC(2)
 194 M_J_ECC<1>  CB<1> @BASEBOARD_FAB2_LIB.BASEBOARD_FAB2(SCH_1):M_J_ECC(1)
  49 M_J_ECC<0>  CB<0> @BASEBOARD_FAB2_LIB.BASEBOARD_FAB2(SCH_1):M_J_ECC(0)
  75 M_J_CLK_DN<2>   CK0N @BASEBOARD_FAB2_LIB.BASEBOARD_FAB2(SCH_1):M_J_CLK_DN(2)
  74 M_J_CLK_DP<2>   CK0P @BASEBOARD_FAB2_LIB.BASEBOARD_FAB2(SCH_1):M_J_CLK_DP(2)
 219 M_J_CLK_DN<3>   CK1N @BASEBOARD_FAB2_LIB.BASEBOARD_FAB2(SCH_1):M_J_CLK_DN(3)
 218 M_J_CLK_DP<3>   CK1P @BASEBOARD_FAB2_LIB.BASEBOARD_FAB2(SCH_1):M_J_CLK_DP(3)
 203 M_J_CKE<3> CKE<1> @BASEBOARD_FAB2_LIB.BASEBOARD_FAB2(SCH_1):M_J_CKE(3)
  60 M_J_CKE<2> CKE<0> @BASEBOARD_FAB2_LIB.BASEBOARD_FAB2(SCH_1):M_J_CKE(2)
 280 M_J_DQ<63> DQ<63> @BASEBOARD_FAB2_LIB.BASEBOARD_FAB2(SCH_1):M_J_DQ(63)
 135 M_J_DQ<62> DQ<62> @BASEBOARD_FAB2_LIB.BASEBOARD_FAB2(SCH_1):M_J_DQ(62)
 273 M_J_DQ<61> DQ<61> @BASEBOARD_FAB2_LIB.BASEBOARD_FAB2(SCH_1):M_J_DQ(61)
 128 M_J_DQ<60> DQ<60> @BASEBOARD_FAB2_LIB.BASEBOARD_FAB2(SCH_1):M_J_DQ(60)
 282 M_J_DQ<59> DQ<59> @BASEBOARD_FAB2_LIB.BASEBOARD_FAB2(SCH_1):M_J_DQ(59)
 137 M_J_DQ<58> DQ<58> @BASEBOARD_FAB2_LIB.BASEBOARD_FAB2(SCH_1):M_J_DQ(58)
 275 M_J_DQ<57> DQ<57> @BASEBOARD_FAB2_LIB.BASEBOARD_FAB2(SCH_1):M_J_DQ(57)
 130 M_J_DQ<56> DQ<56> @BASEBOARD_FAB2_LIB.BASEBOARD_FAB2(SCH_1):M_J_DQ(56)
 269 M_J_DQ<55> DQ<55> @BASEBOARD_FAB2_LIB.BASEBOARD_FAB2(SCH_1):M_J_DQ(55)
 124 M_J_DQ<54> DQ<54> @BASEBOARD_FAB2_LIB.BASEBOARD_FAB2(SCH_1):M_J_DQ(54)
 262 M_J_DQ<53> DQ<53> @BASEBOARD_FAB2_LIB.BASEBOARD_FAB2(SCH_1):M_J_DQ(53)
 117 M_J_DQ<52> DQ<52> @BASEBOARD_FAB2_LIB.BASEBOARD_FAB2(SCH_1):M_J_DQ(52)
 271 M_J_DQ<51> DQ<51> @BASEBOARD_FAB2_LIB.BASEBOARD_FAB2(SCH_1):M_J_DQ(51)
 126 M_J_DQ<50> DQ<50> @BASEBOARD_FAB2_LIB.BASEBOARD_FAB2(SCH_1):M_J_DQ(50)
 264 M_J_DQ<49> DQ<49> @BASEBOARD_FAB2_LIB.BASEBOARD_FAB2(SCH_1):M_J_DQ(49)
 119 M_J_DQ<48> DQ<48> @BASEBOARD_FAB2_LIB.BASEBOARD_FAB2(SCH_1):M_J_DQ(48)
 258 M_J_DQ<47> DQ<47> @BASEBOARD_FAB2_LIB.BASEBOARD_FAB2(SCH_1):M_J_DQ(47)
 113 M_J_DQ<46> DQ<46> @BASEBOARD_FAB2_LIB.BASEBOARD_FAB2(SCH_1):M_J_DQ(46)
 251 M_J_DQ<45> DQ<45> @BASEBOARD_FAB2_LIB.BASEBOARD_FAB2(SCH_1):M_J_DQ(45)
 106 M_J_DQ<44> DQ<44> @BASEBOARD_FAB2_LIB.BASEBOARD_FAB2(SCH_1):M_J_DQ(44)
 260 M_J_DQ<43> DQ<43> @BASEBOARD_FAB2_LIB.BASEBOARD_FAB2(SCH_1):M_J_DQ(43)
 115 M_J_DQ<42> DQ<42> @BASEBOARD_FAB2_LIB.BASEBOARD_FAB2(SCH_1):M_J_DQ(42)
 253 M_J_DQ<41> DQ<41> @BASEBOARD_FAB2_LIB.BASEBOARD_FAB2(SCH_1):M_J_DQ(41)
 108 M_J_DQ<40> DQ<40> @BASEBOARD_FAB2_LIB.BASEBOARD_FAB2(SCH_1):M_J_DQ(40)
 247 M_J_DQ<39> DQ<39> @BASEBOARD_FAB2_LIB.BASEBOARD_FAB2(SCH_1):M_J_DQ(39)
 102 M_J_DQ<38> DQ<38> @BASEBOARD_FAB2_LIB.BASEBOARD_FAB2(SCH_1):M_J_DQ(38)
 240 M_J_DQ<37> DQ<37> @BASEBOARD_FAB2_LIB.BASEBOARD_FAB2(SCH_1):M_J_DQ(37)
  95 M_J_DQ<36> DQ<36> @BASEBOARD_FAB2_LIB.BASEBOARD_FAB2(SCH_1):M_J_DQ(36)
 249 M_J_DQ<35> DQ<35> @BASEBOARD_FAB2_LIB.BASEBOARD_FAB2(SCH_1):M_J_DQ(35)
 104 M_J_DQ<34> DQ<34> @BASEBOARD_FAB2_LIB.BASEBOARD_FAB2(SCH_1):M_J_DQ(34)
 242 M_J_DQ<33> DQ<33> @BASEBOARD_FAB2_LIB.BASEBOARD_FAB2(SCH_1):M_J_DQ(33)
  97 M_J_DQ<32> DQ<32> @BASEBOARD_FAB2_LIB.BASEBOARD_FAB2(SCH_1):M_J_DQ(32)
 188 M_J_DQ<31> DQ<31> @BASEBOARD_FAB2_LIB.BASEBOARD_FAB2(SCH_1):M_J_DQ(31)
  43 M_J_DQ<30> DQ<30> @BASEBOARD_FAB2_LIB.BASEBOARD_FAB2(SCH_1):M_J_DQ(30)
 181 M_J_DQ<29> DQ<29> @BASEBOARD_FAB2_LIB.BASEBOARD_FAB2(SCH_1):M_J_DQ(29)
  36 M_J_DQ<28> DQ<28> @BASEBOARD_FAB2_LIB.BASEBOARD_FAB2(SCH_1):M_J_DQ(28)
 190 M_J_DQ<27> DQ<27> @BASEBOARD_FAB2_LIB.BASEBOARD_FAB2(SCH_1):M_J_DQ(27)
  45 M_J_DQ<26> DQ<26> @BASEBOARD_FAB2_LIB.BASEBOARD_FAB2(SCH_1):M_J_DQ(26)
 183 M_J_DQ<25> DQ<25> @BASEBOARD_FAB2_LIB.BASEBOARD_FAB2(SCH_1):M_J_DQ(25)
  38 M_J_DQ<24> DQ<24> @BASEBOARD_FAB2_LIB.BASEBOARD_FAB2(SCH_1):M_J_DQ(24)
 177 M_J_DQ<23> DQ<23> @BASEBOARD_FAB2_LIB.BASEBOARD_FAB2(SCH_1):M_J_DQ(23)
  32 M_J_DQ<22> DQ<22> @BASEBOARD_FAB2_LIB.BASEBOARD_FAB2(SCH_1):M_J_DQ(22)
 170 M_J_DQ<21> DQ<21> @BASEBOARD_FAB2_LIB.BASEBOARD_FAB2(SCH_1):M_J_DQ(21)
  25 M_J_DQ<20> DQ<20> @BASEBOARD_FAB2_LIB.BASEBOARD_FAB2(SCH_1):M_J_DQ(20)
 179 M_J_DQ<19> DQ<19> @BASEBOARD_FAB2_LIB.BASEBOARD_FAB2(SCH_1):M_J_DQ(19)
  34 M_J_DQ<18> DQ<18> @BASEBOARD_FAB2_LIB.BASEBOARD_FAB2(SCH_1):M_J_DQ(18)
 172 M_J_DQ<17> DQ<17> @BASEBOARD_FAB2_LIB.BASEBOARD_FAB2(SCH_1):M_J_DQ(17)
  27 M_J_DQ<16> DQ<16> @BASEBOARD_FAB2_LIB.BASEBOARD_FAB2(SCH_1):M_J_DQ(16)
 166 M_J_DQ<15> DQ<15> @BASEBOARD_FAB2_LIB.BASEBOARD_FAB2(SCH_1):M_J_DQ(15)
  21 M_J_DQ<14> DQ<14> @BASEBOARD_FAB2_LIB.BASEBOARD_FAB2(SCH_1):M_J_DQ(14)
 159 M_J_DQ<13> DQ<13> @BASEBOARD_FAB2_LIB.BASEBOARD_FAB2(SCH_1):M_J_DQ(13)
  14 M_J_DQ<12> DQ<12> @BASEBOARD_FAB2_LIB.BASEBOARD_FAB2(SCH_1):M_J_DQ(12)
 168 M_J_DQ<11> DQ<11> @BASEBOARD_FAB2_LIB.BASEBOARD_FAB2(SCH_1):M_J_DQ(11)
  23 M_J_DQ<10> DQ<10> @BASEBOARD_FAB2_LIB.BASEBOARD_FAB2(SCH_1):M_J_DQ(10)
 161 M_J_DQ<9>  DQ<9> @BASEBOARD_FAB2_LIB.BASEBOARD_FAB2(SCH_1):M_J_DQ(9)
  16 M_J_DQ<8>  DQ<8> @BASEBOARD_FAB2_LIB.BASEBOARD_FAB2(SCH_1):M_J_DQ(8)
 155 M_J_DQ<7>  DQ<7> @BASEBOARD_FAB2_LIB.BASEBOARD_FAB2(SCH_1):M_J_DQ(7)
  10 M_J_DQ<6>  DQ<6> @BASEBOARD_FAB2_LIB.BASEBOARD_FAB2(SCH_1):M_J_DQ(6)
 148 M_J_DQ<5>  DQ<5> @BASEBOARD_FAB2_LIB.BASEBOARD_FAB2(SCH_1):M_J_DQ(5)
   3 M_J_DQ<4>  DQ<4> @BASEBOARD_FAB2_LIB.BASEBOARD_FAB2(SCH_1):M_J_DQ(4)
 157 M_J_DQ<3>  DQ<3> @BASEBOARD_FAB2_LIB.BASEBOARD_FAB2(SCH_1):M_J_DQ(3)
  12 M_J_DQ<2>  DQ<2> @BASEBOARD_FAB2_LIB.BASEBOARD_FAB2(SCH_1):M_J_DQ(2)
 150 M_J_DQ<1>  DQ<1> @BASEBOARD_FAB2_LIB.BASEBOARD_FAB2(SCH_1):M_J_DQ(1)
   5 M_J_DQ<0>  DQ<0> @BASEBOARD_FAB2_LIB.BASEBOARD_FAB2(SCH_1):M_J_DQ(0)
  78 FM_DIMM_EVENT_COD_N EVENT_N @BASEBOARD_FAB2_LIB.BASEBOARD_FAB2(SCH_1):FM_DIMM_EVENT_COD_N
  91 M_J_ODT<3> ODT<1> @BASEBOARD_FAB2_LIB.BASEBOARD_FAB2(SCH_1):M_J_ODT(3)
  87 M_J_ODT<2> ODT<0> @BASEBOARD_FAB2_LIB.BASEBOARD_FAB2(SCH_1):M_J_ODT(2)
 222 M_J_PAR    PAR @BASEBOARD_FAB2_LIB.BASEBOARD_FAB2(SCH_1):M_J_PAR
  58 M_GHJ_RST_N RESET_N @BASEBOARD_FAB2_LIB.BASEBOARD_FAB2(SCH_1):M_GHJ_RST_N
 144 TP_CH_J_DIMM_J1_RFU_2 RFU<2> @BASEBOARD_FAB2_LIB.BASEBOARD_FAB2(SCH_1):TP_CH_J_DIMM_J1_RFU_2
 227 TP_CH_J_DIMM_J1_RFU_1 RFU<1> @BASEBOARD_FAB2_LIB.BASEBOARD_FAB2(SCH_1):TP_CH_J_DIMM_J1_RFU_1
 205 TP_CH_J_DIMM_J1_RFU_0 RFU<0> @BASEBOARD_FAB2_LIB.BASEBOARD_FAB2(SCH_1):TP_CH_J_DIMM_J1_RFU_0
  84 M_J_CS_N<4>   S0_N @BASEBOARD_FAB2_LIB.BASEBOARD_FAB2(SCH_1):M_J_CS_N(4)
  89 M_J_CS_N<5>   S1_N @BASEBOARD_FAB2_LIB.BASEBOARD_FAB2(SCH_1):M_J_CS_N(5)
  93 M_J_CS_N<6> S2_N_C<0> @BASEBOARD_FAB2_LIB.BASEBOARD_FAB2(SCH_1):M_J_CS_N(6)
 237 M_J_CS_N<7> S3_N_C<1> @BASEBOARD_FAB2_LIB.BASEBOARD_FAB2(SCH_1):M_J_CS_N(7)
 238 PVPP_GHJ  SA<2> @BASEBOARD_FAB2_LIB.BASEBOARD_FAB2(SCH_1):PVPP_GHJ
 140    GND  SA<1> @BASEBOARD_FAB2_LIB.BASEBOARD_FAB2(SCH_1):GND
 139 PVPP_GHJ  SA<0> @BASEBOARD_FAB2_LIB.BASEBOARD_FAB2(SCH_1):PVPP_GHJ
 230 FM_ADR_COMPLETE_GHJ_N SAVE_N_NC @BASEBOARD_FAB2_LIB.BASEBOARD_FAB2(SCH_1):FM_ADR_COMPLETE_GHJ_N
 141 SMB_DDR_GHJ_VPP_SCL    SCL @BASEBOARD_FAB2_LIB.BASEBOARD_FAB2(SCH_1):SMB_DDR_GHJ_VPP_SCL
 285 SMB_DDR_GHJ_VPP_SDA    SDA @BASEBOARD_FAB2_LIB.BASEBOARD_FAB2(SCH_1):SMB_DDR_GHJ_VPP_SDA
 284 PVPP_GHJ VDDSPD @BASEBOARD_FAB2_LIB.BASEBOARD_FAB2(SCH_1):PVPP_GHJ
 146 M_J_VREF VREFCA @BASEBOARD_FAB2_LIB.BASEBOARD_FAB2(SCH_1):M_J_VREF

SCONN288_H44441003_PIP-SCONN,HA  I188  J9U2
   2    GND VSS<93> @BASEBOARD_FAB2_LIB.BASEBOARD_FAB2(SCH_1):GND
   4    GND VSS<92> @BASEBOARD_FAB2_LIB.BASEBOARD_FAB2(SCH_1):GND
   6    GND VSS<91> @BASEBOARD_FAB2_LIB.BASEBOARD_FAB2(SCH_1):GND
   9    GND VSS<90> @BASEBOARD_FAB2_LIB.BASEBOARD_FAB2(SCH_1):GND
  11    GND VSS<89> @BASEBOARD_FAB2_LIB.BASEBOARD_FAB2(SCH_1):GND
  13    GND VSS<88> @BASEBOARD_FAB2_LIB.BASEBOARD_FAB2(SCH_1):GND
  15    GND VSS<87> @BASEBOARD_FAB2_LIB.BASEBOARD_FAB2(SCH_1):GND
  17    GND VSS<86> @BASEBOARD_FAB2_LIB.BASEBOARD_FAB2(SCH_1):GND
  20    GND VSS<85> @BASEBOARD_FAB2_LIB.BASEBOARD_FAB2(SCH_1):GND
  22    GND VSS<84> @BASEBOARD_FAB2_LIB.BASEBOARD_FAB2(SCH_1):GND
  24    GND VSS<83> @BASEBOARD_FAB2_LIB.BASEBOARD_FAB2(SCH_1):GND
  26    GND VSS<82> @BASEBOARD_FAB2_LIB.BASEBOARD_FAB2(SCH_1):GND
  28    GND VSS<81> @BASEBOARD_FAB2_LIB.BASEBOARD_FAB2(SCH_1):GND
  31    GND VSS<80> @BASEBOARD_FAB2_LIB.BASEBOARD_FAB2(SCH_1):GND
  33    GND VSS<79> @BASEBOARD_FAB2_LIB.BASEBOARD_FAB2(SCH_1):GND
  35    GND VSS<78> @BASEBOARD_FAB2_LIB.BASEBOARD_FAB2(SCH_1):GND
  37    GND VSS<77> @BASEBOARD_FAB2_LIB.BASEBOARD_FAB2(SCH_1):GND
  39    GND VSS<76> @BASEBOARD_FAB2_LIB.BASEBOARD_FAB2(SCH_1):GND
  42    GND VSS<75> @BASEBOARD_FAB2_LIB.BASEBOARD_FAB2(SCH_1):GND
  44    GND VSS<74> @BASEBOARD_FAB2_LIB.BASEBOARD_FAB2(SCH_1):GND
  46    GND VSS<73> @BASEBOARD_FAB2_LIB.BASEBOARD_FAB2(SCH_1):GND
  48    GND VSS<72> @BASEBOARD_FAB2_LIB.BASEBOARD_FAB2(SCH_1):GND
  50    GND VSS<71> @BASEBOARD_FAB2_LIB.BASEBOARD_FAB2(SCH_1):GND
  53    GND VSS<70> @BASEBOARD_FAB2_LIB.BASEBOARD_FAB2(SCH_1):GND
  55    GND VSS<69> @BASEBOARD_FAB2_LIB.BASEBOARD_FAB2(SCH_1):GND
  57    GND VSS<68> @BASEBOARD_FAB2_LIB.BASEBOARD_FAB2(SCH_1):GND
  94    GND VSS<67> @BASEBOARD_FAB2_LIB.BASEBOARD_FAB2(SCH_1):GND
  96    GND VSS<66> @BASEBOARD_FAB2_LIB.BASEBOARD_FAB2(SCH_1):GND
  98    GND VSS<65> @BASEBOARD_FAB2_LIB.BASEBOARD_FAB2(SCH_1):GND
 101    GND VSS<64> @BASEBOARD_FAB2_LIB.BASEBOARD_FAB2(SCH_1):GND
 103    GND VSS<63> @BASEBOARD_FAB2_LIB.BASEBOARD_FAB2(SCH_1):GND
 105    GND VSS<62> @BASEBOARD_FAB2_LIB.BASEBOARD_FAB2(SCH_1):GND
 107    GND VSS<61> @BASEBOARD_FAB2_LIB.BASEBOARD_FAB2(SCH_1):GND
 109    GND VSS<60> @BASEBOARD_FAB2_LIB.BASEBOARD_FAB2(SCH_1):GND
 112    GND VSS<59> @BASEBOARD_FAB2_LIB.BASEBOARD_FAB2(SCH_1):GND
 114    GND VSS<58> @BASEBOARD_FAB2_LIB.BASEBOARD_FAB2(SCH_1):GND
 116    GND VSS<57> @BASEBOARD_FAB2_LIB.BASEBOARD_FAB2(SCH_1):GND
 118    GND VSS<56> @BASEBOARD_FAB2_LIB.BASEBOARD_FAB2(SCH_1):GND
 120    GND VSS<55> @BASEBOARD_FAB2_LIB.BASEBOARD_FAB2(SCH_1):GND
 123    GND VSS<54> @BASEBOARD_FAB2_LIB.BASEBOARD_FAB2(SCH_1):GND
 125    GND VSS<53> @BASEBOARD_FAB2_LIB.BASEBOARD_FAB2(SCH_1):GND
 127    GND VSS<52> @BASEBOARD_FAB2_LIB.BASEBOARD_FAB2(SCH_1):GND
 129    GND VSS<51> @BASEBOARD_FAB2_LIB.BASEBOARD_FAB2(SCH_1):GND
 131    GND VSS<50> @BASEBOARD_FAB2_LIB.BASEBOARD_FAB2(SCH_1):GND
 134    GND VSS<49> @BASEBOARD_FAB2_LIB.BASEBOARD_FAB2(SCH_1):GND
 136    GND VSS<48> @BASEBOARD_FAB2_LIB.BASEBOARD_FAB2(SCH_1):GND
 138    GND VSS<47> @BASEBOARD_FAB2_LIB.BASEBOARD_FAB2(SCH_1):GND
 147    GND VSS<46> @BASEBOARD_FAB2_LIB.BASEBOARD_FAB2(SCH_1):GND
 149    GND VSS<45> @BASEBOARD_FAB2_LIB.BASEBOARD_FAB2(SCH_1):GND
 151    GND VSS<44> @BASEBOARD_FAB2_LIB.BASEBOARD_FAB2(SCH_1):GND
 154    GND VSS<43> @BASEBOARD_FAB2_LIB.BASEBOARD_FAB2(SCH_1):GND
 156    GND VSS<42> @BASEBOARD_FAB2_LIB.BASEBOARD_FAB2(SCH_1):GND
 158    GND VSS<41> @BASEBOARD_FAB2_LIB.BASEBOARD_FAB2(SCH_1):GND
 160    GND VSS<40> @BASEBOARD_FAB2_LIB.BASEBOARD_FAB2(SCH_1):GND
 162    GND VSS<39> @BASEBOARD_FAB2_LIB.BASEBOARD_FAB2(SCH_1):GND
 165    GND VSS<38> @BASEBOARD_FAB2_LIB.BASEBOARD_FAB2(SCH_1):GND
 167    GND VSS<37> @BASEBOARD_FAB2_LIB.BASEBOARD_FAB2(SCH_1):GND
 169    GND VSS<36> @BASEBOARD_FAB2_LIB.BASEBOARD_FAB2(SCH_1):GND
 171    GND VSS<35> @BASEBOARD_FAB2_LIB.BASEBOARD_FAB2(SCH_1):GND
 173    GND VSS<34> @BASEBOARD_FAB2_LIB.BASEBOARD_FAB2(SCH_1):GND
 176    GND VSS<33> @BASEBOARD_FAB2_LIB.BASEBOARD_FAB2(SCH_1):GND
 178    GND VSS<32> @BASEBOARD_FAB2_LIB.BASEBOARD_FAB2(SCH_1):GND
 180    GND VSS<31> @BASEBOARD_FAB2_LIB.BASEBOARD_FAB2(SCH_1):GND
 182    GND VSS<30> @BASEBOARD_FAB2_LIB.BASEBOARD_FAB2(SCH_1):GND
 184    GND VSS<29> @BASEBOARD_FAB2_LIB.BASEBOARD_FAB2(SCH_1):GND
 187    GND VSS<28> @BASEBOARD_FAB2_LIB.BASEBOARD_FAB2(SCH_1):GND
 189    GND VSS<27> @BASEBOARD_FAB2_LIB.BASEBOARD_FAB2(SCH_1):GND
 191    GND VSS<26> @BASEBOARD_FAB2_LIB.BASEBOARD_FAB2(SCH_1):GND
 193    GND VSS<25> @BASEBOARD_FAB2_LIB.BASEBOARD_FAB2(SCH_1):GND
 195    GND VSS<24> @BASEBOARD_FAB2_LIB.BASEBOARD_FAB2(SCH_1):GND
 198    GND VSS<23> @BASEBOARD_FAB2_LIB.BASEBOARD_FAB2(SCH_1):GND
 200    GND VSS<22> @BASEBOARD_FAB2_LIB.BASEBOARD_FAB2(SCH_1):GND
 202    GND VSS<21> @BASEBOARD_FAB2_LIB.BASEBOARD_FAB2(SCH_1):GND
 239    GND VSS<20> @BASEBOARD_FAB2_LIB.BASEBOARD_FAB2(SCH_1):GND
 241    GND VSS<19> @BASEBOARD_FAB2_LIB.BASEBOARD_FAB2(SCH_1):GND
 243    GND VSS<18> @BASEBOARD_FAB2_LIB.BASEBOARD_FAB2(SCH_1):GND
 246    GND VSS<17> @BASEBOARD_FAB2_LIB.BASEBOARD_FAB2(SCH_1):GND
 248    GND VSS<16> @BASEBOARD_FAB2_LIB.BASEBOARD_FAB2(SCH_1):GND
 250    GND VSS<15> @BASEBOARD_FAB2_LIB.BASEBOARD_FAB2(SCH_1):GND
 252    GND VSS<14> @BASEBOARD_FAB2_LIB.BASEBOARD_FAB2(SCH_1):GND
 254    GND VSS<13> @BASEBOARD_FAB2_LIB.BASEBOARD_FAB2(SCH_1):GND
 257    GND VSS<12> @BASEBOARD_FAB2_LIB.BASEBOARD_FAB2(SCH_1):GND
 259    GND VSS<11> @BASEBOARD_FAB2_LIB.BASEBOARD_FAB2(SCH_1):GND
 261    GND VSS<10> @BASEBOARD_FAB2_LIB.BASEBOARD_FAB2(SCH_1):GND
 263    GND VSS<9> @BASEBOARD_FAB2_LIB.BASEBOARD_FAB2(SCH_1):GND
 265    GND VSS<8> @BASEBOARD_FAB2_LIB.BASEBOARD_FAB2(SCH_1):GND
 268    GND VSS<7> @BASEBOARD_FAB2_LIB.BASEBOARD_FAB2(SCH_1):GND
 270    GND VSS<6> @BASEBOARD_FAB2_LIB.BASEBOARD_FAB2(SCH_1):GND
 272    GND VSS<5> @BASEBOARD_FAB2_LIB.BASEBOARD_FAB2(SCH_1):GND
 274    GND VSS<4> @BASEBOARD_FAB2_LIB.BASEBOARD_FAB2(SCH_1):GND
 276    GND VSS<3> @BASEBOARD_FAB2_LIB.BASEBOARD_FAB2(SCH_1):GND
 279    GND VSS<2> @BASEBOARD_FAB2_LIB.BASEBOARD_FAB2(SCH_1):GND
 281    GND VSS<1> @BASEBOARD_FAB2_LIB.BASEBOARD_FAB2(SCH_1):GND
 283    GND VSS<0> @BASEBOARD_FAB2_LIB.BASEBOARD_FAB2(SCH_1):GND


DRAWING: @BASEBOARD_FAB2_LIB.BASEBOARD_FAB2(SCH_1):PAGE83 

SCONN288_H44441004_PIP-SCONN,HA  I43  J1B1
   2    GND VSS<93> @BASEBOARD_FAB2_LIB.BASEBOARD_FAB2(SCH_1):GND
   4    GND VSS<92> @BASEBOARD_FAB2_LIB.BASEBOARD_FAB2(SCH_1):GND
   6    GND VSS<91> @BASEBOARD_FAB2_LIB.BASEBOARD_FAB2(SCH_1):GND
   9    GND VSS<90> @BASEBOARD_FAB2_LIB.BASEBOARD_FAB2(SCH_1):GND
  11    GND VSS<89> @BASEBOARD_FAB2_LIB.BASEBOARD_FAB2(SCH_1):GND
  13    GND VSS<88> @BASEBOARD_FAB2_LIB.BASEBOARD_FAB2(SCH_1):GND
  15    GND VSS<87> @BASEBOARD_FAB2_LIB.BASEBOARD_FAB2(SCH_1):GND
  17    GND VSS<86> @BASEBOARD_FAB2_LIB.BASEBOARD_FAB2(SCH_1):GND
  20    GND VSS<85> @BASEBOARD_FAB2_LIB.BASEBOARD_FAB2(SCH_1):GND
  22    GND VSS<84> @BASEBOARD_FAB2_LIB.BASEBOARD_FAB2(SCH_1):GND
  24    GND VSS<83> @BASEBOARD_FAB2_LIB.BASEBOARD_FAB2(SCH_1):GND
  26    GND VSS<82> @BASEBOARD_FAB2_LIB.BASEBOARD_FAB2(SCH_1):GND
  28    GND VSS<81> @BASEBOARD_FAB2_LIB.BASEBOARD_FAB2(SCH_1):GND
  31    GND VSS<80> @BASEBOARD_FAB2_LIB.BASEBOARD_FAB2(SCH_1):GND
  33    GND VSS<79> @BASEBOARD_FAB2_LIB.BASEBOARD_FAB2(SCH_1):GND
  35    GND VSS<78> @BASEBOARD_FAB2_LIB.BASEBOARD_FAB2(SCH_1):GND
  37    GND VSS<77> @BASEBOARD_FAB2_LIB.BASEBOARD_FAB2(SCH_1):GND
  39    GND VSS<76> @BASEBOARD_FAB2_LIB.BASEBOARD_FAB2(SCH_1):GND
  42    GND VSS<75> @BASEBOARD_FAB2_LIB.BASEBOARD_FAB2(SCH_1):GND
  44    GND VSS<74> @BASEBOARD_FAB2_LIB.BASEBOARD_FAB2(SCH_1):GND
  46    GND VSS<73> @BASEBOARD_FAB2_LIB.BASEBOARD_FAB2(SCH_1):GND
  48    GND VSS<72> @BASEBOARD_FAB2_LIB.BASEBOARD_FAB2(SCH_1):GND
  50    GND VSS<71> @BASEBOARD_FAB2_LIB.BASEBOARD_FAB2(SCH_1):GND
  53    GND VSS<70> @BASEBOARD_FAB2_LIB.BASEBOARD_FAB2(SCH_1):GND
  55    GND VSS<69> @BASEBOARD_FAB2_LIB.BASEBOARD_FAB2(SCH_1):GND
  57    GND VSS<68> @BASEBOARD_FAB2_LIB.BASEBOARD_FAB2(SCH_1):GND
  94    GND VSS<67> @BASEBOARD_FAB2_LIB.BASEBOARD_FAB2(SCH_1):GND
  96    GND VSS<66> @BASEBOARD_FAB2_LIB.BASEBOARD_FAB2(SCH_1):GND
  98    GND VSS<65> @BASEBOARD_FAB2_LIB.BASEBOARD_FAB2(SCH_1):GND
 101    GND VSS<64> @BASEBOARD_FAB2_LIB.BASEBOARD_FAB2(SCH_1):GND
 103    GND VSS<63> @BASEBOARD_FAB2_LIB.BASEBOARD_FAB2(SCH_1):GND
 105    GND VSS<62> @BASEBOARD_FAB2_LIB.BASEBOARD_FAB2(SCH_1):GND
 107    GND VSS<61> @BASEBOARD_FAB2_LIB.BASEBOARD_FAB2(SCH_1):GND
 109    GND VSS<60> @BASEBOARD_FAB2_LIB.BASEBOARD_FAB2(SCH_1):GND
 112    GND VSS<59> @BASEBOARD_FAB2_LIB.BASEBOARD_FAB2(SCH_1):GND
 114    GND VSS<58> @BASEBOARD_FAB2_LIB.BASEBOARD_FAB2(SCH_1):GND
 116    GND VSS<57> @BASEBOARD_FAB2_LIB.BASEBOARD_FAB2(SCH_1):GND
 118    GND VSS<56> @BASEBOARD_FAB2_LIB.BASEBOARD_FAB2(SCH_1):GND
 120    GND VSS<55> @BASEBOARD_FAB2_LIB.BASEBOARD_FAB2(SCH_1):GND
 123    GND VSS<54> @BASEBOARD_FAB2_LIB.BASEBOARD_FAB2(SCH_1):GND
 125    GND VSS<53> @BASEBOARD_FAB2_LIB.BASEBOARD_FAB2(SCH_1):GND
 127    GND VSS<52> @BASEBOARD_FAB2_LIB.BASEBOARD_FAB2(SCH_1):GND
 129    GND VSS<51> @BASEBOARD_FAB2_LIB.BASEBOARD_FAB2(SCH_1):GND
 131    GND VSS<50> @BASEBOARD_FAB2_LIB.BASEBOARD_FAB2(SCH_1):GND
 134    GND VSS<49> @BASEBOARD_FAB2_LIB.BASEBOARD_FAB2(SCH_1):GND
 136    GND VSS<48> @BASEBOARD_FAB2_LIB.BASEBOARD_FAB2(SCH_1):GND
 138    GND VSS<47> @BASEBOARD_FAB2_LIB.BASEBOARD_FAB2(SCH_1):GND
 147    GND VSS<46> @BASEBOARD_FAB2_LIB.BASEBOARD_FAB2(SCH_1):GND
 149    GND VSS<45> @BASEBOARD_FAB2_LIB.BASEBOARD_FAB2(SCH_1):GND
 151    GND VSS<44> @BASEBOARD_FAB2_LIB.BASEBOARD_FAB2(SCH_1):GND
 154    GND VSS<43> @BASEBOARD_FAB2_LIB.BASEBOARD_FAB2(SCH_1):GND
 156    GND VSS<42> @BASEBOARD_FAB2_LIB.BASEBOARD_FAB2(SCH_1):GND
 158    GND VSS<41> @BASEBOARD_FAB2_LIB.BASEBOARD_FAB2(SCH_1):GND
 160    GND VSS<40> @BASEBOARD_FAB2_LIB.BASEBOARD_FAB2(SCH_1):GND
 162    GND VSS<39> @BASEBOARD_FAB2_LIB.BASEBOARD_FAB2(SCH_1):GND
 165    GND VSS<38> @BASEBOARD_FAB2_LIB.BASEBOARD_FAB2(SCH_1):GND
 167    GND VSS<37> @BASEBOARD_FAB2_LIB.BASEBOARD_FAB2(SCH_1):GND
 169    GND VSS<36> @BASEBOARD_FAB2_LIB.BASEBOARD_FAB2(SCH_1):GND
 171    GND VSS<35> @BASEBOARD_FAB2_LIB.BASEBOARD_FAB2(SCH_1):GND
 173    GND VSS<34> @BASEBOARD_FAB2_LIB.BASEBOARD_FAB2(SCH_1):GND
 176    GND VSS<33> @BASEBOARD_FAB2_LIB.BASEBOARD_FAB2(SCH_1):GND
 178    GND VSS<32> @BASEBOARD_FAB2_LIB.BASEBOARD_FAB2(SCH_1):GND
 180    GND VSS<31> @BASEBOARD_FAB2_LIB.BASEBOARD_FAB2(SCH_1):GND
 182    GND VSS<30> @BASEBOARD_FAB2_LIB.BASEBOARD_FAB2(SCH_1):GND
 184    GND VSS<29> @BASEBOARD_FAB2_LIB.BASEBOARD_FAB2(SCH_1):GND
 187    GND VSS<28> @BASEBOARD_FAB2_LIB.BASEBOARD_FAB2(SCH_1):GND
 189    GND VSS<27> @BASEBOARD_FAB2_LIB.BASEBOARD_FAB2(SCH_1):GND
 191    GND VSS<26> @BASEBOARD_FAB2_LIB.BASEBOARD_FAB2(SCH_1):GND
 193    GND VSS<25> @BASEBOARD_FAB2_LIB.BASEBOARD_FAB2(SCH_1):GND
 195    GND VSS<24> @BASEBOARD_FAB2_LIB.BASEBOARD_FAB2(SCH_1):GND
 198    GND VSS<23> @BASEBOARD_FAB2_LIB.BASEBOARD_FAB2(SCH_1):GND
 200    GND VSS<22> @BASEBOARD_FAB2_LIB.BASEBOARD_FAB2(SCH_1):GND
 202    GND VSS<21> @BASEBOARD_FAB2_LIB.BASEBOARD_FAB2(SCH_1):GND
 239    GND VSS<20> @BASEBOARD_FAB2_LIB.BASEBOARD_FAB2(SCH_1):GND
 241    GND VSS<19> @BASEBOARD_FAB2_LIB.BASEBOARD_FAB2(SCH_1):GND
 243    GND VSS<18> @BASEBOARD_FAB2_LIB.BASEBOARD_FAB2(SCH_1):GND
 246    GND VSS<17> @BASEBOARD_FAB2_LIB.BASEBOARD_FAB2(SCH_1):GND
 248    GND VSS<16> @BASEBOARD_FAB2_LIB.BASEBOARD_FAB2(SCH_1):GND
 250    GND VSS<15> @BASEBOARD_FAB2_LIB.BASEBOARD_FAB2(SCH_1):GND
 252    GND VSS<14> @BASEBOARD_FAB2_LIB.BASEBOARD_FAB2(SCH_1):GND
 254    GND VSS<13> @BASEBOARD_FAB2_LIB.BASEBOARD_FAB2(SCH_1):GND
 257    GND VSS<12> @BASEBOARD_FAB2_LIB.BASEBOARD_FAB2(SCH_1):GND
 259    GND VSS<11> @BASEBOARD_FAB2_LIB.BASEBOARD_FAB2(SCH_1):GND
 261    GND VSS<10> @BASEBOARD_FAB2_LIB.BASEBOARD_FAB2(SCH_1):GND
 263    GND VSS<9> @BASEBOARD_FAB2_LIB.BASEBOARD_FAB2(SCH_1):GND
 265    GND VSS<8> @BASEBOARD_FAB2_LIB.BASEBOARD_FAB2(SCH_1):GND
 268    GND VSS<7> @BASEBOARD_FAB2_LIB.BASEBOARD_FAB2(SCH_1):GND
 270    GND VSS<6> @BASEBOARD_FAB2_LIB.BASEBOARD_FAB2(SCH_1):GND
 272    GND VSS<5> @BASEBOARD_FAB2_LIB.BASEBOARD_FAB2(SCH_1):GND
 274    GND VSS<4> @BASEBOARD_FAB2_LIB.BASEBOARD_FAB2(SCH_1):GND
 276    GND VSS<3> @BASEBOARD_FAB2_LIB.BASEBOARD_FAB2(SCH_1):GND
 279    GND VSS<2> @BASEBOARD_FAB2_LIB.BASEBOARD_FAB2(SCH_1):GND
 281    GND VSS<1> @BASEBOARD_FAB2_LIB.BASEBOARD_FAB2(SCH_1):GND
 283    GND VSS<0> @BASEBOARD_FAB2_LIB.BASEBOARD_FAB2(SCH_1):GND

SCONN288_H44441004_PIP-SCONN,HA  I66  J1B1
 152 M_K_DQS_DN<0>  DQS0N @BASEBOARD_FAB2_LIB.BASEBOARD_FAB2(SCH_1):M_K_DQS_DN(0)
 153 M_K_DQS_DP<0>  DQS0P @BASEBOARD_FAB2_LIB.BASEBOARD_FAB2(SCH_1):M_K_DQS_DP(0)
  19 M_K_DQS_DN<10> DQS10N @BASEBOARD_FAB2_LIB.BASEBOARD_FAB2(SCH_1):M_K_DQS_DN(10)
  18 M_K_DQS_DP<10> DQS10P @BASEBOARD_FAB2_LIB.BASEBOARD_FAB2(SCH_1):M_K_DQS_DP(10)
  30 M_K_DQS_DN<11> DQS11N @BASEBOARD_FAB2_LIB.BASEBOARD_FAB2(SCH_1):M_K_DQS_DN(11)
  29 M_K_DQS_DP<11> DQS11P @BASEBOARD_FAB2_LIB.BASEBOARD_FAB2(SCH_1):M_K_DQS_DP(11)
  41 M_K_DQS_DN<12> DQS12N @BASEBOARD_FAB2_LIB.BASEBOARD_FAB2(SCH_1):M_K_DQS_DN(12)
  40 M_K_DQS_DP<12> DQS12P @BASEBOARD_FAB2_LIB.BASEBOARD_FAB2(SCH_1):M_K_DQS_DP(12)
 100 M_K_DQS_DN<13> DQS13N @BASEBOARD_FAB2_LIB.BASEBOARD_FAB2(SCH_1):M_K_DQS_DN(13)
  99 M_K_DQS_DP<13> DQS13P @BASEBOARD_FAB2_LIB.BASEBOARD_FAB2(SCH_1):M_K_DQS_DP(13)
 111 M_K_DQS_DN<14> DQS14N @BASEBOARD_FAB2_LIB.BASEBOARD_FAB2(SCH_1):M_K_DQS_DN(14)
 110 M_K_DQS_DP<14> DQS14P @BASEBOARD_FAB2_LIB.BASEBOARD_FAB2(SCH_1):M_K_DQS_DP(14)
 122 M_K_DQS_DN<15> DQS15N @BASEBOARD_FAB2_LIB.BASEBOARD_FAB2(SCH_1):M_K_DQS_DN(15)
 121 M_K_DQS_DP<15> DQS15P @BASEBOARD_FAB2_LIB.BASEBOARD_FAB2(SCH_1):M_K_DQS_DP(15)
 133 M_K_DQS_DN<16> DQS16N @BASEBOARD_FAB2_LIB.BASEBOARD_FAB2(SCH_1):M_K_DQS_DN(16)
 132 M_K_DQS_DP<16> DQS16P @BASEBOARD_FAB2_LIB.BASEBOARD_FAB2(SCH_1):M_K_DQS_DP(16)
  52 M_K_DQS_DN<17> DQS17N @BASEBOARD_FAB2_LIB.BASEBOARD_FAB2(SCH_1):M_K_DQS_DN(17)
  51 M_K_DQS_DP<17> DQS17P @BASEBOARD_FAB2_LIB.BASEBOARD_FAB2(SCH_1):M_K_DQS_DP(17)
 163 M_K_DQS_DN<1>  DQS1N @BASEBOARD_FAB2_LIB.BASEBOARD_FAB2(SCH_1):M_K_DQS_DN(1)
 164 M_K_DQS_DP<1>  DQS1P @BASEBOARD_FAB2_LIB.BASEBOARD_FAB2(SCH_1):M_K_DQS_DP(1)
 174 M_K_DQS_DN<2>  DQS2N @BASEBOARD_FAB2_LIB.BASEBOARD_FAB2(SCH_1):M_K_DQS_DN(2)
 175 M_K_DQS_DP<2>  DQS2P @BASEBOARD_FAB2_LIB.BASEBOARD_FAB2(SCH_1):M_K_DQS_DP(2)
 185 M_K_DQS_DN<3>  DQS3N @BASEBOARD_FAB2_LIB.BASEBOARD_FAB2(SCH_1):M_K_DQS_DN(3)
 186 M_K_DQS_DP<3>  DQS3P @BASEBOARD_FAB2_LIB.BASEBOARD_FAB2(SCH_1):M_K_DQS_DP(3)
 244 M_K_DQS_DN<4>  DQS4N @BASEBOARD_FAB2_LIB.BASEBOARD_FAB2(SCH_1):M_K_DQS_DN(4)
 245 M_K_DQS_DP<4>  DQS4P @BASEBOARD_FAB2_LIB.BASEBOARD_FAB2(SCH_1):M_K_DQS_DP(4)
 255 M_K_DQS_DN<5>  DQS5N @BASEBOARD_FAB2_LIB.BASEBOARD_FAB2(SCH_1):M_K_DQS_DN(5)
 256 M_K_DQS_DP<5>  DQS5P @BASEBOARD_FAB2_LIB.BASEBOARD_FAB2(SCH_1):M_K_DQS_DP(5)
 266 M_K_DQS_DN<6>  DQS6N @BASEBOARD_FAB2_LIB.BASEBOARD_FAB2(SCH_1):M_K_DQS_DN(6)
 267 M_K_DQS_DP<6>  DQS6P @BASEBOARD_FAB2_LIB.BASEBOARD_FAB2(SCH_1):M_K_DQS_DP(6)
 277 M_K_DQS_DN<7>  DQS7N @BASEBOARD_FAB2_LIB.BASEBOARD_FAB2(SCH_1):M_K_DQS_DN(7)
 278 M_K_DQS_DP<7>  DQS7P @BASEBOARD_FAB2_LIB.BASEBOARD_FAB2(SCH_1):M_K_DQS_DP(7)
 196 M_K_DQS_DN<8>  DQS8N @BASEBOARD_FAB2_LIB.BASEBOARD_FAB2(SCH_1):M_K_DQS_DN(8)
 197 M_K_DQS_DP<8>  DQS8P @BASEBOARD_FAB2_LIB.BASEBOARD_FAB2(SCH_1):M_K_DQS_DP(8)
   8 M_K_DQS_DN<9>  DQS9N @BASEBOARD_FAB2_LIB.BASEBOARD_FAB2(SCH_1):M_K_DQS_DN(9)
   7 M_K_DQS_DP<9>  DQS9P @BASEBOARD_FAB2_LIB.BASEBOARD_FAB2(SCH_1):M_K_DQS_DP(9)

SCONN288_H44441004_PIP-SCONN,HA  I111  J1B1
  79 M_K_MA<0>     A0 @BASEBOARD_FAB2_LIB.BASEBOARD_FAB2(SCH_1):M_K_MA(0)
  72 M_K_MA<1>     A1 @BASEBOARD_FAB2_LIB.BASEBOARD_FAB2(SCH_1):M_K_MA(1)
 225 M_K_MA<10>    A10 @BASEBOARD_FAB2_LIB.BASEBOARD_FAB2(SCH_1):M_K_MA(10)
 210 M_K_MA<11>    A11 @BASEBOARD_FAB2_LIB.BASEBOARD_FAB2(SCH_1):M_K_MA(11)
  65 M_K_MA<12>    A12 @BASEBOARD_FAB2_LIB.BASEBOARD_FAB2(SCH_1):M_K_MA(12)
 232 M_K_MA<13>    A13 @BASEBOARD_FAB2_LIB.BASEBOARD_FAB2(SCH_1):M_K_MA(13)
 228 M_K_MA<14> A14_WE_N @BASEBOARD_FAB2_LIB.BASEBOARD_FAB2(SCH_1):M_K_MA(14)
  86 M_K_MA<15> A15_CAS_N @BASEBOARD_FAB2_LIB.BASEBOARD_FAB2(SCH_1):M_K_MA(15)
  82 M_K_MA<16> A16_RAS_N @BASEBOARD_FAB2_LIB.BASEBOARD_FAB2(SCH_1):M_K_MA(16)
 234 M_K_MA<17>    A17 @BASEBOARD_FAB2_LIB.BASEBOARD_FAB2(SCH_1):M_K_MA(17)
 216 M_K_MA<2>     A2 @BASEBOARD_FAB2_LIB.BASEBOARD_FAB2(SCH_1):M_K_MA(2)
  71 M_K_MA<3>     A3 @BASEBOARD_FAB2_LIB.BASEBOARD_FAB2(SCH_1):M_K_MA(3)
 214 M_K_MA<4>     A4 @BASEBOARD_FAB2_LIB.BASEBOARD_FAB2(SCH_1):M_K_MA(4)
 213 M_K_MA<5>     A5 @BASEBOARD_FAB2_LIB.BASEBOARD_FAB2(SCH_1):M_K_MA(5)
  69 M_K_MA<6>     A6 @BASEBOARD_FAB2_LIB.BASEBOARD_FAB2(SCH_1):M_K_MA(6)
 211 M_K_MA<7>     A7 @BASEBOARD_FAB2_LIB.BASEBOARD_FAB2(SCH_1):M_K_MA(7)
  68 M_K_MA<8>     A8 @BASEBOARD_FAB2_LIB.BASEBOARD_FAB2(SCH_1):M_K_MA(8)
  66 M_K_MA<9>     A9 @BASEBOARD_FAB2_LIB.BASEBOARD_FAB2(SCH_1):M_K_MA(9)
  62 M_K_ACT_N  ACT_N @BASEBOARD_FAB2_LIB.BASEBOARD_FAB2(SCH_1):M_K_ACT_N
 208 M_K_ALERT_N ALERT_N @BASEBOARD_FAB2_LIB.BASEBOARD_FAB2(SCH_1):M_K_ALERT_N
 224 M_K_BA<1>  BA<1> @BASEBOARD_FAB2_LIB.BASEBOARD_FAB2(SCH_1):M_K_BA(1)
  81 M_K_BA<0>  BA<0> @BASEBOARD_FAB2_LIB.BASEBOARD_FAB2(SCH_1):M_K_BA(0)
 207 M_K_BG<1>  BG<1> @BASEBOARD_FAB2_LIB.BASEBOARD_FAB2(SCH_1):M_K_BG(1)
  63 M_K_BG<0>  BG<0> @BASEBOARD_FAB2_LIB.BASEBOARD_FAB2(SCH_1):M_K_BG(0)
 235 M_K_C<2>   C<2> @BASEBOARD_FAB2_LIB.BASEBOARD_FAB2(SCH_1):M_K_C(2)
 199 M_K_ECC<6>  CB<7> @BASEBOARD_FAB2_LIB.BASEBOARD_FAB2(SCH_1):M_K_ECC(6)
  54 M_K_ECC<7>  CB<6> @BASEBOARD_FAB2_LIB.BASEBOARD_FAB2(SCH_1):M_K_ECC(7)
 192 M_K_ECC<4>  CB<5> @BASEBOARD_FAB2_LIB.BASEBOARD_FAB2(SCH_1):M_K_ECC(4)
  47 M_K_ECC<5>  CB<4> @BASEBOARD_FAB2_LIB.BASEBOARD_FAB2(SCH_1):M_K_ECC(5)
 201 M_K_ECC<2>  CB<3> @BASEBOARD_FAB2_LIB.BASEBOARD_FAB2(SCH_1):M_K_ECC(2)
  56 M_K_ECC<3>  CB<2> @BASEBOARD_FAB2_LIB.BASEBOARD_FAB2(SCH_1):M_K_ECC(3)
 194 M_K_ECC<0>  CB<1> @BASEBOARD_FAB2_LIB.BASEBOARD_FAB2(SCH_1):M_K_ECC(0)
  49 M_K_ECC<1>  CB<0> @BASEBOARD_FAB2_LIB.BASEBOARD_FAB2(SCH_1):M_K_ECC(1)
  75 M_K_CLK_DN<0>   CK0N @BASEBOARD_FAB2_LIB.BASEBOARD_FAB2(SCH_1):M_K_CLK_DN(0)
  74 M_K_CLK_DP<0>   CK0P @BASEBOARD_FAB2_LIB.BASEBOARD_FAB2(SCH_1):M_K_CLK_DP(0)
 219 M_K_CLK_DN<1>   CK1N @BASEBOARD_FAB2_LIB.BASEBOARD_FAB2(SCH_1):M_K_CLK_DN(1)
 218 M_K_CLK_DP<1>   CK1P @BASEBOARD_FAB2_LIB.BASEBOARD_FAB2(SCH_1):M_K_CLK_DP(1)
 203 M_K_CKE<1> CKE<1> @BASEBOARD_FAB2_LIB.BASEBOARD_FAB2(SCH_1):M_K_CKE(1)
  60 M_K_CKE<0> CKE<0> @BASEBOARD_FAB2_LIB.BASEBOARD_FAB2(SCH_1):M_K_CKE(0)
 280 M_K_DQ<62> DQ<63> @BASEBOARD_FAB2_LIB.BASEBOARD_FAB2(SCH_1):M_K_DQ(62)
 135 M_K_DQ<63> DQ<62> @BASEBOARD_FAB2_LIB.BASEBOARD_FAB2(SCH_1):M_K_DQ(63)
 273 M_K_DQ<60> DQ<61> @BASEBOARD_FAB2_LIB.BASEBOARD_FAB2(SCH_1):M_K_DQ(60)
 128 M_K_DQ<61> DQ<60> @BASEBOARD_FAB2_LIB.BASEBOARD_FAB2(SCH_1):M_K_DQ(61)
 282 M_K_DQ<58> DQ<59> @BASEBOARD_FAB2_LIB.BASEBOARD_FAB2(SCH_1):M_K_DQ(58)
 137 M_K_DQ<59> DQ<58> @BASEBOARD_FAB2_LIB.BASEBOARD_FAB2(SCH_1):M_K_DQ(59)
 275 M_K_DQ<56> DQ<57> @BASEBOARD_FAB2_LIB.BASEBOARD_FAB2(SCH_1):M_K_DQ(56)
 130 M_K_DQ<57> DQ<56> @BASEBOARD_FAB2_LIB.BASEBOARD_FAB2(SCH_1):M_K_DQ(57)
 269 M_K_DQ<54> DQ<55> @BASEBOARD_FAB2_LIB.BASEBOARD_FAB2(SCH_1):M_K_DQ(54)
 124 M_K_DQ<55> DQ<54> @BASEBOARD_FAB2_LIB.BASEBOARD_FAB2(SCH_1):M_K_DQ(55)
 262 M_K_DQ<52> DQ<53> @BASEBOARD_FAB2_LIB.BASEBOARD_FAB2(SCH_1):M_K_DQ(52)
 117 M_K_DQ<53> DQ<52> @BASEBOARD_FAB2_LIB.BASEBOARD_FAB2(SCH_1):M_K_DQ(53)
 271 M_K_DQ<50> DQ<51> @BASEBOARD_FAB2_LIB.BASEBOARD_FAB2(SCH_1):M_K_DQ(50)
 126 M_K_DQ<51> DQ<50> @BASEBOARD_FAB2_LIB.BASEBOARD_FAB2(SCH_1):M_K_DQ(51)
 264 M_K_DQ<48> DQ<49> @BASEBOARD_FAB2_LIB.BASEBOARD_FAB2(SCH_1):M_K_DQ(48)
 119 M_K_DQ<49> DQ<48> @BASEBOARD_FAB2_LIB.BASEBOARD_FAB2(SCH_1):M_K_DQ(49)
 258 M_K_DQ<46> DQ<47> @BASEBOARD_FAB2_LIB.BASEBOARD_FAB2(SCH_1):M_K_DQ(46)
 113 M_K_DQ<47> DQ<46> @BASEBOARD_FAB2_LIB.BASEBOARD_FAB2(SCH_1):M_K_DQ(47)
 251 M_K_DQ<44> DQ<45> @BASEBOARD_FAB2_LIB.BASEBOARD_FAB2(SCH_1):M_K_DQ(44)
 106 M_K_DQ<45> DQ<44> @BASEBOARD_FAB2_LIB.BASEBOARD_FAB2(SCH_1):M_K_DQ(45)
 260 M_K_DQ<42> DQ<43> @BASEBOARD_FAB2_LIB.BASEBOARD_FAB2(SCH_1):M_K_DQ(42)
 115 M_K_DQ<43> DQ<42> @BASEBOARD_FAB2_LIB.BASEBOARD_FAB2(SCH_1):M_K_DQ(43)
 253 M_K_DQ<40> DQ<41> @BASEBOARD_FAB2_LIB.BASEBOARD_FAB2(SCH_1):M_K_DQ(40)
 108 M_K_DQ<41> DQ<40> @BASEBOARD_FAB2_LIB.BASEBOARD_FAB2(SCH_1):M_K_DQ(41)
 247 M_K_DQ<38> DQ<39> @BASEBOARD_FAB2_LIB.BASEBOARD_FAB2(SCH_1):M_K_DQ(38)
 102 M_K_DQ<39> DQ<38> @BASEBOARD_FAB2_LIB.BASEBOARD_FAB2(SCH_1):M_K_DQ(39)
 240 M_K_DQ<36> DQ<37> @BASEBOARD_FAB2_LIB.BASEBOARD_FAB2(SCH_1):M_K_DQ(36)
  95 M_K_DQ<37> DQ<36> @BASEBOARD_FAB2_LIB.BASEBOARD_FAB2(SCH_1):M_K_DQ(37)
 249 M_K_DQ<34> DQ<35> @BASEBOARD_FAB2_LIB.BASEBOARD_FAB2(SCH_1):M_K_DQ(34)
 104 M_K_DQ<35> DQ<34> @BASEBOARD_FAB2_LIB.BASEBOARD_FAB2(SCH_1):M_K_DQ(35)
 242 M_K_DQ<32> DQ<33> @BASEBOARD_FAB2_LIB.BASEBOARD_FAB2(SCH_1):M_K_DQ(32)
  97 M_K_DQ<33> DQ<32> @BASEBOARD_FAB2_LIB.BASEBOARD_FAB2(SCH_1):M_K_DQ(33)
 188 M_K_DQ<30> DQ<31> @BASEBOARD_FAB2_LIB.BASEBOARD_FAB2(SCH_1):M_K_DQ(30)
  43 M_K_DQ<31> DQ<30> @BASEBOARD_FAB2_LIB.BASEBOARD_FAB2(SCH_1):M_K_DQ(31)
 181 M_K_DQ<28> DQ<29> @BASEBOARD_FAB2_LIB.BASEBOARD_FAB2(SCH_1):M_K_DQ(28)
  36 M_K_DQ<29> DQ<28> @BASEBOARD_FAB2_LIB.BASEBOARD_FAB2(SCH_1):M_K_DQ(29)
 190 M_K_DQ<26> DQ<27> @BASEBOARD_FAB2_LIB.BASEBOARD_FAB2(SCH_1):M_K_DQ(26)
  45 M_K_DQ<27> DQ<26> @BASEBOARD_FAB2_LIB.BASEBOARD_FAB2(SCH_1):M_K_DQ(27)
 183 M_K_DQ<24> DQ<25> @BASEBOARD_FAB2_LIB.BASEBOARD_FAB2(SCH_1):M_K_DQ(24)
  38 M_K_DQ<25> DQ<24> @BASEBOARD_FAB2_LIB.BASEBOARD_FAB2(SCH_1):M_K_DQ(25)
 177 M_K_DQ<22> DQ<23> @BASEBOARD_FAB2_LIB.BASEBOARD_FAB2(SCH_1):M_K_DQ(22)
  32 M_K_DQ<23> DQ<22> @BASEBOARD_FAB2_LIB.BASEBOARD_FAB2(SCH_1):M_K_DQ(23)
 170 M_K_DQ<20> DQ<21> @BASEBOARD_FAB2_LIB.BASEBOARD_FAB2(SCH_1):M_K_DQ(20)
  25 M_K_DQ<21> DQ<20> @BASEBOARD_FAB2_LIB.BASEBOARD_FAB2(SCH_1):M_K_DQ(21)
 179 M_K_DQ<18> DQ<19> @BASEBOARD_FAB2_LIB.BASEBOARD_FAB2(SCH_1):M_K_DQ(18)
  34 M_K_DQ<19> DQ<18> @BASEBOARD_FAB2_LIB.BASEBOARD_FAB2(SCH_1):M_K_DQ(19)
 172 M_K_DQ<16> DQ<17> @BASEBOARD_FAB2_LIB.BASEBOARD_FAB2(SCH_1):M_K_DQ(16)
  27 M_K_DQ<17> DQ<16> @BASEBOARD_FAB2_LIB.BASEBOARD_FAB2(SCH_1):M_K_DQ(17)
 166 M_K_DQ<14> DQ<15> @BASEBOARD_FAB2_LIB.BASEBOARD_FAB2(SCH_1):M_K_DQ(14)
  21 M_K_DQ<15> DQ<14> @BASEBOARD_FAB2_LIB.BASEBOARD_FAB2(SCH_1):M_K_DQ(15)
 159 M_K_DQ<12> DQ<13> @BASEBOARD_FAB2_LIB.BASEBOARD_FAB2(SCH_1):M_K_DQ(12)
  14 M_K_DQ<13> DQ<12> @BASEBOARD_FAB2_LIB.BASEBOARD_FAB2(SCH_1):M_K_DQ(13)
 168 M_K_DQ<10> DQ<11> @BASEBOARD_FAB2_LIB.BASEBOARD_FAB2(SCH_1):M_K_DQ(10)
  23 M_K_DQ<11> DQ<10> @BASEBOARD_FAB2_LIB.BASEBOARD_FAB2(SCH_1):M_K_DQ(11)
 161 M_K_DQ<8>  DQ<9> @BASEBOARD_FAB2_LIB.BASEBOARD_FAB2(SCH_1):M_K_DQ(8)
  16 M_K_DQ<9>  DQ<8> @BASEBOARD_FAB2_LIB.BASEBOARD_FAB2(SCH_1):M_K_DQ(9)
 155 M_K_DQ<6>  DQ<7> @BASEBOARD_FAB2_LIB.BASEBOARD_FAB2(SCH_1):M_K_DQ(6)
  10 M_K_DQ<7>  DQ<6> @BASEBOARD_FAB2_LIB.BASEBOARD_FAB2(SCH_1):M_K_DQ(7)
 148 M_K_DQ<4>  DQ<5> @BASEBOARD_FAB2_LIB.BASEBOARD_FAB2(SCH_1):M_K_DQ(4)
   3 M_K_DQ<5>  DQ<4> @BASEBOARD_FAB2_LIB.BASEBOARD_FAB2(SCH_1):M_K_DQ(5)
 157 M_K_DQ<2>  DQ<3> @BASEBOARD_FAB2_LIB.BASEBOARD_FAB2(SCH_1):M_K_DQ(2)
  12 M_K_DQ<3>  DQ<2> @BASEBOARD_FAB2_LIB.BASEBOARD_FAB2(SCH_1):M_K_DQ(3)
 150 M_K_DQ<0>  DQ<1> @BASEBOARD_FAB2_LIB.BASEBOARD_FAB2(SCH_1):M_K_DQ(0)
   5 M_K_DQ<1>  DQ<0> @BASEBOARD_FAB2_LIB.BASEBOARD_FAB2(SCH_1):M_K_DQ(1)
  78 FM_DIMM_EVENT_COD_N EVENT_N @BASEBOARD_FAB2_LIB.BASEBOARD_FAB2(SCH_1):FM_DIMM_EVENT_COD_N
  91 M_K_ODT<1> ODT<1> @BASEBOARD_FAB2_LIB.BASEBOARD_FAB2(SCH_1):M_K_ODT(1)
  87 M_K_ODT<0> ODT<0> @BASEBOARD_FAB2_LIB.BASEBOARD_FAB2(SCH_1):M_K_ODT(0)
 222 M_K_PAR    PAR @BASEBOARD_FAB2_LIB.BASEBOARD_FAB2(SCH_1):M_K_PAR
  58 M_KLM_RST_N RESET_N @BASEBOARD_FAB2_LIB.BASEBOARD_FAB2(SCH_1):M_KLM_RST_N
 144 TP_CH_K_DIMM_K0_RFU_2 RFU<2> @BASEBOARD_FAB2_LIB.BASEBOARD_FAB2(SCH_1):TP_CH_K_DIMM_K0_RFU_2
 227 TP_CH_K_DIMM_K0_RFU_1 RFU<1> @BASEBOARD_FAB2_LIB.BASEBOARD_FAB2(SCH_1):TP_CH_K_DIMM_K0_RFU_1
 205 TP_CH_K_DIMM_K0_RFU_0 RFU<0> @BASEBOARD_FAB2_LIB.BASEBOARD_FAB2(SCH_1):TP_CH_K_DIMM_K0_RFU_0
  84 M_K_CS_N<0>   S0_N @BASEBOARD_FAB2_LIB.BASEBOARD_FAB2(SCH_1):M_K_CS_N(0)
  89 M_K_CS_N<1>   S1_N @BASEBOARD_FAB2_LIB.BASEBOARD_FAB2(SCH_1):M_K_CS_N(1)
  93 M_K_CS_N<2> S2_N_C<0> @BASEBOARD_FAB2_LIB.BASEBOARD_FAB2(SCH_1):M_K_CS_N(2)
 237 M_K_CS_N<3> S3_N_C<1> @BASEBOARD_FAB2_LIB.BASEBOARD_FAB2(SCH_1):M_K_CS_N(3)
 238    GND  SA<2> @BASEBOARD_FAB2_LIB.BASEBOARD_FAB2(SCH_1):GND
 140    GND  SA<1> @BASEBOARD_FAB2_LIB.BASEBOARD_FAB2(SCH_1):GND
 139    GND  SA<0> @BASEBOARD_FAB2_LIB.BASEBOARD_FAB2(SCH_1):GND
 230 FM_ADR_COMPLETE_KLM_N SAVE_N_NC @BASEBOARD_FAB2_LIB.BASEBOARD_FAB2(SCH_1):FM_ADR_COMPLETE_KLM_N
 141 SMB_DDR_KLM_VPP_SCL    SCL @BASEBOARD_FAB2_LIB.BASEBOARD_FAB2(SCH_1):SMB_DDR_KLM_VPP_SCL
 285 SMB_DDR_KLM_VPP_SDA    SDA @BASEBOARD_FAB2_LIB.BASEBOARD_FAB2(SCH_1):SMB_DDR_KLM_VPP_SDA
 284 PVPP_KLM VDDSPD @BASEBOARD_FAB2_LIB.BASEBOARD_FAB2(SCH_1):PVPP_KLM
 146 M_K_VREF VREFCA @BASEBOARD_FAB2_LIB.BASEBOARD_FAB2(SCH_1):M_K_VREF

SCONN288_H44441004_PIP-SCONN,HA  I167  J1B1
   1 P12V_NVDIMM_KLM 12V<1> @BASEBOARD_FAB2_LIB.BASEBOARD_FAB2(SCH_1):P12V_NVDIMM_KLM
 145 P12V_NVDIMM_KLM 12V<0> @BASEBOARD_FAB2_LIB.BASEBOARD_FAB2(SCH_1):P12V_NVDIMM_KLM
  59 PVDDQ_KLM VDD<25> @BASEBOARD_FAB2_LIB.BASEBOARD_FAB2(SCH_1):PVDDQ_KLM
  61 PVDDQ_KLM VDD<24> @BASEBOARD_FAB2_LIB.BASEBOARD_FAB2(SCH_1):PVDDQ_KLM
  64 PVDDQ_KLM VDD<23> @BASEBOARD_FAB2_LIB.BASEBOARD_FAB2(SCH_1):PVDDQ_KLM
  67 PVDDQ_KLM VDD<22> @BASEBOARD_FAB2_LIB.BASEBOARD_FAB2(SCH_1):PVDDQ_KLM
  70 PVDDQ_KLM VDD<21> @BASEBOARD_FAB2_LIB.BASEBOARD_FAB2(SCH_1):PVDDQ_KLM
  73 PVDDQ_KLM VDD<20> @BASEBOARD_FAB2_LIB.BASEBOARD_FAB2(SCH_1):PVDDQ_KLM
  76 PVDDQ_KLM VDD<19> @BASEBOARD_FAB2_LIB.BASEBOARD_FAB2(SCH_1):PVDDQ_KLM
  80 PVDDQ_KLM VDD<18> @BASEBOARD_FAB2_LIB.BASEBOARD_FAB2(SCH_1):PVDDQ_KLM
  83 PVDDQ_KLM VDD<17> @BASEBOARD_FAB2_LIB.BASEBOARD_FAB2(SCH_1):PVDDQ_KLM
  85 PVDDQ_KLM VDD<16> @BASEBOARD_FAB2_LIB.BASEBOARD_FAB2(SCH_1):PVDDQ_KLM
  88 PVDDQ_KLM VDD<15> @BASEBOARD_FAB2_LIB.BASEBOARD_FAB2(SCH_1):PVDDQ_KLM
  90 PVDDQ_KLM VDD<14> @BASEBOARD_FAB2_LIB.BASEBOARD_FAB2(SCH_1):PVDDQ_KLM
  92 PVDDQ_KLM VDD<13> @BASEBOARD_FAB2_LIB.BASEBOARD_FAB2(SCH_1):PVDDQ_KLM
 204 PVDDQ_KLM VDD<12> @BASEBOARD_FAB2_LIB.BASEBOARD_FAB2(SCH_1):PVDDQ_KLM
 206 PVDDQ_KLM VDD<11> @BASEBOARD_FAB2_LIB.BASEBOARD_FAB2(SCH_1):PVDDQ_KLM
 209 PVDDQ_KLM VDD<10> @BASEBOARD_FAB2_LIB.BASEBOARD_FAB2(SCH_1):PVDDQ_KLM
 212 PVDDQ_KLM VDD<9> @BASEBOARD_FAB2_LIB.BASEBOARD_FAB2(SCH_1):PVDDQ_KLM
 215 PVDDQ_KLM VDD<8> @BASEBOARD_FAB2_LIB.BASEBOARD_FAB2(SCH_1):PVDDQ_KLM
 217 PVDDQ_KLM VDD<7> @BASEBOARD_FAB2_LIB.BASEBOARD_FAB2(SCH_1):PVDDQ_KLM
 220 PVDDQ_KLM VDD<6> @BASEBOARD_FAB2_LIB.BASEBOARD_FAB2(SCH_1):PVDDQ_KLM
 223 PVDDQ_KLM VDD<5> @BASEBOARD_FAB2_LIB.BASEBOARD_FAB2(SCH_1):PVDDQ_KLM
 226 PVDDQ_KLM VDD<4> @BASEBOARD_FAB2_LIB.BASEBOARD_FAB2(SCH_1):PVDDQ_KLM
 229 PVDDQ_KLM VDD<3> @BASEBOARD_FAB2_LIB.BASEBOARD_FAB2(SCH_1):PVDDQ_KLM
 231 PVDDQ_KLM VDD<2> @BASEBOARD_FAB2_LIB.BASEBOARD_FAB2(SCH_1):PVDDQ_KLM
 233 PVDDQ_KLM VDD<1> @BASEBOARD_FAB2_LIB.BASEBOARD_FAB2(SCH_1):PVDDQ_KLM
 236 PVDDQ_KLM VDD<0> @BASEBOARD_FAB2_LIB.BASEBOARD_FAB2(SCH_1):PVDDQ_KLM
 142 PVPP_KLM VPP<4> @BASEBOARD_FAB2_LIB.BASEBOARD_FAB2(SCH_1):PVPP_KLM
 143 PVPP_KLM VPP<3> @BASEBOARD_FAB2_LIB.BASEBOARD_FAB2(SCH_1):PVPP_KLM
 288 PVPP_KLM VPP<2> @BASEBOARD_FAB2_LIB.BASEBOARD_FAB2(SCH_1):PVPP_KLM
 286 PVPP_KLM VPP<1> @BASEBOARD_FAB2_LIB.BASEBOARD_FAB2(SCH_1):PVPP_KLM
 287 PVPP_KLM VPP<0> @BASEBOARD_FAB2_LIB.BASEBOARD_FAB2(SCH_1):PVPP_KLM
  77 PVTT_KLM VTT<1> @BASEBOARD_FAB2_LIB.BASEBOARD_FAB2(SCH_1):PVTT_KLM
 221 PVTT_KLM VTT<0> @BASEBOARD_FAB2_LIB.BASEBOARD_FAB2(SCH_1):PVTT_KLM

CAP_A_0402V-0.01UF,25V,10%,X7RA  I176  C1B9
   1 M_K_VREF      A @BASEBOARD_FAB2_LIB.BASEBOARD_FAB2(SCH_1):M_K_VREF
   2    GND      B @BASEBOARD_FAB2_LIB.BASEBOARD_FAB2(SCH_1):GND


DRAWING: @BASEBOARD_FAB2_LIB.BASEBOARD_FAB2(SCH_1):PAGE84 

CAP_A_0402V-0.01UF,25V,10%,X7RA  I4  C9M1
   1 M_K_VREF      A @BASEBOARD_FAB2_LIB.BASEBOARD_FAB2(SCH_1):M_K_VREF
   2    GND      B @BASEBOARD_FAB2_LIB.BASEBOARD_FAB2(SCH_1):GND

SCONN288_H44441003_PIP-SCONN,HA  I14  J9M1
  79 M_K_MA<0>     A0 @BASEBOARD_FAB2_LIB.BASEBOARD_FAB2(SCH_1):M_K_MA(0)
  72 M_K_MA<1>     A1 @BASEBOARD_FAB2_LIB.BASEBOARD_FAB2(SCH_1):M_K_MA(1)
 225 M_K_MA<10>    A10 @BASEBOARD_FAB2_LIB.BASEBOARD_FAB2(SCH_1):M_K_MA(10)
 210 M_K_MA<11>    A11 @BASEBOARD_FAB2_LIB.BASEBOARD_FAB2(SCH_1):M_K_MA(11)
  65 M_K_MA<12>    A12 @BASEBOARD_FAB2_LIB.BASEBOARD_FAB2(SCH_1):M_K_MA(12)
 232 M_K_MA<13>    A13 @BASEBOARD_FAB2_LIB.BASEBOARD_FAB2(SCH_1):M_K_MA(13)
 228 M_K_MA<14> A14_WE_N @BASEBOARD_FAB2_LIB.BASEBOARD_FAB2(SCH_1):M_K_MA(14)
  86 M_K_MA<15> A15_CAS_N @BASEBOARD_FAB2_LIB.BASEBOARD_FAB2(SCH_1):M_K_MA(15)
  82 M_K_MA<16> A16_RAS_N @BASEBOARD_FAB2_LIB.BASEBOARD_FAB2(SCH_1):M_K_MA(16)
 234 M_K_MA<17>    A17 @BASEBOARD_FAB2_LIB.BASEBOARD_FAB2(SCH_1):M_K_MA(17)
 216 M_K_MA<2>     A2 @BASEBOARD_FAB2_LIB.BASEBOARD_FAB2(SCH_1):M_K_MA(2)
  71 M_K_MA<3>     A3 @BASEBOARD_FAB2_LIB.BASEBOARD_FAB2(SCH_1):M_K_MA(3)
 214 M_K_MA<4>     A4 @BASEBOARD_FAB2_LIB.BASEBOARD_FAB2(SCH_1):M_K_MA(4)
 213 M_K_MA<5>     A5 @BASEBOARD_FAB2_LIB.BASEBOARD_FAB2(SCH_1):M_K_MA(5)
  69 M_K_MA<6>     A6 @BASEBOARD_FAB2_LIB.BASEBOARD_FAB2(SCH_1):M_K_MA(6)
 211 M_K_MA<7>     A7 @BASEBOARD_FAB2_LIB.BASEBOARD_FAB2(SCH_1):M_K_MA(7)
  68 M_K_MA<8>     A8 @BASEBOARD_FAB2_LIB.BASEBOARD_FAB2(SCH_1):M_K_MA(8)
  66 M_K_MA<9>     A9 @BASEBOARD_FAB2_LIB.BASEBOARD_FAB2(SCH_1):M_K_MA(9)
  62 M_K_ACT_N  ACT_N @BASEBOARD_FAB2_LIB.BASEBOARD_FAB2(SCH_1):M_K_ACT_N
 208 M_K_ALERT_N ALERT_N @BASEBOARD_FAB2_LIB.BASEBOARD_FAB2(SCH_1):M_K_ALERT_N
 224 M_K_BA<1>  BA<1> @BASEBOARD_FAB2_LIB.BASEBOARD_FAB2(SCH_1):M_K_BA(1)
  81 M_K_BA<0>  BA<0> @BASEBOARD_FAB2_LIB.BASEBOARD_FAB2(SCH_1):M_K_BA(0)
 207 M_K_BG<1>  BG<1> @BASEBOARD_FAB2_LIB.BASEBOARD_FAB2(SCH_1):M_K_BG(1)
  63 M_K_BG<0>  BG<0> @BASEBOARD_FAB2_LIB.BASEBOARD_FAB2(SCH_1):M_K_BG(0)
 235 M_K_C<2>   C<2> @BASEBOARD_FAB2_LIB.BASEBOARD_FAB2(SCH_1):M_K_C(2)
 199 M_K_ECC<7>  CB<7> @BASEBOARD_FAB2_LIB.BASEBOARD_FAB2(SCH_1):M_K_ECC(7)
  54 M_K_ECC<6>  CB<6> @BASEBOARD_FAB2_LIB.BASEBOARD_FAB2(SCH_1):M_K_ECC(6)
 192 M_K_ECC<5>  CB<5> @BASEBOARD_FAB2_LIB.BASEBOARD_FAB2(SCH_1):M_K_ECC(5)
  47 M_K_ECC<4>  CB<4> @BASEBOARD_FAB2_LIB.BASEBOARD_FAB2(SCH_1):M_K_ECC(4)
 201 M_K_ECC<3>  CB<3> @BASEBOARD_FAB2_LIB.BASEBOARD_FAB2(SCH_1):M_K_ECC(3)
  56 M_K_ECC<2>  CB<2> @BASEBOARD_FAB2_LIB.BASEBOARD_FAB2(SCH_1):M_K_ECC(2)
 194 M_K_ECC<1>  CB<1> @BASEBOARD_FAB2_LIB.BASEBOARD_FAB2(SCH_1):M_K_ECC(1)
  49 M_K_ECC<0>  CB<0> @BASEBOARD_FAB2_LIB.BASEBOARD_FAB2(SCH_1):M_K_ECC(0)
  75 M_K_CLK_DN<2>   CK0N @BASEBOARD_FAB2_LIB.BASEBOARD_FAB2(SCH_1):M_K_CLK_DN(2)
  74 M_K_CLK_DP<2>   CK0P @BASEBOARD_FAB2_LIB.BASEBOARD_FAB2(SCH_1):M_K_CLK_DP(2)
 219 M_K_CLK_DN<3>   CK1N @BASEBOARD_FAB2_LIB.BASEBOARD_FAB2(SCH_1):M_K_CLK_DN(3)
 218 M_K_CLK_DP<3>   CK1P @BASEBOARD_FAB2_LIB.BASEBOARD_FAB2(SCH_1):M_K_CLK_DP(3)
 203 M_K_CKE<3> CKE<1> @BASEBOARD_FAB2_LIB.BASEBOARD_FAB2(SCH_1):M_K_CKE(3)
  60 M_K_CKE<2> CKE<0> @BASEBOARD_FAB2_LIB.BASEBOARD_FAB2(SCH_1):M_K_CKE(2)
 280 M_K_DQ<63> DQ<63> @BASEBOARD_FAB2_LIB.BASEBOARD_FAB2(SCH_1):M_K_DQ(63)
 135 M_K_DQ<62> DQ<62> @BASEBOARD_FAB2_LIB.BASEBOARD_FAB2(SCH_1):M_K_DQ(62)
 273 M_K_DQ<61> DQ<61> @BASEBOARD_FAB2_LIB.BASEBOARD_FAB2(SCH_1):M_K_DQ(61)
 128 M_K_DQ<60> DQ<60> @BASEBOARD_FAB2_LIB.BASEBOARD_FAB2(SCH_1):M_K_DQ(60)
 282 M_K_DQ<59> DQ<59> @BASEBOARD_FAB2_LIB.BASEBOARD_FAB2(SCH_1):M_K_DQ(59)
 137 M_K_DQ<58> DQ<58> @BASEBOARD_FAB2_LIB.BASEBOARD_FAB2(SCH_1):M_K_DQ(58)
 275 M_K_DQ<57> DQ<57> @BASEBOARD_FAB2_LIB.BASEBOARD_FAB2(SCH_1):M_K_DQ(57)
 130 M_K_DQ<56> DQ<56> @BASEBOARD_FAB2_LIB.BASEBOARD_FAB2(SCH_1):M_K_DQ(56)
 269 M_K_DQ<55> DQ<55> @BASEBOARD_FAB2_LIB.BASEBOARD_FAB2(SCH_1):M_K_DQ(55)
 124 M_K_DQ<54> DQ<54> @BASEBOARD_FAB2_LIB.BASEBOARD_FAB2(SCH_1):M_K_DQ(54)
 262 M_K_DQ<53> DQ<53> @BASEBOARD_FAB2_LIB.BASEBOARD_FAB2(SCH_1):M_K_DQ(53)
 117 M_K_DQ<52> DQ<52> @BASEBOARD_FAB2_LIB.BASEBOARD_FAB2(SCH_1):M_K_DQ(52)
 271 M_K_DQ<51> DQ<51> @BASEBOARD_FAB2_LIB.BASEBOARD_FAB2(SCH_1):M_K_DQ(51)
 126 M_K_DQ<50> DQ<50> @BASEBOARD_FAB2_LIB.BASEBOARD_FAB2(SCH_1):M_K_DQ(50)
 264 M_K_DQ<49> DQ<49> @BASEBOARD_FAB2_LIB.BASEBOARD_FAB2(SCH_1):M_K_DQ(49)
 119 M_K_DQ<48> DQ<48> @BASEBOARD_FAB2_LIB.BASEBOARD_FAB2(SCH_1):M_K_DQ(48)
 258 M_K_DQ<47> DQ<47> @BASEBOARD_FAB2_LIB.BASEBOARD_FAB2(SCH_1):M_K_DQ(47)
 113 M_K_DQ<46> DQ<46> @BASEBOARD_FAB2_LIB.BASEBOARD_FAB2(SCH_1):M_K_DQ(46)
 251 M_K_DQ<45> DQ<45> @BASEBOARD_FAB2_LIB.BASEBOARD_FAB2(SCH_1):M_K_DQ(45)
 106 M_K_DQ<44> DQ<44> @BASEBOARD_FAB2_LIB.BASEBOARD_FAB2(SCH_1):M_K_DQ(44)
 260 M_K_DQ<43> DQ<43> @BASEBOARD_FAB2_LIB.BASEBOARD_FAB2(SCH_1):M_K_DQ(43)
 115 M_K_DQ<42> DQ<42> @BASEBOARD_FAB2_LIB.BASEBOARD_FAB2(SCH_1):M_K_DQ(42)
 253 M_K_DQ<41> DQ<41> @BASEBOARD_FAB2_LIB.BASEBOARD_FAB2(SCH_1):M_K_DQ(41)
 108 M_K_DQ<40> DQ<40> @BASEBOARD_FAB2_LIB.BASEBOARD_FAB2(SCH_1):M_K_DQ(40)
 247 M_K_DQ<39> DQ<39> @BASEBOARD_FAB2_LIB.BASEBOARD_FAB2(SCH_1):M_K_DQ(39)
 102 M_K_DQ<38> DQ<38> @BASEBOARD_FAB2_LIB.BASEBOARD_FAB2(SCH_1):M_K_DQ(38)
 240 M_K_DQ<37> DQ<37> @BASEBOARD_FAB2_LIB.BASEBOARD_FAB2(SCH_1):M_K_DQ(37)
  95 M_K_DQ<36> DQ<36> @BASEBOARD_FAB2_LIB.BASEBOARD_FAB2(SCH_1):M_K_DQ(36)
 249 M_K_DQ<35> DQ<35> @BASEBOARD_FAB2_LIB.BASEBOARD_FAB2(SCH_1):M_K_DQ(35)
 104 M_K_DQ<34> DQ<34> @BASEBOARD_FAB2_LIB.BASEBOARD_FAB2(SCH_1):M_K_DQ(34)
 242 M_K_DQ<33> DQ<33> @BASEBOARD_FAB2_LIB.BASEBOARD_FAB2(SCH_1):M_K_DQ(33)
  97 M_K_DQ<32> DQ<32> @BASEBOARD_FAB2_LIB.BASEBOARD_FAB2(SCH_1):M_K_DQ(32)
 188 M_K_DQ<31> DQ<31> @BASEBOARD_FAB2_LIB.BASEBOARD_FAB2(SCH_1):M_K_DQ(31)
  43 M_K_DQ<30> DQ<30> @BASEBOARD_FAB2_LIB.BASEBOARD_FAB2(SCH_1):M_K_DQ(30)
 181 M_K_DQ<29> DQ<29> @BASEBOARD_FAB2_LIB.BASEBOARD_FAB2(SCH_1):M_K_DQ(29)
  36 M_K_DQ<28> DQ<28> @BASEBOARD_FAB2_LIB.BASEBOARD_FAB2(SCH_1):M_K_DQ(28)
 190 M_K_DQ<27> DQ<27> @BASEBOARD_FAB2_LIB.BASEBOARD_FAB2(SCH_1):M_K_DQ(27)
  45 M_K_DQ<26> DQ<26> @BASEBOARD_FAB2_LIB.BASEBOARD_FAB2(SCH_1):M_K_DQ(26)
 183 M_K_DQ<25> DQ<25> @BASEBOARD_FAB2_LIB.BASEBOARD_FAB2(SCH_1):M_K_DQ(25)
  38 M_K_DQ<24> DQ<24> @BASEBOARD_FAB2_LIB.BASEBOARD_FAB2(SCH_1):M_K_DQ(24)
 177 M_K_DQ<23> DQ<23> @BASEBOARD_FAB2_LIB.BASEBOARD_FAB2(SCH_1):M_K_DQ(23)
  32 M_K_DQ<22> DQ<22> @BASEBOARD_FAB2_LIB.BASEBOARD_FAB2(SCH_1):M_K_DQ(22)
 170 M_K_DQ<21> DQ<21> @BASEBOARD_FAB2_LIB.BASEBOARD_FAB2(SCH_1):M_K_DQ(21)
  25 M_K_DQ<20> DQ<20> @BASEBOARD_FAB2_LIB.BASEBOARD_FAB2(SCH_1):M_K_DQ(20)
 179 M_K_DQ<19> DQ<19> @BASEBOARD_FAB2_LIB.BASEBOARD_FAB2(SCH_1):M_K_DQ(19)
  34 M_K_DQ<18> DQ<18> @BASEBOARD_FAB2_LIB.BASEBOARD_FAB2(SCH_1):M_K_DQ(18)
 172 M_K_DQ<17> DQ<17> @BASEBOARD_FAB2_LIB.BASEBOARD_FAB2(SCH_1):M_K_DQ(17)
  27 M_K_DQ<16> DQ<16> @BASEBOARD_FAB2_LIB.BASEBOARD_FAB2(SCH_1):M_K_DQ(16)
 166 M_K_DQ<15> DQ<15> @BASEBOARD_FAB2_LIB.BASEBOARD_FAB2(SCH_1):M_K_DQ(15)
  21 M_K_DQ<14> DQ<14> @BASEBOARD_FAB2_LIB.BASEBOARD_FAB2(SCH_1):M_K_DQ(14)
 159 M_K_DQ<13> DQ<13> @BASEBOARD_FAB2_LIB.BASEBOARD_FAB2(SCH_1):M_K_DQ(13)
  14 M_K_DQ<12> DQ<12> @BASEBOARD_FAB2_LIB.BASEBOARD_FAB2(SCH_1):M_K_DQ(12)
 168 M_K_DQ<11> DQ<11> @BASEBOARD_FAB2_LIB.BASEBOARD_FAB2(SCH_1):M_K_DQ(11)
  23 M_K_DQ<10> DQ<10> @BASEBOARD_FAB2_LIB.BASEBOARD_FAB2(SCH_1):M_K_DQ(10)
 161 M_K_DQ<9>  DQ<9> @BASEBOARD_FAB2_LIB.BASEBOARD_FAB2(SCH_1):M_K_DQ(9)
  16 M_K_DQ<8>  DQ<8> @BASEBOARD_FAB2_LIB.BASEBOARD_FAB2(SCH_1):M_K_DQ(8)
 155 M_K_DQ<7>  DQ<7> @BASEBOARD_FAB2_LIB.BASEBOARD_FAB2(SCH_1):M_K_DQ(7)
  10 M_K_DQ<6>  DQ<6> @BASEBOARD_FAB2_LIB.BASEBOARD_FAB2(SCH_1):M_K_DQ(6)
 148 M_K_DQ<5>  DQ<5> @BASEBOARD_FAB2_LIB.BASEBOARD_FAB2(SCH_1):M_K_DQ(5)
   3 M_K_DQ<4>  DQ<4> @BASEBOARD_FAB2_LIB.BASEBOARD_FAB2(SCH_1):M_K_DQ(4)
 157 M_K_DQ<3>  DQ<3> @BASEBOARD_FAB2_LIB.BASEBOARD_FAB2(SCH_1):M_K_DQ(3)
  12 M_K_DQ<2>  DQ<2> @BASEBOARD_FAB2_LIB.BASEBOARD_FAB2(SCH_1):M_K_DQ(2)
 150 M_K_DQ<1>  DQ<1> @BASEBOARD_FAB2_LIB.BASEBOARD_FAB2(SCH_1):M_K_DQ(1)
   5 M_K_DQ<0>  DQ<0> @BASEBOARD_FAB2_LIB.BASEBOARD_FAB2(SCH_1):M_K_DQ(0)
  78 FM_DIMM_EVENT_COD_N EVENT_N @BASEBOARD_FAB2_LIB.BASEBOARD_FAB2(SCH_1):FM_DIMM_EVENT_COD_N
  91 M_K_ODT<3> ODT<1> @BASEBOARD_FAB2_LIB.BASEBOARD_FAB2(SCH_1):M_K_ODT(3)
  87 M_K_ODT<2> ODT<0> @BASEBOARD_FAB2_LIB.BASEBOARD_FAB2(SCH_1):M_K_ODT(2)
 222 M_K_PAR    PAR @BASEBOARD_FAB2_LIB.BASEBOARD_FAB2(SCH_1):M_K_PAR
  58 M_KLM_RST_N RESET_N @BASEBOARD_FAB2_LIB.BASEBOARD_FAB2(SCH_1):M_KLM_RST_N
 144 TP_CH_K_DIMM0_RFU_2 RFU<2> @BASEBOARD_FAB2_LIB.BASEBOARD_FAB2(SCH_1):TP_CH_K_DIMM0_RFU_2
 227 TP_CH_K_DIMM0_RFU_1 RFU<1> @BASEBOARD_FAB2_LIB.BASEBOARD_FAB2(SCH_1):TP_CH_K_DIMM0_RFU_1
 205 TP_CH_K_DIMM0_RFU_0 RFU<0> @BASEBOARD_FAB2_LIB.BASEBOARD_FAB2(SCH_1):TP_CH_K_DIMM0_RFU_0
  84 M_K_CS_N<4>   S0_N @BASEBOARD_FAB2_LIB.BASEBOARD_FAB2(SCH_1):M_K_CS_N(4)
  89 M_K_CS_N<5>   S1_N @BASEBOARD_FAB2_LIB.BASEBOARD_FAB2(SCH_1):M_K_CS_N(5)
  93 M_K_CS_N<6> S2_N_C<0> @BASEBOARD_FAB2_LIB.BASEBOARD_FAB2(SCH_1):M_K_CS_N(6)
 237 M_K_CS_N<7> S3_N_C<1> @BASEBOARD_FAB2_LIB.BASEBOARD_FAB2(SCH_1):M_K_CS_N(7)
 238    GND  SA<2> @BASEBOARD_FAB2_LIB.BASEBOARD_FAB2(SCH_1):GND
 140    GND  SA<1> @BASEBOARD_FAB2_LIB.BASEBOARD_FAB2(SCH_1):GND
 139 PVPP_KLM  SA<0> @BASEBOARD_FAB2_LIB.BASEBOARD_FAB2(SCH_1):PVPP_KLM
 230 FM_ADR_COMPLETE_KLM_N SAVE_N_NC @BASEBOARD_FAB2_LIB.BASEBOARD_FAB2(SCH_1):FM_ADR_COMPLETE_KLM_N
 141 SMB_DDR_KLM_VPP_SCL    SCL @BASEBOARD_FAB2_LIB.BASEBOARD_FAB2(SCH_1):SMB_DDR_KLM_VPP_SCL
 285 SMB_DDR_KLM_VPP_SDA    SDA @BASEBOARD_FAB2_LIB.BASEBOARD_FAB2(SCH_1):SMB_DDR_KLM_VPP_SDA
 284 PVPP_KLM VDDSPD @BASEBOARD_FAB2_LIB.BASEBOARD_FAB2(SCH_1):PVPP_KLM
 146 M_K_VREF VREFCA @BASEBOARD_FAB2_LIB.BASEBOARD_FAB2(SCH_1):M_K_VREF

SCONN288_H44441003_PIP-SCONN,HA  I57  J9M1
   1 P12V_NVDIMM_KLM 12V<1> @BASEBOARD_FAB2_LIB.BASEBOARD_FAB2(SCH_1):P12V_NVDIMM_KLM
 145 P12V_NVDIMM_KLM 12V<0> @BASEBOARD_FAB2_LIB.BASEBOARD_FAB2(SCH_1):P12V_NVDIMM_KLM
  59 PVDDQ_KLM VDD<25> @BASEBOARD_FAB2_LIB.BASEBOARD_FAB2(SCH_1):PVDDQ_KLM
  61 PVDDQ_KLM VDD<24> @BASEBOARD_FAB2_LIB.BASEBOARD_FAB2(SCH_1):PVDDQ_KLM
  64 PVDDQ_KLM VDD<23> @BASEBOARD_FAB2_LIB.BASEBOARD_FAB2(SCH_1):PVDDQ_KLM
  67 PVDDQ_KLM VDD<22> @BASEBOARD_FAB2_LIB.BASEBOARD_FAB2(SCH_1):PVDDQ_KLM
  70 PVDDQ_KLM VDD<21> @BASEBOARD_FAB2_LIB.BASEBOARD_FAB2(SCH_1):PVDDQ_KLM
  73 PVDDQ_KLM VDD<20> @BASEBOARD_FAB2_LIB.BASEBOARD_FAB2(SCH_1):PVDDQ_KLM
  76 PVDDQ_KLM VDD<19> @BASEBOARD_FAB2_LIB.BASEBOARD_FAB2(SCH_1):PVDDQ_KLM
  80 PVDDQ_KLM VDD<18> @BASEBOARD_FAB2_LIB.BASEBOARD_FAB2(SCH_1):PVDDQ_KLM
  83 PVDDQ_KLM VDD<17> @BASEBOARD_FAB2_LIB.BASEBOARD_FAB2(SCH_1):PVDDQ_KLM
  85 PVDDQ_KLM VDD<16> @BASEBOARD_FAB2_LIB.BASEBOARD_FAB2(SCH_1):PVDDQ_KLM
  88 PVDDQ_KLM VDD<15> @BASEBOARD_FAB2_LIB.BASEBOARD_FAB2(SCH_1):PVDDQ_KLM
  90 PVDDQ_KLM VDD<14> @BASEBOARD_FAB2_LIB.BASEBOARD_FAB2(SCH_1):PVDDQ_KLM
  92 PVDDQ_KLM VDD<13> @BASEBOARD_FAB2_LIB.BASEBOARD_FAB2(SCH_1):PVDDQ_KLM
 204 PVDDQ_KLM VDD<12> @BASEBOARD_FAB2_LIB.BASEBOARD_FAB2(SCH_1):PVDDQ_KLM
 206 PVDDQ_KLM VDD<11> @BASEBOARD_FAB2_LIB.BASEBOARD_FAB2(SCH_1):PVDDQ_KLM
 209 PVDDQ_KLM VDD<10> @BASEBOARD_FAB2_LIB.BASEBOARD_FAB2(SCH_1):PVDDQ_KLM
 212 PVDDQ_KLM VDD<9> @BASEBOARD_FAB2_LIB.BASEBOARD_FAB2(SCH_1):PVDDQ_KLM
 215 PVDDQ_KLM VDD<8> @BASEBOARD_FAB2_LIB.BASEBOARD_FAB2(SCH_1):PVDDQ_KLM
 217 PVDDQ_KLM VDD<7> @BASEBOARD_FAB2_LIB.BASEBOARD_FAB2(SCH_1):PVDDQ_KLM
 220 PVDDQ_KLM VDD<6> @BASEBOARD_FAB2_LIB.BASEBOARD_FAB2(SCH_1):PVDDQ_KLM
 223 PVDDQ_KLM VDD<5> @BASEBOARD_FAB2_LIB.BASEBOARD_FAB2(SCH_1):PVDDQ_KLM
 226 PVDDQ_KLM VDD<4> @BASEBOARD_FAB2_LIB.BASEBOARD_FAB2(SCH_1):PVDDQ_KLM
 229 PVDDQ_KLM VDD<3> @BASEBOARD_FAB2_LIB.BASEBOARD_FAB2(SCH_1):PVDDQ_KLM
 231 PVDDQ_KLM VDD<2> @BASEBOARD_FAB2_LIB.BASEBOARD_FAB2(SCH_1):PVDDQ_KLM
 233 PVDDQ_KLM VDD<1> @BASEBOARD_FAB2_LIB.BASEBOARD_FAB2(SCH_1):PVDDQ_KLM
 236 PVDDQ_KLM VDD<0> @BASEBOARD_FAB2_LIB.BASEBOARD_FAB2(SCH_1):PVDDQ_KLM
 142 PVPP_KLM VPP<4> @BASEBOARD_FAB2_LIB.BASEBOARD_FAB2(SCH_1):PVPP_KLM
 143 PVPP_KLM VPP<3> @BASEBOARD_FAB2_LIB.BASEBOARD_FAB2(SCH_1):PVPP_KLM
 288 PVPP_KLM VPP<2> @BASEBOARD_FAB2_LIB.BASEBOARD_FAB2(SCH_1):PVPP_KLM
 286 PVPP_KLM VPP<1> @BASEBOARD_FAB2_LIB.BASEBOARD_FAB2(SCH_1):PVPP_KLM
 287 PVPP_KLM VPP<0> @BASEBOARD_FAB2_LIB.BASEBOARD_FAB2(SCH_1):PVPP_KLM
  77 PVTT_KLM VTT<1> @BASEBOARD_FAB2_LIB.BASEBOARD_FAB2(SCH_1):PVTT_KLM
 221 PVTT_KLM VTT<0> @BASEBOARD_FAB2_LIB.BASEBOARD_FAB2(SCH_1):PVTT_KLM

SCONN288_H44441003_PIP-SCONN,HA  I102  J9M1
 152 M_K_DQS_DN<0>  DQS0N @BASEBOARD_FAB2_LIB.BASEBOARD_FAB2(SCH_1):M_K_DQS_DN(0)
 153 M_K_DQS_DP<0>  DQS0P @BASEBOARD_FAB2_LIB.BASEBOARD_FAB2(SCH_1):M_K_DQS_DP(0)
  19 M_K_DQS_DN<10> DQS10N @BASEBOARD_FAB2_LIB.BASEBOARD_FAB2(SCH_1):M_K_DQS_DN(10)
  18 M_K_DQS_DP<10> DQS10P @BASEBOARD_FAB2_LIB.BASEBOARD_FAB2(SCH_1):M_K_DQS_DP(10)
  30 M_K_DQS_DN<11> DQS11N @BASEBOARD_FAB2_LIB.BASEBOARD_FAB2(SCH_1):M_K_DQS_DN(11)
  29 M_K_DQS_DP<11> DQS11P @BASEBOARD_FAB2_LIB.BASEBOARD_FAB2(SCH_1):M_K_DQS_DP(11)
  41 M_K_DQS_DN<12> DQS12N @BASEBOARD_FAB2_LIB.BASEBOARD_FAB2(SCH_1):M_K_DQS_DN(12)
  40 M_K_DQS_DP<12> DQS12P @BASEBOARD_FAB2_LIB.BASEBOARD_FAB2(SCH_1):M_K_DQS_DP(12)
 100 M_K_DQS_DN<13> DQS13N @BASEBOARD_FAB2_LIB.BASEBOARD_FAB2(SCH_1):M_K_DQS_DN(13)
  99 M_K_DQS_DP<13> DQS13P @BASEBOARD_FAB2_LIB.BASEBOARD_FAB2(SCH_1):M_K_DQS_DP(13)
 111 M_K_DQS_DN<14> DQS14N @BASEBOARD_FAB2_LIB.BASEBOARD_FAB2(SCH_1):M_K_DQS_DN(14)
 110 M_K_DQS_DP<14> DQS14P @BASEBOARD_FAB2_LIB.BASEBOARD_FAB2(SCH_1):M_K_DQS_DP(14)
 122 M_K_DQS_DN<15> DQS15N @BASEBOARD_FAB2_LIB.BASEBOARD_FAB2(SCH_1):M_K_DQS_DN(15)
 121 M_K_DQS_DP<15> DQS15P @BASEBOARD_FAB2_LIB.BASEBOARD_FAB2(SCH_1):M_K_DQS_DP(15)
 133 M_K_DQS_DN<16> DQS16N @BASEBOARD_FAB2_LIB.BASEBOARD_FAB2(SCH_1):M_K_DQS_DN(16)
 132 M_K_DQS_DP<16> DQS16P @BASEBOARD_FAB2_LIB.BASEBOARD_FAB2(SCH_1):M_K_DQS_DP(16)
  52 M_K_DQS_DN<17> DQS17N @BASEBOARD_FAB2_LIB.BASEBOARD_FAB2(SCH_1):M_K_DQS_DN(17)
  51 M_K_DQS_DP<17> DQS17P @BASEBOARD_FAB2_LIB.BASEBOARD_FAB2(SCH_1):M_K_DQS_DP(17)
 163 M_K_DQS_DN<1>  DQS1N @BASEBOARD_FAB2_LIB.BASEBOARD_FAB2(SCH_1):M_K_DQS_DN(1)
 164 M_K_DQS_DP<1>  DQS1P @BASEBOARD_FAB2_LIB.BASEBOARD_FAB2(SCH_1):M_K_DQS_DP(1)
 174 M_K_DQS_DN<2>  DQS2N @BASEBOARD_FAB2_LIB.BASEBOARD_FAB2(SCH_1):M_K_DQS_DN(2)
 175 M_K_DQS_DP<2>  DQS2P @BASEBOARD_FAB2_LIB.BASEBOARD_FAB2(SCH_1):M_K_DQS_DP(2)
 185 M_K_DQS_DN<3>  DQS3N @BASEBOARD_FAB2_LIB.BASEBOARD_FAB2(SCH_1):M_K_DQS_DN(3)
 186 M_K_DQS_DP<3>  DQS3P @BASEBOARD_FAB2_LIB.BASEBOARD_FAB2(SCH_1):M_K_DQS_DP(3)
 244 M_K_DQS_DN<4>  DQS4N @BASEBOARD_FAB2_LIB.BASEBOARD_FAB2(SCH_1):M_K_DQS_DN(4)
 245 M_K_DQS_DP<4>  DQS4P @BASEBOARD_FAB2_LIB.BASEBOARD_FAB2(SCH_1):M_K_DQS_DP(4)
 255 M_K_DQS_DN<5>  DQS5N @BASEBOARD_FAB2_LIB.BASEBOARD_FAB2(SCH_1):M_K_DQS_DN(5)
 256 M_K_DQS_DP<5>  DQS5P @BASEBOARD_FAB2_LIB.BASEBOARD_FAB2(SCH_1):M_K_DQS_DP(5)
 266 M_K_DQS_DN<6>  DQS6N @BASEBOARD_FAB2_LIB.BASEBOARD_FAB2(SCH_1):M_K_DQS_DN(6)
 267 M_K_DQS_DP<6>  DQS6P @BASEBOARD_FAB2_LIB.BASEBOARD_FAB2(SCH_1):M_K_DQS_DP(6)
 277 M_K_DQS_DN<7>  DQS7N @BASEBOARD_FAB2_LIB.BASEBOARD_FAB2(SCH_1):M_K_DQS_DN(7)
 278 M_K_DQS_DP<7>  DQS7P @BASEBOARD_FAB2_LIB.BASEBOARD_FAB2(SCH_1):M_K_DQS_DP(7)
 196 M_K_DQS_DN<8>  DQS8N @BASEBOARD_FAB2_LIB.BASEBOARD_FAB2(SCH_1):M_K_DQS_DN(8)
 197 M_K_DQS_DP<8>  DQS8P @BASEBOARD_FAB2_LIB.BASEBOARD_FAB2(SCH_1):M_K_DQS_DP(8)
   8 M_K_DQS_DN<9>  DQS9N @BASEBOARD_FAB2_LIB.BASEBOARD_FAB2(SCH_1):M_K_DQS_DN(9)
   7 M_K_DQS_DP<9>  DQS9P @BASEBOARD_FAB2_LIB.BASEBOARD_FAB2(SCH_1):M_K_DQS_DP(9)

SCONN288_H44441003_PIP-SCONN,HA  I138  J9M1
   2    GND VSS<93> @BASEBOARD_FAB2_LIB.BASEBOARD_FAB2(SCH_1):GND
   4    GND VSS<92> @BASEBOARD_FAB2_LIB.BASEBOARD_FAB2(SCH_1):GND
   6    GND VSS<91> @BASEBOARD_FAB2_LIB.BASEBOARD_FAB2(SCH_1):GND
   9    GND VSS<90> @BASEBOARD_FAB2_LIB.BASEBOARD_FAB2(SCH_1):GND
  11    GND VSS<89> @BASEBOARD_FAB2_LIB.BASEBOARD_FAB2(SCH_1):GND
  13    GND VSS<88> @BASEBOARD_FAB2_LIB.BASEBOARD_FAB2(SCH_1):GND
  15    GND VSS<87> @BASEBOARD_FAB2_LIB.BASEBOARD_FAB2(SCH_1):GND
  17    GND VSS<86> @BASEBOARD_FAB2_LIB.BASEBOARD_FAB2(SCH_1):GND
  20    GND VSS<85> @BASEBOARD_FAB2_LIB.BASEBOARD_FAB2(SCH_1):GND
  22    GND VSS<84> @BASEBOARD_FAB2_LIB.BASEBOARD_FAB2(SCH_1):GND
  24    GND VSS<83> @BASEBOARD_FAB2_LIB.BASEBOARD_FAB2(SCH_1):GND
  26    GND VSS<82> @BASEBOARD_FAB2_LIB.BASEBOARD_FAB2(SCH_1):GND
  28    GND VSS<81> @BASEBOARD_FAB2_LIB.BASEBOARD_FAB2(SCH_1):GND
  31    GND VSS<80> @BASEBOARD_FAB2_LIB.BASEBOARD_FAB2(SCH_1):GND
  33    GND VSS<79> @BASEBOARD_FAB2_LIB.BASEBOARD_FAB2(SCH_1):GND
  35    GND VSS<78> @BASEBOARD_FAB2_LIB.BASEBOARD_FAB2(SCH_1):GND
  37    GND VSS<77> @BASEBOARD_FAB2_LIB.BASEBOARD_FAB2(SCH_1):GND
  39    GND VSS<76> @BASEBOARD_FAB2_LIB.BASEBOARD_FAB2(SCH_1):GND
  42    GND VSS<75> @BASEBOARD_FAB2_LIB.BASEBOARD_FAB2(SCH_1):GND
  44    GND VSS<74> @BASEBOARD_FAB2_LIB.BASEBOARD_FAB2(SCH_1):GND
  46    GND VSS<73> @BASEBOARD_FAB2_LIB.BASEBOARD_FAB2(SCH_1):GND
  48    GND VSS<72> @BASEBOARD_FAB2_LIB.BASEBOARD_FAB2(SCH_1):GND
  50    GND VSS<71> @BASEBOARD_FAB2_LIB.BASEBOARD_FAB2(SCH_1):GND
  53    GND VSS<70> @BASEBOARD_FAB2_LIB.BASEBOARD_FAB2(SCH_1):GND
  55    GND VSS<69> @BASEBOARD_FAB2_LIB.BASEBOARD_FAB2(SCH_1):GND
  57    GND VSS<68> @BASEBOARD_FAB2_LIB.BASEBOARD_FAB2(SCH_1):GND
  94    GND VSS<67> @BASEBOARD_FAB2_LIB.BASEBOARD_FAB2(SCH_1):GND
  96    GND VSS<66> @BASEBOARD_FAB2_LIB.BASEBOARD_FAB2(SCH_1):GND
  98    GND VSS<65> @BASEBOARD_FAB2_LIB.BASEBOARD_FAB2(SCH_1):GND
 101    GND VSS<64> @BASEBOARD_FAB2_LIB.BASEBOARD_FAB2(SCH_1):GND
 103    GND VSS<63> @BASEBOARD_FAB2_LIB.BASEBOARD_FAB2(SCH_1):GND
 105    GND VSS<62> @BASEBOARD_FAB2_LIB.BASEBOARD_FAB2(SCH_1):GND
 107    GND VSS<61> @BASEBOARD_FAB2_LIB.BASEBOARD_FAB2(SCH_1):GND
 109    GND VSS<60> @BASEBOARD_FAB2_LIB.BASEBOARD_FAB2(SCH_1):GND
 112    GND VSS<59> @BASEBOARD_FAB2_LIB.BASEBOARD_FAB2(SCH_1):GND
 114    GND VSS<58> @BASEBOARD_FAB2_LIB.BASEBOARD_FAB2(SCH_1):GND
 116    GND VSS<57> @BASEBOARD_FAB2_LIB.BASEBOARD_FAB2(SCH_1):GND
 118    GND VSS<56> @BASEBOARD_FAB2_LIB.BASEBOARD_FAB2(SCH_1):GND
 120    GND VSS<55> @BASEBOARD_FAB2_LIB.BASEBOARD_FAB2(SCH_1):GND
 123    GND VSS<54> @BASEBOARD_FAB2_LIB.BASEBOARD_FAB2(SCH_1):GND
 125    GND VSS<53> @BASEBOARD_FAB2_LIB.BASEBOARD_FAB2(SCH_1):GND
 127    GND VSS<52> @BASEBOARD_FAB2_LIB.BASEBOARD_FAB2(SCH_1):GND
 129    GND VSS<51> @BASEBOARD_FAB2_LIB.BASEBOARD_FAB2(SCH_1):GND
 131    GND VSS<50> @BASEBOARD_FAB2_LIB.BASEBOARD_FAB2(SCH_1):GND
 134    GND VSS<49> @BASEBOARD_FAB2_LIB.BASEBOARD_FAB2(SCH_1):GND
 136    GND VSS<48> @BASEBOARD_FAB2_LIB.BASEBOARD_FAB2(SCH_1):GND
 138    GND VSS<47> @BASEBOARD_FAB2_LIB.BASEBOARD_FAB2(SCH_1):GND
 147    GND VSS<46> @BASEBOARD_FAB2_LIB.BASEBOARD_FAB2(SCH_1):GND
 149    GND VSS<45> @BASEBOARD_FAB2_LIB.BASEBOARD_FAB2(SCH_1):GND
 151    GND VSS<44> @BASEBOARD_FAB2_LIB.BASEBOARD_FAB2(SCH_1):GND
 154    GND VSS<43> @BASEBOARD_FAB2_LIB.BASEBOARD_FAB2(SCH_1):GND
 156    GND VSS<42> @BASEBOARD_FAB2_LIB.BASEBOARD_FAB2(SCH_1):GND
 158    GND VSS<41> @BASEBOARD_FAB2_LIB.BASEBOARD_FAB2(SCH_1):GND
 160    GND VSS<40> @BASEBOARD_FAB2_LIB.BASEBOARD_FAB2(SCH_1):GND
 162    GND VSS<39> @BASEBOARD_FAB2_LIB.BASEBOARD_FAB2(SCH_1):GND
 165    GND VSS<38> @BASEBOARD_FAB2_LIB.BASEBOARD_FAB2(SCH_1):GND
 167    GND VSS<37> @BASEBOARD_FAB2_LIB.BASEBOARD_FAB2(SCH_1):GND
 169    GND VSS<36> @BASEBOARD_FAB2_LIB.BASEBOARD_FAB2(SCH_1):GND
 171    GND VSS<35> @BASEBOARD_FAB2_LIB.BASEBOARD_FAB2(SCH_1):GND
 173    GND VSS<34> @BASEBOARD_FAB2_LIB.BASEBOARD_FAB2(SCH_1):GND
 176    GND VSS<33> @BASEBOARD_FAB2_LIB.BASEBOARD_FAB2(SCH_1):GND
 178    GND VSS<32> @BASEBOARD_FAB2_LIB.BASEBOARD_FAB2(SCH_1):GND
 180    GND VSS<31> @BASEBOARD_FAB2_LIB.BASEBOARD_FAB2(SCH_1):GND
 182    GND VSS<30> @BASEBOARD_FAB2_LIB.BASEBOARD_FAB2(SCH_1):GND
 184    GND VSS<29> @BASEBOARD_FAB2_LIB.BASEBOARD_FAB2(SCH_1):GND
 187    GND VSS<28> @BASEBOARD_FAB2_LIB.BASEBOARD_FAB2(SCH_1):GND
 189    GND VSS<27> @BASEBOARD_FAB2_LIB.BASEBOARD_FAB2(SCH_1):GND
 191    GND VSS<26> @BASEBOARD_FAB2_LIB.BASEBOARD_FAB2(SCH_1):GND
 193    GND VSS<25> @BASEBOARD_FAB2_LIB.BASEBOARD_FAB2(SCH_1):GND
 195    GND VSS<24> @BASEBOARD_FAB2_LIB.BASEBOARD_FAB2(SCH_1):GND
 198    GND VSS<23> @BASEBOARD_FAB2_LIB.BASEBOARD_FAB2(SCH_1):GND
 200    GND VSS<22> @BASEBOARD_FAB2_LIB.BASEBOARD_FAB2(SCH_1):GND
 202    GND VSS<21> @BASEBOARD_FAB2_LIB.BASEBOARD_FAB2(SCH_1):GND
 239    GND VSS<20> @BASEBOARD_FAB2_LIB.BASEBOARD_FAB2(SCH_1):GND
 241    GND VSS<19> @BASEBOARD_FAB2_LIB.BASEBOARD_FAB2(SCH_1):GND
 243    GND VSS<18> @BASEBOARD_FAB2_LIB.BASEBOARD_FAB2(SCH_1):GND
 246    GND VSS<17> @BASEBOARD_FAB2_LIB.BASEBOARD_FAB2(SCH_1):GND
 248    GND VSS<16> @BASEBOARD_FAB2_LIB.BASEBOARD_FAB2(SCH_1):GND
 250    GND VSS<15> @BASEBOARD_FAB2_LIB.BASEBOARD_FAB2(SCH_1):GND
 252    GND VSS<14> @BASEBOARD_FAB2_LIB.BASEBOARD_FAB2(SCH_1):GND
 254    GND VSS<13> @BASEBOARD_FAB2_LIB.BASEBOARD_FAB2(SCH_1):GND
 257    GND VSS<12> @BASEBOARD_FAB2_LIB.BASEBOARD_FAB2(SCH_1):GND
 259    GND VSS<11> @BASEBOARD_FAB2_LIB.BASEBOARD_FAB2(SCH_1):GND
 261    GND VSS<10> @BASEBOARD_FAB2_LIB.BASEBOARD_FAB2(SCH_1):GND
 263    GND VSS<9> @BASEBOARD_FAB2_LIB.BASEBOARD_FAB2(SCH_1):GND
 265    GND VSS<8> @BASEBOARD_FAB2_LIB.BASEBOARD_FAB2(SCH_1):GND
 268    GND VSS<7> @BASEBOARD_FAB2_LIB.BASEBOARD_FAB2(SCH_1):GND
 270    GND VSS<6> @BASEBOARD_FAB2_LIB.BASEBOARD_FAB2(SCH_1):GND
 272    GND VSS<5> @BASEBOARD_FAB2_LIB.BASEBOARD_FAB2(SCH_1):GND
 274    GND VSS<4> @BASEBOARD_FAB2_LIB.BASEBOARD_FAB2(SCH_1):GND
 276    GND VSS<3> @BASEBOARD_FAB2_LIB.BASEBOARD_FAB2(SCH_1):GND
 279    GND VSS<2> @BASEBOARD_FAB2_LIB.BASEBOARD_FAB2(SCH_1):GND
 281    GND VSS<1> @BASEBOARD_FAB2_LIB.BASEBOARD_FAB2(SCH_1):GND
 283    GND VSS<0> @BASEBOARD_FAB2_LIB.BASEBOARD_FAB2(SCH_1):GND


DRAWING: @BASEBOARD_FAB2_LIB.BASEBOARD_FAB2(SCH_1):PAGE85 

SCONN288_H44441004_PIP-SCONN,HA  I43  J1A2
   2    GND VSS<93> @BASEBOARD_FAB2_LIB.BASEBOARD_FAB2(SCH_1):GND
   4    GND VSS<92> @BASEBOARD_FAB2_LIB.BASEBOARD_FAB2(SCH_1):GND
   6    GND VSS<91> @BASEBOARD_FAB2_LIB.BASEBOARD_FAB2(SCH_1):GND
   9    GND VSS<90> @BASEBOARD_FAB2_LIB.BASEBOARD_FAB2(SCH_1):GND
  11    GND VSS<89> @BASEBOARD_FAB2_LIB.BASEBOARD_FAB2(SCH_1):GND
  13    GND VSS<88> @BASEBOARD_FAB2_LIB.BASEBOARD_FAB2(SCH_1):GND
  15    GND VSS<87> @BASEBOARD_FAB2_LIB.BASEBOARD_FAB2(SCH_1):GND
  17    GND VSS<86> @BASEBOARD_FAB2_LIB.BASEBOARD_FAB2(SCH_1):GND
  20    GND VSS<85> @BASEBOARD_FAB2_LIB.BASEBOARD_FAB2(SCH_1):GND
  22    GND VSS<84> @BASEBOARD_FAB2_LIB.BASEBOARD_FAB2(SCH_1):GND
  24    GND VSS<83> @BASEBOARD_FAB2_LIB.BASEBOARD_FAB2(SCH_1):GND
  26    GND VSS<82> @BASEBOARD_FAB2_LIB.BASEBOARD_FAB2(SCH_1):GND
  28    GND VSS<81> @BASEBOARD_FAB2_LIB.BASEBOARD_FAB2(SCH_1):GND
  31    GND VSS<80> @BASEBOARD_FAB2_LIB.BASEBOARD_FAB2(SCH_1):GND
  33    GND VSS<79> @BASEBOARD_FAB2_LIB.BASEBOARD_FAB2(SCH_1):GND
  35    GND VSS<78> @BASEBOARD_FAB2_LIB.BASEBOARD_FAB2(SCH_1):GND
  37    GND VSS<77> @BASEBOARD_FAB2_LIB.BASEBOARD_FAB2(SCH_1):GND
  39    GND VSS<76> @BASEBOARD_FAB2_LIB.BASEBOARD_FAB2(SCH_1):GND
  42    GND VSS<75> @BASEBOARD_FAB2_LIB.BASEBOARD_FAB2(SCH_1):GND
  44    GND VSS<74> @BASEBOARD_FAB2_LIB.BASEBOARD_FAB2(SCH_1):GND
  46    GND VSS<73> @BASEBOARD_FAB2_LIB.BASEBOARD_FAB2(SCH_1):GND
  48    GND VSS<72> @BASEBOARD_FAB2_LIB.BASEBOARD_FAB2(SCH_1):GND
  50    GND VSS<71> @BASEBOARD_FAB2_LIB.BASEBOARD_FAB2(SCH_1):GND
  53    GND VSS<70> @BASEBOARD_FAB2_LIB.BASEBOARD_FAB2(SCH_1):GND
  55    GND VSS<69> @BASEBOARD_FAB2_LIB.BASEBOARD_FAB2(SCH_1):GND
  57    GND VSS<68> @BASEBOARD_FAB2_LIB.BASEBOARD_FAB2(SCH_1):GND
  94    GND VSS<67> @BASEBOARD_FAB2_LIB.BASEBOARD_FAB2(SCH_1):GND
  96    GND VSS<66> @BASEBOARD_FAB2_LIB.BASEBOARD_FAB2(SCH_1):GND
  98    GND VSS<65> @BASEBOARD_FAB2_LIB.BASEBOARD_FAB2(SCH_1):GND
 101    GND VSS<64> @BASEBOARD_FAB2_LIB.BASEBOARD_FAB2(SCH_1):GND
 103    GND VSS<63> @BASEBOARD_FAB2_LIB.BASEBOARD_FAB2(SCH_1):GND
 105    GND VSS<62> @BASEBOARD_FAB2_LIB.BASEBOARD_FAB2(SCH_1):GND
 107    GND VSS<61> @BASEBOARD_FAB2_LIB.BASEBOARD_FAB2(SCH_1):GND
 109    GND VSS<60> @BASEBOARD_FAB2_LIB.BASEBOARD_FAB2(SCH_1):GND
 112    GND VSS<59> @BASEBOARD_FAB2_LIB.BASEBOARD_FAB2(SCH_1):GND
 114    GND VSS<58> @BASEBOARD_FAB2_LIB.BASEBOARD_FAB2(SCH_1):GND
 116    GND VSS<57> @BASEBOARD_FAB2_LIB.BASEBOARD_FAB2(SCH_1):GND
 118    GND VSS<56> @BASEBOARD_FAB2_LIB.BASEBOARD_FAB2(SCH_1):GND
 120    GND VSS<55> @BASEBOARD_FAB2_LIB.BASEBOARD_FAB2(SCH_1):GND
 123    GND VSS<54> @BASEBOARD_FAB2_LIB.BASEBOARD_FAB2(SCH_1):GND
 125    GND VSS<53> @BASEBOARD_FAB2_LIB.BASEBOARD_FAB2(SCH_1):GND
 127    GND VSS<52> @BASEBOARD_FAB2_LIB.BASEBOARD_FAB2(SCH_1):GND
 129    GND VSS<51> @BASEBOARD_FAB2_LIB.BASEBOARD_FAB2(SCH_1):GND
 131    GND VSS<50> @BASEBOARD_FAB2_LIB.BASEBOARD_FAB2(SCH_1):GND
 134    GND VSS<49> @BASEBOARD_FAB2_LIB.BASEBOARD_FAB2(SCH_1):GND
 136    GND VSS<48> @BASEBOARD_FAB2_LIB.BASEBOARD_FAB2(SCH_1):GND
 138    GND VSS<47> @BASEBOARD_FAB2_LIB.BASEBOARD_FAB2(SCH_1):GND
 147    GND VSS<46> @BASEBOARD_FAB2_LIB.BASEBOARD_FAB2(SCH_1):GND
 149    GND VSS<45> @BASEBOARD_FAB2_LIB.BASEBOARD_FAB2(SCH_1):GND
 151    GND VSS<44> @BASEBOARD_FAB2_LIB.BASEBOARD_FAB2(SCH_1):GND
 154    GND VSS<43> @BASEBOARD_FAB2_LIB.BASEBOARD_FAB2(SCH_1):GND
 156    GND VSS<42> @BASEBOARD_FAB2_LIB.BASEBOARD_FAB2(SCH_1):GND
 158    GND VSS<41> @BASEBOARD_FAB2_LIB.BASEBOARD_FAB2(SCH_1):GND
 160    GND VSS<40> @BASEBOARD_FAB2_LIB.BASEBOARD_FAB2(SCH_1):GND
 162    GND VSS<39> @BASEBOARD_FAB2_LIB.BASEBOARD_FAB2(SCH_1):GND
 165    GND VSS<38> @BASEBOARD_FAB2_LIB.BASEBOARD_FAB2(SCH_1):GND
 167    GND VSS<37> @BASEBOARD_FAB2_LIB.BASEBOARD_FAB2(SCH_1):GND
 169    GND VSS<36> @BASEBOARD_FAB2_LIB.BASEBOARD_FAB2(SCH_1):GND
 171    GND VSS<35> @BASEBOARD_FAB2_LIB.BASEBOARD_FAB2(SCH_1):GND
 173    GND VSS<34> @BASEBOARD_FAB2_LIB.BASEBOARD_FAB2(SCH_1):GND
 176    GND VSS<33> @BASEBOARD_FAB2_LIB.BASEBOARD_FAB2(SCH_1):GND
 178    GND VSS<32> @BASEBOARD_FAB2_LIB.BASEBOARD_FAB2(SCH_1):GND
 180    GND VSS<31> @BASEBOARD_FAB2_LIB.BASEBOARD_FAB2(SCH_1):GND
 182    GND VSS<30> @BASEBOARD_FAB2_LIB.BASEBOARD_FAB2(SCH_1):GND
 184    GND VSS<29> @BASEBOARD_FAB2_LIB.BASEBOARD_FAB2(SCH_1):GND
 187    GND VSS<28> @BASEBOARD_FAB2_LIB.BASEBOARD_FAB2(SCH_1):GND
 189    GND VSS<27> @BASEBOARD_FAB2_LIB.BASEBOARD_FAB2(SCH_1):GND
 191    GND VSS<26> @BASEBOARD_FAB2_LIB.BASEBOARD_FAB2(SCH_1):GND
 193    GND VSS<25> @BASEBOARD_FAB2_LIB.BASEBOARD_FAB2(SCH_1):GND
 195    GND VSS<24> @BASEBOARD_FAB2_LIB.BASEBOARD_FAB2(SCH_1):GND
 198    GND VSS<23> @BASEBOARD_FAB2_LIB.BASEBOARD_FAB2(SCH_1):GND
 200    GND VSS<22> @BASEBOARD_FAB2_LIB.BASEBOARD_FAB2(SCH_1):GND
 202    GND VSS<21> @BASEBOARD_FAB2_LIB.BASEBOARD_FAB2(SCH_1):GND
 239    GND VSS<20> @BASEBOARD_FAB2_LIB.BASEBOARD_FAB2(SCH_1):GND
 241    GND VSS<19> @BASEBOARD_FAB2_LIB.BASEBOARD_FAB2(SCH_1):GND
 243    GND VSS<18> @BASEBOARD_FAB2_LIB.BASEBOARD_FAB2(SCH_1):GND
 246    GND VSS<17> @BASEBOARD_FAB2_LIB.BASEBOARD_FAB2(SCH_1):GND
 248    GND VSS<16> @BASEBOARD_FAB2_LIB.BASEBOARD_FAB2(SCH_1):GND
 250    GND VSS<15> @BASEBOARD_FAB2_LIB.BASEBOARD_FAB2(SCH_1):GND
 252    GND VSS<14> @BASEBOARD_FAB2_LIB.BASEBOARD_FAB2(SCH_1):GND
 254    GND VSS<13> @BASEBOARD_FAB2_LIB.BASEBOARD_FAB2(SCH_1):GND
 257    GND VSS<12> @BASEBOARD_FAB2_LIB.BASEBOARD_FAB2(SCH_1):GND
 259    GND VSS<11> @BASEBOARD_FAB2_LIB.BASEBOARD_FAB2(SCH_1):GND
 261    GND VSS<10> @BASEBOARD_FAB2_LIB.BASEBOARD_FAB2(SCH_1):GND
 263    GND VSS<9> @BASEBOARD_FAB2_LIB.BASEBOARD_FAB2(SCH_1):GND
 265    GND VSS<8> @BASEBOARD_FAB2_LIB.BASEBOARD_FAB2(SCH_1):GND
 268    GND VSS<7> @BASEBOARD_FAB2_LIB.BASEBOARD_FAB2(SCH_1):GND
 270    GND VSS<6> @BASEBOARD_FAB2_LIB.BASEBOARD_FAB2(SCH_1):GND
 272    GND VSS<5> @BASEBOARD_FAB2_LIB.BASEBOARD_FAB2(SCH_1):GND
 274    GND VSS<4> @BASEBOARD_FAB2_LIB.BASEBOARD_FAB2(SCH_1):GND
 276    GND VSS<3> @BASEBOARD_FAB2_LIB.BASEBOARD_FAB2(SCH_1):GND
 279    GND VSS<2> @BASEBOARD_FAB2_LIB.BASEBOARD_FAB2(SCH_1):GND
 281    GND VSS<1> @BASEBOARD_FAB2_LIB.BASEBOARD_FAB2(SCH_1):GND
 283    GND VSS<0> @BASEBOARD_FAB2_LIB.BASEBOARD_FAB2(SCH_1):GND

SCONN288_H44441004_PIP-SCONN,HA  I66  J1A2
 152 M_L_DQS_DN<0>  DQS0N @BASEBOARD_FAB2_LIB.BASEBOARD_FAB2(SCH_1):M_L_DQS_DN(0)
 153 M_L_DQS_DP<0>  DQS0P @BASEBOARD_FAB2_LIB.BASEBOARD_FAB2(SCH_1):M_L_DQS_DP(0)
  19 M_L_DQS_DN<10> DQS10N @BASEBOARD_FAB2_LIB.BASEBOARD_FAB2(SCH_1):M_L_DQS_DN(10)
  18 M_L_DQS_DP<10> DQS10P @BASEBOARD_FAB2_LIB.BASEBOARD_FAB2(SCH_1):M_L_DQS_DP(10)
  30 M_L_DQS_DN<11> DQS11N @BASEBOARD_FAB2_LIB.BASEBOARD_FAB2(SCH_1):M_L_DQS_DN(11)
  29 M_L_DQS_DP<11> DQS11P @BASEBOARD_FAB2_LIB.BASEBOARD_FAB2(SCH_1):M_L_DQS_DP(11)
  41 M_L_DQS_DN<12> DQS12N @BASEBOARD_FAB2_LIB.BASEBOARD_FAB2(SCH_1):M_L_DQS_DN(12)
  40 M_L_DQS_DP<12> DQS12P @BASEBOARD_FAB2_LIB.BASEBOARD_FAB2(SCH_1):M_L_DQS_DP(12)
 100 M_L_DQS_DN<13> DQS13N @BASEBOARD_FAB2_LIB.BASEBOARD_FAB2(SCH_1):M_L_DQS_DN(13)
  99 M_L_DQS_DP<13> DQS13P @BASEBOARD_FAB2_LIB.BASEBOARD_FAB2(SCH_1):M_L_DQS_DP(13)
 111 M_L_DQS_DN<14> DQS14N @BASEBOARD_FAB2_LIB.BASEBOARD_FAB2(SCH_1):M_L_DQS_DN(14)
 110 M_L_DQS_DP<14> DQS14P @BASEBOARD_FAB2_LIB.BASEBOARD_FAB2(SCH_1):M_L_DQS_DP(14)
 122 M_L_DQS_DN<15> DQS15N @BASEBOARD_FAB2_LIB.BASEBOARD_FAB2(SCH_1):M_L_DQS_DN(15)
 121 M_L_DQS_DP<15> DQS15P @BASEBOARD_FAB2_LIB.BASEBOARD_FAB2(SCH_1):M_L_DQS_DP(15)
 133 M_L_DQS_DN<16> DQS16N @BASEBOARD_FAB2_LIB.BASEBOARD_FAB2(SCH_1):M_L_DQS_DN(16)
 132 M_L_DQS_DP<16> DQS16P @BASEBOARD_FAB2_LIB.BASEBOARD_FAB2(SCH_1):M_L_DQS_DP(16)
  52 M_L_DQS_DN<17> DQS17N @BASEBOARD_FAB2_LIB.BASEBOARD_FAB2(SCH_1):M_L_DQS_DN(17)
  51 M_L_DQS_DP<17> DQS17P @BASEBOARD_FAB2_LIB.BASEBOARD_FAB2(SCH_1):M_L_DQS_DP(17)
 163 M_L_DQS_DN<1>  DQS1N @BASEBOARD_FAB2_LIB.BASEBOARD_FAB2(SCH_1):M_L_DQS_DN(1)
 164 M_L_DQS_DP<1>  DQS1P @BASEBOARD_FAB2_LIB.BASEBOARD_FAB2(SCH_1):M_L_DQS_DP(1)
 174 M_L_DQS_DN<2>  DQS2N @BASEBOARD_FAB2_LIB.BASEBOARD_FAB2(SCH_1):M_L_DQS_DN(2)
 175 M_L_DQS_DP<2>  DQS2P @BASEBOARD_FAB2_LIB.BASEBOARD_FAB2(SCH_1):M_L_DQS_DP(2)
 185 M_L_DQS_DN<3>  DQS3N @BASEBOARD_FAB2_LIB.BASEBOARD_FAB2(SCH_1):M_L_DQS_DN(3)
 186 M_L_DQS_DP<3>  DQS3P @BASEBOARD_FAB2_LIB.BASEBOARD_FAB2(SCH_1):M_L_DQS_DP(3)
 244 M_L_DQS_DN<4>  DQS4N @BASEBOARD_FAB2_LIB.BASEBOARD_FAB2(SCH_1):M_L_DQS_DN(4)
 245 M_L_DQS_DP<4>  DQS4P @BASEBOARD_FAB2_LIB.BASEBOARD_FAB2(SCH_1):M_L_DQS_DP(4)
 255 M_L_DQS_DN<5>  DQS5N @BASEBOARD_FAB2_LIB.BASEBOARD_FAB2(SCH_1):M_L_DQS_DN(5)
 256 M_L_DQS_DP<5>  DQS5P @BASEBOARD_FAB2_LIB.BASEBOARD_FAB2(SCH_1):M_L_DQS_DP(5)
 266 M_L_DQS_DN<6>  DQS6N @BASEBOARD_FAB2_LIB.BASEBOARD_FAB2(SCH_1):M_L_DQS_DN(6)
 267 M_L_DQS_DP<6>  DQS6P @BASEBOARD_FAB2_LIB.BASEBOARD_FAB2(SCH_1):M_L_DQS_DP(6)
 277 M_L_DQS_DN<7>  DQS7N @BASEBOARD_FAB2_LIB.BASEBOARD_FAB2(SCH_1):M_L_DQS_DN(7)
 278 M_L_DQS_DP<7>  DQS7P @BASEBOARD_FAB2_LIB.BASEBOARD_FAB2(SCH_1):M_L_DQS_DP(7)
 196 M_L_DQS_DN<8>  DQS8N @BASEBOARD_FAB2_LIB.BASEBOARD_FAB2(SCH_1):M_L_DQS_DN(8)
 197 M_L_DQS_DP<8>  DQS8P @BASEBOARD_FAB2_LIB.BASEBOARD_FAB2(SCH_1):M_L_DQS_DP(8)
   8 M_L_DQS_DN<9>  DQS9N @BASEBOARD_FAB2_LIB.BASEBOARD_FAB2(SCH_1):M_L_DQS_DN(9)
   7 M_L_DQS_DP<9>  DQS9P @BASEBOARD_FAB2_LIB.BASEBOARD_FAB2(SCH_1):M_L_DQS_DP(9)

SCONN288_H44441004_PIP-SCONN,HA  I111  J1A2
  79 M_L_MA<0>     A0 @BASEBOARD_FAB2_LIB.BASEBOARD_FAB2(SCH_1):M_L_MA(0)
  72 M_L_MA<1>     A1 @BASEBOARD_FAB2_LIB.BASEBOARD_FAB2(SCH_1):M_L_MA(1)
 225 M_L_MA<10>    A10 @BASEBOARD_FAB2_LIB.BASEBOARD_FAB2(SCH_1):M_L_MA(10)
 210 M_L_MA<11>    A11 @BASEBOARD_FAB2_LIB.BASEBOARD_FAB2(SCH_1):M_L_MA(11)
  65 M_L_MA<12>    A12 @BASEBOARD_FAB2_LIB.BASEBOARD_FAB2(SCH_1):M_L_MA(12)
 232 M_L_MA<13>    A13 @BASEBOARD_FAB2_LIB.BASEBOARD_FAB2(SCH_1):M_L_MA(13)
 228 M_L_MA<14> A14_WE_N @BASEBOARD_FAB2_LIB.BASEBOARD_FAB2(SCH_1):M_L_MA(14)
  86 M_L_MA<15> A15_CAS_N @BASEBOARD_FAB2_LIB.BASEBOARD_FAB2(SCH_1):M_L_MA(15)
  82 M_L_MA<16> A16_RAS_N @BASEBOARD_FAB2_LIB.BASEBOARD_FAB2(SCH_1):M_L_MA(16)
 234 M_L_MA<17>    A17 @BASEBOARD_FAB2_LIB.BASEBOARD_FAB2(SCH_1):M_L_MA(17)
 216 M_L_MA<2>     A2 @BASEBOARD_FAB2_LIB.BASEBOARD_FAB2(SCH_1):M_L_MA(2)
  71 M_L_MA<3>     A3 @BASEBOARD_FAB2_LIB.BASEBOARD_FAB2(SCH_1):M_L_MA(3)
 214 M_L_MA<4>     A4 @BASEBOARD_FAB2_LIB.BASEBOARD_FAB2(SCH_1):M_L_MA(4)
 213 M_L_MA<5>     A5 @BASEBOARD_FAB2_LIB.BASEBOARD_FAB2(SCH_1):M_L_MA(5)
  69 M_L_MA<6>     A6 @BASEBOARD_FAB2_LIB.BASEBOARD_FAB2(SCH_1):M_L_MA(6)
 211 M_L_MA<7>     A7 @BASEBOARD_FAB2_LIB.BASEBOARD_FAB2(SCH_1):M_L_MA(7)
  68 M_L_MA<8>     A8 @BASEBOARD_FAB2_LIB.BASEBOARD_FAB2(SCH_1):M_L_MA(8)
  66 M_L_MA<9>     A9 @BASEBOARD_FAB2_LIB.BASEBOARD_FAB2(SCH_1):M_L_MA(9)
  62 M_L_ACT_N  ACT_N @BASEBOARD_FAB2_LIB.BASEBOARD_FAB2(SCH_1):M_L_ACT_N
 208 M_L_ALERT_N ALERT_N @BASEBOARD_FAB2_LIB.BASEBOARD_FAB2(SCH_1):M_L_ALERT_N
 224 M_L_BA<1>  BA<1> @BASEBOARD_FAB2_LIB.BASEBOARD_FAB2(SCH_1):M_L_BA(1)
  81 M_L_BA<0>  BA<0> @BASEBOARD_FAB2_LIB.BASEBOARD_FAB2(SCH_1):M_L_BA(0)
 207 M_L_BG<1>  BG<1> @BASEBOARD_FAB2_LIB.BASEBOARD_FAB2(SCH_1):M_L_BG(1)
  63 M_L_BG<0>  BG<0> @BASEBOARD_FAB2_LIB.BASEBOARD_FAB2(SCH_1):M_L_BG(0)
 235 M_L_C<2>   C<2> @BASEBOARD_FAB2_LIB.BASEBOARD_FAB2(SCH_1):M_L_C(2)
 199 M_L_ECC<6>  CB<7> @BASEBOARD_FAB2_LIB.BASEBOARD_FAB2(SCH_1):M_L_ECC(6)
  54 M_L_ECC<7>  CB<6> @BASEBOARD_FAB2_LIB.BASEBOARD_FAB2(SCH_1):M_L_ECC(7)
 192 M_L_ECC<4>  CB<5> @BASEBOARD_FAB2_LIB.BASEBOARD_FAB2(SCH_1):M_L_ECC(4)
  47 M_L_ECC<5>  CB<4> @BASEBOARD_FAB2_LIB.BASEBOARD_FAB2(SCH_1):M_L_ECC(5)
 201 M_L_ECC<2>  CB<3> @BASEBOARD_FAB2_LIB.BASEBOARD_FAB2(SCH_1):M_L_ECC(2)
  56 M_L_ECC<3>  CB<2> @BASEBOARD_FAB2_LIB.BASEBOARD_FAB2(SCH_1):M_L_ECC(3)
 194 M_L_ECC<0>  CB<1> @BASEBOARD_FAB2_LIB.BASEBOARD_FAB2(SCH_1):M_L_ECC(0)
  49 M_L_ECC<1>  CB<0> @BASEBOARD_FAB2_LIB.BASEBOARD_FAB2(SCH_1):M_L_ECC(1)
  75 M_L_CLK_DN<0>   CK0N @BASEBOARD_FAB2_LIB.BASEBOARD_FAB2(SCH_1):M_L_CLK_DN(0)
  74 M_L_CLK_DP<0>   CK0P @BASEBOARD_FAB2_LIB.BASEBOARD_FAB2(SCH_1):M_L_CLK_DP(0)
 219 M_L_CLK_DN<1>   CK1N @BASEBOARD_FAB2_LIB.BASEBOARD_FAB2(SCH_1):M_L_CLK_DN(1)
 218 M_L_CLK_DP<1>   CK1P @BASEBOARD_FAB2_LIB.BASEBOARD_FAB2(SCH_1):M_L_CLK_DP(1)
 203 M_L_CKE<1> CKE<1> @BASEBOARD_FAB2_LIB.BASEBOARD_FAB2(SCH_1):M_L_CKE(1)
  60 M_L_CKE<0> CKE<0> @BASEBOARD_FAB2_LIB.BASEBOARD_FAB2(SCH_1):M_L_CKE(0)
 280 M_L_DQ<62> DQ<63> @BASEBOARD_FAB2_LIB.BASEBOARD_FAB2(SCH_1):M_L_DQ(62)
 135 M_L_DQ<63> DQ<62> @BASEBOARD_FAB2_LIB.BASEBOARD_FAB2(SCH_1):M_L_DQ(63)
 273 M_L_DQ<60> DQ<61> @BASEBOARD_FAB2_LIB.BASEBOARD_FAB2(SCH_1):M_L_DQ(60)
 128 M_L_DQ<61> DQ<60> @BASEBOARD_FAB2_LIB.BASEBOARD_FAB2(SCH_1):M_L_DQ(61)
 282 M_L_DQ<58> DQ<59> @BASEBOARD_FAB2_LIB.BASEBOARD_FAB2(SCH_1):M_L_DQ(58)
 137 M_L_DQ<59> DQ<58> @BASEBOARD_FAB2_LIB.BASEBOARD_FAB2(SCH_1):M_L_DQ(59)
 275 M_L_DQ<56> DQ<57> @BASEBOARD_FAB2_LIB.BASEBOARD_FAB2(SCH_1):M_L_DQ(56)
 130 M_L_DQ<57> DQ<56> @BASEBOARD_FAB2_LIB.BASEBOARD_FAB2(SCH_1):M_L_DQ(57)
 269 M_L_DQ<54> DQ<55> @BASEBOARD_FAB2_LIB.BASEBOARD_FAB2(SCH_1):M_L_DQ(54)
 124 M_L_DQ<55> DQ<54> @BASEBOARD_FAB2_LIB.BASEBOARD_FAB2(SCH_1):M_L_DQ(55)
 262 M_L_DQ<52> DQ<53> @BASEBOARD_FAB2_LIB.BASEBOARD_FAB2(SCH_1):M_L_DQ(52)
 117 M_L_DQ<53> DQ<52> @BASEBOARD_FAB2_LIB.BASEBOARD_FAB2(SCH_1):M_L_DQ(53)
 271 M_L_DQ<50> DQ<51> @BASEBOARD_FAB2_LIB.BASEBOARD_FAB2(SCH_1):M_L_DQ(50)
 126 M_L_DQ<51> DQ<50> @BASEBOARD_FAB2_LIB.BASEBOARD_FAB2(SCH_1):M_L_DQ(51)
 264 M_L_DQ<48> DQ<49> @BASEBOARD_FAB2_LIB.BASEBOARD_FAB2(SCH_1):M_L_DQ(48)
 119 M_L_DQ<49> DQ<48> @BASEBOARD_FAB2_LIB.BASEBOARD_FAB2(SCH_1):M_L_DQ(49)
 258 M_L_DQ<46> DQ<47> @BASEBOARD_FAB2_LIB.BASEBOARD_FAB2(SCH_1):M_L_DQ(46)
 113 M_L_DQ<47> DQ<46> @BASEBOARD_FAB2_LIB.BASEBOARD_FAB2(SCH_1):M_L_DQ(47)
 251 M_L_DQ<44> DQ<45> @BASEBOARD_FAB2_LIB.BASEBOARD_FAB2(SCH_1):M_L_DQ(44)
 106 M_L_DQ<45> DQ<44> @BASEBOARD_FAB2_LIB.BASEBOARD_FAB2(SCH_1):M_L_DQ(45)
 260 M_L_DQ<42> DQ<43> @BASEBOARD_FAB2_LIB.BASEBOARD_FAB2(SCH_1):M_L_DQ(42)
 115 M_L_DQ<43> DQ<42> @BASEBOARD_FAB2_LIB.BASEBOARD_FAB2(SCH_1):M_L_DQ(43)
 253 M_L_DQ<40> DQ<41> @BASEBOARD_FAB2_LIB.BASEBOARD_FAB2(SCH_1):M_L_DQ(40)
 108 M_L_DQ<41> DQ<40> @BASEBOARD_FAB2_LIB.BASEBOARD_FAB2(SCH_1):M_L_DQ(41)
 247 M_L_DQ<38> DQ<39> @BASEBOARD_FAB2_LIB.BASEBOARD_FAB2(SCH_1):M_L_DQ(38)
 102 M_L_DQ<39> DQ<38> @BASEBOARD_FAB2_LIB.BASEBOARD_FAB2(SCH_1):M_L_DQ(39)
 240 M_L_DQ<36> DQ<37> @BASEBOARD_FAB2_LIB.BASEBOARD_FAB2(SCH_1):M_L_DQ(36)
  95 M_L_DQ<37> DQ<36> @BASEBOARD_FAB2_LIB.BASEBOARD_FAB2(SCH_1):M_L_DQ(37)
 249 M_L_DQ<34> DQ<35> @BASEBOARD_FAB2_LIB.BASEBOARD_FAB2(SCH_1):M_L_DQ(34)
 104 M_L_DQ<35> DQ<34> @BASEBOARD_FAB2_LIB.BASEBOARD_FAB2(SCH_1):M_L_DQ(35)
 242 M_L_DQ<32> DQ<33> @BASEBOARD_FAB2_LIB.BASEBOARD_FAB2(SCH_1):M_L_DQ(32)
  97 M_L_DQ<33> DQ<32> @BASEBOARD_FAB2_LIB.BASEBOARD_FAB2(SCH_1):M_L_DQ(33)
 188 M_L_DQ<30> DQ<31> @BASEBOARD_FAB2_LIB.BASEBOARD_FAB2(SCH_1):M_L_DQ(30)
  43 M_L_DQ<31> DQ<30> @BASEBOARD_FAB2_LIB.BASEBOARD_FAB2(SCH_1):M_L_DQ(31)
 181 M_L_DQ<28> DQ<29> @BASEBOARD_FAB2_LIB.BASEBOARD_FAB2(SCH_1):M_L_DQ(28)
  36 M_L_DQ<29> DQ<28> @BASEBOARD_FAB2_LIB.BASEBOARD_FAB2(SCH_1):M_L_DQ(29)
 190 M_L_DQ<26> DQ<27> @BASEBOARD_FAB2_LIB.BASEBOARD_FAB2(SCH_1):M_L_DQ(26)
  45 M_L_DQ<27> DQ<26> @BASEBOARD_FAB2_LIB.BASEBOARD_FAB2(SCH_1):M_L_DQ(27)
 183 M_L_DQ<24> DQ<25> @BASEBOARD_FAB2_LIB.BASEBOARD_FAB2(SCH_1):M_L_DQ(24)
  38 M_L_DQ<25> DQ<24> @BASEBOARD_FAB2_LIB.BASEBOARD_FAB2(SCH_1):M_L_DQ(25)
 177 M_L_DQ<22> DQ<23> @BASEBOARD_FAB2_LIB.BASEBOARD_FAB2(SCH_1):M_L_DQ(22)
  32 M_L_DQ<23> DQ<22> @BASEBOARD_FAB2_LIB.BASEBOARD_FAB2(SCH_1):M_L_DQ(23)
 170 M_L_DQ<20> DQ<21> @BASEBOARD_FAB2_LIB.BASEBOARD_FAB2(SCH_1):M_L_DQ(20)
  25 M_L_DQ<21> DQ<20> @BASEBOARD_FAB2_LIB.BASEBOARD_FAB2(SCH_1):M_L_DQ(21)
 179 M_L_DQ<18> DQ<19> @BASEBOARD_FAB2_LIB.BASEBOARD_FAB2(SCH_1):M_L_DQ(18)
  34 M_L_DQ<19> DQ<18> @BASEBOARD_FAB2_LIB.BASEBOARD_FAB2(SCH_1):M_L_DQ(19)
 172 M_L_DQ<16> DQ<17> @BASEBOARD_FAB2_LIB.BASEBOARD_FAB2(SCH_1):M_L_DQ(16)
  27 M_L_DQ<17> DQ<16> @BASEBOARD_FAB2_LIB.BASEBOARD_FAB2(SCH_1):M_L_DQ(17)
 166 M_L_DQ<14> DQ<15> @BASEBOARD_FAB2_LIB.BASEBOARD_FAB2(SCH_1):M_L_DQ(14)
  21 M_L_DQ<15> DQ<14> @BASEBOARD_FAB2_LIB.BASEBOARD_FAB2(SCH_1):M_L_DQ(15)
 159 M_L_DQ<12> DQ<13> @BASEBOARD_FAB2_LIB.BASEBOARD_FAB2(SCH_1):M_L_DQ(12)
  14 M_L_DQ<13> DQ<12> @BASEBOARD_FAB2_LIB.BASEBOARD_FAB2(SCH_1):M_L_DQ(13)
 168 M_L_DQ<10> DQ<11> @BASEBOARD_FAB2_LIB.BASEBOARD_FAB2(SCH_1):M_L_DQ(10)
  23 M_L_DQ<11> DQ<10> @BASEBOARD_FAB2_LIB.BASEBOARD_FAB2(SCH_1):M_L_DQ(11)
 161 M_L_DQ<8>  DQ<9> @BASEBOARD_FAB2_LIB.BASEBOARD_FAB2(SCH_1):M_L_DQ(8)
  16 M_L_DQ<9>  DQ<8> @BASEBOARD_FAB2_LIB.BASEBOARD_FAB2(SCH_1):M_L_DQ(9)
 155 M_L_DQ<6>  DQ<7> @BASEBOARD_FAB2_LIB.BASEBOARD_FAB2(SCH_1):M_L_DQ(6)
  10 M_L_DQ<7>  DQ<6> @BASEBOARD_FAB2_LIB.BASEBOARD_FAB2(SCH_1):M_L_DQ(7)
 148 M_L_DQ<4>  DQ<5> @BASEBOARD_FAB2_LIB.BASEBOARD_FAB2(SCH_1):M_L_DQ(4)
   3 M_L_DQ<5>  DQ<4> @BASEBOARD_FAB2_LIB.BASEBOARD_FAB2(SCH_1):M_L_DQ(5)
 157 M_L_DQ<2>  DQ<3> @BASEBOARD_FAB2_LIB.BASEBOARD_FAB2(SCH_1):M_L_DQ(2)
  12 M_L_DQ<3>  DQ<2> @BASEBOARD_FAB2_LIB.BASEBOARD_FAB2(SCH_1):M_L_DQ(3)
 150 M_L_DQ<0>  DQ<1> @BASEBOARD_FAB2_LIB.BASEBOARD_FAB2(SCH_1):M_L_DQ(0)
   5 M_L_DQ<1>  DQ<0> @BASEBOARD_FAB2_LIB.BASEBOARD_FAB2(SCH_1):M_L_DQ(1)
  78 FM_DIMM_EVENT_COD_N EVENT_N @BASEBOARD_FAB2_LIB.BASEBOARD_FAB2(SCH_1):FM_DIMM_EVENT_COD_N
  91 M_L_ODT<1> ODT<1> @BASEBOARD_FAB2_LIB.BASEBOARD_FAB2(SCH_1):M_L_ODT(1)
  87 M_L_ODT<0> ODT<0> @BASEBOARD_FAB2_LIB.BASEBOARD_FAB2(SCH_1):M_L_ODT(0)
 222 M_L_PAR    PAR @BASEBOARD_FAB2_LIB.BASEBOARD_FAB2(SCH_1):M_L_PAR
  58 M_KLM_RST_N RESET_N @BASEBOARD_FAB2_LIB.BASEBOARD_FAB2(SCH_1):M_KLM_RST_N
 144 TP_CH_L_DIMM_L0_RFU_2 RFU<2> @BASEBOARD_FAB2_LIB.BASEBOARD_FAB2(SCH_1):TP_CH_L_DIMM_L0_RFU_2
 227 TP_CH_L_DIMM_L0_RFU_1 RFU<1> @BASEBOARD_FAB2_LIB.BASEBOARD_FAB2(SCH_1):TP_CH_L_DIMM_L0_RFU_1
 205 TP_CH_L_DIMM_L0_RFU_0 RFU<0> @BASEBOARD_FAB2_LIB.BASEBOARD_FAB2(SCH_1):TP_CH_L_DIMM_L0_RFU_0
  84 M_L_CS_N<0>   S0_N @BASEBOARD_FAB2_LIB.BASEBOARD_FAB2(SCH_1):M_L_CS_N(0)
  89 M_L_CS_N<1>   S1_N @BASEBOARD_FAB2_LIB.BASEBOARD_FAB2(SCH_1):M_L_CS_N(1)
  93 M_L_CS_N<2> S2_N_C<0> @BASEBOARD_FAB2_LIB.BASEBOARD_FAB2(SCH_1):M_L_CS_N(2)
 237 M_L_CS_N<3> S3_N_C<1> @BASEBOARD_FAB2_LIB.BASEBOARD_FAB2(SCH_1):M_L_CS_N(3)
 238    GND  SA<2> @BASEBOARD_FAB2_LIB.BASEBOARD_FAB2(SCH_1):GND
 140 PVPP_KLM  SA<1> @BASEBOARD_FAB2_LIB.BASEBOARD_FAB2(SCH_1):PVPP_KLM
 139    GND  SA<0> @BASEBOARD_FAB2_LIB.BASEBOARD_FAB2(SCH_1):GND
 230 FM_ADR_COMPLETE_KLM_N SAVE_N_NC @BASEBOARD_FAB2_LIB.BASEBOARD_FAB2(SCH_1):FM_ADR_COMPLETE_KLM_N
 141 SMB_DDR_KLM_VPP_SCL    SCL @BASEBOARD_FAB2_LIB.BASEBOARD_FAB2(SCH_1):SMB_DDR_KLM_VPP_SCL
 285 SMB_DDR_KLM_VPP_SDA    SDA @BASEBOARD_FAB2_LIB.BASEBOARD_FAB2(SCH_1):SMB_DDR_KLM_VPP_SDA
 284 PVPP_KLM VDDSPD @BASEBOARD_FAB2_LIB.BASEBOARD_FAB2(SCH_1):PVPP_KLM
 146 M_L_VREF VREFCA @BASEBOARD_FAB2_LIB.BASEBOARD_FAB2(SCH_1):M_L_VREF

SCONN288_H44441004_PIP-SCONN,HA  I172  J1A2
   1 P12V_NVDIMM_KLM 12V<1> @BASEBOARD_FAB2_LIB.BASEBOARD_FAB2(SCH_1):P12V_NVDIMM_KLM
 145 P12V_NVDIMM_KLM 12V<0> @BASEBOARD_FAB2_LIB.BASEBOARD_FAB2(SCH_1):P12V_NVDIMM_KLM
  59 PVDDQ_KLM VDD<25> @BASEBOARD_FAB2_LIB.BASEBOARD_FAB2(SCH_1):PVDDQ_KLM
  61 PVDDQ_KLM VDD<24> @BASEBOARD_FAB2_LIB.BASEBOARD_FAB2(SCH_1):PVDDQ_KLM
  64 PVDDQ_KLM VDD<23> @BASEBOARD_FAB2_LIB.BASEBOARD_FAB2(SCH_1):PVDDQ_KLM
  67 PVDDQ_KLM VDD<22> @BASEBOARD_FAB2_LIB.BASEBOARD_FAB2(SCH_1):PVDDQ_KLM
  70 PVDDQ_KLM VDD<21> @BASEBOARD_FAB2_LIB.BASEBOARD_FAB2(SCH_1):PVDDQ_KLM
  73 PVDDQ_KLM VDD<20> @BASEBOARD_FAB2_LIB.BASEBOARD_FAB2(SCH_1):PVDDQ_KLM
  76 PVDDQ_KLM VDD<19> @BASEBOARD_FAB2_LIB.BASEBOARD_FAB2(SCH_1):PVDDQ_KLM
  80 PVDDQ_KLM VDD<18> @BASEBOARD_FAB2_LIB.BASEBOARD_FAB2(SCH_1):PVDDQ_KLM
  83 PVDDQ_KLM VDD<17> @BASEBOARD_FAB2_LIB.BASEBOARD_FAB2(SCH_1):PVDDQ_KLM
  85 PVDDQ_KLM VDD<16> @BASEBOARD_FAB2_LIB.BASEBOARD_FAB2(SCH_1):PVDDQ_KLM
  88 PVDDQ_KLM VDD<15> @BASEBOARD_FAB2_LIB.BASEBOARD_FAB2(SCH_1):PVDDQ_KLM
  90 PVDDQ_KLM VDD<14> @BASEBOARD_FAB2_LIB.BASEBOARD_FAB2(SCH_1):PVDDQ_KLM
  92 PVDDQ_KLM VDD<13> @BASEBOARD_FAB2_LIB.BASEBOARD_FAB2(SCH_1):PVDDQ_KLM
 204 PVDDQ_KLM VDD<12> @BASEBOARD_FAB2_LIB.BASEBOARD_FAB2(SCH_1):PVDDQ_KLM
 206 PVDDQ_KLM VDD<11> @BASEBOARD_FAB2_LIB.BASEBOARD_FAB2(SCH_1):PVDDQ_KLM
 209 PVDDQ_KLM VDD<10> @BASEBOARD_FAB2_LIB.BASEBOARD_FAB2(SCH_1):PVDDQ_KLM
 212 PVDDQ_KLM VDD<9> @BASEBOARD_FAB2_LIB.BASEBOARD_FAB2(SCH_1):PVDDQ_KLM
 215 PVDDQ_KLM VDD<8> @BASEBOARD_FAB2_LIB.BASEBOARD_FAB2(SCH_1):PVDDQ_KLM
 217 PVDDQ_KLM VDD<7> @BASEBOARD_FAB2_LIB.BASEBOARD_FAB2(SCH_1):PVDDQ_KLM
 220 PVDDQ_KLM VDD<6> @BASEBOARD_FAB2_LIB.BASEBOARD_FAB2(SCH_1):PVDDQ_KLM
 223 PVDDQ_KLM VDD<5> @BASEBOARD_FAB2_LIB.BASEBOARD_FAB2(SCH_1):PVDDQ_KLM
 226 PVDDQ_KLM VDD<4> @BASEBOARD_FAB2_LIB.BASEBOARD_FAB2(SCH_1):PVDDQ_KLM
 229 PVDDQ_KLM VDD<3> @BASEBOARD_FAB2_LIB.BASEBOARD_FAB2(SCH_1):PVDDQ_KLM
 231 PVDDQ_KLM VDD<2> @BASEBOARD_FAB2_LIB.BASEBOARD_FAB2(SCH_1):PVDDQ_KLM
 233 PVDDQ_KLM VDD<1> @BASEBOARD_FAB2_LIB.BASEBOARD_FAB2(SCH_1):PVDDQ_KLM
 236 PVDDQ_KLM VDD<0> @BASEBOARD_FAB2_LIB.BASEBOARD_FAB2(SCH_1):PVDDQ_KLM
 142 PVPP_KLM VPP<4> @BASEBOARD_FAB2_LIB.BASEBOARD_FAB2(SCH_1):PVPP_KLM
 143 PVPP_KLM VPP<3> @BASEBOARD_FAB2_LIB.BASEBOARD_FAB2(SCH_1):PVPP_KLM
 288 PVPP_KLM VPP<2> @BASEBOARD_FAB2_LIB.BASEBOARD_FAB2(SCH_1):PVPP_KLM
 286 PVPP_KLM VPP<1> @BASEBOARD_FAB2_LIB.BASEBOARD_FAB2(SCH_1):PVPP_KLM
 287 PVPP_KLM VPP<0> @BASEBOARD_FAB2_LIB.BASEBOARD_FAB2(SCH_1):PVPP_KLM
  77 PVTT_KLM VTT<1> @BASEBOARD_FAB2_LIB.BASEBOARD_FAB2(SCH_1):PVTT_KLM
 221 PVTT_KLM VTT<0> @BASEBOARD_FAB2_LIB.BASEBOARD_FAB2(SCH_1):PVTT_KLM

CAP_A_0402V-0.01UF,25V,10%,X7RA  I181  C9L7
   1 M_L_VREF      A @BASEBOARD_FAB2_LIB.BASEBOARD_FAB2(SCH_1):M_L_VREF
   2    GND      B @BASEBOARD_FAB2_LIB.BASEBOARD_FAB2(SCH_1):GND


DRAWING: @BASEBOARD_FAB2_LIB.BASEBOARD_FAB2(SCH_1):PAGE86 

SCONN288_H44441003_PIP-SCONN,HA  I12  J9L2
  79 M_L_MA<0>     A0 @BASEBOARD_FAB2_LIB.BASEBOARD_FAB2(SCH_1):M_L_MA(0)
  72 M_L_MA<1>     A1 @BASEBOARD_FAB2_LIB.BASEBOARD_FAB2(SCH_1):M_L_MA(1)
 225 M_L_MA<10>    A10 @BASEBOARD_FAB2_LIB.BASEBOARD_FAB2(SCH_1):M_L_MA(10)
 210 M_L_MA<11>    A11 @BASEBOARD_FAB2_LIB.BASEBOARD_FAB2(SCH_1):M_L_MA(11)
  65 M_L_MA<12>    A12 @BASEBOARD_FAB2_LIB.BASEBOARD_FAB2(SCH_1):M_L_MA(12)
 232 M_L_MA<13>    A13 @BASEBOARD_FAB2_LIB.BASEBOARD_FAB2(SCH_1):M_L_MA(13)
 228 M_L_MA<14> A14_WE_N @BASEBOARD_FAB2_LIB.BASEBOARD_FAB2(SCH_1):M_L_MA(14)
  86 M_L_MA<15> A15_CAS_N @BASEBOARD_FAB2_LIB.BASEBOARD_FAB2(SCH_1):M_L_MA(15)
  82 M_L_MA<16> A16_RAS_N @BASEBOARD_FAB2_LIB.BASEBOARD_FAB2(SCH_1):M_L_MA(16)
 234 M_L_MA<17>    A17 @BASEBOARD_FAB2_LIB.BASEBOARD_FAB2(SCH_1):M_L_MA(17)
 216 M_L_MA<2>     A2 @BASEBOARD_FAB2_LIB.BASEBOARD_FAB2(SCH_1):M_L_MA(2)
  71 M_L_MA<3>     A3 @BASEBOARD_FAB2_LIB.BASEBOARD_FAB2(SCH_1):M_L_MA(3)
 214 M_L_MA<4>     A4 @BASEBOARD_FAB2_LIB.BASEBOARD_FAB2(SCH_1):M_L_MA(4)
 213 M_L_MA<5>     A5 @BASEBOARD_FAB2_LIB.BASEBOARD_FAB2(SCH_1):M_L_MA(5)
  69 M_L_MA<6>     A6 @BASEBOARD_FAB2_LIB.BASEBOARD_FAB2(SCH_1):M_L_MA(6)
 211 M_L_MA<7>     A7 @BASEBOARD_FAB2_LIB.BASEBOARD_FAB2(SCH_1):M_L_MA(7)
  68 M_L_MA<8>     A8 @BASEBOARD_FAB2_LIB.BASEBOARD_FAB2(SCH_1):M_L_MA(8)
  66 M_L_MA<9>     A9 @BASEBOARD_FAB2_LIB.BASEBOARD_FAB2(SCH_1):M_L_MA(9)
  62 M_L_ACT_N  ACT_N @BASEBOARD_FAB2_LIB.BASEBOARD_FAB2(SCH_1):M_L_ACT_N
 208 M_L_ALERT_N ALERT_N @BASEBOARD_FAB2_LIB.BASEBOARD_FAB2(SCH_1):M_L_ALERT_N
 224 M_L_BA<1>  BA<1> @BASEBOARD_FAB2_LIB.BASEBOARD_FAB2(SCH_1):M_L_BA(1)
  81 M_L_BA<0>  BA<0> @BASEBOARD_FAB2_LIB.BASEBOARD_FAB2(SCH_1):M_L_BA(0)
 207 M_L_BG<1>  BG<1> @BASEBOARD_FAB2_LIB.BASEBOARD_FAB2(SCH_1):M_L_BG(1)
  63 M_L_BG<0>  BG<0> @BASEBOARD_FAB2_LIB.BASEBOARD_FAB2(SCH_1):M_L_BG(0)
 235 M_L_C<2>   C<2> @BASEBOARD_FAB2_LIB.BASEBOARD_FAB2(SCH_1):M_L_C(2)
 199 M_L_ECC<7>  CB<7> @BASEBOARD_FAB2_LIB.BASEBOARD_FAB2(SCH_1):M_L_ECC(7)
  54 M_L_ECC<6>  CB<6> @BASEBOARD_FAB2_LIB.BASEBOARD_FAB2(SCH_1):M_L_ECC(6)
 192 M_L_ECC<5>  CB<5> @BASEBOARD_FAB2_LIB.BASEBOARD_FAB2(SCH_1):M_L_ECC(5)
  47 M_L_ECC<4>  CB<4> @BASEBOARD_FAB2_LIB.BASEBOARD_FAB2(SCH_1):M_L_ECC(4)
 201 M_L_ECC<3>  CB<3> @BASEBOARD_FAB2_LIB.BASEBOARD_FAB2(SCH_1):M_L_ECC(3)
  56 M_L_ECC<2>  CB<2> @BASEBOARD_FAB2_LIB.BASEBOARD_FAB2(SCH_1):M_L_ECC(2)
 194 M_L_ECC<1>  CB<1> @BASEBOARD_FAB2_LIB.BASEBOARD_FAB2(SCH_1):M_L_ECC(1)
  49 M_L_ECC<0>  CB<0> @BASEBOARD_FAB2_LIB.BASEBOARD_FAB2(SCH_1):M_L_ECC(0)
  75 M_L_CLK_DN<2>   CK0N @BASEBOARD_FAB2_LIB.BASEBOARD_FAB2(SCH_1):M_L_CLK_DN(2)
  74 M_L_CLK_DP<2>   CK0P @BASEBOARD_FAB2_LIB.BASEBOARD_FAB2(SCH_1):M_L_CLK_DP(2)
 219 M_L_CLK_DN<3>   CK1N @BASEBOARD_FAB2_LIB.BASEBOARD_FAB2(SCH_1):M_L_CLK_DN(3)
 218 M_L_CLK_DP<3>   CK1P @BASEBOARD_FAB2_LIB.BASEBOARD_FAB2(SCH_1):M_L_CLK_DP(3)
 203 M_L_CKE<3> CKE<1> @BASEBOARD_FAB2_LIB.BASEBOARD_FAB2(SCH_1):M_L_CKE(3)
  60 M_L_CKE<2> CKE<0> @BASEBOARD_FAB2_LIB.BASEBOARD_FAB2(SCH_1):M_L_CKE(2)
 280 M_L_DQ<63> DQ<63> @BASEBOARD_FAB2_LIB.BASEBOARD_FAB2(SCH_1):M_L_DQ(63)
 135 M_L_DQ<62> DQ<62> @BASEBOARD_FAB2_LIB.BASEBOARD_FAB2(SCH_1):M_L_DQ(62)
 273 M_L_DQ<61> DQ<61> @BASEBOARD_FAB2_LIB.BASEBOARD_FAB2(SCH_1):M_L_DQ(61)
 128 M_L_DQ<60> DQ<60> @BASEBOARD_FAB2_LIB.BASEBOARD_FAB2(SCH_1):M_L_DQ(60)
 282 M_L_DQ<59> DQ<59> @BASEBOARD_FAB2_LIB.BASEBOARD_FAB2(SCH_1):M_L_DQ(59)
 137 M_L_DQ<58> DQ<58> @BASEBOARD_FAB2_LIB.BASEBOARD_FAB2(SCH_1):M_L_DQ(58)
 275 M_L_DQ<57> DQ<57> @BASEBOARD_FAB2_LIB.BASEBOARD_FAB2(SCH_1):M_L_DQ(57)
 130 M_L_DQ<56> DQ<56> @BASEBOARD_FAB2_LIB.BASEBOARD_FAB2(SCH_1):M_L_DQ(56)
 269 M_L_DQ<55> DQ<55> @BASEBOARD_FAB2_LIB.BASEBOARD_FAB2(SCH_1):M_L_DQ(55)
 124 M_L_DQ<54> DQ<54> @BASEBOARD_FAB2_LIB.BASEBOARD_FAB2(SCH_1):M_L_DQ(54)
 262 M_L_DQ<53> DQ<53> @BASEBOARD_FAB2_LIB.BASEBOARD_FAB2(SCH_1):M_L_DQ(53)
 117 M_L_DQ<52> DQ<52> @BASEBOARD_FAB2_LIB.BASEBOARD_FAB2(SCH_1):M_L_DQ(52)
 271 M_L_DQ<51> DQ<51> @BASEBOARD_FAB2_LIB.BASEBOARD_FAB2(SCH_1):M_L_DQ(51)
 126 M_L_DQ<50> DQ<50> @BASEBOARD_FAB2_LIB.BASEBOARD_FAB2(SCH_1):M_L_DQ(50)
 264 M_L_DQ<49> DQ<49> @BASEBOARD_FAB2_LIB.BASEBOARD_FAB2(SCH_1):M_L_DQ(49)
 119 M_L_DQ<48> DQ<48> @BASEBOARD_FAB2_LIB.BASEBOARD_FAB2(SCH_1):M_L_DQ(48)
 258 M_L_DQ<47> DQ<47> @BASEBOARD_FAB2_LIB.BASEBOARD_FAB2(SCH_1):M_L_DQ(47)
 113 M_L_DQ<46> DQ<46> @BASEBOARD_FAB2_LIB.BASEBOARD_FAB2(SCH_1):M_L_DQ(46)
 251 M_L_DQ<45> DQ<45> @BASEBOARD_FAB2_LIB.BASEBOARD_FAB2(SCH_1):M_L_DQ(45)
 106 M_L_DQ<44> DQ<44> @BASEBOARD_FAB2_LIB.BASEBOARD_FAB2(SCH_1):M_L_DQ(44)
 260 M_L_DQ<43> DQ<43> @BASEBOARD_FAB2_LIB.BASEBOARD_FAB2(SCH_1):M_L_DQ(43)
 115 M_L_DQ<42> DQ<42> @BASEBOARD_FAB2_LIB.BASEBOARD_FAB2(SCH_1):M_L_DQ(42)
 253 M_L_DQ<41> DQ<41> @BASEBOARD_FAB2_LIB.BASEBOARD_FAB2(SCH_1):M_L_DQ(41)
 108 M_L_DQ<40> DQ<40> @BASEBOARD_FAB2_LIB.BASEBOARD_FAB2(SCH_1):M_L_DQ(40)
 247 M_L_DQ<39> DQ<39> @BASEBOARD_FAB2_LIB.BASEBOARD_FAB2(SCH_1):M_L_DQ(39)
 102 M_L_DQ<38> DQ<38> @BASEBOARD_FAB2_LIB.BASEBOARD_FAB2(SCH_1):M_L_DQ(38)
 240 M_L_DQ<37> DQ<37> @BASEBOARD_FAB2_LIB.BASEBOARD_FAB2(SCH_1):M_L_DQ(37)
  95 M_L_DQ<36> DQ<36> @BASEBOARD_FAB2_LIB.BASEBOARD_FAB2(SCH_1):M_L_DQ(36)
 249 M_L_DQ<35> DQ<35> @BASEBOARD_FAB2_LIB.BASEBOARD_FAB2(SCH_1):M_L_DQ(35)
 104 M_L_DQ<34> DQ<34> @BASEBOARD_FAB2_LIB.BASEBOARD_FAB2(SCH_1):M_L_DQ(34)
 242 M_L_DQ<33> DQ<33> @BASEBOARD_FAB2_LIB.BASEBOARD_FAB2(SCH_1):M_L_DQ(33)
  97 M_L_DQ<32> DQ<32> @BASEBOARD_FAB2_LIB.BASEBOARD_FAB2(SCH_1):M_L_DQ(32)
 188 M_L_DQ<31> DQ<31> @BASEBOARD_FAB2_LIB.BASEBOARD_FAB2(SCH_1):M_L_DQ(31)
  43 M_L_DQ<30> DQ<30> @BASEBOARD_FAB2_LIB.BASEBOARD_FAB2(SCH_1):M_L_DQ(30)
 181 M_L_DQ<29> DQ<29> @BASEBOARD_FAB2_LIB.BASEBOARD_FAB2(SCH_1):M_L_DQ(29)
  36 M_L_DQ<28> DQ<28> @BASEBOARD_FAB2_LIB.BASEBOARD_FAB2(SCH_1):M_L_DQ(28)
 190 M_L_DQ<27> DQ<27> @BASEBOARD_FAB2_LIB.BASEBOARD_FAB2(SCH_1):M_L_DQ(27)
  45 M_L_DQ<26> DQ<26> @BASEBOARD_FAB2_LIB.BASEBOARD_FAB2(SCH_1):M_L_DQ(26)
 183 M_L_DQ<25> DQ<25> @BASEBOARD_FAB2_LIB.BASEBOARD_FAB2(SCH_1):M_L_DQ(25)
  38 M_L_DQ<24> DQ<24> @BASEBOARD_FAB2_LIB.BASEBOARD_FAB2(SCH_1):M_L_DQ(24)
 177 M_L_DQ<23> DQ<23> @BASEBOARD_FAB2_LIB.BASEBOARD_FAB2(SCH_1):M_L_DQ(23)
  32 M_L_DQ<22> DQ<22> @BASEBOARD_FAB2_LIB.BASEBOARD_FAB2(SCH_1):M_L_DQ(22)
 170 M_L_DQ<21> DQ<21> @BASEBOARD_FAB2_LIB.BASEBOARD_FAB2(SCH_1):M_L_DQ(21)
  25 M_L_DQ<20> DQ<20> @BASEBOARD_FAB2_LIB.BASEBOARD_FAB2(SCH_1):M_L_DQ(20)
 179 M_L_DQ<19> DQ<19> @BASEBOARD_FAB2_LIB.BASEBOARD_FAB2(SCH_1):M_L_DQ(19)
  34 M_L_DQ<18> DQ<18> @BASEBOARD_FAB2_LIB.BASEBOARD_FAB2(SCH_1):M_L_DQ(18)
 172 M_L_DQ<17> DQ<17> @BASEBOARD_FAB2_LIB.BASEBOARD_FAB2(SCH_1):M_L_DQ(17)
  27 M_L_DQ<16> DQ<16> @BASEBOARD_FAB2_LIB.BASEBOARD_FAB2(SCH_1):M_L_DQ(16)
 166 M_L_DQ<15> DQ<15> @BASEBOARD_FAB2_LIB.BASEBOARD_FAB2(SCH_1):M_L_DQ(15)
  21 M_L_DQ<14> DQ<14> @BASEBOARD_FAB2_LIB.BASEBOARD_FAB2(SCH_1):M_L_DQ(14)
 159 M_L_DQ<13> DQ<13> @BASEBOARD_FAB2_LIB.BASEBOARD_FAB2(SCH_1):M_L_DQ(13)
  14 M_L_DQ<12> DQ<12> @BASEBOARD_FAB2_LIB.BASEBOARD_FAB2(SCH_1):M_L_DQ(12)
 168 M_L_DQ<11> DQ<11> @BASEBOARD_FAB2_LIB.BASEBOARD_FAB2(SCH_1):M_L_DQ(11)
  23 M_L_DQ<10> DQ<10> @BASEBOARD_FAB2_LIB.BASEBOARD_FAB2(SCH_1):M_L_DQ(10)
 161 M_L_DQ<9>  DQ<9> @BASEBOARD_FAB2_LIB.BASEBOARD_FAB2(SCH_1):M_L_DQ(9)
  16 M_L_DQ<8>  DQ<8> @BASEBOARD_FAB2_LIB.BASEBOARD_FAB2(SCH_1):M_L_DQ(8)
 155 M_L_DQ<7>  DQ<7> @BASEBOARD_FAB2_LIB.BASEBOARD_FAB2(SCH_1):M_L_DQ(7)
  10 M_L_DQ<6>  DQ<6> @BASEBOARD_FAB2_LIB.BASEBOARD_FAB2(SCH_1):M_L_DQ(6)
 148 M_L_DQ<5>  DQ<5> @BASEBOARD_FAB2_LIB.BASEBOARD_FAB2(SCH_1):M_L_DQ(5)
   3 M_L_DQ<4>  DQ<4> @BASEBOARD_FAB2_LIB.BASEBOARD_FAB2(SCH_1):M_L_DQ(4)
 157 M_L_DQ<3>  DQ<3> @BASEBOARD_FAB2_LIB.BASEBOARD_FAB2(SCH_1):M_L_DQ(3)
  12 M_L_DQ<2>  DQ<2> @BASEBOARD_FAB2_LIB.BASEBOARD_FAB2(SCH_1):M_L_DQ(2)
 150 M_L_DQ<1>  DQ<1> @BASEBOARD_FAB2_LIB.BASEBOARD_FAB2(SCH_1):M_L_DQ(1)
   5 M_L_DQ<0>  DQ<0> @BASEBOARD_FAB2_LIB.BASEBOARD_FAB2(SCH_1):M_L_DQ(0)
  78 FM_DIMM_EVENT_COD_N EVENT_N @BASEBOARD_FAB2_LIB.BASEBOARD_FAB2(SCH_1):FM_DIMM_EVENT_COD_N
  91 M_L_ODT<3> ODT<1> @BASEBOARD_FAB2_LIB.BASEBOARD_FAB2(SCH_1):M_L_ODT(3)
  87 M_L_ODT<2> ODT<0> @BASEBOARD_FAB2_LIB.BASEBOARD_FAB2(SCH_1):M_L_ODT(2)
 222 M_L_PAR    PAR @BASEBOARD_FAB2_LIB.BASEBOARD_FAB2(SCH_1):M_L_PAR
  58 M_KLM_RST_N RESET_N @BASEBOARD_FAB2_LIB.BASEBOARD_FAB2(SCH_1):M_KLM_RST_N
 144 TP_CH_L_DIMM0_RFU_2 RFU<2> @BASEBOARD_FAB2_LIB.BASEBOARD_FAB2(SCH_1):TP_CH_L_DIMM0_RFU_2
 227 TP_CH_L_DIMM0_RFU_1 RFU<1> @BASEBOARD_FAB2_LIB.BASEBOARD_FAB2(SCH_1):TP_CH_L_DIMM0_RFU_1
 205 TP_CH_L_DIMM0_RFU_0 RFU<0> @BASEBOARD_FAB2_LIB.BASEBOARD_FAB2(SCH_1):TP_CH_L_DIMM0_RFU_0
  84 M_L_CS_N<4>   S0_N @BASEBOARD_FAB2_LIB.BASEBOARD_FAB2(SCH_1):M_L_CS_N(4)
  89 M_L_CS_N<5>   S1_N @BASEBOARD_FAB2_LIB.BASEBOARD_FAB2(SCH_1):M_L_CS_N(5)
  93 M_L_CS_N<6> S2_N_C<0> @BASEBOARD_FAB2_LIB.BASEBOARD_FAB2(SCH_1):M_L_CS_N(6)
 237 M_L_CS_N<7> S3_N_C<1> @BASEBOARD_FAB2_LIB.BASEBOARD_FAB2(SCH_1):M_L_CS_N(7)
 238    GND  SA<2> @BASEBOARD_FAB2_LIB.BASEBOARD_FAB2(SCH_1):GND
 140 PVPP_KLM  SA<1> @BASEBOARD_FAB2_LIB.BASEBOARD_FAB2(SCH_1):PVPP_KLM
 139 PVPP_KLM  SA<0> @BASEBOARD_FAB2_LIB.BASEBOARD_FAB2(SCH_1):PVPP_KLM
 230 FM_ADR_COMPLETE_KLM_N SAVE_N_NC @BASEBOARD_FAB2_LIB.BASEBOARD_FAB2(SCH_1):FM_ADR_COMPLETE_KLM_N
 141 SMB_DDR_KLM_VPP_SCL    SCL @BASEBOARD_FAB2_LIB.BASEBOARD_FAB2(SCH_1):SMB_DDR_KLM_VPP_SCL
 285 SMB_DDR_KLM_VPP_SDA    SDA @BASEBOARD_FAB2_LIB.BASEBOARD_FAB2(SCH_1):SMB_DDR_KLM_VPP_SDA
 284 PVPP_KLM VDDSPD @BASEBOARD_FAB2_LIB.BASEBOARD_FAB2(SCH_1):PVPP_KLM
 146 M_L_VREF VREFCA @BASEBOARD_FAB2_LIB.BASEBOARD_FAB2(SCH_1):M_L_VREF

SCONN288_H44441003_PIP-SCONN,HA  I55  J9L2
   1 P12V_NVDIMM_KLM 12V<1> @BASEBOARD_FAB2_LIB.BASEBOARD_FAB2(SCH_1):P12V_NVDIMM_KLM
 145 P12V_NVDIMM_KLM 12V<0> @BASEBOARD_FAB2_LIB.BASEBOARD_FAB2(SCH_1):P12V_NVDIMM_KLM
  59 PVDDQ_KLM VDD<25> @BASEBOARD_FAB2_LIB.BASEBOARD_FAB2(SCH_1):PVDDQ_KLM
  61 PVDDQ_KLM VDD<24> @BASEBOARD_FAB2_LIB.BASEBOARD_FAB2(SCH_1):PVDDQ_KLM
  64 PVDDQ_KLM VDD<23> @BASEBOARD_FAB2_LIB.BASEBOARD_FAB2(SCH_1):PVDDQ_KLM
  67 PVDDQ_KLM VDD<22> @BASEBOARD_FAB2_LIB.BASEBOARD_FAB2(SCH_1):PVDDQ_KLM
  70 PVDDQ_KLM VDD<21> @BASEBOARD_FAB2_LIB.BASEBOARD_FAB2(SCH_1):PVDDQ_KLM
  73 PVDDQ_KLM VDD<20> @BASEBOARD_FAB2_LIB.BASEBOARD_FAB2(SCH_1):PVDDQ_KLM
  76 PVDDQ_KLM VDD<19> @BASEBOARD_FAB2_LIB.BASEBOARD_FAB2(SCH_1):PVDDQ_KLM
  80 PVDDQ_KLM VDD<18> @BASEBOARD_FAB2_LIB.BASEBOARD_FAB2(SCH_1):PVDDQ_KLM
  83 PVDDQ_KLM VDD<17> @BASEBOARD_FAB2_LIB.BASEBOARD_FAB2(SCH_1):PVDDQ_KLM
  85 PVDDQ_KLM VDD<16> @BASEBOARD_FAB2_LIB.BASEBOARD_FAB2(SCH_1):PVDDQ_KLM
  88 PVDDQ_KLM VDD<15> @BASEBOARD_FAB2_LIB.BASEBOARD_FAB2(SCH_1):PVDDQ_KLM
  90 PVDDQ_KLM VDD<14> @BASEBOARD_FAB2_LIB.BASEBOARD_FAB2(SCH_1):PVDDQ_KLM
  92 PVDDQ_KLM VDD<13> @BASEBOARD_FAB2_LIB.BASEBOARD_FAB2(SCH_1):PVDDQ_KLM
 204 PVDDQ_KLM VDD<12> @BASEBOARD_FAB2_LIB.BASEBOARD_FAB2(SCH_1):PVDDQ_KLM
 206 PVDDQ_KLM VDD<11> @BASEBOARD_FAB2_LIB.BASEBOARD_FAB2(SCH_1):PVDDQ_KLM
 209 PVDDQ_KLM VDD<10> @BASEBOARD_FAB2_LIB.BASEBOARD_FAB2(SCH_1):PVDDQ_KLM
 212 PVDDQ_KLM VDD<9> @BASEBOARD_FAB2_LIB.BASEBOARD_FAB2(SCH_1):PVDDQ_KLM
 215 PVDDQ_KLM VDD<8> @BASEBOARD_FAB2_LIB.BASEBOARD_FAB2(SCH_1):PVDDQ_KLM
 217 PVDDQ_KLM VDD<7> @BASEBOARD_FAB2_LIB.BASEBOARD_FAB2(SCH_1):PVDDQ_KLM
 220 PVDDQ_KLM VDD<6> @BASEBOARD_FAB2_LIB.BASEBOARD_FAB2(SCH_1):PVDDQ_KLM
 223 PVDDQ_KLM VDD<5> @BASEBOARD_FAB2_LIB.BASEBOARD_FAB2(SCH_1):PVDDQ_KLM
 226 PVDDQ_KLM VDD<4> @BASEBOARD_FAB2_LIB.BASEBOARD_FAB2(SCH_1):PVDDQ_KLM
 229 PVDDQ_KLM VDD<3> @BASEBOARD_FAB2_LIB.BASEBOARD_FAB2(SCH_1):PVDDQ_KLM
 231 PVDDQ_KLM VDD<2> @BASEBOARD_FAB2_LIB.BASEBOARD_FAB2(SCH_1):PVDDQ_KLM
 233 PVDDQ_KLM VDD<1> @BASEBOARD_FAB2_LIB.BASEBOARD_FAB2(SCH_1):PVDDQ_KLM
 236 PVDDQ_KLM VDD<0> @BASEBOARD_FAB2_LIB.BASEBOARD_FAB2(SCH_1):PVDDQ_KLM
 142 PVPP_KLM VPP<4> @BASEBOARD_FAB2_LIB.BASEBOARD_FAB2(SCH_1):PVPP_KLM
 143 PVPP_KLM VPP<3> @BASEBOARD_FAB2_LIB.BASEBOARD_FAB2(SCH_1):PVPP_KLM
 288 PVPP_KLM VPP<2> @BASEBOARD_FAB2_LIB.BASEBOARD_FAB2(SCH_1):PVPP_KLM
 286 PVPP_KLM VPP<1> @BASEBOARD_FAB2_LIB.BASEBOARD_FAB2(SCH_1):PVPP_KLM
 287 PVPP_KLM VPP<0> @BASEBOARD_FAB2_LIB.BASEBOARD_FAB2(SCH_1):PVPP_KLM
  77 PVTT_KLM VTT<1> @BASEBOARD_FAB2_LIB.BASEBOARD_FAB2(SCH_1):PVTT_KLM
 221 PVTT_KLM VTT<0> @BASEBOARD_FAB2_LIB.BASEBOARD_FAB2(SCH_1):PVTT_KLM

SCONN288_H44441003_PIP-SCONN,HA  I100  J9L2
 152 M_L_DQS_DN<0>  DQS0N @BASEBOARD_FAB2_LIB.BASEBOARD_FAB2(SCH_1):M_L_DQS_DN(0)
 153 M_L_DQS_DP<0>  DQS0P @BASEBOARD_FAB2_LIB.BASEBOARD_FAB2(SCH_1):M_L_DQS_DP(0)
  19 M_L_DQS_DN<10> DQS10N @BASEBOARD_FAB2_LIB.BASEBOARD_FAB2(SCH_1):M_L_DQS_DN(10)
  18 M_L_DQS_DP<10> DQS10P @BASEBOARD_FAB2_LIB.BASEBOARD_FAB2(SCH_1):M_L_DQS_DP(10)
  30 M_L_DQS_DN<11> DQS11N @BASEBOARD_FAB2_LIB.BASEBOARD_FAB2(SCH_1):M_L_DQS_DN(11)
  29 M_L_DQS_DP<11> DQS11P @BASEBOARD_FAB2_LIB.BASEBOARD_FAB2(SCH_1):M_L_DQS_DP(11)
  41 M_L_DQS_DN<12> DQS12N @BASEBOARD_FAB2_LIB.BASEBOARD_FAB2(SCH_1):M_L_DQS_DN(12)
  40 M_L_DQS_DP<12> DQS12P @BASEBOARD_FAB2_LIB.BASEBOARD_FAB2(SCH_1):M_L_DQS_DP(12)
 100 M_L_DQS_DN<13> DQS13N @BASEBOARD_FAB2_LIB.BASEBOARD_FAB2(SCH_1):M_L_DQS_DN(13)
  99 M_L_DQS_DP<13> DQS13P @BASEBOARD_FAB2_LIB.BASEBOARD_FAB2(SCH_1):M_L_DQS_DP(13)
 111 M_L_DQS_DN<14> DQS14N @BASEBOARD_FAB2_LIB.BASEBOARD_FAB2(SCH_1):M_L_DQS_DN(14)
 110 M_L_DQS_DP<14> DQS14P @BASEBOARD_FAB2_LIB.BASEBOARD_FAB2(SCH_1):M_L_DQS_DP(14)
 122 M_L_DQS_DN<15> DQS15N @BASEBOARD_FAB2_LIB.BASEBOARD_FAB2(SCH_1):M_L_DQS_DN(15)
 121 M_L_DQS_DP<15> DQS15P @BASEBOARD_FAB2_LIB.BASEBOARD_FAB2(SCH_1):M_L_DQS_DP(15)
 133 M_L_DQS_DN<16> DQS16N @BASEBOARD_FAB2_LIB.BASEBOARD_FAB2(SCH_1):M_L_DQS_DN(16)
 132 M_L_DQS_DP<16> DQS16P @BASEBOARD_FAB2_LIB.BASEBOARD_FAB2(SCH_1):M_L_DQS_DP(16)
  52 M_L_DQS_DN<17> DQS17N @BASEBOARD_FAB2_LIB.BASEBOARD_FAB2(SCH_1):M_L_DQS_DN(17)
  51 M_L_DQS_DP<17> DQS17P @BASEBOARD_FAB2_LIB.BASEBOARD_FAB2(SCH_1):M_L_DQS_DP(17)
 163 M_L_DQS_DN<1>  DQS1N @BASEBOARD_FAB2_LIB.BASEBOARD_FAB2(SCH_1):M_L_DQS_DN(1)
 164 M_L_DQS_DP<1>  DQS1P @BASEBOARD_FAB2_LIB.BASEBOARD_FAB2(SCH_1):M_L_DQS_DP(1)
 174 M_L_DQS_DN<2>  DQS2N @BASEBOARD_FAB2_LIB.BASEBOARD_FAB2(SCH_1):M_L_DQS_DN(2)
 175 M_L_DQS_DP<2>  DQS2P @BASEBOARD_FAB2_LIB.BASEBOARD_FAB2(SCH_1):M_L_DQS_DP(2)
 185 M_L_DQS_DN<3>  DQS3N @BASEBOARD_FAB2_LIB.BASEBOARD_FAB2(SCH_1):M_L_DQS_DN(3)
 186 M_L_DQS_DP<3>  DQS3P @BASEBOARD_FAB2_LIB.BASEBOARD_FAB2(SCH_1):M_L_DQS_DP(3)
 244 M_L_DQS_DN<4>  DQS4N @BASEBOARD_FAB2_LIB.BASEBOARD_FAB2(SCH_1):M_L_DQS_DN(4)
 245 M_L_DQS_DP<4>  DQS4P @BASEBOARD_FAB2_LIB.BASEBOARD_FAB2(SCH_1):M_L_DQS_DP(4)
 255 M_L_DQS_DN<5>  DQS5N @BASEBOARD_FAB2_LIB.BASEBOARD_FAB2(SCH_1):M_L_DQS_DN(5)
 256 M_L_DQS_DP<5>  DQS5P @BASEBOARD_FAB2_LIB.BASEBOARD_FAB2(SCH_1):M_L_DQS_DP(5)
 266 M_L_DQS_DN<6>  DQS6N @BASEBOARD_FAB2_LIB.BASEBOARD_FAB2(SCH_1):M_L_DQS_DN(6)
 267 M_L_DQS_DP<6>  DQS6P @BASEBOARD_FAB2_LIB.BASEBOARD_FAB2(SCH_1):M_L_DQS_DP(6)
 277 M_L_DQS_DN<7>  DQS7N @BASEBOARD_FAB2_LIB.BASEBOARD_FAB2(SCH_1):M_L_DQS_DN(7)
 278 M_L_DQS_DP<7>  DQS7P @BASEBOARD_FAB2_LIB.BASEBOARD_FAB2(SCH_1):M_L_DQS_DP(7)
 196 M_L_DQS_DN<8>  DQS8N @BASEBOARD_FAB2_LIB.BASEBOARD_FAB2(SCH_1):M_L_DQS_DN(8)
 197 M_L_DQS_DP<8>  DQS8P @BASEBOARD_FAB2_LIB.BASEBOARD_FAB2(SCH_1):M_L_DQS_DP(8)
   8 M_L_DQS_DN<9>  DQS9N @BASEBOARD_FAB2_LIB.BASEBOARD_FAB2(SCH_1):M_L_DQS_DN(9)
   7 M_L_DQS_DP<9>  DQS9P @BASEBOARD_FAB2_LIB.BASEBOARD_FAB2(SCH_1):M_L_DQS_DP(9)

SCONN288_H44441003_PIP-SCONN,HA  I138  J9L2
   2    GND VSS<93> @BASEBOARD_FAB2_LIB.BASEBOARD_FAB2(SCH_1):GND
   4    GND VSS<92> @BASEBOARD_FAB2_LIB.BASEBOARD_FAB2(SCH_1):GND
   6    GND VSS<91> @BASEBOARD_FAB2_LIB.BASEBOARD_FAB2(SCH_1):GND
   9    GND VSS<90> @BASEBOARD_FAB2_LIB.BASEBOARD_FAB2(SCH_1):GND
  11    GND VSS<89> @BASEBOARD_FAB2_LIB.BASEBOARD_FAB2(SCH_1):GND
  13    GND VSS<88> @BASEBOARD_FAB2_LIB.BASEBOARD_FAB2(SCH_1):GND
  15    GND VSS<87> @BASEBOARD_FAB2_LIB.BASEBOARD_FAB2(SCH_1):GND
  17    GND VSS<86> @BASEBOARD_FAB2_LIB.BASEBOARD_FAB2(SCH_1):GND
  20    GND VSS<85> @BASEBOARD_FAB2_LIB.BASEBOARD_FAB2(SCH_1):GND
  22    GND VSS<84> @BASEBOARD_FAB2_LIB.BASEBOARD_FAB2(SCH_1):GND
  24    GND VSS<83> @BASEBOARD_FAB2_LIB.BASEBOARD_FAB2(SCH_1):GND
  26    GND VSS<82> @BASEBOARD_FAB2_LIB.BASEBOARD_FAB2(SCH_1):GND
  28    GND VSS<81> @BASEBOARD_FAB2_LIB.BASEBOARD_FAB2(SCH_1):GND
  31    GND VSS<80> @BASEBOARD_FAB2_LIB.BASEBOARD_FAB2(SCH_1):GND
  33    GND VSS<79> @BASEBOARD_FAB2_LIB.BASEBOARD_FAB2(SCH_1):GND
  35    GND VSS<78> @BASEBOARD_FAB2_LIB.BASEBOARD_FAB2(SCH_1):GND
  37    GND VSS<77> @BASEBOARD_FAB2_LIB.BASEBOARD_FAB2(SCH_1):GND
  39    GND VSS<76> @BASEBOARD_FAB2_LIB.BASEBOARD_FAB2(SCH_1):GND
  42    GND VSS<75> @BASEBOARD_FAB2_LIB.BASEBOARD_FAB2(SCH_1):GND
  44    GND VSS<74> @BASEBOARD_FAB2_LIB.BASEBOARD_FAB2(SCH_1):GND
  46    GND VSS<73> @BASEBOARD_FAB2_LIB.BASEBOARD_FAB2(SCH_1):GND
  48    GND VSS<72> @BASEBOARD_FAB2_LIB.BASEBOARD_FAB2(SCH_1):GND
  50    GND VSS<71> @BASEBOARD_FAB2_LIB.BASEBOARD_FAB2(SCH_1):GND
  53    GND VSS<70> @BASEBOARD_FAB2_LIB.BASEBOARD_FAB2(SCH_1):GND
  55    GND VSS<69> @BASEBOARD_FAB2_LIB.BASEBOARD_FAB2(SCH_1):GND
  57    GND VSS<68> @BASEBOARD_FAB2_LIB.BASEBOARD_FAB2(SCH_1):GND
  94    GND VSS<67> @BASEBOARD_FAB2_LIB.BASEBOARD_FAB2(SCH_1):GND
  96    GND VSS<66> @BASEBOARD_FAB2_LIB.BASEBOARD_FAB2(SCH_1):GND
  98    GND VSS<65> @BASEBOARD_FAB2_LIB.BASEBOARD_FAB2(SCH_1):GND
 101    GND VSS<64> @BASEBOARD_FAB2_LIB.BASEBOARD_FAB2(SCH_1):GND
 103    GND VSS<63> @BASEBOARD_FAB2_LIB.BASEBOARD_FAB2(SCH_1):GND
 105    GND VSS<62> @BASEBOARD_FAB2_LIB.BASEBOARD_FAB2(SCH_1):GND
 107    GND VSS<61> @BASEBOARD_FAB2_LIB.BASEBOARD_FAB2(SCH_1):GND
 109    GND VSS<60> @BASEBOARD_FAB2_LIB.BASEBOARD_FAB2(SCH_1):GND
 112    GND VSS<59> @BASEBOARD_FAB2_LIB.BASEBOARD_FAB2(SCH_1):GND
 114    GND VSS<58> @BASEBOARD_FAB2_LIB.BASEBOARD_FAB2(SCH_1):GND
 116    GND VSS<57> @BASEBOARD_FAB2_LIB.BASEBOARD_FAB2(SCH_1):GND
 118    GND VSS<56> @BASEBOARD_FAB2_LIB.BASEBOARD_FAB2(SCH_1):GND
 120    GND VSS<55> @BASEBOARD_FAB2_LIB.BASEBOARD_FAB2(SCH_1):GND
 123    GND VSS<54> @BASEBOARD_FAB2_LIB.BASEBOARD_FAB2(SCH_1):GND
 125    GND VSS<53> @BASEBOARD_FAB2_LIB.BASEBOARD_FAB2(SCH_1):GND
 127    GND VSS<52> @BASEBOARD_FAB2_LIB.BASEBOARD_FAB2(SCH_1):GND
 129    GND VSS<51> @BASEBOARD_FAB2_LIB.BASEBOARD_FAB2(SCH_1):GND
 131    GND VSS<50> @BASEBOARD_FAB2_LIB.BASEBOARD_FAB2(SCH_1):GND
 134    GND VSS<49> @BASEBOARD_FAB2_LIB.BASEBOARD_FAB2(SCH_1):GND
 136    GND VSS<48> @BASEBOARD_FAB2_LIB.BASEBOARD_FAB2(SCH_1):GND
 138    GND VSS<47> @BASEBOARD_FAB2_LIB.BASEBOARD_FAB2(SCH_1):GND
 147    GND VSS<46> @BASEBOARD_FAB2_LIB.BASEBOARD_FAB2(SCH_1):GND
 149    GND VSS<45> @BASEBOARD_FAB2_LIB.BASEBOARD_FAB2(SCH_1):GND
 151    GND VSS<44> @BASEBOARD_FAB2_LIB.BASEBOARD_FAB2(SCH_1):GND
 154    GND VSS<43> @BASEBOARD_FAB2_LIB.BASEBOARD_FAB2(SCH_1):GND
 156    GND VSS<42> @BASEBOARD_FAB2_LIB.BASEBOARD_FAB2(SCH_1):GND
 158    GND VSS<41> @BASEBOARD_FAB2_LIB.BASEBOARD_FAB2(SCH_1):GND
 160    GND VSS<40> @BASEBOARD_FAB2_LIB.BASEBOARD_FAB2(SCH_1):GND
 162    GND VSS<39> @BASEBOARD_FAB2_LIB.BASEBOARD_FAB2(SCH_1):GND
 165    GND VSS<38> @BASEBOARD_FAB2_LIB.BASEBOARD_FAB2(SCH_1):GND
 167    GND VSS<37> @BASEBOARD_FAB2_LIB.BASEBOARD_FAB2(SCH_1):GND
 169    GND VSS<36> @BASEBOARD_FAB2_LIB.BASEBOARD_FAB2(SCH_1):GND
 171    GND VSS<35> @BASEBOARD_FAB2_LIB.BASEBOARD_FAB2(SCH_1):GND
 173    GND VSS<34> @BASEBOARD_FAB2_LIB.BASEBOARD_FAB2(SCH_1):GND
 176    GND VSS<33> @BASEBOARD_FAB2_LIB.BASEBOARD_FAB2(SCH_1):GND
 178    GND VSS<32> @BASEBOARD_FAB2_LIB.BASEBOARD_FAB2(SCH_1):GND
 180    GND VSS<31> @BASEBOARD_FAB2_LIB.BASEBOARD_FAB2(SCH_1):GND
 182    GND VSS<30> @BASEBOARD_FAB2_LIB.BASEBOARD_FAB2(SCH_1):GND
 184    GND VSS<29> @BASEBOARD_FAB2_LIB.BASEBOARD_FAB2(SCH_1):GND
 187    GND VSS<28> @BASEBOARD_FAB2_LIB.BASEBOARD_FAB2(SCH_1):GND
 189    GND VSS<27> @BASEBOARD_FAB2_LIB.BASEBOARD_FAB2(SCH_1):GND
 191    GND VSS<26> @BASEBOARD_FAB2_LIB.BASEBOARD_FAB2(SCH_1):GND
 193    GND VSS<25> @BASEBOARD_FAB2_LIB.BASEBOARD_FAB2(SCH_1):GND
 195    GND VSS<24> @BASEBOARD_FAB2_LIB.BASEBOARD_FAB2(SCH_1):GND
 198    GND VSS<23> @BASEBOARD_FAB2_LIB.BASEBOARD_FAB2(SCH_1):GND
 200    GND VSS<22> @BASEBOARD_FAB2_LIB.BASEBOARD_FAB2(SCH_1):GND
 202    GND VSS<21> @BASEBOARD_FAB2_LIB.BASEBOARD_FAB2(SCH_1):GND
 239    GND VSS<20> @BASEBOARD_FAB2_LIB.BASEBOARD_FAB2(SCH_1):GND
 241    GND VSS<19> @BASEBOARD_FAB2_LIB.BASEBOARD_FAB2(SCH_1):GND
 243    GND VSS<18> @BASEBOARD_FAB2_LIB.BASEBOARD_FAB2(SCH_1):GND
 246    GND VSS<17> @BASEBOARD_FAB2_LIB.BASEBOARD_FAB2(SCH_1):GND
 248    GND VSS<16> @BASEBOARD_FAB2_LIB.BASEBOARD_FAB2(SCH_1):GND
 250    GND VSS<15> @BASEBOARD_FAB2_LIB.BASEBOARD_FAB2(SCH_1):GND
 252    GND VSS<14> @BASEBOARD_FAB2_LIB.BASEBOARD_FAB2(SCH_1):GND
 254    GND VSS<13> @BASEBOARD_FAB2_LIB.BASEBOARD_FAB2(SCH_1):GND
 257    GND VSS<12> @BASEBOARD_FAB2_LIB.BASEBOARD_FAB2(SCH_1):GND
 259    GND VSS<11> @BASEBOARD_FAB2_LIB.BASEBOARD_FAB2(SCH_1):GND
 261    GND VSS<10> @BASEBOARD_FAB2_LIB.BASEBOARD_FAB2(SCH_1):GND
 263    GND VSS<9> @BASEBOARD_FAB2_LIB.BASEBOARD_FAB2(SCH_1):GND
 265    GND VSS<8> @BASEBOARD_FAB2_LIB.BASEBOARD_FAB2(SCH_1):GND
 268    GND VSS<7> @BASEBOARD_FAB2_LIB.BASEBOARD_FAB2(SCH_1):GND
 270    GND VSS<6> @BASEBOARD_FAB2_LIB.BASEBOARD_FAB2(SCH_1):GND
 272    GND VSS<5> @BASEBOARD_FAB2_LIB.BASEBOARD_FAB2(SCH_1):GND
 274    GND VSS<4> @BASEBOARD_FAB2_LIB.BASEBOARD_FAB2(SCH_1):GND
 276    GND VSS<3> @BASEBOARD_FAB2_LIB.BASEBOARD_FAB2(SCH_1):GND
 279    GND VSS<2> @BASEBOARD_FAB2_LIB.BASEBOARD_FAB2(SCH_1):GND
 281    GND VSS<1> @BASEBOARD_FAB2_LIB.BASEBOARD_FAB2(SCH_1):GND
 283    GND VSS<0> @BASEBOARD_FAB2_LIB.BASEBOARD_FAB2(SCH_1):GND

CAP_A_0402V-0.01UF,25V,10%,X7RA  I182  C1A17
   1 M_L_VREF      A @BASEBOARD_FAB2_LIB.BASEBOARD_FAB2(SCH_1):M_L_VREF
   2    GND      B @BASEBOARD_FAB2_LIB.BASEBOARD_FAB2(SCH_1):GND


DRAWING: @BASEBOARD_FAB2_LIB.BASEBOARD_FAB2(SCH_1):PAGE87 

SCONN288_H44441004_PIP-SCONN,HA  I169  J1A1
   1 P12V_NVDIMM_KLM 12V<1> @BASEBOARD_FAB2_LIB.BASEBOARD_FAB2(SCH_1):P12V_NVDIMM_KLM
 145 P12V_NVDIMM_KLM 12V<0> @BASEBOARD_FAB2_LIB.BASEBOARD_FAB2(SCH_1):P12V_NVDIMM_KLM
  59 PVDDQ_KLM VDD<25> @BASEBOARD_FAB2_LIB.BASEBOARD_FAB2(SCH_1):PVDDQ_KLM
  61 PVDDQ_KLM VDD<24> @BASEBOARD_FAB2_LIB.BASEBOARD_FAB2(SCH_1):PVDDQ_KLM
  64 PVDDQ_KLM VDD<23> @BASEBOARD_FAB2_LIB.BASEBOARD_FAB2(SCH_1):PVDDQ_KLM
  67 PVDDQ_KLM VDD<22> @BASEBOARD_FAB2_LIB.BASEBOARD_FAB2(SCH_1):PVDDQ_KLM
  70 PVDDQ_KLM VDD<21> @BASEBOARD_FAB2_LIB.BASEBOARD_FAB2(SCH_1):PVDDQ_KLM
  73 PVDDQ_KLM VDD<20> @BASEBOARD_FAB2_LIB.BASEBOARD_FAB2(SCH_1):PVDDQ_KLM
  76 PVDDQ_KLM VDD<19> @BASEBOARD_FAB2_LIB.BASEBOARD_FAB2(SCH_1):PVDDQ_KLM
  80 PVDDQ_KLM VDD<18> @BASEBOARD_FAB2_LIB.BASEBOARD_FAB2(SCH_1):PVDDQ_KLM
  83 PVDDQ_KLM VDD<17> @BASEBOARD_FAB2_LIB.BASEBOARD_FAB2(SCH_1):PVDDQ_KLM
  85 PVDDQ_KLM VDD<16> @BASEBOARD_FAB2_LIB.BASEBOARD_FAB2(SCH_1):PVDDQ_KLM
  88 PVDDQ_KLM VDD<15> @BASEBOARD_FAB2_LIB.BASEBOARD_FAB2(SCH_1):PVDDQ_KLM
  90 PVDDQ_KLM VDD<14> @BASEBOARD_FAB2_LIB.BASEBOARD_FAB2(SCH_1):PVDDQ_KLM
  92 PVDDQ_KLM VDD<13> @BASEBOARD_FAB2_LIB.BASEBOARD_FAB2(SCH_1):PVDDQ_KLM
 204 PVDDQ_KLM VDD<12> @BASEBOARD_FAB2_LIB.BASEBOARD_FAB2(SCH_1):PVDDQ_KLM
 206 PVDDQ_KLM VDD<11> @BASEBOARD_FAB2_LIB.BASEBOARD_FAB2(SCH_1):PVDDQ_KLM
 209 PVDDQ_KLM VDD<10> @BASEBOARD_FAB2_LIB.BASEBOARD_FAB2(SCH_1):PVDDQ_KLM
 212 PVDDQ_KLM VDD<9> @BASEBOARD_FAB2_LIB.BASEBOARD_FAB2(SCH_1):PVDDQ_KLM
 215 PVDDQ_KLM VDD<8> @BASEBOARD_FAB2_LIB.BASEBOARD_FAB2(SCH_1):PVDDQ_KLM
 217 PVDDQ_KLM VDD<7> @BASEBOARD_FAB2_LIB.BASEBOARD_FAB2(SCH_1):PVDDQ_KLM
 220 PVDDQ_KLM VDD<6> @BASEBOARD_FAB2_LIB.BASEBOARD_FAB2(SCH_1):PVDDQ_KLM
 223 PVDDQ_KLM VDD<5> @BASEBOARD_FAB2_LIB.BASEBOARD_FAB2(SCH_1):PVDDQ_KLM
 226 PVDDQ_KLM VDD<4> @BASEBOARD_FAB2_LIB.BASEBOARD_FAB2(SCH_1):PVDDQ_KLM
 229 PVDDQ_KLM VDD<3> @BASEBOARD_FAB2_LIB.BASEBOARD_FAB2(SCH_1):PVDDQ_KLM
 231 PVDDQ_KLM VDD<2> @BASEBOARD_FAB2_LIB.BASEBOARD_FAB2(SCH_1):PVDDQ_KLM
 233 PVDDQ_KLM VDD<1> @BASEBOARD_FAB2_LIB.BASEBOARD_FAB2(SCH_1):PVDDQ_KLM
 236 PVDDQ_KLM VDD<0> @BASEBOARD_FAB2_LIB.BASEBOARD_FAB2(SCH_1):PVDDQ_KLM
 142 PVPP_KLM VPP<4> @BASEBOARD_FAB2_LIB.BASEBOARD_FAB2(SCH_1):PVPP_KLM
 143 PVPP_KLM VPP<3> @BASEBOARD_FAB2_LIB.BASEBOARD_FAB2(SCH_1):PVPP_KLM
 288 PVPP_KLM VPP<2> @BASEBOARD_FAB2_LIB.BASEBOARD_FAB2(SCH_1):PVPP_KLM
 286 PVPP_KLM VPP<1> @BASEBOARD_FAB2_LIB.BASEBOARD_FAB2(SCH_1):PVPP_KLM
 287 PVPP_KLM VPP<0> @BASEBOARD_FAB2_LIB.BASEBOARD_FAB2(SCH_1):PVPP_KLM
  77 PVTT_KLM VTT<1> @BASEBOARD_FAB2_LIB.BASEBOARD_FAB2(SCH_1):PVTT_KLM
 221 PVTT_KLM VTT<0> @BASEBOARD_FAB2_LIB.BASEBOARD_FAB2(SCH_1):PVTT_KLM

CAP_A_0402V-0.01UF,25V,10%,X7RA  I178  C1A5
   1 M_M_VREF      A @BASEBOARD_FAB2_LIB.BASEBOARD_FAB2(SCH_1):M_M_VREF
   2    GND      B @BASEBOARD_FAB2_LIB.BASEBOARD_FAB2(SCH_1):GND

SCONN288_H44441004_PIP-SCONN,HA  I185  J1A1
   2    GND VSS<93> @BASEBOARD_FAB2_LIB.BASEBOARD_FAB2(SCH_1):GND
   4    GND VSS<92> @BASEBOARD_FAB2_LIB.BASEBOARD_FAB2(SCH_1):GND
   6    GND VSS<91> @BASEBOARD_FAB2_LIB.BASEBOARD_FAB2(SCH_1):GND
   9    GND VSS<90> @BASEBOARD_FAB2_LIB.BASEBOARD_FAB2(SCH_1):GND
  11    GND VSS<89> @BASEBOARD_FAB2_LIB.BASEBOARD_FAB2(SCH_1):GND
  13    GND VSS<88> @BASEBOARD_FAB2_LIB.BASEBOARD_FAB2(SCH_1):GND
  15    GND VSS<87> @BASEBOARD_FAB2_LIB.BASEBOARD_FAB2(SCH_1):GND
  17    GND VSS<86> @BASEBOARD_FAB2_LIB.BASEBOARD_FAB2(SCH_1):GND
  20    GND VSS<85> @BASEBOARD_FAB2_LIB.BASEBOARD_FAB2(SCH_1):GND
  22    GND VSS<84> @BASEBOARD_FAB2_LIB.BASEBOARD_FAB2(SCH_1):GND
  24    GND VSS<83> @BASEBOARD_FAB2_LIB.BASEBOARD_FAB2(SCH_1):GND
  26    GND VSS<82> @BASEBOARD_FAB2_LIB.BASEBOARD_FAB2(SCH_1):GND
  28    GND VSS<81> @BASEBOARD_FAB2_LIB.BASEBOARD_FAB2(SCH_1):GND
  31    GND VSS<80> @BASEBOARD_FAB2_LIB.BASEBOARD_FAB2(SCH_1):GND
  33    GND VSS<79> @BASEBOARD_FAB2_LIB.BASEBOARD_FAB2(SCH_1):GND
  35    GND VSS<78> @BASEBOARD_FAB2_LIB.BASEBOARD_FAB2(SCH_1):GND
  37    GND VSS<77> @BASEBOARD_FAB2_LIB.BASEBOARD_FAB2(SCH_1):GND
  39    GND VSS<76> @BASEBOARD_FAB2_LIB.BASEBOARD_FAB2(SCH_1):GND
  42    GND VSS<75> @BASEBOARD_FAB2_LIB.BASEBOARD_FAB2(SCH_1):GND
  44    GND VSS<74> @BASEBOARD_FAB2_LIB.BASEBOARD_FAB2(SCH_1):GND
  46    GND VSS<73> @BASEBOARD_FAB2_LIB.BASEBOARD_FAB2(SCH_1):GND
  48    GND VSS<72> @BASEBOARD_FAB2_LIB.BASEBOARD_FAB2(SCH_1):GND
  50    GND VSS<71> @BASEBOARD_FAB2_LIB.BASEBOARD_FAB2(SCH_1):GND
  53    GND VSS<70> @BASEBOARD_FAB2_LIB.BASEBOARD_FAB2(SCH_1):GND
  55    GND VSS<69> @BASEBOARD_FAB2_LIB.BASEBOARD_FAB2(SCH_1):GND
  57    GND VSS<68> @BASEBOARD_FAB2_LIB.BASEBOARD_FAB2(SCH_1):GND
  94    GND VSS<67> @BASEBOARD_FAB2_LIB.BASEBOARD_FAB2(SCH_1):GND
  96    GND VSS<66> @BASEBOARD_FAB2_LIB.BASEBOARD_FAB2(SCH_1):GND
  98    GND VSS<65> @BASEBOARD_FAB2_LIB.BASEBOARD_FAB2(SCH_1):GND
 101    GND VSS<64> @BASEBOARD_FAB2_LIB.BASEBOARD_FAB2(SCH_1):GND
 103    GND VSS<63> @BASEBOARD_FAB2_LIB.BASEBOARD_FAB2(SCH_1):GND
 105    GND VSS<62> @BASEBOARD_FAB2_LIB.BASEBOARD_FAB2(SCH_1):GND
 107    GND VSS<61> @BASEBOARD_FAB2_LIB.BASEBOARD_FAB2(SCH_1):GND
 109    GND VSS<60> @BASEBOARD_FAB2_LIB.BASEBOARD_FAB2(SCH_1):GND
 112    GND VSS<59> @BASEBOARD_FAB2_LIB.BASEBOARD_FAB2(SCH_1):GND
 114    GND VSS<58> @BASEBOARD_FAB2_LIB.BASEBOARD_FAB2(SCH_1):GND
 116    GND VSS<57> @BASEBOARD_FAB2_LIB.BASEBOARD_FAB2(SCH_1):GND
 118    GND VSS<56> @BASEBOARD_FAB2_LIB.BASEBOARD_FAB2(SCH_1):GND
 120    GND VSS<55> @BASEBOARD_FAB2_LIB.BASEBOARD_FAB2(SCH_1):GND
 123    GND VSS<54> @BASEBOARD_FAB2_LIB.BASEBOARD_FAB2(SCH_1):GND
 125    GND VSS<53> @BASEBOARD_FAB2_LIB.BASEBOARD_FAB2(SCH_1):GND
 127    GND VSS<52> @BASEBOARD_FAB2_LIB.BASEBOARD_FAB2(SCH_1):GND
 129    GND VSS<51> @BASEBOARD_FAB2_LIB.BASEBOARD_FAB2(SCH_1):GND
 131    GND VSS<50> @BASEBOARD_FAB2_LIB.BASEBOARD_FAB2(SCH_1):GND
 134    GND VSS<49> @BASEBOARD_FAB2_LIB.BASEBOARD_FAB2(SCH_1):GND
 136    GND VSS<48> @BASEBOARD_FAB2_LIB.BASEBOARD_FAB2(SCH_1):GND
 138    GND VSS<47> @BASEBOARD_FAB2_LIB.BASEBOARD_FAB2(SCH_1):GND
 147    GND VSS<46> @BASEBOARD_FAB2_LIB.BASEBOARD_FAB2(SCH_1):GND
 149    GND VSS<45> @BASEBOARD_FAB2_LIB.BASEBOARD_FAB2(SCH_1):GND
 151    GND VSS<44> @BASEBOARD_FAB2_LIB.BASEBOARD_FAB2(SCH_1):GND
 154    GND VSS<43> @BASEBOARD_FAB2_LIB.BASEBOARD_FAB2(SCH_1):GND
 156    GND VSS<42> @BASEBOARD_FAB2_LIB.BASEBOARD_FAB2(SCH_1):GND
 158    GND VSS<41> @BASEBOARD_FAB2_LIB.BASEBOARD_FAB2(SCH_1):GND
 160    GND VSS<40> @BASEBOARD_FAB2_LIB.BASEBOARD_FAB2(SCH_1):GND
 162    GND VSS<39> @BASEBOARD_FAB2_LIB.BASEBOARD_FAB2(SCH_1):GND
 165    GND VSS<38> @BASEBOARD_FAB2_LIB.BASEBOARD_FAB2(SCH_1):GND
 167    GND VSS<37> @BASEBOARD_FAB2_LIB.BASEBOARD_FAB2(SCH_1):GND
 169    GND VSS<36> @BASEBOARD_FAB2_LIB.BASEBOARD_FAB2(SCH_1):GND
 171    GND VSS<35> @BASEBOARD_FAB2_LIB.BASEBOARD_FAB2(SCH_1):GND
 173    GND VSS<34> @BASEBOARD_FAB2_LIB.BASEBOARD_FAB2(SCH_1):GND
 176    GND VSS<33> @BASEBOARD_FAB2_LIB.BASEBOARD_FAB2(SCH_1):GND
 178    GND VSS<32> @BASEBOARD_FAB2_LIB.BASEBOARD_FAB2(SCH_1):GND
 180    GND VSS<31> @BASEBOARD_FAB2_LIB.BASEBOARD_FAB2(SCH_1):GND
 182    GND VSS<30> @BASEBOARD_FAB2_LIB.BASEBOARD_FAB2(SCH_1):GND
 184    GND VSS<29> @BASEBOARD_FAB2_LIB.BASEBOARD_FAB2(SCH_1):GND
 187    GND VSS<28> @BASEBOARD_FAB2_LIB.BASEBOARD_FAB2(SCH_1):GND
 189    GND VSS<27> @BASEBOARD_FAB2_LIB.BASEBOARD_FAB2(SCH_1):GND
 191    GND VSS<26> @BASEBOARD_FAB2_LIB.BASEBOARD_FAB2(SCH_1):GND
 193    GND VSS<25> @BASEBOARD_FAB2_LIB.BASEBOARD_FAB2(SCH_1):GND
 195    GND VSS<24> @BASEBOARD_FAB2_LIB.BASEBOARD_FAB2(SCH_1):GND
 198    GND VSS<23> @BASEBOARD_FAB2_LIB.BASEBOARD_FAB2(SCH_1):GND
 200    GND VSS<22> @BASEBOARD_FAB2_LIB.BASEBOARD_FAB2(SCH_1):GND
 202    GND VSS<21> @BASEBOARD_FAB2_LIB.BASEBOARD_FAB2(SCH_1):GND
 239    GND VSS<20> @BASEBOARD_FAB2_LIB.BASEBOARD_FAB2(SCH_1):GND
 241    GND VSS<19> @BASEBOARD_FAB2_LIB.BASEBOARD_FAB2(SCH_1):GND
 243    GND VSS<18> @BASEBOARD_FAB2_LIB.BASEBOARD_FAB2(SCH_1):GND
 246    GND VSS<17> @BASEBOARD_FAB2_LIB.BASEBOARD_FAB2(SCH_1):GND
 248    GND VSS<16> @BASEBOARD_FAB2_LIB.BASEBOARD_FAB2(SCH_1):GND
 250    GND VSS<15> @BASEBOARD_FAB2_LIB.BASEBOARD_FAB2(SCH_1):GND
 252    GND VSS<14> @BASEBOARD_FAB2_LIB.BASEBOARD_FAB2(SCH_1):GND
 254    GND VSS<13> @BASEBOARD_FAB2_LIB.BASEBOARD_FAB2(SCH_1):GND
 257    GND VSS<12> @BASEBOARD_FAB2_LIB.BASEBOARD_FAB2(SCH_1):GND
 259    GND VSS<11> @BASEBOARD_FAB2_LIB.BASEBOARD_FAB2(SCH_1):GND
 261    GND VSS<10> @BASEBOARD_FAB2_LIB.BASEBOARD_FAB2(SCH_1):GND
 263    GND VSS<9> @BASEBOARD_FAB2_LIB.BASEBOARD_FAB2(SCH_1):GND
 265    GND VSS<8> @BASEBOARD_FAB2_LIB.BASEBOARD_FAB2(SCH_1):GND
 268    GND VSS<7> @BASEBOARD_FAB2_LIB.BASEBOARD_FAB2(SCH_1):GND
 270    GND VSS<6> @BASEBOARD_FAB2_LIB.BASEBOARD_FAB2(SCH_1):GND
 272    GND VSS<5> @BASEBOARD_FAB2_LIB.BASEBOARD_FAB2(SCH_1):GND
 274    GND VSS<4> @BASEBOARD_FAB2_LIB.BASEBOARD_FAB2(SCH_1):GND
 276    GND VSS<3> @BASEBOARD_FAB2_LIB.BASEBOARD_FAB2(SCH_1):GND
 279    GND VSS<2> @BASEBOARD_FAB2_LIB.BASEBOARD_FAB2(SCH_1):GND
 281    GND VSS<1> @BASEBOARD_FAB2_LIB.BASEBOARD_FAB2(SCH_1):GND
 283    GND VSS<0> @BASEBOARD_FAB2_LIB.BASEBOARD_FAB2(SCH_1):GND

SCONN288_H44441004_PIP-SCONN,HA  I186  J1A1
  79 M_M_MA<0>     A0 @BASEBOARD_FAB2_LIB.BASEBOARD_FAB2(SCH_1):M_M_MA(0)
  72 M_M_MA<1>     A1 @BASEBOARD_FAB2_LIB.BASEBOARD_FAB2(SCH_1):M_M_MA(1)
 225 M_M_MA<10>    A10 @BASEBOARD_FAB2_LIB.BASEBOARD_FAB2(SCH_1):M_M_MA(10)
 210 M_M_MA<11>    A11 @BASEBOARD_FAB2_LIB.BASEBOARD_FAB2(SCH_1):M_M_MA(11)
  65 M_M_MA<12>    A12 @BASEBOARD_FAB2_LIB.BASEBOARD_FAB2(SCH_1):M_M_MA(12)
 232 M_M_MA<13>    A13 @BASEBOARD_FAB2_LIB.BASEBOARD_FAB2(SCH_1):M_M_MA(13)
 228 M_M_MA<14> A14_WE_N @BASEBOARD_FAB2_LIB.BASEBOARD_FAB2(SCH_1):M_M_MA(14)
  86 M_M_MA<15> A15_CAS_N @BASEBOARD_FAB2_LIB.BASEBOARD_FAB2(SCH_1):M_M_MA(15)
  82 M_M_MA<16> A16_RAS_N @BASEBOARD_FAB2_LIB.BASEBOARD_FAB2(SCH_1):M_M_MA(16)
 234 M_M_MA<17>    A17 @BASEBOARD_FAB2_LIB.BASEBOARD_FAB2(SCH_1):M_M_MA(17)
 216 M_M_MA<2>     A2 @BASEBOARD_FAB2_LIB.BASEBOARD_FAB2(SCH_1):M_M_MA(2)
  71 M_M_MA<3>     A3 @BASEBOARD_FAB2_LIB.BASEBOARD_FAB2(SCH_1):M_M_MA(3)
 214 M_M_MA<4>     A4 @BASEBOARD_FAB2_LIB.BASEBOARD_FAB2(SCH_1):M_M_MA(4)
 213 M_M_MA<5>     A5 @BASEBOARD_FAB2_LIB.BASEBOARD_FAB2(SCH_1):M_M_MA(5)
  69 M_M_MA<6>     A6 @BASEBOARD_FAB2_LIB.BASEBOARD_FAB2(SCH_1):M_M_MA(6)
 211 M_M_MA<7>     A7 @BASEBOARD_FAB2_LIB.BASEBOARD_FAB2(SCH_1):M_M_MA(7)
  68 M_M_MA<8>     A8 @BASEBOARD_FAB2_LIB.BASEBOARD_FAB2(SCH_1):M_M_MA(8)
  66 M_M_MA<9>     A9 @BASEBOARD_FAB2_LIB.BASEBOARD_FAB2(SCH_1):M_M_MA(9)
  62 M_M_ACT_N  ACT_N @BASEBOARD_FAB2_LIB.BASEBOARD_FAB2(SCH_1):M_M_ACT_N
 208 M_M_ALERT_N ALERT_N @BASEBOARD_FAB2_LIB.BASEBOARD_FAB2(SCH_1):M_M_ALERT_N
 224 M_M_BA<1>  BA<1> @BASEBOARD_FAB2_LIB.BASEBOARD_FAB2(SCH_1):M_M_BA(1)
  81 M_M_BA<0>  BA<0> @BASEBOARD_FAB2_LIB.BASEBOARD_FAB2(SCH_1):M_M_BA(0)
 207 M_M_BG<1>  BG<1> @BASEBOARD_FAB2_LIB.BASEBOARD_FAB2(SCH_1):M_M_BG(1)
  63 M_M_BG<0>  BG<0> @BASEBOARD_FAB2_LIB.BASEBOARD_FAB2(SCH_1):M_M_BG(0)
 235 M_M_C<2>   C<2> @BASEBOARD_FAB2_LIB.BASEBOARD_FAB2(SCH_1):M_M_C(2)
 199 M_M_ECC<6>  CB<7> @BASEBOARD_FAB2_LIB.BASEBOARD_FAB2(SCH_1):M_M_ECC(6)
  54 M_M_ECC<7>  CB<6> @BASEBOARD_FAB2_LIB.BASEBOARD_FAB2(SCH_1):M_M_ECC(7)
 192 M_M_ECC<4>  CB<5> @BASEBOARD_FAB2_LIB.BASEBOARD_FAB2(SCH_1):M_M_ECC(4)
  47 M_M_ECC<5>  CB<4> @BASEBOARD_FAB2_LIB.BASEBOARD_FAB2(SCH_1):M_M_ECC(5)
 201 M_M_ECC<2>  CB<3> @BASEBOARD_FAB2_LIB.BASEBOARD_FAB2(SCH_1):M_M_ECC(2)
  56 M_M_ECC<3>  CB<2> @BASEBOARD_FAB2_LIB.BASEBOARD_FAB2(SCH_1):M_M_ECC(3)
 194 M_M_ECC<0>  CB<1> @BASEBOARD_FAB2_LIB.BASEBOARD_FAB2(SCH_1):M_M_ECC(0)
  49 M_M_ECC<1>  CB<0> @BASEBOARD_FAB2_LIB.BASEBOARD_FAB2(SCH_1):M_M_ECC(1)
  75 M_M_CLK_DN<0>   CK0N @BASEBOARD_FAB2_LIB.BASEBOARD_FAB2(SCH_1):M_M_CLK_DN(0)
  74 M_M_CLK_DP<0>   CK0P @BASEBOARD_FAB2_LIB.BASEBOARD_FAB2(SCH_1):M_M_CLK_DP(0)
 219 M_M_CLK_DN<1>   CK1N @BASEBOARD_FAB2_LIB.BASEBOARD_FAB2(SCH_1):M_M_CLK_DN(1)
 218 M_M_CLK_DP<1>   CK1P @BASEBOARD_FAB2_LIB.BASEBOARD_FAB2(SCH_1):M_M_CLK_DP(1)
 203 M_M_CKE<1> CKE<1> @BASEBOARD_FAB2_LIB.BASEBOARD_FAB2(SCH_1):M_M_CKE(1)
  60 M_M_CKE<0> CKE<0> @BASEBOARD_FAB2_LIB.BASEBOARD_FAB2(SCH_1):M_M_CKE(0)
 280 M_M_DQ<62> DQ<63> @BASEBOARD_FAB2_LIB.BASEBOARD_FAB2(SCH_1):M_M_DQ(62)
 135 M_M_DQ<63> DQ<62> @BASEBOARD_FAB2_LIB.BASEBOARD_FAB2(SCH_1):M_M_DQ(63)
 273 M_M_DQ<60> DQ<61> @BASEBOARD_FAB2_LIB.BASEBOARD_FAB2(SCH_1):M_M_DQ(60)
 128 M_M_DQ<61> DQ<60> @BASEBOARD_FAB2_LIB.BASEBOARD_FAB2(SCH_1):M_M_DQ(61)
 282 M_M_DQ<58> DQ<59> @BASEBOARD_FAB2_LIB.BASEBOARD_FAB2(SCH_1):M_M_DQ(58)
 137 M_M_DQ<59> DQ<58> @BASEBOARD_FAB2_LIB.BASEBOARD_FAB2(SCH_1):M_M_DQ(59)
 275 M_M_DQ<56> DQ<57> @BASEBOARD_FAB2_LIB.BASEBOARD_FAB2(SCH_1):M_M_DQ(56)
 130 M_M_DQ<57> DQ<56> @BASEBOARD_FAB2_LIB.BASEBOARD_FAB2(SCH_1):M_M_DQ(57)
 269 M_M_DQ<54> DQ<55> @BASEBOARD_FAB2_LIB.BASEBOARD_FAB2(SCH_1):M_M_DQ(54)
 124 M_M_DQ<55> DQ<54> @BASEBOARD_FAB2_LIB.BASEBOARD_FAB2(SCH_1):M_M_DQ(55)
 262 M_M_DQ<52> DQ<53> @BASEBOARD_FAB2_LIB.BASEBOARD_FAB2(SCH_1):M_M_DQ(52)
 117 M_M_DQ<53> DQ<52> @BASEBOARD_FAB2_LIB.BASEBOARD_FAB2(SCH_1):M_M_DQ(53)
 271 M_M_DQ<50> DQ<51> @BASEBOARD_FAB2_LIB.BASEBOARD_FAB2(SCH_1):M_M_DQ(50)
 126 M_M_DQ<51> DQ<50> @BASEBOARD_FAB2_LIB.BASEBOARD_FAB2(SCH_1):M_M_DQ(51)
 264 M_M_DQ<48> DQ<49> @BASEBOARD_FAB2_LIB.BASEBOARD_FAB2(SCH_1):M_M_DQ(48)
 119 M_M_DQ<49> DQ<48> @BASEBOARD_FAB2_LIB.BASEBOARD_FAB2(SCH_1):M_M_DQ(49)
 258 M_M_DQ<46> DQ<47> @BASEBOARD_FAB2_LIB.BASEBOARD_FAB2(SCH_1):M_M_DQ(46)
 113 M_M_DQ<47> DQ<46> @BASEBOARD_FAB2_LIB.BASEBOARD_FAB2(SCH_1):M_M_DQ(47)
 251 M_M_DQ<44> DQ<45> @BASEBOARD_FAB2_LIB.BASEBOARD_FAB2(SCH_1):M_M_DQ(44)
 106 M_M_DQ<45> DQ<44> @BASEBOARD_FAB2_LIB.BASEBOARD_FAB2(SCH_1):M_M_DQ(45)
 260 M_M_DQ<42> DQ<43> @BASEBOARD_FAB2_LIB.BASEBOARD_FAB2(SCH_1):M_M_DQ(42)
 115 M_M_DQ<43> DQ<42> @BASEBOARD_FAB2_LIB.BASEBOARD_FAB2(SCH_1):M_M_DQ(43)
 253 M_M_DQ<40> DQ<41> @BASEBOARD_FAB2_LIB.BASEBOARD_FAB2(SCH_1):M_M_DQ(40)
 108 M_M_DQ<41> DQ<40> @BASEBOARD_FAB2_LIB.BASEBOARD_FAB2(SCH_1):M_M_DQ(41)
 247 M_M_DQ<38> DQ<39> @BASEBOARD_FAB2_LIB.BASEBOARD_FAB2(SCH_1):M_M_DQ(38)
 102 M_M_DQ<39> DQ<38> @BASEBOARD_FAB2_LIB.BASEBOARD_FAB2(SCH_1):M_M_DQ(39)
 240 M_M_DQ<36> DQ<37> @BASEBOARD_FAB2_LIB.BASEBOARD_FAB2(SCH_1):M_M_DQ(36)
  95 M_M_DQ<37> DQ<36> @BASEBOARD_FAB2_LIB.BASEBOARD_FAB2(SCH_1):M_M_DQ(37)
 249 M_M_DQ<34> DQ<35> @BASEBOARD_FAB2_LIB.BASEBOARD_FAB2(SCH_1):M_M_DQ(34)
 104 M_M_DQ<35> DQ<34> @BASEBOARD_FAB2_LIB.BASEBOARD_FAB2(SCH_1):M_M_DQ(35)
 242 M_M_DQ<32> DQ<33> @BASEBOARD_FAB2_LIB.BASEBOARD_FAB2(SCH_1):M_M_DQ(32)
  97 M_M_DQ<33> DQ<32> @BASEBOARD_FAB2_LIB.BASEBOARD_FAB2(SCH_1):M_M_DQ(33)
 188 M_M_DQ<30> DQ<31> @BASEBOARD_FAB2_LIB.BASEBOARD_FAB2(SCH_1):M_M_DQ(30)
  43 M_M_DQ<31> DQ<30> @BASEBOARD_FAB2_LIB.BASEBOARD_FAB2(SCH_1):M_M_DQ(31)
 181 M_M_DQ<28> DQ<29> @BASEBOARD_FAB2_LIB.BASEBOARD_FAB2(SCH_1):M_M_DQ(28)
  36 M_M_DQ<29> DQ<28> @BASEBOARD_FAB2_LIB.BASEBOARD_FAB2(SCH_1):M_M_DQ(29)
 190 M_M_DQ<26> DQ<27> @BASEBOARD_FAB2_LIB.BASEBOARD_FAB2(SCH_1):M_M_DQ(26)
  45 M_M_DQ<27> DQ<26> @BASEBOARD_FAB2_LIB.BASEBOARD_FAB2(SCH_1):M_M_DQ(27)
 183 M_M_DQ<24> DQ<25> @BASEBOARD_FAB2_LIB.BASEBOARD_FAB2(SCH_1):M_M_DQ(24)
  38 M_M_DQ<25> DQ<24> @BASEBOARD_FAB2_LIB.BASEBOARD_FAB2(SCH_1):M_M_DQ(25)
 177 M_M_DQ<22> DQ<23> @BASEBOARD_FAB2_LIB.BASEBOARD_FAB2(SCH_1):M_M_DQ(22)
  32 M_M_DQ<23> DQ<22> @BASEBOARD_FAB2_LIB.BASEBOARD_FAB2(SCH_1):M_M_DQ(23)
 170 M_M_DQ<20> DQ<21> @BASEBOARD_FAB2_LIB.BASEBOARD_FAB2(SCH_1):M_M_DQ(20)
  25 M_M_DQ<21> DQ<20> @BASEBOARD_FAB2_LIB.BASEBOARD_FAB2(SCH_1):M_M_DQ(21)
 179 M_M_DQ<18> DQ<19> @BASEBOARD_FAB2_LIB.BASEBOARD_FAB2(SCH_1):M_M_DQ(18)
  34 M_M_DQ<19> DQ<18> @BASEBOARD_FAB2_LIB.BASEBOARD_FAB2(SCH_1):M_M_DQ(19)
 172 M_M_DQ<16> DQ<17> @BASEBOARD_FAB2_LIB.BASEBOARD_FAB2(SCH_1):M_M_DQ(16)
  27 M_M_DQ<17> DQ<16> @BASEBOARD_FAB2_LIB.BASEBOARD_FAB2(SCH_1):M_M_DQ(17)
 166 M_M_DQ<14> DQ<15> @BASEBOARD_FAB2_LIB.BASEBOARD_FAB2(SCH_1):M_M_DQ(14)
  21 M_M_DQ<15> DQ<14> @BASEBOARD_FAB2_LIB.BASEBOARD_FAB2(SCH_1):M_M_DQ(15)
 159 M_M_DQ<12> DQ<13> @BASEBOARD_FAB2_LIB.BASEBOARD_FAB2(SCH_1):M_M_DQ(12)
  14 M_M_DQ<13> DQ<12> @BASEBOARD_FAB2_LIB.BASEBOARD_FAB2(SCH_1):M_M_DQ(13)
 168 M_M_DQ<10> DQ<11> @BASEBOARD_FAB2_LIB.BASEBOARD_FAB2(SCH_1):M_M_DQ(10)
  23 M_M_DQ<11> DQ<10> @BASEBOARD_FAB2_LIB.BASEBOARD_FAB2(SCH_1):M_M_DQ(11)
 161 M_M_DQ<8>  DQ<9> @BASEBOARD_FAB2_LIB.BASEBOARD_FAB2(SCH_1):M_M_DQ(8)
  16 M_M_DQ<9>  DQ<8> @BASEBOARD_FAB2_LIB.BASEBOARD_FAB2(SCH_1):M_M_DQ(9)
 155 M_M_DQ<6>  DQ<7> @BASEBOARD_FAB2_LIB.BASEBOARD_FAB2(SCH_1):M_M_DQ(6)
  10 M_M_DQ<7>  DQ<6> @BASEBOARD_FAB2_LIB.BASEBOARD_FAB2(SCH_1):M_M_DQ(7)
 148 M_M_DQ<4>  DQ<5> @BASEBOARD_FAB2_LIB.BASEBOARD_FAB2(SCH_1):M_M_DQ(4)
   3 M_M_DQ<5>  DQ<4> @BASEBOARD_FAB2_LIB.BASEBOARD_FAB2(SCH_1):M_M_DQ(5)
 157 M_M_DQ<2>  DQ<3> @BASEBOARD_FAB2_LIB.BASEBOARD_FAB2(SCH_1):M_M_DQ(2)
  12 M_M_DQ<3>  DQ<2> @BASEBOARD_FAB2_LIB.BASEBOARD_FAB2(SCH_1):M_M_DQ(3)
 150 M_M_DQ<0>  DQ<1> @BASEBOARD_FAB2_LIB.BASEBOARD_FAB2(SCH_1):M_M_DQ(0)
   5 M_M_DQ<1>  DQ<0> @BASEBOARD_FAB2_LIB.BASEBOARD_FAB2(SCH_1):M_M_DQ(1)
  78 FM_DIMM_EVENT_COD_N EVENT_N @BASEBOARD_FAB2_LIB.BASEBOARD_FAB2(SCH_1):FM_DIMM_EVENT_COD_N
  91 M_M_ODT<1> ODT<1> @BASEBOARD_FAB2_LIB.BASEBOARD_FAB2(SCH_1):M_M_ODT(1)
  87 M_M_ODT<0> ODT<0> @BASEBOARD_FAB2_LIB.BASEBOARD_FAB2(SCH_1):M_M_ODT(0)
 222 M_M_PAR    PAR @BASEBOARD_FAB2_LIB.BASEBOARD_FAB2(SCH_1):M_M_PAR
  58 M_KLM_RST_N RESET_N @BASEBOARD_FAB2_LIB.BASEBOARD_FAB2(SCH_1):M_KLM_RST_N
 144 TP_CH_M_DIMM_M0_RFU_2 RFU<2> @BASEBOARD_FAB2_LIB.BASEBOARD_FAB2(SCH_1):TP_CH_M_DIMM_M0_RFU_2
 227 TP_CH_M_DIMM_M0_RFU_1 RFU<1> @BASEBOARD_FAB2_LIB.BASEBOARD_FAB2(SCH_1):TP_CH_M_DIMM_M0_RFU_1
 205 TP_CH_M_DIMM_M0_RFU_0 RFU<0> @BASEBOARD_FAB2_LIB.BASEBOARD_FAB2(SCH_1):TP_CH_M_DIMM_M0_RFU_0
  84 M_M_CS_N<0>   S0_N @BASEBOARD_FAB2_LIB.BASEBOARD_FAB2(SCH_1):M_M_CS_N(0)
  89 M_M_CS_N<1>   S1_N @BASEBOARD_FAB2_LIB.BASEBOARD_FAB2(SCH_1):M_M_CS_N(1)
  93 M_M_CS_N<2> S2_N_C<0> @BASEBOARD_FAB2_LIB.BASEBOARD_FAB2(SCH_1):M_M_CS_N(2)
 237 M_M_CS_N<3> S3_N_C<1> @BASEBOARD_FAB2_LIB.BASEBOARD_FAB2(SCH_1):M_M_CS_N(3)
 238 PVPP_KLM  SA<2> @BASEBOARD_FAB2_LIB.BASEBOARD_FAB2(SCH_1):PVPP_KLM
 140    GND  SA<1> @BASEBOARD_FAB2_LIB.BASEBOARD_FAB2(SCH_1):GND
 139    GND  SA<0> @BASEBOARD_FAB2_LIB.BASEBOARD_FAB2(SCH_1):GND
 230 FM_ADR_COMPLETE_KLM_N SAVE_N_NC @BASEBOARD_FAB2_LIB.BASEBOARD_FAB2(SCH_1):FM_ADR_COMPLETE_KLM_N
 141 SMB_DDR_KLM_VPP_SCL    SCL @BASEBOARD_FAB2_LIB.BASEBOARD_FAB2(SCH_1):SMB_DDR_KLM_VPP_SCL
 285 SMB_DDR_KLM_VPP_SDA    SDA @BASEBOARD_FAB2_LIB.BASEBOARD_FAB2(SCH_1):SMB_DDR_KLM_VPP_SDA
 284 PVPP_KLM VDDSPD @BASEBOARD_FAB2_LIB.BASEBOARD_FAB2(SCH_1):PVPP_KLM
 146 M_M_VREF VREFCA @BASEBOARD_FAB2_LIB.BASEBOARD_FAB2(SCH_1):M_M_VREF

SCONN288_H44441004_PIP-SCONN,HA  I187  J1A1
 152 M_M_DQS_DN<0>  DQS0N @BASEBOARD_FAB2_LIB.BASEBOARD_FAB2(SCH_1):M_M_DQS_DN(0)
 153 M_M_DQS_DP<0>  DQS0P @BASEBOARD_FAB2_LIB.BASEBOARD_FAB2(SCH_1):M_M_DQS_DP(0)
  19 M_M_DQS_DN<10> DQS10N @BASEBOARD_FAB2_LIB.BASEBOARD_FAB2(SCH_1):M_M_DQS_DN(10)
  18 M_M_DQS_DP<10> DQS10P @BASEBOARD_FAB2_LIB.BASEBOARD_FAB2(SCH_1):M_M_DQS_DP(10)
  30 M_M_DQS_DN<11> DQS11N @BASEBOARD_FAB2_LIB.BASEBOARD_FAB2(SCH_1):M_M_DQS_DN(11)
  29 M_M_DQS_DP<11> DQS11P @BASEBOARD_FAB2_LIB.BASEBOARD_FAB2(SCH_1):M_M_DQS_DP(11)
  41 M_M_DQS_DN<12> DQS12N @BASEBOARD_FAB2_LIB.BASEBOARD_FAB2(SCH_1):M_M_DQS_DN(12)
  40 M_M_DQS_DP<12> DQS12P @BASEBOARD_FAB2_LIB.BASEBOARD_FAB2(SCH_1):M_M_DQS_DP(12)
 100 M_M_DQS_DN<13> DQS13N @BASEBOARD_FAB2_LIB.BASEBOARD_FAB2(SCH_1):M_M_DQS_DN(13)
  99 M_M_DQS_DP<13> DQS13P @BASEBOARD_FAB2_LIB.BASEBOARD_FAB2(SCH_1):M_M_DQS_DP(13)
 111 M_M_DQS_DN<14> DQS14N @BASEBOARD_FAB2_LIB.BASEBOARD_FAB2(SCH_1):M_M_DQS_DN(14)
 110 M_M_DQS_DP<14> DQS14P @BASEBOARD_FAB2_LIB.BASEBOARD_FAB2(SCH_1):M_M_DQS_DP(14)
 122 M_M_DQS_DN<15> DQS15N @BASEBOARD_FAB2_LIB.BASEBOARD_FAB2(SCH_1):M_M_DQS_DN(15)
 121 M_M_DQS_DP<15> DQS15P @BASEBOARD_FAB2_LIB.BASEBOARD_FAB2(SCH_1):M_M_DQS_DP(15)
 133 M_M_DQS_DN<16> DQS16N @BASEBOARD_FAB2_LIB.BASEBOARD_FAB2(SCH_1):M_M_DQS_DN(16)
 132 M_M_DQS_DP<16> DQS16P @BASEBOARD_FAB2_LIB.BASEBOARD_FAB2(SCH_1):M_M_DQS_DP(16)
  52 M_M_DQS_DN<17> DQS17N @BASEBOARD_FAB2_LIB.BASEBOARD_FAB2(SCH_1):M_M_DQS_DN(17)
  51 M_M_DQS_DP<17> DQS17P @BASEBOARD_FAB2_LIB.BASEBOARD_FAB2(SCH_1):M_M_DQS_DP(17)
 163 M_M_DQS_DN<1>  DQS1N @BASEBOARD_FAB2_LIB.BASEBOARD_FAB2(SCH_1):M_M_DQS_DN(1)
 164 M_M_DQS_DP<1>  DQS1P @BASEBOARD_FAB2_LIB.BASEBOARD_FAB2(SCH_1):M_M_DQS_DP(1)
 174 M_M_DQS_DN<2>  DQS2N @BASEBOARD_FAB2_LIB.BASEBOARD_FAB2(SCH_1):M_M_DQS_DN(2)
 175 M_M_DQS_DP<2>  DQS2P @BASEBOARD_FAB2_LIB.BASEBOARD_FAB2(SCH_1):M_M_DQS_DP(2)
 185 M_M_DQS_DN<3>  DQS3N @BASEBOARD_FAB2_LIB.BASEBOARD_FAB2(SCH_1):M_M_DQS_DN(3)
 186 M_M_DQS_DP<3>  DQS3P @BASEBOARD_FAB2_LIB.BASEBOARD_FAB2(SCH_1):M_M_DQS_DP(3)
 244 M_M_DQS_DN<4>  DQS4N @BASEBOARD_FAB2_LIB.BASEBOARD_FAB2(SCH_1):M_M_DQS_DN(4)
 245 M_M_DQS_DP<4>  DQS4P @BASEBOARD_FAB2_LIB.BASEBOARD_FAB2(SCH_1):M_M_DQS_DP(4)
 255 M_M_DQS_DN<5>  DQS5N @BASEBOARD_FAB2_LIB.BASEBOARD_FAB2(SCH_1):M_M_DQS_DN(5)
 256 M_M_DQS_DP<5>  DQS5P @BASEBOARD_FAB2_LIB.BASEBOARD_FAB2(SCH_1):M_M_DQS_DP(5)
 266 M_M_DQS_DN<6>  DQS6N @BASEBOARD_FAB2_LIB.BASEBOARD_FAB2(SCH_1):M_M_DQS_DN(6)
 267 M_M_DQS_DP<6>  DQS6P @BASEBOARD_FAB2_LIB.BASEBOARD_FAB2(SCH_1):M_M_DQS_DP(6)
 277 M_M_DQS_DN<7>  DQS7N @BASEBOARD_FAB2_LIB.BASEBOARD_FAB2(SCH_1):M_M_DQS_DN(7)
 278 M_M_DQS_DP<7>  DQS7P @BASEBOARD_FAB2_LIB.BASEBOARD_FAB2(SCH_1):M_M_DQS_DP(7)
 196 M_M_DQS_DN<8>  DQS8N @BASEBOARD_FAB2_LIB.BASEBOARD_FAB2(SCH_1):M_M_DQS_DN(8)
 197 M_M_DQS_DP<8>  DQS8P @BASEBOARD_FAB2_LIB.BASEBOARD_FAB2(SCH_1):M_M_DQS_DP(8)
   8 M_M_DQS_DN<9>  DQS9N @BASEBOARD_FAB2_LIB.BASEBOARD_FAB2(SCH_1):M_M_DQS_DN(9)
   7 M_M_DQS_DP<9>  DQS9P @BASEBOARD_FAB2_LIB.BASEBOARD_FAB2(SCH_1):M_M_DQS_DP(9)


DRAWING: @BASEBOARD_FAB2_LIB.BASEBOARD_FAB2(SCH_1):PAGE88 

SCONN288_H44441003_PIP-SCONN,HA  I25  J9L1
   2    GND VSS<93> @BASEBOARD_FAB2_LIB.BASEBOARD_FAB2(SCH_1):GND
   4    GND VSS<92> @BASEBOARD_FAB2_LIB.BASEBOARD_FAB2(SCH_1):GND
   6    GND VSS<91> @BASEBOARD_FAB2_LIB.BASEBOARD_FAB2(SCH_1):GND
   9    GND VSS<90> @BASEBOARD_FAB2_LIB.BASEBOARD_FAB2(SCH_1):GND
  11    GND VSS<89> @BASEBOARD_FAB2_LIB.BASEBOARD_FAB2(SCH_1):GND
  13    GND VSS<88> @BASEBOARD_FAB2_LIB.BASEBOARD_FAB2(SCH_1):GND
  15    GND VSS<87> @BASEBOARD_FAB2_LIB.BASEBOARD_FAB2(SCH_1):GND
  17    GND VSS<86> @BASEBOARD_FAB2_LIB.BASEBOARD_FAB2(SCH_1):GND
  20    GND VSS<85> @BASEBOARD_FAB2_LIB.BASEBOARD_FAB2(SCH_1):GND
  22    GND VSS<84> @BASEBOARD_FAB2_LIB.BASEBOARD_FAB2(SCH_1):GND
  24    GND VSS<83> @BASEBOARD_FAB2_LIB.BASEBOARD_FAB2(SCH_1):GND
  26    GND VSS<82> @BASEBOARD_FAB2_LIB.BASEBOARD_FAB2(SCH_1):GND
  28    GND VSS<81> @BASEBOARD_FAB2_LIB.BASEBOARD_FAB2(SCH_1):GND
  31    GND VSS<80> @BASEBOARD_FAB2_LIB.BASEBOARD_FAB2(SCH_1):GND
  33    GND VSS<79> @BASEBOARD_FAB2_LIB.BASEBOARD_FAB2(SCH_1):GND
  35    GND VSS<78> @BASEBOARD_FAB2_LIB.BASEBOARD_FAB2(SCH_1):GND
  37    GND VSS<77> @BASEBOARD_FAB2_LIB.BASEBOARD_FAB2(SCH_1):GND
  39    GND VSS<76> @BASEBOARD_FAB2_LIB.BASEBOARD_FAB2(SCH_1):GND
  42    GND VSS<75> @BASEBOARD_FAB2_LIB.BASEBOARD_FAB2(SCH_1):GND
  44    GND VSS<74> @BASEBOARD_FAB2_LIB.BASEBOARD_FAB2(SCH_1):GND
  46    GND VSS<73> @BASEBOARD_FAB2_LIB.BASEBOARD_FAB2(SCH_1):GND
  48    GND VSS<72> @BASEBOARD_FAB2_LIB.BASEBOARD_FAB2(SCH_1):GND
  50    GND VSS<71> @BASEBOARD_FAB2_LIB.BASEBOARD_FAB2(SCH_1):GND
  53    GND VSS<70> @BASEBOARD_FAB2_LIB.BASEBOARD_FAB2(SCH_1):GND
  55    GND VSS<69> @BASEBOARD_FAB2_LIB.BASEBOARD_FAB2(SCH_1):GND
  57    GND VSS<68> @BASEBOARD_FAB2_LIB.BASEBOARD_FAB2(SCH_1):GND
  94    GND VSS<67> @BASEBOARD_FAB2_LIB.BASEBOARD_FAB2(SCH_1):GND
  96    GND VSS<66> @BASEBOARD_FAB2_LIB.BASEBOARD_FAB2(SCH_1):GND
  98    GND VSS<65> @BASEBOARD_FAB2_LIB.BASEBOARD_FAB2(SCH_1):GND
 101    GND VSS<64> @BASEBOARD_FAB2_LIB.BASEBOARD_FAB2(SCH_1):GND
 103    GND VSS<63> @BASEBOARD_FAB2_LIB.BASEBOARD_FAB2(SCH_1):GND
 105    GND VSS<62> @BASEBOARD_FAB2_LIB.BASEBOARD_FAB2(SCH_1):GND
 107    GND VSS<61> @BASEBOARD_FAB2_LIB.BASEBOARD_FAB2(SCH_1):GND
 109    GND VSS<60> @BASEBOARD_FAB2_LIB.BASEBOARD_FAB2(SCH_1):GND
 112    GND VSS<59> @BASEBOARD_FAB2_LIB.BASEBOARD_FAB2(SCH_1):GND
 114    GND VSS<58> @BASEBOARD_FAB2_LIB.BASEBOARD_FAB2(SCH_1):GND
 116    GND VSS<57> @BASEBOARD_FAB2_LIB.BASEBOARD_FAB2(SCH_1):GND
 118    GND VSS<56> @BASEBOARD_FAB2_LIB.BASEBOARD_FAB2(SCH_1):GND
 120    GND VSS<55> @BASEBOARD_FAB2_LIB.BASEBOARD_FAB2(SCH_1):GND
 123    GND VSS<54> @BASEBOARD_FAB2_LIB.BASEBOARD_FAB2(SCH_1):GND
 125    GND VSS<53> @BASEBOARD_FAB2_LIB.BASEBOARD_FAB2(SCH_1):GND
 127    GND VSS<52> @BASEBOARD_FAB2_LIB.BASEBOARD_FAB2(SCH_1):GND
 129    GND VSS<51> @BASEBOARD_FAB2_LIB.BASEBOARD_FAB2(SCH_1):GND
 131    GND VSS<50> @BASEBOARD_FAB2_LIB.BASEBOARD_FAB2(SCH_1):GND
 134    GND VSS<49> @BASEBOARD_FAB2_LIB.BASEBOARD_FAB2(SCH_1):GND
 136    GND VSS<48> @BASEBOARD_FAB2_LIB.BASEBOARD_FAB2(SCH_1):GND
 138    GND VSS<47> @BASEBOARD_FAB2_LIB.BASEBOARD_FAB2(SCH_1):GND
 147    GND VSS<46> @BASEBOARD_FAB2_LIB.BASEBOARD_FAB2(SCH_1):GND
 149    GND VSS<45> @BASEBOARD_FAB2_LIB.BASEBOARD_FAB2(SCH_1):GND
 151    GND VSS<44> @BASEBOARD_FAB2_LIB.BASEBOARD_FAB2(SCH_1):GND
 154    GND VSS<43> @BASEBOARD_FAB2_LIB.BASEBOARD_FAB2(SCH_1):GND
 156    GND VSS<42> @BASEBOARD_FAB2_LIB.BASEBOARD_FAB2(SCH_1):GND
 158    GND VSS<41> @BASEBOARD_FAB2_LIB.BASEBOARD_FAB2(SCH_1):GND
 160    GND VSS<40> @BASEBOARD_FAB2_LIB.BASEBOARD_FAB2(SCH_1):GND
 162    GND VSS<39> @BASEBOARD_FAB2_LIB.BASEBOARD_FAB2(SCH_1):GND
 165    GND VSS<38> @BASEBOARD_FAB2_LIB.BASEBOARD_FAB2(SCH_1):GND
 167    GND VSS<37> @BASEBOARD_FAB2_LIB.BASEBOARD_FAB2(SCH_1):GND
 169    GND VSS<36> @BASEBOARD_FAB2_LIB.BASEBOARD_FAB2(SCH_1):GND
 171    GND VSS<35> @BASEBOARD_FAB2_LIB.BASEBOARD_FAB2(SCH_1):GND
 173    GND VSS<34> @BASEBOARD_FAB2_LIB.BASEBOARD_FAB2(SCH_1):GND
 176    GND VSS<33> @BASEBOARD_FAB2_LIB.BASEBOARD_FAB2(SCH_1):GND
 178    GND VSS<32> @BASEBOARD_FAB2_LIB.BASEBOARD_FAB2(SCH_1):GND
 180    GND VSS<31> @BASEBOARD_FAB2_LIB.BASEBOARD_FAB2(SCH_1):GND
 182    GND VSS<30> @BASEBOARD_FAB2_LIB.BASEBOARD_FAB2(SCH_1):GND
 184    GND VSS<29> @BASEBOARD_FAB2_LIB.BASEBOARD_FAB2(SCH_1):GND
 187    GND VSS<28> @BASEBOARD_FAB2_LIB.BASEBOARD_FAB2(SCH_1):GND
 189    GND VSS<27> @BASEBOARD_FAB2_LIB.BASEBOARD_FAB2(SCH_1):GND
 191    GND VSS<26> @BASEBOARD_FAB2_LIB.BASEBOARD_FAB2(SCH_1):GND
 193    GND VSS<25> @BASEBOARD_FAB2_LIB.BASEBOARD_FAB2(SCH_1):GND
 195    GND VSS<24> @BASEBOARD_FAB2_LIB.BASEBOARD_FAB2(SCH_1):GND
 198    GND VSS<23> @BASEBOARD_FAB2_LIB.BASEBOARD_FAB2(SCH_1):GND
 200    GND VSS<22> @BASEBOARD_FAB2_LIB.BASEBOARD_FAB2(SCH_1):GND
 202    GND VSS<21> @BASEBOARD_FAB2_LIB.BASEBOARD_FAB2(SCH_1):GND
 239    GND VSS<20> @BASEBOARD_FAB2_LIB.BASEBOARD_FAB2(SCH_1):GND
 241    GND VSS<19> @BASEBOARD_FAB2_LIB.BASEBOARD_FAB2(SCH_1):GND
 243    GND VSS<18> @BASEBOARD_FAB2_LIB.BASEBOARD_FAB2(SCH_1):GND
 246    GND VSS<17> @BASEBOARD_FAB2_LIB.BASEBOARD_FAB2(SCH_1):GND
 248    GND VSS<16> @BASEBOARD_FAB2_LIB.BASEBOARD_FAB2(SCH_1):GND
 250    GND VSS<15> @BASEBOARD_FAB2_LIB.BASEBOARD_FAB2(SCH_1):GND
 252    GND VSS<14> @BASEBOARD_FAB2_LIB.BASEBOARD_FAB2(SCH_1):GND
 254    GND VSS<13> @BASEBOARD_FAB2_LIB.BASEBOARD_FAB2(SCH_1):GND
 257    GND VSS<12> @BASEBOARD_FAB2_LIB.BASEBOARD_FAB2(SCH_1):GND
 259    GND VSS<11> @BASEBOARD_FAB2_LIB.BASEBOARD_FAB2(SCH_1):GND
 261    GND VSS<10> @BASEBOARD_FAB2_LIB.BASEBOARD_FAB2(SCH_1):GND
 263    GND VSS<9> @BASEBOARD_FAB2_LIB.BASEBOARD_FAB2(SCH_1):GND
 265    GND VSS<8> @BASEBOARD_FAB2_LIB.BASEBOARD_FAB2(SCH_1):GND
 268    GND VSS<7> @BASEBOARD_FAB2_LIB.BASEBOARD_FAB2(SCH_1):GND
 270    GND VSS<6> @BASEBOARD_FAB2_LIB.BASEBOARD_FAB2(SCH_1):GND
 272    GND VSS<5> @BASEBOARD_FAB2_LIB.BASEBOARD_FAB2(SCH_1):GND
 274    GND VSS<4> @BASEBOARD_FAB2_LIB.BASEBOARD_FAB2(SCH_1):GND
 276    GND VSS<3> @BASEBOARD_FAB2_LIB.BASEBOARD_FAB2(SCH_1):GND
 279    GND VSS<2> @BASEBOARD_FAB2_LIB.BASEBOARD_FAB2(SCH_1):GND
 281    GND VSS<1> @BASEBOARD_FAB2_LIB.BASEBOARD_FAB2(SCH_1):GND
 283    GND VSS<0> @BASEBOARD_FAB2_LIB.BASEBOARD_FAB2(SCH_1):GND

SCONN288_H44441003_PIP-SCONN,HA  I87  J9L1
 152 M_M_DQS_DN<0>  DQS0N @BASEBOARD_FAB2_LIB.BASEBOARD_FAB2(SCH_1):M_M_DQS_DN(0)
 153 M_M_DQS_DP<0>  DQS0P @BASEBOARD_FAB2_LIB.BASEBOARD_FAB2(SCH_1):M_M_DQS_DP(0)
  19 M_M_DQS_DN<10> DQS10N @BASEBOARD_FAB2_LIB.BASEBOARD_FAB2(SCH_1):M_M_DQS_DN(10)
  18 M_M_DQS_DP<10> DQS10P @BASEBOARD_FAB2_LIB.BASEBOARD_FAB2(SCH_1):M_M_DQS_DP(10)
  30 M_M_DQS_DN<11> DQS11N @BASEBOARD_FAB2_LIB.BASEBOARD_FAB2(SCH_1):M_M_DQS_DN(11)
  29 M_M_DQS_DP<11> DQS11P @BASEBOARD_FAB2_LIB.BASEBOARD_FAB2(SCH_1):M_M_DQS_DP(11)
  41 M_M_DQS_DN<12> DQS12N @BASEBOARD_FAB2_LIB.BASEBOARD_FAB2(SCH_1):M_M_DQS_DN(12)
  40 M_M_DQS_DP<12> DQS12P @BASEBOARD_FAB2_LIB.BASEBOARD_FAB2(SCH_1):M_M_DQS_DP(12)
 100 M_M_DQS_DN<13> DQS13N @BASEBOARD_FAB2_LIB.BASEBOARD_FAB2(SCH_1):M_M_DQS_DN(13)
  99 M_M_DQS_DP<13> DQS13P @BASEBOARD_FAB2_LIB.BASEBOARD_FAB2(SCH_1):M_M_DQS_DP(13)
 111 M_M_DQS_DN<14> DQS14N @BASEBOARD_FAB2_LIB.BASEBOARD_FAB2(SCH_1):M_M_DQS_DN(14)
 110 M_M_DQS_DP<14> DQS14P @BASEBOARD_FAB2_LIB.BASEBOARD_FAB2(SCH_1):M_M_DQS_DP(14)
 122 M_M_DQS_DN<15> DQS15N @BASEBOARD_FAB2_LIB.BASEBOARD_FAB2(SCH_1):M_M_DQS_DN(15)
 121 M_M_DQS_DP<15> DQS15P @BASEBOARD_FAB2_LIB.BASEBOARD_FAB2(SCH_1):M_M_DQS_DP(15)
 133 M_M_DQS_DN<16> DQS16N @BASEBOARD_FAB2_LIB.BASEBOARD_FAB2(SCH_1):M_M_DQS_DN(16)
 132 M_M_DQS_DP<16> DQS16P @BASEBOARD_FAB2_LIB.BASEBOARD_FAB2(SCH_1):M_M_DQS_DP(16)
  52 M_M_DQS_DN<17> DQS17N @BASEBOARD_FAB2_LIB.BASEBOARD_FAB2(SCH_1):M_M_DQS_DN(17)
  51 M_M_DQS_DP<17> DQS17P @BASEBOARD_FAB2_LIB.BASEBOARD_FAB2(SCH_1):M_M_DQS_DP(17)
 163 M_M_DQS_DN<1>  DQS1N @BASEBOARD_FAB2_LIB.BASEBOARD_FAB2(SCH_1):M_M_DQS_DN(1)
 164 M_M_DQS_DP<1>  DQS1P @BASEBOARD_FAB2_LIB.BASEBOARD_FAB2(SCH_1):M_M_DQS_DP(1)
 174 M_M_DQS_DN<2>  DQS2N @BASEBOARD_FAB2_LIB.BASEBOARD_FAB2(SCH_1):M_M_DQS_DN(2)
 175 M_M_DQS_DP<2>  DQS2P @BASEBOARD_FAB2_LIB.BASEBOARD_FAB2(SCH_1):M_M_DQS_DP(2)
 185 M_M_DQS_DN<3>  DQS3N @BASEBOARD_FAB2_LIB.BASEBOARD_FAB2(SCH_1):M_M_DQS_DN(3)
 186 M_M_DQS_DP<3>  DQS3P @BASEBOARD_FAB2_LIB.BASEBOARD_FAB2(SCH_1):M_M_DQS_DP(3)
 244 M_M_DQS_DN<4>  DQS4N @BASEBOARD_FAB2_LIB.BASEBOARD_FAB2(SCH_1):M_M_DQS_DN(4)
 245 M_M_DQS_DP<4>  DQS4P @BASEBOARD_FAB2_LIB.BASEBOARD_FAB2(SCH_1):M_M_DQS_DP(4)
 255 M_M_DQS_DN<5>  DQS5N @BASEBOARD_FAB2_LIB.BASEBOARD_FAB2(SCH_1):M_M_DQS_DN(5)
 256 M_M_DQS_DP<5>  DQS5P @BASEBOARD_FAB2_LIB.BASEBOARD_FAB2(SCH_1):M_M_DQS_DP(5)
 266 M_M_DQS_DN<6>  DQS6N @BASEBOARD_FAB2_LIB.BASEBOARD_FAB2(SCH_1):M_M_DQS_DN(6)
 267 M_M_DQS_DP<6>  DQS6P @BASEBOARD_FAB2_LIB.BASEBOARD_FAB2(SCH_1):M_M_DQS_DP(6)
 277 M_M_DQS_DN<7>  DQS7N @BASEBOARD_FAB2_LIB.BASEBOARD_FAB2(SCH_1):M_M_DQS_DN(7)
 278 M_M_DQS_DP<7>  DQS7P @BASEBOARD_FAB2_LIB.BASEBOARD_FAB2(SCH_1):M_M_DQS_DP(7)
 196 M_M_DQS_DN<8>  DQS8N @BASEBOARD_FAB2_LIB.BASEBOARD_FAB2(SCH_1):M_M_DQS_DN(8)
 197 M_M_DQS_DP<8>  DQS8P @BASEBOARD_FAB2_LIB.BASEBOARD_FAB2(SCH_1):M_M_DQS_DP(8)
   8 M_M_DQS_DN<9>  DQS9N @BASEBOARD_FAB2_LIB.BASEBOARD_FAB2(SCH_1):M_M_DQS_DN(9)
   7 M_M_DQS_DP<9>  DQS9P @BASEBOARD_FAB2_LIB.BASEBOARD_FAB2(SCH_1):M_M_DQS_DP(9)

SCONN288_H44441003_PIP-SCONN,HA  I111  J9L1
  79 M_M_MA<0>     A0 @BASEBOARD_FAB2_LIB.BASEBOARD_FAB2(SCH_1):M_M_MA(0)
  72 M_M_MA<1>     A1 @BASEBOARD_FAB2_LIB.BASEBOARD_FAB2(SCH_1):M_M_MA(1)
 225 M_M_MA<10>    A10 @BASEBOARD_FAB2_LIB.BASEBOARD_FAB2(SCH_1):M_M_MA(10)
 210 M_M_MA<11>    A11 @BASEBOARD_FAB2_LIB.BASEBOARD_FAB2(SCH_1):M_M_MA(11)
  65 M_M_MA<12>    A12 @BASEBOARD_FAB2_LIB.BASEBOARD_FAB2(SCH_1):M_M_MA(12)
 232 M_M_MA<13>    A13 @BASEBOARD_FAB2_LIB.BASEBOARD_FAB2(SCH_1):M_M_MA(13)
 228 M_M_MA<14> A14_WE_N @BASEBOARD_FAB2_LIB.BASEBOARD_FAB2(SCH_1):M_M_MA(14)
  86 M_M_MA<15> A15_CAS_N @BASEBOARD_FAB2_LIB.BASEBOARD_FAB2(SCH_1):M_M_MA(15)
  82 M_M_MA<16> A16_RAS_N @BASEBOARD_FAB2_LIB.BASEBOARD_FAB2(SCH_1):M_M_MA(16)
 234 M_M_MA<17>    A17 @BASEBOARD_FAB2_LIB.BASEBOARD_FAB2(SCH_1):M_M_MA(17)
 216 M_M_MA<2>     A2 @BASEBOARD_FAB2_LIB.BASEBOARD_FAB2(SCH_1):M_M_MA(2)
  71 M_M_MA<3>     A3 @BASEBOARD_FAB2_LIB.BASEBOARD_FAB2(SCH_1):M_M_MA(3)
 214 M_M_MA<4>     A4 @BASEBOARD_FAB2_LIB.BASEBOARD_FAB2(SCH_1):M_M_MA(4)
 213 M_M_MA<5>     A5 @BASEBOARD_FAB2_LIB.BASEBOARD_FAB2(SCH_1):M_M_MA(5)
  69 M_M_MA<6>     A6 @BASEBOARD_FAB2_LIB.BASEBOARD_FAB2(SCH_1):M_M_MA(6)
 211 M_M_MA<7>     A7 @BASEBOARD_FAB2_LIB.BASEBOARD_FAB2(SCH_1):M_M_MA(7)
  68 M_M_MA<8>     A8 @BASEBOARD_FAB2_LIB.BASEBOARD_FAB2(SCH_1):M_M_MA(8)
  66 M_M_MA<9>     A9 @BASEBOARD_FAB2_LIB.BASEBOARD_FAB2(SCH_1):M_M_MA(9)
  62 M_M_ACT_N  ACT_N @BASEBOARD_FAB2_LIB.BASEBOARD_FAB2(SCH_1):M_M_ACT_N
 208 M_M_ALERT_N ALERT_N @BASEBOARD_FAB2_LIB.BASEBOARD_FAB2(SCH_1):M_M_ALERT_N
 224 M_M_BA<1>  BA<1> @BASEBOARD_FAB2_LIB.BASEBOARD_FAB2(SCH_1):M_M_BA(1)
  81 M_M_BA<0>  BA<0> @BASEBOARD_FAB2_LIB.BASEBOARD_FAB2(SCH_1):M_M_BA(0)
 207 M_M_BG<1>  BG<1> @BASEBOARD_FAB2_LIB.BASEBOARD_FAB2(SCH_1):M_M_BG(1)
  63 M_M_BG<0>  BG<0> @BASEBOARD_FAB2_LIB.BASEBOARD_FAB2(SCH_1):M_M_BG(0)
 235 M_M_C<2>   C<2> @BASEBOARD_FAB2_LIB.BASEBOARD_FAB2(SCH_1):M_M_C(2)
 199 M_M_ECC<7>  CB<7> @BASEBOARD_FAB2_LIB.BASEBOARD_FAB2(SCH_1):M_M_ECC(7)
  54 M_M_ECC<6>  CB<6> @BASEBOARD_FAB2_LIB.BASEBOARD_FAB2(SCH_1):M_M_ECC(6)
 192 M_M_ECC<5>  CB<5> @BASEBOARD_FAB2_LIB.BASEBOARD_FAB2(SCH_1):M_M_ECC(5)
  47 M_M_ECC<4>  CB<4> @BASEBOARD_FAB2_LIB.BASEBOARD_FAB2(SCH_1):M_M_ECC(4)
 201 M_M_ECC<3>  CB<3> @BASEBOARD_FAB2_LIB.BASEBOARD_FAB2(SCH_1):M_M_ECC(3)
  56 M_M_ECC<2>  CB<2> @BASEBOARD_FAB2_LIB.BASEBOARD_FAB2(SCH_1):M_M_ECC(2)
 194 M_M_ECC<1>  CB<1> @BASEBOARD_FAB2_LIB.BASEBOARD_FAB2(SCH_1):M_M_ECC(1)
  49 M_M_ECC<0>  CB<0> @BASEBOARD_FAB2_LIB.BASEBOARD_FAB2(SCH_1):M_M_ECC(0)
  75 M_M_CLK_DN<2>   CK0N @BASEBOARD_FAB2_LIB.BASEBOARD_FAB2(SCH_1):M_M_CLK_DN(2)
  74 M_M_CLK_DP<2>   CK0P @BASEBOARD_FAB2_LIB.BASEBOARD_FAB2(SCH_1):M_M_CLK_DP(2)
 219 M_M_CLK_DN<3>   CK1N @BASEBOARD_FAB2_LIB.BASEBOARD_FAB2(SCH_1):M_M_CLK_DN(3)
 218 M_M_CLK_DP<3>   CK1P @BASEBOARD_FAB2_LIB.BASEBOARD_FAB2(SCH_1):M_M_CLK_DP(3)
 203 M_M_CKE<3> CKE<1> @BASEBOARD_FAB2_LIB.BASEBOARD_FAB2(SCH_1):M_M_CKE(3)
  60 M_M_CKE<2> CKE<0> @BASEBOARD_FAB2_LIB.BASEBOARD_FAB2(SCH_1):M_M_CKE(2)
 280 M_M_DQ<63> DQ<63> @BASEBOARD_FAB2_LIB.BASEBOARD_FAB2(SCH_1):M_M_DQ(63)
 135 M_M_DQ<62> DQ<62> @BASEBOARD_FAB2_LIB.BASEBOARD_FAB2(SCH_1):M_M_DQ(62)
 273 M_M_DQ<61> DQ<61> @BASEBOARD_FAB2_LIB.BASEBOARD_FAB2(SCH_1):M_M_DQ(61)
 128 M_M_DQ<60> DQ<60> @BASEBOARD_FAB2_LIB.BASEBOARD_FAB2(SCH_1):M_M_DQ(60)
 282 M_M_DQ<59> DQ<59> @BASEBOARD_FAB2_LIB.BASEBOARD_FAB2(SCH_1):M_M_DQ(59)
 137 M_M_DQ<58> DQ<58> @BASEBOARD_FAB2_LIB.BASEBOARD_FAB2(SCH_1):M_M_DQ(58)
 275 M_M_DQ<57> DQ<57> @BASEBOARD_FAB2_LIB.BASEBOARD_FAB2(SCH_1):M_M_DQ(57)
 130 M_M_DQ<56> DQ<56> @BASEBOARD_FAB2_LIB.BASEBOARD_FAB2(SCH_1):M_M_DQ(56)
 269 M_M_DQ<55> DQ<55> @BASEBOARD_FAB2_LIB.BASEBOARD_FAB2(SCH_1):M_M_DQ(55)
 124 M_M_DQ<54> DQ<54> @BASEBOARD_FAB2_LIB.BASEBOARD_FAB2(SCH_1):M_M_DQ(54)
 262 M_M_DQ<53> DQ<53> @BASEBOARD_FAB2_LIB.BASEBOARD_FAB2(SCH_1):M_M_DQ(53)
 117 M_M_DQ<52> DQ<52> @BASEBOARD_FAB2_LIB.BASEBOARD_FAB2(SCH_1):M_M_DQ(52)
 271 M_M_DQ<51> DQ<51> @BASEBOARD_FAB2_LIB.BASEBOARD_FAB2(SCH_1):M_M_DQ(51)
 126 M_M_DQ<50> DQ<50> @BASEBOARD_FAB2_LIB.BASEBOARD_FAB2(SCH_1):M_M_DQ(50)
 264 M_M_DQ<49> DQ<49> @BASEBOARD_FAB2_LIB.BASEBOARD_FAB2(SCH_1):M_M_DQ(49)
 119 M_M_DQ<48> DQ<48> @BASEBOARD_FAB2_LIB.BASEBOARD_FAB2(SCH_1):M_M_DQ(48)
 258 M_M_DQ<47> DQ<47> @BASEBOARD_FAB2_LIB.BASEBOARD_FAB2(SCH_1):M_M_DQ(47)
 113 M_M_DQ<46> DQ<46> @BASEBOARD_FAB2_LIB.BASEBOARD_FAB2(SCH_1):M_M_DQ(46)
 251 M_M_DQ<45> DQ<45> @BASEBOARD_FAB2_LIB.BASEBOARD_FAB2(SCH_1):M_M_DQ(45)
 106 M_M_DQ<44> DQ<44> @BASEBOARD_FAB2_LIB.BASEBOARD_FAB2(SCH_1):M_M_DQ(44)
 260 M_M_DQ<43> DQ<43> @BASEBOARD_FAB2_LIB.BASEBOARD_FAB2(SCH_1):M_M_DQ(43)
 115 M_M_DQ<42> DQ<42> @BASEBOARD_FAB2_LIB.BASEBOARD_FAB2(SCH_1):M_M_DQ(42)
 253 M_M_DQ<41> DQ<41> @BASEBOARD_FAB2_LIB.BASEBOARD_FAB2(SCH_1):M_M_DQ(41)
 108 M_M_DQ<40> DQ<40> @BASEBOARD_FAB2_LIB.BASEBOARD_FAB2(SCH_1):M_M_DQ(40)
 247 M_M_DQ<39> DQ<39> @BASEBOARD_FAB2_LIB.BASEBOARD_FAB2(SCH_1):M_M_DQ(39)
 102 M_M_DQ<38> DQ<38> @BASEBOARD_FAB2_LIB.BASEBOARD_FAB2(SCH_1):M_M_DQ(38)
 240 M_M_DQ<37> DQ<37> @BASEBOARD_FAB2_LIB.BASEBOARD_FAB2(SCH_1):M_M_DQ(37)
  95 M_M_DQ<36> DQ<36> @BASEBOARD_FAB2_LIB.BASEBOARD_FAB2(SCH_1):M_M_DQ(36)
 249 M_M_DQ<35> DQ<35> @BASEBOARD_FAB2_LIB.BASEBOARD_FAB2(SCH_1):M_M_DQ(35)
 104 M_M_DQ<34> DQ<34> @BASEBOARD_FAB2_LIB.BASEBOARD_FAB2(SCH_1):M_M_DQ(34)
 242 M_M_DQ<33> DQ<33> @BASEBOARD_FAB2_LIB.BASEBOARD_FAB2(SCH_1):M_M_DQ(33)
  97 M_M_DQ<32> DQ<32> @BASEBOARD_FAB2_LIB.BASEBOARD_FAB2(SCH_1):M_M_DQ(32)
 188 M_M_DQ<31> DQ<31> @BASEBOARD_FAB2_LIB.BASEBOARD_FAB2(SCH_1):M_M_DQ(31)
  43 M_M_DQ<30> DQ<30> @BASEBOARD_FAB2_LIB.BASEBOARD_FAB2(SCH_1):M_M_DQ(30)
 181 M_M_DQ<29> DQ<29> @BASEBOARD_FAB2_LIB.BASEBOARD_FAB2(SCH_1):M_M_DQ(29)
  36 M_M_DQ<28> DQ<28> @BASEBOARD_FAB2_LIB.BASEBOARD_FAB2(SCH_1):M_M_DQ(28)
 190 M_M_DQ<27> DQ<27> @BASEBOARD_FAB2_LIB.BASEBOARD_FAB2(SCH_1):M_M_DQ(27)
  45 M_M_DQ<26> DQ<26> @BASEBOARD_FAB2_LIB.BASEBOARD_FAB2(SCH_1):M_M_DQ(26)
 183 M_M_DQ<25> DQ<25> @BASEBOARD_FAB2_LIB.BASEBOARD_FAB2(SCH_1):M_M_DQ(25)
  38 M_M_DQ<24> DQ<24> @BASEBOARD_FAB2_LIB.BASEBOARD_FAB2(SCH_1):M_M_DQ(24)
 177 M_M_DQ<23> DQ<23> @BASEBOARD_FAB2_LIB.BASEBOARD_FAB2(SCH_1):M_M_DQ(23)
  32 M_M_DQ<22> DQ<22> @BASEBOARD_FAB2_LIB.BASEBOARD_FAB2(SCH_1):M_M_DQ(22)
 170 M_M_DQ<21> DQ<21> @BASEBOARD_FAB2_LIB.BASEBOARD_FAB2(SCH_1):M_M_DQ(21)
  25 M_M_DQ<20> DQ<20> @BASEBOARD_FAB2_LIB.BASEBOARD_FAB2(SCH_1):M_M_DQ(20)
 179 M_M_DQ<19> DQ<19> @BASEBOARD_FAB2_LIB.BASEBOARD_FAB2(SCH_1):M_M_DQ(19)
  34 M_M_DQ<18> DQ<18> @BASEBOARD_FAB2_LIB.BASEBOARD_FAB2(SCH_1):M_M_DQ(18)
 172 M_M_DQ<17> DQ<17> @BASEBOARD_FAB2_LIB.BASEBOARD_FAB2(SCH_1):M_M_DQ(17)
  27 M_M_DQ<16> DQ<16> @BASEBOARD_FAB2_LIB.BASEBOARD_FAB2(SCH_1):M_M_DQ(16)
 166 M_M_DQ<15> DQ<15> @BASEBOARD_FAB2_LIB.BASEBOARD_FAB2(SCH_1):M_M_DQ(15)
  21 M_M_DQ<14> DQ<14> @BASEBOARD_FAB2_LIB.BASEBOARD_FAB2(SCH_1):M_M_DQ(14)
 159 M_M_DQ<13> DQ<13> @BASEBOARD_FAB2_LIB.BASEBOARD_FAB2(SCH_1):M_M_DQ(13)
  14 M_M_DQ<12> DQ<12> @BASEBOARD_FAB2_LIB.BASEBOARD_FAB2(SCH_1):M_M_DQ(12)
 168 M_M_DQ<11> DQ<11> @BASEBOARD_FAB2_LIB.BASEBOARD_FAB2(SCH_1):M_M_DQ(11)
  23 M_M_DQ<10> DQ<10> @BASEBOARD_FAB2_LIB.BASEBOARD_FAB2(SCH_1):M_M_DQ(10)
 161 M_M_DQ<9>  DQ<9> @BASEBOARD_FAB2_LIB.BASEBOARD_FAB2(SCH_1):M_M_DQ(9)
  16 M_M_DQ<8>  DQ<8> @BASEBOARD_FAB2_LIB.BASEBOARD_FAB2(SCH_1):M_M_DQ(8)
 155 M_M_DQ<7>  DQ<7> @BASEBOARD_FAB2_LIB.BASEBOARD_FAB2(SCH_1):M_M_DQ(7)
  10 M_M_DQ<6>  DQ<6> @BASEBOARD_FAB2_LIB.BASEBOARD_FAB2(SCH_1):M_M_DQ(6)
 148 M_M_DQ<5>  DQ<5> @BASEBOARD_FAB2_LIB.BASEBOARD_FAB2(SCH_1):M_M_DQ(5)
   3 M_M_DQ<4>  DQ<4> @BASEBOARD_FAB2_LIB.BASEBOARD_FAB2(SCH_1):M_M_DQ(4)
 157 M_M_DQ<3>  DQ<3> @BASEBOARD_FAB2_LIB.BASEBOARD_FAB2(SCH_1):M_M_DQ(3)
  12 M_M_DQ<2>  DQ<2> @BASEBOARD_FAB2_LIB.BASEBOARD_FAB2(SCH_1):M_M_DQ(2)
 150 M_M_DQ<1>  DQ<1> @BASEBOARD_FAB2_LIB.BASEBOARD_FAB2(SCH_1):M_M_DQ(1)
   5 M_M_DQ<0>  DQ<0> @BASEBOARD_FAB2_LIB.BASEBOARD_FAB2(SCH_1):M_M_DQ(0)
  78 FM_DIMM_EVENT_COD_N EVENT_N @BASEBOARD_FAB2_LIB.BASEBOARD_FAB2(SCH_1):FM_DIMM_EVENT_COD_N
  91 M_M_ODT<3> ODT<1> @BASEBOARD_FAB2_LIB.BASEBOARD_FAB2(SCH_1):M_M_ODT(3)
  87 M_M_ODT<2> ODT<0> @BASEBOARD_FAB2_LIB.BASEBOARD_FAB2(SCH_1):M_M_ODT(2)
 222 M_M_PAR    PAR @BASEBOARD_FAB2_LIB.BASEBOARD_FAB2(SCH_1):M_M_PAR
  58 M_KLM_RST_N RESET_N @BASEBOARD_FAB2_LIB.BASEBOARD_FAB2(SCH_1):M_KLM_RST_N
 144 TP_CH_M_DIMM_M1_RFU_2 RFU<2> @BASEBOARD_FAB2_LIB.BASEBOARD_FAB2(SCH_1):TP_CH_M_DIMM_M1_RFU_2
 227 TP_CH_M_DIMM_M1_RFU_1 RFU<1> @BASEBOARD_FAB2_LIB.BASEBOARD_FAB2(SCH_1):TP_CH_M_DIMM_M1_RFU_1
 205 TP_CH_M_DIMM_M1_RFU_0 RFU<0> @BASEBOARD_FAB2_LIB.BASEBOARD_FAB2(SCH_1):TP_CH_M_DIMM_M1_RFU_0
  84 M_M_CS_N<4>   S0_N @BASEBOARD_FAB2_LIB.BASEBOARD_FAB2(SCH_1):M_M_CS_N(4)
  89 M_M_CS_N<5>   S1_N @BASEBOARD_FAB2_LIB.BASEBOARD_FAB2(SCH_1):M_M_CS_N(5)
  93 M_M_CS_N<6> S2_N_C<0> @BASEBOARD_FAB2_LIB.BASEBOARD_FAB2(SCH_1):M_M_CS_N(6)
 237 M_M_CS_N<7> S3_N_C<1> @BASEBOARD_FAB2_LIB.BASEBOARD_FAB2(SCH_1):M_M_CS_N(7)
 238 PVPP_KLM  SA<2> @BASEBOARD_FAB2_LIB.BASEBOARD_FAB2(SCH_1):PVPP_KLM
 140    GND  SA<1> @BASEBOARD_FAB2_LIB.BASEBOARD_FAB2(SCH_1):GND
 139 PVPP_KLM  SA<0> @BASEBOARD_FAB2_LIB.BASEBOARD_FAB2(SCH_1):PVPP_KLM
 230 FM_ADR_COMPLETE_KLM_N SAVE_N_NC @BASEBOARD_FAB2_LIB.BASEBOARD_FAB2(SCH_1):FM_ADR_COMPLETE_KLM_N
 141 SMB_DDR_KLM_VPP_SCL    SCL @BASEBOARD_FAB2_LIB.BASEBOARD_FAB2(SCH_1):SMB_DDR_KLM_VPP_SCL
 285 SMB_DDR_KLM_VPP_SDA    SDA @BASEBOARD_FAB2_LIB.BASEBOARD_FAB2(SCH_1):SMB_DDR_KLM_VPP_SDA
 284 PVPP_KLM VDDSPD @BASEBOARD_FAB2_LIB.BASEBOARD_FAB2(SCH_1):PVPP_KLM
 146 M_M_VREF VREFCA @BASEBOARD_FAB2_LIB.BASEBOARD_FAB2(SCH_1):M_M_VREF

SCONN288_H44441003_PIP-SCONN,HA  I168  J9L1
   1 P12V_NVDIMM_KLM 12V<1> @BASEBOARD_FAB2_LIB.BASEBOARD_FAB2(SCH_1):P12V_NVDIMM_KLM
 145 P12V_NVDIMM_KLM 12V<0> @BASEBOARD_FAB2_LIB.BASEBOARD_FAB2(SCH_1):P12V_NVDIMM_KLM
  59 PVDDQ_KLM VDD<25> @BASEBOARD_FAB2_LIB.BASEBOARD_FAB2(SCH_1):PVDDQ_KLM
  61 PVDDQ_KLM VDD<24> @BASEBOARD_FAB2_LIB.BASEBOARD_FAB2(SCH_1):PVDDQ_KLM
  64 PVDDQ_KLM VDD<23> @BASEBOARD_FAB2_LIB.BASEBOARD_FAB2(SCH_1):PVDDQ_KLM
  67 PVDDQ_KLM VDD<22> @BASEBOARD_FAB2_LIB.BASEBOARD_FAB2(SCH_1):PVDDQ_KLM
  70 PVDDQ_KLM VDD<21> @BASEBOARD_FAB2_LIB.BASEBOARD_FAB2(SCH_1):PVDDQ_KLM
  73 PVDDQ_KLM VDD<20> @BASEBOARD_FAB2_LIB.BASEBOARD_FAB2(SCH_1):PVDDQ_KLM
  76 PVDDQ_KLM VDD<19> @BASEBOARD_FAB2_LIB.BASEBOARD_FAB2(SCH_1):PVDDQ_KLM
  80 PVDDQ_KLM VDD<18> @BASEBOARD_FAB2_LIB.BASEBOARD_FAB2(SCH_1):PVDDQ_KLM
  83 PVDDQ_KLM VDD<17> @BASEBOARD_FAB2_LIB.BASEBOARD_FAB2(SCH_1):PVDDQ_KLM
  85 PVDDQ_KLM VDD<16> @BASEBOARD_FAB2_LIB.BASEBOARD_FAB2(SCH_1):PVDDQ_KLM
  88 PVDDQ_KLM VDD<15> @BASEBOARD_FAB2_LIB.BASEBOARD_FAB2(SCH_1):PVDDQ_KLM
  90 PVDDQ_KLM VDD<14> @BASEBOARD_FAB2_LIB.BASEBOARD_FAB2(SCH_1):PVDDQ_KLM
  92 PVDDQ_KLM VDD<13> @BASEBOARD_FAB2_LIB.BASEBOARD_FAB2(SCH_1):PVDDQ_KLM
 204 PVDDQ_KLM VDD<12> @BASEBOARD_FAB2_LIB.BASEBOARD_FAB2(SCH_1):PVDDQ_KLM
 206 PVDDQ_KLM VDD<11> @BASEBOARD_FAB2_LIB.BASEBOARD_FAB2(SCH_1):PVDDQ_KLM
 209 PVDDQ_KLM VDD<10> @BASEBOARD_FAB2_LIB.BASEBOARD_FAB2(SCH_1):PVDDQ_KLM
 212 PVDDQ_KLM VDD<9> @BASEBOARD_FAB2_LIB.BASEBOARD_FAB2(SCH_1):PVDDQ_KLM
 215 PVDDQ_KLM VDD<8> @BASEBOARD_FAB2_LIB.BASEBOARD_FAB2(SCH_1):PVDDQ_KLM
 217 PVDDQ_KLM VDD<7> @BASEBOARD_FAB2_LIB.BASEBOARD_FAB2(SCH_1):PVDDQ_KLM
 220 PVDDQ_KLM VDD<6> @BASEBOARD_FAB2_LIB.BASEBOARD_FAB2(SCH_1):PVDDQ_KLM
 223 PVDDQ_KLM VDD<5> @BASEBOARD_FAB2_LIB.BASEBOARD_FAB2(SCH_1):PVDDQ_KLM
 226 PVDDQ_KLM VDD<4> @BASEBOARD_FAB2_LIB.BASEBOARD_FAB2(SCH_1):PVDDQ_KLM
 229 PVDDQ_KLM VDD<3> @BASEBOARD_FAB2_LIB.BASEBOARD_FAB2(SCH_1):PVDDQ_KLM
 231 PVDDQ_KLM VDD<2> @BASEBOARD_FAB2_LIB.BASEBOARD_FAB2(SCH_1):PVDDQ_KLM
 233 PVDDQ_KLM VDD<1> @BASEBOARD_FAB2_LIB.BASEBOARD_FAB2(SCH_1):PVDDQ_KLM
 236 PVDDQ_KLM VDD<0> @BASEBOARD_FAB2_LIB.BASEBOARD_FAB2(SCH_1):PVDDQ_KLM
 142 PVPP_KLM VPP<4> @BASEBOARD_FAB2_LIB.BASEBOARD_FAB2(SCH_1):PVPP_KLM
 143 PVPP_KLM VPP<3> @BASEBOARD_FAB2_LIB.BASEBOARD_FAB2(SCH_1):PVPP_KLM
 288 PVPP_KLM VPP<2> @BASEBOARD_FAB2_LIB.BASEBOARD_FAB2(SCH_1):PVPP_KLM
 286 PVPP_KLM VPP<1> @BASEBOARD_FAB2_LIB.BASEBOARD_FAB2(SCH_1):PVPP_KLM
 287 PVPP_KLM VPP<0> @BASEBOARD_FAB2_LIB.BASEBOARD_FAB2(SCH_1):PVPP_KLM
  77 PVTT_KLM VTT<1> @BASEBOARD_FAB2_LIB.BASEBOARD_FAB2(SCH_1):PVTT_KLM
 221 PVTT_KLM VTT<0> @BASEBOARD_FAB2_LIB.BASEBOARD_FAB2(SCH_1):PVTT_KLM

CAP_A_0402V-0.01UF,25V,10%,X7RA  I177  C9L1
   1 M_M_VREF      A @BASEBOARD_FAB2_LIB.BASEBOARD_FAB2(SCH_1):M_M_VREF
   2    GND      B @BASEBOARD_FAB2_LIB.BASEBOARD_FAB2(SCH_1):GND


DRAWING: @BASEBOARD_FAB2_LIB.BASEBOARD_FAB2(SCH_1):PAGE89 

RES_0402-0.0,5%,1/16W,EMPTY,G2A  I1  R4T2
   1 FM_ADR_COMPLETE      A @BASEBOARD_FAB2_LIB.BASEBOARD_FAB2(SCH_1):FM_ADR_COMPLETE
   2 FM_ADR_COMPLETE_R      B @BASEBOARD_FAB2_LIB.BASEBOARD_FAB2(SCH_1):FM_ADR_COMPLETE_R

RES_0402-0.0,5%,1/16W,CHIP,G21A  I2  R4T1
   1 FM_ADR_COMPLETE_DLY      A @BASEBOARD_FAB2_LIB.BASEBOARD_FAB2(SCH_1):FM_ADR_COMPLETE_DLY
   2 FM_ADR_COMPLETE_R      B @BASEBOARD_FAB2_LIB.BASEBOARD_FAB2(SCH_1):FM_ADR_COMPLETE_R

RES_0402-49.9,1%,1/16W,CHIP,G2A  I3  R6F4
   1 IRQ_DIMM_SAVE_N      A @BASEBOARD_FAB2_LIB.BASEBOARD_FAB2(SCH_1):IRQ_DIMM_SAVE_N
   2 FM_ADR_COMPLETE_ABC_N      B @BASEBOARD_FAB2_LIB.BASEBOARD_FAB2(SCH_1):FM_ADR_COMPLETE_ABC_N

RES_0402-49.9,1%,1/16W,CHIP,G2A  I4  R6F1
   1 IRQ_DIMM_SAVE_N      A @BASEBOARD_FAB2_LIB.BASEBOARD_FAB2(SCH_1):IRQ_DIMM_SAVE_N
   2 FM_ADR_COMPLETE_DEF_N      B @BASEBOARD_FAB2_LIB.BASEBOARD_FAB2(SCH_1):FM_ADR_COMPLETE_DEF_N

RES_0402-49.9,1%,1/16W,CHIP,G2A  I5  R6F5
   1 FM_ADR_COMPLETE_CPU1_N      A @BASEBOARD_FAB2_LIB.BASEBOARD_FAB2(SCH_1):FM_ADR_COMPLETE_CPU1_N
   2 FM_ADR_COMPLETE_GHJ_N      B @BASEBOARD_FAB2_LIB.BASEBOARD_FAB2(SCH_1):FM_ADR_COMPLETE_GHJ_N

RES_0402-49.9,1%,1/16W,CHIP,G2A  I6  R6F2
   1 FM_ADR_COMPLETE_CPU1_N      A @BASEBOARD_FAB2_LIB.BASEBOARD_FAB2(SCH_1):FM_ADR_COMPLETE_CPU1_N
   2 FM_ADR_COMPLETE_KLM_N      B @BASEBOARD_FAB2_LIB.BASEBOARD_FAB2(SCH_1):FM_ADR_COMPLETE_KLM_N

RES_0402-10.0K,1%,1/16W,CHIP,GA  I7  R6F3
   1 PVPP_ABC      A @BASEBOARD_FAB2_LIB.BASEBOARD_FAB2(SCH_1):PVPP_ABC
   2 IRQ_DIMM_SAVE_N      B @BASEBOARD_FAB2_LIB.BASEBOARD_FAB2(SCH_1):IRQ_DIMM_SAVE_N

RES_0402-0.0,5%,1/16W,EMPTY,G2A  I23  R2P12
   1 IRQ_DIMM_SAVE_LVT3_N      A @BASEBOARD_FAB2_LIB.BASEBOARD_FAB2(SCH_1):IRQ_DIMM_SAVE_LVT3_N
   2 FM_ADR_SMI_GPIO_N      B @BASEBOARD_FAB2_LIB.BASEBOARD_FAB2(SCH_1):FM_ADR_SMI_GPIO_N

RES_0402-4.75K,1%,1/16W,CHIP,GA  I26  R8D29
   1 P3V3_STBY      A @BASEBOARD_FAB2_LIB.BASEBOARD_FAB2(SCH_1):P3V3_STBY
   2 IRQ_DIMM_SAVE_LVT3      B @BASEBOARD_FAB2_LIB.BASEBOARD_FAB2(SCH_1):IRQ_DIMM_SAVE_LVT3

RES_0402-4.75K,1%,1/16W,CHIP,GA  I27  R8D31
   1 P3V3_STBY      A @BASEBOARD_FAB2_LIB.BASEBOARD_FAB2(SCH_1):P3V3_STBY
   2 IRQ_DIMM_SAVE_LVT3_N      B @BASEBOARD_FAB2_LIB.BASEBOARD_FAB2(SCH_1):IRQ_DIMM_SAVE_LVT3_N

RES_0402-10.0K,1%,1/16W,CHIP,GA  I34  R8D30
   1 IRQ_DIMM_SAVE_N      A @BASEBOARD_FAB2_LIB.BASEBOARD_FAB2(SCH_1):IRQ_DIMM_SAVE_N
   2 IRQ_DIMM_SAVE_R_N      B @BASEBOARD_FAB2_LIB.BASEBOARD_FAB2(SCH_1):IRQ_DIMM_SAVE_R_N

NPN_DUAL_SSOPLF-MBT3904,XSTR,CA  I35  Q8D1
   5 IRQ_DIMM_SAVE_R_N   B<0> @BASEBOARD_FAB2_LIB.BASEBOARD_FAB2(SCH_1):IRQ_DIMM_SAVE_R_N
   3 IRQ_DIMM_SAVE_LVT3   C<0> @BASEBOARD_FAB2_LIB.BASEBOARD_FAB2(SCH_1):IRQ_DIMM_SAVE_LVT3
   4    GND   E<0> @BASEBOARD_FAB2_LIB.BASEBOARD_FAB2(SCH_1):GND

RES_0402-10.0K,1%,1/16W,CHIP,GA  I40  R6W29
   1 PVPP_ABC      A @BASEBOARD_FAB2_LIB.BASEBOARD_FAB2(SCH_1):PVPP_ABC
   2 FM_ADR_COMPLETE_CPU1_N      B @BASEBOARD_FAB2_LIB.BASEBOARD_FAB2(SCH_1):FM_ADR_COMPLETE_CPU1_N

RES_0402-10.0K,1%,1/16W,CHIP,GA  I45  WR8D30
   1 FM_ADR_COMPLETE_CPU1_N      A @BASEBOARD_FAB2_LIB.BASEBOARD_FAB2(SCH_1):FM_ADR_COMPLETE_CPU1_N
   2 IRQ_DIMM_SAVE_CPU1_R_N      B @BASEBOARD_FAB2_LIB.BASEBOARD_FAB2(SCH_1):IRQ_DIMM_SAVE_CPU1_R_N

NPN_DUAL_SSOPLF-MBT3904,XSTR,CA  I46  Q8D1
   2 IRQ_DIMM_SAVE_LVT3   B<0> @BASEBOARD_FAB2_LIB.BASEBOARD_FAB2(SCH_1):IRQ_DIMM_SAVE_LVT3
   6 IRQ_DIMM_SAVE_LVT3_N   C<0> @BASEBOARD_FAB2_LIB.BASEBOARD_FAB2(SCH_1):IRQ_DIMM_SAVE_LVT3_N
   1    GND   E<0> @BASEBOARD_FAB2_LIB.BASEBOARD_FAB2(SCH_1):GND

RES_0402-4.75K,1%,1/16W,CHIP,GA  I49  R8W9
   1 P3V3_STBY      A @BASEBOARD_FAB2_LIB.BASEBOARD_FAB2(SCH_1):P3V3_STBY
   2 IRQ_DIMM_SAVE_LVT3_CPU1      B @BASEBOARD_FAB2_LIB.BASEBOARD_FAB2(SCH_1):IRQ_DIMM_SAVE_LVT3_CPU1

NPN_DUAL_SSOPLF-MBT3904,XSTR,CA  I51  Q8W1
   2 IRQ_DIMM_SAVE_LVT3_CPU1   B<0> @BASEBOARD_FAB2_LIB.BASEBOARD_FAB2(SCH_1):IRQ_DIMM_SAVE_LVT3_CPU1
   6 IRQ_DIMM_SAVE_LVT3_N   C<0> @BASEBOARD_FAB2_LIB.BASEBOARD_FAB2(SCH_1):IRQ_DIMM_SAVE_LVT3_N
   1    GND   E<0> @BASEBOARD_FAB2_LIB.BASEBOARD_FAB2(SCH_1):GND

NPN_DUAL_SSOPLF-MBT3904,XSTR,CA  I52  Q8W1
   5 IRQ_DIMM_SAVE_CPU1_R_N   B<0> @BASEBOARD_FAB2_LIB.BASEBOARD_FAB2(SCH_1):IRQ_DIMM_SAVE_CPU1_R_N
   3 IRQ_DIMM_SAVE_LVT3_CPU1   C<0> @BASEBOARD_FAB2_LIB.BASEBOARD_FAB2(SCH_1):IRQ_DIMM_SAVE_LVT3_CPU1
   4    GND   E<0> @BASEBOARD_FAB2_LIB.BASEBOARD_FAB2(SCH_1):GND

NPN_SM-MMBT3904,IC,C52245-001  I53  Q1F1
   1 FM_ADR_COMPLETE_CPU0_R      B @BASEBOARD_FAB2_LIB.BASEBOARD_FAB2(SCH_1):FM_ADR_COMPLETE_CPU0_R
   3 IRQ_DIMM_SAVE_N      C @BASEBOARD_FAB2_LIB.BASEBOARD_FAB2(SCH_1):IRQ_DIMM_SAVE_N
   2    GND      E @BASEBOARD_FAB2_LIB.BASEBOARD_FAB2(SCH_1):GND

RES_0402-330,5%,1/16W,CHIP,G21A  I54  R1W32
   1 FM_ADR_COMPLETE_R      A @BASEBOARD_FAB2_LIB.BASEBOARD_FAB2(SCH_1):FM_ADR_COMPLETE_R
   2 FM_ADR_COMPLETE_CPU0_R      B @BASEBOARD_FAB2_LIB.BASEBOARD_FAB2(SCH_1):FM_ADR_COMPLETE_CPU0_R

NPN_SM-MMBT3904,IC,C52245-001  I55  Q1W6
   1 FM_ADR_COMPLETE_CPU1_R      B @BASEBOARD_FAB2_LIB.BASEBOARD_FAB2(SCH_1):FM_ADR_COMPLETE_CPU1_R
   3 FM_ADR_COMPLETE_CPU1_N      C @BASEBOARD_FAB2_LIB.BASEBOARD_FAB2(SCH_1):FM_ADR_COMPLETE_CPU1_N
   2    GND      E @BASEBOARD_FAB2_LIB.BASEBOARD_FAB2(SCH_1):GND

RES_0402-330,5%,1/16W,CHIP,G21A  I56  R1W31
   1 FM_ADR_COMPLETE_R      A @BASEBOARD_FAB2_LIB.BASEBOARD_FAB2(SCH_1):FM_ADR_COMPLETE_R
   2 FM_ADR_COMPLETE_CPU1_R      B @BASEBOARD_FAB2_LIB.BASEBOARD_FAB2(SCH_1):FM_ADR_COMPLETE_CPU1_R


DRAWING: @BASEBOARD_FAB2_LIB.BASEBOARD_FAB2(SCH_1):PAGE90 

RES_0402-240,1.0%,1/16W,EMPTY,A  I17  R3D22
   1 PVCCIO_CPU1      A @BASEBOARD_FAB2_LIB.BASEBOARD_FAB2(SCH_1):PVCCIO_CPU1
   2 PU_CPU1_FRMAGENT      B @BASEBOARD_FAB2_LIB.BASEBOARD_FAB2(SCH_1):PU_CPU1_FRMAGENT

RES_0402-240,1.0%,1/16W,EMPTY,A  I24  R3D16
   1 PVCCIO_CPU1      A @BASEBOARD_FAB2_LIB.BASEBOARD_FAB2(SCH_1):PVCCIO_CPU1
   2 H_CPU1_BMCINIT      B @BASEBOARD_FAB2_LIB.BASEBOARD_FAB2(SCH_1):H_CPU1_BMCINIT

RES_0402-240,1.0%,1/16W,EMPTY,A  I25  R3D23
   1 PVCCIO_CPU1      A @BASEBOARD_FAB2_LIB.BASEBOARD_FAB2(SCH_1):PVCCIO_CPU1
   2 PU_CPU1_TXT_AGENT      B @BASEBOARD_FAB2_LIB.BASEBOARD_FAB2(SCH_1):PU_CPU1_TXT_AGENT

RES_0402-240,1.0%,1/16W,EMPTY,A  I28  R3D26
   1 PVCCIO_CPU1      A @BASEBOARD_FAB2_LIB.BASEBOARD_FAB2(SCH_1):PVCCIO_CPU1
   2 PU_CPU1_SAFE_MODE_BOOT      B @BASEBOARD_FAB2_LIB.BASEBOARD_FAB2(SCH_1):PU_CPU1_SAFE_MODE_BOOT

RES_0402-240,1.0%,1/16W,CHIP,GA  I29  R5D3
   1 PVCCIO_CPU0      A @BASEBOARD_FAB2_LIB.BASEBOARD_FAB2(SCH_1):PVCCIO_CPU0
   2 PU_CPU0_FRMAGENT      B @BASEBOARD_FAB2_LIB.BASEBOARD_FAB2(SCH_1):PU_CPU0_FRMAGENT

RES_0402-240,1.0%,1/16W,EMPTY,A  I31  R6D7
   1 PVCCIO_CPU0      A @BASEBOARD_FAB2_LIB.BASEBOARD_FAB2(SCH_1):PVCCIO_CPU0
   2 H_CPU0_BMCINIT      B @BASEBOARD_FAB2_LIB.BASEBOARD_FAB2(SCH_1):H_CPU0_BMCINIT

RES_0402-240,1.0%,1/16W,EMPTY,A  I33  R6D13
   1 PVCCIO_CPU0      A @BASEBOARD_FAB2_LIB.BASEBOARD_FAB2(SCH_1):PVCCIO_CPU0
   2 PU_CPU0_SAFE_MODE_BOOT      B @BASEBOARD_FAB2_LIB.BASEBOARD_FAB2(SCH_1):PU_CPU0_SAFE_MODE_BOOT

RES_0402-240,1.0%,1/16W,EMPTY,A  I48  R6D15
   1 PVCCIO_CPU0      A @BASEBOARD_FAB2_LIB.BASEBOARD_FAB2(SCH_1):PVCCIO_CPU0
   2 PU_CPU0_SOCKET_ID_0      B @BASEBOARD_FAB2_LIB.BASEBOARD_FAB2(SCH_1):PU_CPU0_SOCKET_ID_0

RES_0402-240,1.0%,1/16W,EMPTY,A  I49  R6D10
   1 PVCCIO_CPU0      A @BASEBOARD_FAB2_LIB.BASEBOARD_FAB2(SCH_1):PVCCIO_CPU0
   2 PU_CPU0_SOCKET_ID_1      B @BASEBOARD_FAB2_LIB.BASEBOARD_FAB2(SCH_1):PU_CPU0_SOCKET_ID_1

RES_0402-240,1.0%,1/16W,EMPTY,A  I52  R6D14
   1    GND      A @BASEBOARD_FAB2_LIB.BASEBOARD_FAB2(SCH_1):GND
   2 PD_CPU0_EAR_N      B @BASEBOARD_FAB2_LIB.BASEBOARD_FAB2(SCH_1):PD_CPU0_EAR_N

RES_0402-240,1.0%,1/16W,CHIP,GA  I53  R4P14
   1 PVCCIO_CPU0      A @BASEBOARD_FAB2_LIB.BASEBOARD_FAB2(SCH_1):PVCCIO_CPU0
   2 PU_CPU0_LEGACY_SKT      B @BASEBOARD_FAB2_LIB.BASEBOARD_FAB2(SCH_1):PU_CPU0_LEGACY_SKT

RES_0402-240,1.0%,1/16W,CHIP,GA  I59  R3D24
   1 PVCCIO_CPU1      A @BASEBOARD_FAB2_LIB.BASEBOARD_FAB2(SCH_1):PVCCIO_CPU1
   2 PU_CPU1_SOCKET_ID_0      B @BASEBOARD_FAB2_LIB.BASEBOARD_FAB2(SCH_1):PU_CPU1_SOCKET_ID_0

RES_0402-240,1.0%,1/16W,EMPTY,A  I60  R3D17
   1 PVCCIO_CPU1      A @BASEBOARD_FAB2_LIB.BASEBOARD_FAB2(SCH_1):PVCCIO_CPU1
   2 PU_CPU1_SOCKET_ID_1      B @BASEBOARD_FAB2_LIB.BASEBOARD_FAB2(SCH_1):PU_CPU1_SOCKET_ID_1

RES_0402-240,1.0%,1/16W,EMPTY,A  I66  R3D25
   1    GND      A @BASEBOARD_FAB2_LIB.BASEBOARD_FAB2(SCH_1):GND
   2 PD_CPU1_EAR_N      B @BASEBOARD_FAB2_LIB.BASEBOARD_FAB2(SCH_1):PD_CPU1_EAR_N

RES_0402-240,1.0%,1/16W,EMPTY,A  I68  R4P6
   1    GND      A @BASEBOARD_FAB2_LIB.BASEBOARD_FAB2(SCH_1):GND
   2 PD_CPU0_DMIMODE_OVERRIDE      B @BASEBOARD_FAB2_LIB.BASEBOARD_FAB2(SCH_1):PD_CPU0_DMIMODE_OVERRIDE

RES_0402-240,1.0%,1/16W,EMPTY,A  I72  R4P7
   1    GND      A @BASEBOARD_FAB2_LIB.BASEBOARD_FAB2(SCH_1):GND
   2 PD_CPU0_KSFC_DIS      B @BASEBOARD_FAB2_LIB.BASEBOARD_FAB2(SCH_1):PD_CPU0_KSFC_DIS

RES_0402-240,1.0%,1/16W,EMPTY,A  I74  R7P15
   1    GND      A @BASEBOARD_FAB2_LIB.BASEBOARD_FAB2(SCH_1):GND
   2 PD_CPU1_KSFC_DIS      B @BASEBOARD_FAB2_LIB.BASEBOARD_FAB2(SCH_1):PD_CPU1_KSFC_DIS

RES_0402-240,1.0%,1/16W,EMPTY,A  I76  R7P22
   1 PVCCIO_CPU1      A @BASEBOARD_FAB2_LIB.BASEBOARD_FAB2(SCH_1):PVCCIO_CPU1
   2 PU_CPU1_LEGACY_SKT      B @BASEBOARD_FAB2_LIB.BASEBOARD_FAB2(SCH_1):PU_CPU1_LEGACY_SKT

RES_0402-49.9,1%,1/16W,CHIP,G2A  I79  R5P2
   1 PD_CPU0_TEST14      A @BASEBOARD_FAB2_LIB.BASEBOARD_FAB2(SCH_1):PD_CPU0_TEST14
   2    GND      B @BASEBOARD_FAB2_LIB.BASEBOARD_FAB2(SCH_1):GND

RES_0402-49.9,1%,1/16W,CHIP,G2A  I80  R5P3
   1 PD_CPU0_TEST13      A @BASEBOARD_FAB2_LIB.BASEBOARD_FAB2(SCH_1):PD_CPU0_TEST13
   2    GND      B @BASEBOARD_FAB2_LIB.BASEBOARD_FAB2(SCH_1):GND

RES_0402-49.9,1%,1/16W,CHIP,G2A  I81  R6D5
   1 PD_CPU0_TEST12      A @BASEBOARD_FAB2_LIB.BASEBOARD_FAB2(SCH_1):PD_CPU0_TEST12
   2    GND      B @BASEBOARD_FAB2_LIB.BASEBOARD_FAB2(SCH_1):GND

RES_0402-49.9,1%,1/16W,CHIP,G2A  I85  R8P1
   1 PD_CPU1_TEST14      A @BASEBOARD_FAB2_LIB.BASEBOARD_FAB2(SCH_1):PD_CPU1_TEST14
   2    GND      B @BASEBOARD_FAB2_LIB.BASEBOARD_FAB2(SCH_1):GND

RES_0402-49.9,1%,1/16W,CHIP,G2A  I86  R8P2
   1 PD_CPU1_TEST13      A @BASEBOARD_FAB2_LIB.BASEBOARD_FAB2(SCH_1):PD_CPU1_TEST13
   2    GND      B @BASEBOARD_FAB2_LIB.BASEBOARD_FAB2(SCH_1):GND

RES_0402-49.9,1%,1/16W,CHIP,G2A  I88  R3D9
   1 PD_CPU1_TEST12      A @BASEBOARD_FAB2_LIB.BASEBOARD_FAB2(SCH_1):PD_CPU1_TEST12
   2    GND      B @BASEBOARD_FAB2_LIB.BASEBOARD_FAB2(SCH_1):GND

RES_0402-240,1.0%,1/16W,CHIP,GA  I96  R5D4
   1 PVCCIO_CPU0      A @BASEBOARD_FAB2_LIB.BASEBOARD_FAB2(SCH_1):PVCCIO_CPU0
   2 PU_CPU0_TXT_AGENT      B @BASEBOARD_FAB2_LIB.BASEBOARD_FAB2(SCH_1):PU_CPU0_TXT_AGENT

RES_0402-240,1.0%,1/16W,EMPTY,A  I98  R4P1
   1    GND      A @BASEBOARD_FAB2_LIB.BASEBOARD_FAB2(SCH_1):GND
   2 PD_CPU0_BIST_ENABLE      B @BASEBOARD_FAB2_LIB.BASEBOARD_FAB2(SCH_1):PD_CPU0_BIST_ENABLE

RES_0402-240,1.0%,1/16W,EMPTY,A  I99  R3D13
   1    GND      A @BASEBOARD_FAB2_LIB.BASEBOARD_FAB2(SCH_1):GND
   2 PD_CPU1_BIST_ENABLE      B @BASEBOARD_FAB2_LIB.BASEBOARD_FAB2(SCH_1):PD_CPU1_BIST_ENABLE

RES_0402-240,1.0%,1/16W,CHIP,GA  I100  R7P14
   1    GND      A @BASEBOARD_FAB2_LIB.BASEBOARD_FAB2(SCH_1):GND
   2 PD_CPU1_DMIMODE_OVERRIDE      B @BASEBOARD_FAB2_LIB.BASEBOARD_FAB2(SCH_1):PD_CPU1_DMIMODE_OVERRIDE

RES_0402-240,1.0%,1/16W,EMPTY,A  I101  R6D6
   1    GND      A @BASEBOARD_FAB2_LIB.BASEBOARD_FAB2(SCH_1):GND
   2 PD_CPU0_TXT_PLTEN      B @BASEBOARD_FAB2_LIB.BASEBOARD_FAB2(SCH_1):PD_CPU0_TXT_PLTEN

RES_0402-240,1.0%,1/16W,EMPTY,A  I102  R3D12
   1    GND      A @BASEBOARD_FAB2_LIB.BASEBOARD_FAB2(SCH_1):GND
   2 PD_CPU1_TXT_PLTEN      B @BASEBOARD_FAB2_LIB.BASEBOARD_FAB2(SCH_1):PD_CPU1_TXT_PLTEN


DRAWING: @BASEBOARD_FAB2_LIB.BASEBOARD_FAB2(SCH_1):PAGE91 

SCONN24_H46321001_SM-SCONN,H46A  I1  J8B1
   1    GND    IO1 @BASEBOARD_FAB2_LIB.BASEBOARD_FAB2(SCH_1):GND
  10 SMB_HFI1_CPU0_LVC2_SCL   IO10 @BASEBOARD_FAB2_LIB.BASEBOARD_FAB2(SCH_1):SMB_HFI1_CPU0_LVC2_SCL
  11 FM_MODPRST_HFI1_CPU0_LVT2_N   IO11 @BASEBOARD_FAB2_LIB.BASEBOARD_FAB2(SCH_1):FM_MODPRST_HFI1_CPU0_LVT2_N
  12 SMB_HFI1_CPU0_LVC2_SDA   IO12 @BASEBOARD_FAB2_LIB.BASEBOARD_FAB2(SCH_1):SMB_HFI1_CPU0_LVC2_SDA
  13 LED_HFI1_CPU0_N   IO13 @BASEBOARD_FAB2_LIB.BASEBOARD_FAB2(SCH_1):LED_HFI1_CPU0_N
  14 RST_HFI1_CPU0_LVT2_N   IO14 @BASEBOARD_FAB2_LIB.BASEBOARD_FAB2(SCH_1):RST_HFI1_CPU0_LVT2_N
  15    GND   IO15 @BASEBOARD_FAB2_LIB.BASEBOARD_FAB2(SCH_1):GND
  16 IRQ_HFI1_CPU0_LVT2_N   IO16 @BASEBOARD_FAB2_LIB.BASEBOARD_FAB2(SCH_1):IRQ_HFI1_CPU0_LVT2_N
  17 TP_HFI_IO_CONN0_RSVD_17   IO17 @BASEBOARD_FAB2_LIB.BASEBOARD_FAB2(SCH_1):TP_HFI_IO_CONN0_RSVD_17
  18   P3V3   IO18 @BASEBOARD_FAB2_LIB.BASEBOARD_FAB2(SCH_1):P3V3
  19 PWRGD_PVPP_ABC   IO19 @BASEBOARD_FAB2_LIB.BASEBOARD_FAB2(SCH_1):PWRGD_PVPP_ABC
   2 SMB_HFI0_CPU0_LVC2_SCL    IO2 @BASEBOARD_FAB2_LIB.BASEBOARD_FAB2(SCH_1):SMB_HFI0_CPU0_LVC2_SCL
  20   P3V3   IO20 @BASEBOARD_FAB2_LIB.BASEBOARD_FAB2(SCH_1):P3V3
  21 PVPP_ABC   IO21 @BASEBOARD_FAB2_LIB.BASEBOARD_FAB2(SCH_1):PVPP_ABC
  22 SMB_OCP_FRU_STBY_LVC3_SCL   IO22 @BASEBOARD_FAB2_LIB.BASEBOARD_FAB2(SCH_1):SMB_OCP_FRU_STBY_LVC3_SCL
  23    GND   IO23 @BASEBOARD_FAB2_LIB.BASEBOARD_FAB2(SCH_1):GND
  24 SMB_OCP_FRU_STBY_LVC3_SDA   IO24 @BASEBOARD_FAB2_LIB.BASEBOARD_FAB2(SCH_1):SMB_OCP_FRU_STBY_LVC3_SDA
   3 FM_MODPRST_HFI0_CPU0_LVT2_N    IO3 @BASEBOARD_FAB2_LIB.BASEBOARD_FAB2(SCH_1):FM_MODPRST_HFI0_CPU0_LVT2_N
   4 SMB_HFI0_CPU0_LVC2_SDA    IO4 @BASEBOARD_FAB2_LIB.BASEBOARD_FAB2(SCH_1):SMB_HFI0_CPU0_LVC2_SDA
   5 LED_HFI0_CPU0_N    IO5 @BASEBOARD_FAB2_LIB.BASEBOARD_FAB2(SCH_1):LED_HFI0_CPU0_N
   6 RST_HFI0_CPU0_LVT2_N    IO6 @BASEBOARD_FAB2_LIB.BASEBOARD_FAB2(SCH_1):RST_HFI0_CPU0_LVT2_N
   7    GND    IO7 @BASEBOARD_FAB2_LIB.BASEBOARD_FAB2(SCH_1):GND
   8 IRQ_HFI0_CPU0_LVT2_N    IO8 @BASEBOARD_FAB2_LIB.BASEBOARD_FAB2(SCH_1):IRQ_HFI0_CPU0_LVT2_N
   9    GND    IO9 @BASEBOARD_FAB2_LIB.BASEBOARD_FAB2(SCH_1):GND
 MP1    GND    MP1 @BASEBOARD_FAB2_LIB.BASEBOARD_FAB2(SCH_1):GND
 MP2    GND    MP2 @BASEBOARD_FAB2_LIB.BASEBOARD_FAB2(SCH_1):GND

RES_0402-4.75K,1%,1/16W,CHIP,GA  I14  R8B8
   1 PVPP_ABC      A @BASEBOARD_FAB2_LIB.BASEBOARD_FAB2(SCH_1):PVPP_ABC
   2 RST_HFI0_CPU0_LVT2_N      B @BASEBOARD_FAB2_LIB.BASEBOARD_FAB2(SCH_1):RST_HFI0_CPU0_LVT2_N

RES_0402-4.75K,1%,1/16W,CHIP,GA  I16  R8B10
   1 PVPP_ABC      A @BASEBOARD_FAB2_LIB.BASEBOARD_FAB2(SCH_1):PVPP_ABC
   2 IRQ_HFI0_CPU0_LVT2_N      B @BASEBOARD_FAB2_LIB.BASEBOARD_FAB2(SCH_1):IRQ_HFI0_CPU0_LVT2_N

RES_0402-4.75K,1%,1/16W,CHIP,GA  I17  R8B16
   1 PVPP_ABC      A @BASEBOARD_FAB2_LIB.BASEBOARD_FAB2(SCH_1):PVPP_ABC
   2 RST_HFI1_CPU0_LVT2_N      B @BASEBOARD_FAB2_LIB.BASEBOARD_FAB2(SCH_1):RST_HFI1_CPU0_LVT2_N

RES_0402-4.75K,1%,1/16W,CHIP,GA  I18  R8B17
   1 PVPP_ABC      A @BASEBOARD_FAB2_LIB.BASEBOARD_FAB2(SCH_1):PVPP_ABC
   2 IRQ_HFI1_CPU0_LVT2_N      B @BASEBOARD_FAB2_LIB.BASEBOARD_FAB2(SCH_1):IRQ_HFI1_CPU0_LVT2_N

RES_0402-4.75K,1%,1/16W,CHIP,GA  I20  R8B18
   1 PVPP_ABC      A @BASEBOARD_FAB2_LIB.BASEBOARD_FAB2(SCH_1):PVPP_ABC
   2 LED_HFI1_CPU0_N      B @BASEBOARD_FAB2_LIB.BASEBOARD_FAB2(SCH_1):LED_HFI1_CPU0_N

RES_0402-4.75K,1%,1/16W,CHIP,GA  I21  R8B19
   1 PVPP_ABC      A @BASEBOARD_FAB2_LIB.BASEBOARD_FAB2(SCH_1):PVPP_ABC
   2 FM_MODPRST_HFI1_CPU0_LVT2_N      B @BASEBOARD_FAB2_LIB.BASEBOARD_FAB2(SCH_1):FM_MODPRST_HFI1_CPU0_LVT2_N

RES_0402-4.75K,1%,1/16W,CHIP,GA  I22  R8B5
   1 PVPP_ABC      A @BASEBOARD_FAB2_LIB.BASEBOARD_FAB2(SCH_1):PVPP_ABC
   2 LED_HFI0_CPU0_N      B @BASEBOARD_FAB2_LIB.BASEBOARD_FAB2(SCH_1):LED_HFI0_CPU0_N

RES_0402-4.75K,1%,1/16W,CHIP,GA  I24  R8B3
   1 PVPP_ABC      A @BASEBOARD_FAB2_LIB.BASEBOARD_FAB2(SCH_1):PVPP_ABC
   2 FM_MODPRST_HFI0_CPU0_LVT2_N      B @BASEBOARD_FAB2_LIB.BASEBOARD_FAB2(SCH_1):FM_MODPRST_HFI0_CPU0_LVT2_N

RES_0402-1.8K,1%,1/16W,CHIP,G2A  I34  R8B13
   1 PVPP_ABC      A @BASEBOARD_FAB2_LIB.BASEBOARD_FAB2(SCH_1):PVPP_ABC
   2 SMB_HFI1_CPU0_LVC2_SDA      B @BASEBOARD_FAB2_LIB.BASEBOARD_FAB2(SCH_1):SMB_HFI1_CPU0_LVC2_SDA

RES_0402-1.8K,1%,1/16W,CHIP,G2A  I35  R8B11
   1 PVPP_ABC      A @BASEBOARD_FAB2_LIB.BASEBOARD_FAB2(SCH_1):PVPP_ABC
   2 SMB_HFI1_CPU0_LVC2_SCL      B @BASEBOARD_FAB2_LIB.BASEBOARD_FAB2(SCH_1):SMB_HFI1_CPU0_LVC2_SCL

RES_0402-1.8K,1%,1/16W,CHIP,G2A  I36  R8B7
   1 PVPP_ABC      A @BASEBOARD_FAB2_LIB.BASEBOARD_FAB2(SCH_1):PVPP_ABC
   2 SMB_HFI0_CPU0_LVC2_SDA      B @BASEBOARD_FAB2_LIB.BASEBOARD_FAB2(SCH_1):SMB_HFI0_CPU0_LVC2_SDA

RES_0402-1.8K,1%,1/16W,CHIP,G2A  I37  R8B6
   1 PVPP_ABC      A @BASEBOARD_FAB2_LIB.BASEBOARD_FAB2(SCH_1):PVPP_ABC
   2 SMB_HFI0_CPU0_LVC2_SCL      B @BASEBOARD_FAB2_LIB.BASEBOARD_FAB2(SCH_1):SMB_HFI0_CPU0_LVC2_SCL


DRAWING: @BASEBOARD_FAB2_LIB.BASEBOARD_FAB2(SCH_1):PAGE92 

GTL2014_SM-IC,D66151-001  I1  U3P2
  13 PWRGD_CPUPWRGD_R1     A0 @BASEBOARD_FAB2_LIB.BASEBOARD_FAB2(SCH_1):PWRGD_CPUPWRGD_R1
  12 FM_CPU1_FIVR_FAULT_R_LVT3     A1 @BASEBOARD_FAB2_LIB.BASEBOARD_FAB2(SCH_1):FM_CPU1_FIVR_FAULT_R_LVT3
  10 FM_CPU_CATERR_LVT3_R2_N     A2 @BASEBOARD_FAB2_LIB.BASEBOARD_FAB2(SCH_1):FM_CPU_CATERR_LVT3_R2_N
   9 FM_CPU1_THERMTRIP_LVT3_R_N     A3 @BASEBOARD_FAB2_LIB.BASEBOARD_FAB2(SCH_1):FM_CPU1_THERMTRIP_LVT3_R_N
   2 PWRGD_CPUPWRGD_GTL     B0 @BASEBOARD_FAB2_LIB.BASEBOARD_FAB2(SCH_1):PWRGD_CPUPWRGD_GTL
   3 H_CPU1_FIVR_FAULT_G     B1 @BASEBOARD_FAB2_LIB.BASEBOARD_FAB2(SCH_1):H_CPU1_FIVR_FAULT_G
   5 H_CPU_CATERR_G_N     B2 @BASEBOARD_FAB2_LIB.BASEBOARD_FAB2(SCH_1):H_CPU_CATERR_G_N
   6 H_CPU1_THERMTRIP_G_N     B3 @BASEBOARD_FAB2_LIB.BASEBOARD_FAB2(SCH_1):H_CPU1_THERMTRIP_G_N
   1 PD_GTL2104_DIR_1    DIR @BASEBOARD_FAB2_LIB.BASEBOARD_FAB2(SCH_1):PD_GTL2104_DIR_1
  11    GND GND<2> @BASEBOARD_FAB2_LIB.BASEBOARD_FAB2(SCH_1):GND
   8    GND GND<1> @BASEBOARD_FAB2_LIB.BASEBOARD_FAB2(SCH_1):GND
   7    GND GND<0> @BASEBOARD_FAB2_LIB.BASEBOARD_FAB2(SCH_1):GND
  14   P3V3    VCC @BASEBOARD_FAB2_LIB.BASEBOARD_FAB2(SCH_1):P3V3
   4 P0V7_GTL2104_VREF_1   VREF @BASEBOARD_FAB2_LIB.BASEBOARD_FAB2(SCH_1):P0V7_GTL2104_VREF_1

RES_0402-75,1.0%,1/16W,CHIP,G2A  I9  R3P41
   1 PVCCIO_CPU1      A @BASEBOARD_FAB2_LIB.BASEBOARD_FAB2(SCH_1):PVCCIO_CPU1
   2 H_CPU1_THERMTRIP_G_N      B @BASEBOARD_FAB2_LIB.BASEBOARD_FAB2(SCH_1):H_CPU1_THERMTRIP_G_N

RES_0402-33.2,1%,1/16W,CHIP,G2A  I12  R3P46
   1 FM_CPU1_FIVR_FAULT_R_LVT3      A @BASEBOARD_FAB2_LIB.BASEBOARD_FAB2(SCH_1):FM_CPU1_FIVR_FAULT_R_LVT3
   2 FM_CPU1_FIVR_FAULT_LVT3      B @BASEBOARD_FAB2_LIB.BASEBOARD_FAB2(SCH_1):FM_CPU1_FIVR_FAULT_LVT3

RES_0402-33.2,1%,1/16W,CHIP,G2A  I13  R3P43
   1 FM_CPU_CATERR_LVT3_R2_N      A @BASEBOARD_FAB2_LIB.BASEBOARD_FAB2(SCH_1):FM_CPU_CATERR_LVT3_R2_N
   2 FM_CPU_CATERR_LVT3_N      B @BASEBOARD_FAB2_LIB.BASEBOARD_FAB2(SCH_1):FM_CPU_CATERR_LVT3_N

RES_0402-33.2,1%,1/16W,CHIP,G2A  I14  R3P42
   1 FM_CPU1_THERMTRIP_LVT3_R_N      A @BASEBOARD_FAB2_LIB.BASEBOARD_FAB2(SCH_1):FM_CPU1_THERMTRIP_LVT3_R_N
   2 FM_CPU1_THERMTRIP_LVT3_N      B @BASEBOARD_FAB2_LIB.BASEBOARD_FAB2(SCH_1):FM_CPU1_THERMTRIP_LVT3_N

RES_0402-75,1.0%,1/16W,CHIP,G2A  I19  R7E2
   1 PVCCIO_CPU0      A @BASEBOARD_FAB2_LIB.BASEBOARD_FAB2(SCH_1):PVCCIO_CPU0
   2 H_CPU0_THERMTRIP_G_N      B @BASEBOARD_FAB2_LIB.BASEBOARD_FAB2(SCH_1):H_CPU0_THERMTRIP_G_N

RES_0402-33.2,1%,1/16W,CHIP,G2A  I24  R7D34
   1 FM_CPU0_THERMTRIP_LVT3_R_N      A @BASEBOARD_FAB2_LIB.BASEBOARD_FAB2(SCH_1):FM_CPU0_THERMTRIP_LVT3_R_N
   2 FM_CPU0_THERMTRIP_LVT3_N      B @BASEBOARD_FAB2_LIB.BASEBOARD_FAB2(SCH_1):FM_CPU0_THERMTRIP_LVT3_N

RES_0402-33.2,1%,1/16W,CHIP,G2A  I29  R7D31
   1 FM_CPU_ERR2_LVT3_R_N      A @BASEBOARD_FAB2_LIB.BASEBOARD_FAB2(SCH_1):FM_CPU_ERR2_LVT3_R_N
   2 FM_CPU_ERR2_LVT3_N      B @BASEBOARD_FAB2_LIB.BASEBOARD_FAB2(SCH_1):FM_CPU_ERR2_LVT3_N

RES_0402-33.2,1%,1/16W,CHIP,G2A  I30  R7D29
   1 FM_CPU0_FIVR_FAULT_R_LVT3      A @BASEBOARD_FAB2_LIB.BASEBOARD_FAB2(SCH_1):FM_CPU0_FIVR_FAULT_R_LVT3
   2 FM_CPU0_FIVR_FAULT_LVT3      B @BASEBOARD_FAB2_LIB.BASEBOARD_FAB2(SCH_1):FM_CPU0_FIVR_FAULT_LVT3

GTL2014_SM-IC,D66151-001  I32  U7D2
  13 FM_CPU_MSMI_LVT3_R_N     A0 @BASEBOARD_FAB2_LIB.BASEBOARD_FAB2(SCH_1):FM_CPU_MSMI_LVT3_R_N
  12 FM_CPU0_FIVR_FAULT_R_LVT3     A1 @BASEBOARD_FAB2_LIB.BASEBOARD_FAB2(SCH_1):FM_CPU0_FIVR_FAULT_R_LVT3
  10 FM_CPU_ERR2_LVT3_R_N     A2 @BASEBOARD_FAB2_LIB.BASEBOARD_FAB2(SCH_1):FM_CPU_ERR2_LVT3_R_N
   9 FM_CPU0_THERMTRIP_LVT3_R_N     A3 @BASEBOARD_FAB2_LIB.BASEBOARD_FAB2(SCH_1):FM_CPU0_THERMTRIP_LVT3_R_N
   2 H_CPU_MSMI_G_N     B0 @BASEBOARD_FAB2_LIB.BASEBOARD_FAB2(SCH_1):H_CPU_MSMI_G_N
   3 H_CPU0_FIVR_FAULT_G     B1 @BASEBOARD_FAB2_LIB.BASEBOARD_FAB2(SCH_1):H_CPU0_FIVR_FAULT_G
   5 H_CPU_ERR2_GTL_N     B2 @BASEBOARD_FAB2_LIB.BASEBOARD_FAB2(SCH_1):H_CPU_ERR2_GTL_N
   6 H_CPU0_THERMTRIP_G_N     B3 @BASEBOARD_FAB2_LIB.BASEBOARD_FAB2(SCH_1):H_CPU0_THERMTRIP_G_N
   1 PD_GTL2104_DIR_0    DIR @BASEBOARD_FAB2_LIB.BASEBOARD_FAB2(SCH_1):PD_GTL2104_DIR_0
  11    GND GND<2> @BASEBOARD_FAB2_LIB.BASEBOARD_FAB2(SCH_1):GND
   8    GND GND<1> @BASEBOARD_FAB2_LIB.BASEBOARD_FAB2(SCH_1):GND
   7    GND GND<0> @BASEBOARD_FAB2_LIB.BASEBOARD_FAB2(SCH_1):GND
  14   P3V3    VCC @BASEBOARD_FAB2_LIB.BASEBOARD_FAB2(SCH_1):P3V3
   4 P0V7_GTL2104_VREF_0   VREF @BASEBOARD_FAB2_LIB.BASEBOARD_FAB2(SCH_1):P0V7_GTL2104_VREF_0

CAP_A_0402V-0.1UF,16V,10%,X7R,A  I37  C3P49
   1 P0V7_GTL2104_VREF_1      A @BASEBOARD_FAB2_LIB.BASEBOARD_FAB2(SCH_1):P0V7_GTL2104_VREF_1
   2    GND      B @BASEBOARD_FAB2_LIB.BASEBOARD_FAB2(SCH_1):GND

RES_0402-100.0,1%,1/16W,CHIP,GA  I38  R3P49
   1 P0V7_GTL2104_VREF_1      A @BASEBOARD_FAB2_LIB.BASEBOARD_FAB2(SCH_1):P0V7_GTL2104_VREF_1
   2    GND      B @BASEBOARD_FAB2_LIB.BASEBOARD_FAB2(SCH_1):GND

RES_0402-1.00K,1%,1/16W,CHIP,GA  I46  R3R1
   1 PD_GTL2104_DIR_1      A @BASEBOARD_FAB2_LIB.BASEBOARD_FAB2(SCH_1):PD_GTL2104_DIR_1
   2    GND      B @BASEBOARD_FAB2_LIB.BASEBOARD_FAB2(SCH_1):GND

RES_0402-100.0,1%,1/16W,CHIP,GA  I48  R7D32
   1 P0V7_GTL2104_VREF_0      A @BASEBOARD_FAB2_LIB.BASEBOARD_FAB2(SCH_1):P0V7_GTL2104_VREF_0
   2    GND      B @BASEBOARD_FAB2_LIB.BASEBOARD_FAB2(SCH_1):GND

CAP_A_0402V-0.1UF,16V,10%,X7R,A  I52  C7D5
   1 P0V7_GTL2104_VREF_0      A @BASEBOARD_FAB2_LIB.BASEBOARD_FAB2(SCH_1):P0V7_GTL2104_VREF_0
   2    GND      B @BASEBOARD_FAB2_LIB.BASEBOARD_FAB2(SCH_1):GND

RES_0402-1.00K,1%,1/16W,CHIP,GA  I54  R7D26
   1 PD_GTL2104_DIR_0      A @BASEBOARD_FAB2_LIB.BASEBOARD_FAB2(SCH_1):PD_GTL2104_DIR_0
   2    GND      B @BASEBOARD_FAB2_LIB.BASEBOARD_FAB2(SCH_1):GND

RES_0402-33.2,1%,1/16W,CHIP,G2A  I61  R3R3
   1 PWRGD_CPUPWRGD_R1      A @BASEBOARD_FAB2_LIB.BASEBOARD_FAB2(SCH_1):PWRGD_CPUPWRGD_R1
   2 PWRGD_CPUPWRGD      B @BASEBOARD_FAB2_LIB.BASEBOARD_FAB2(SCH_1):PWRGD_CPUPWRGD

RES_0402-150.0,1%,1/16W,CHIP,GA  I64  R6D9
   1 PVCCIO_CPU0      A @BASEBOARD_FAB2_LIB.BASEBOARD_FAB2(SCH_1):PVCCIO_CPU0
   2 H_CPU0_MSMI_G_N      B @BASEBOARD_FAB2_LIB.BASEBOARD_FAB2(SCH_1):H_CPU0_MSMI_G_N

RES_0402-150.0,1%,1/16W,CHIP,GA  I65  R7P27
   1 PVCCIO_CPU0      A @BASEBOARD_FAB2_LIB.BASEBOARD_FAB2(SCH_1):PVCCIO_CPU0
   2 H_CPU1_MSMI_G_N      B @BASEBOARD_FAB2_LIB.BASEBOARD_FAB2(SCH_1):H_CPU1_MSMI_G_N

RES_0402-0.0,5%,1/16W,CHIP,G21A  I67  R7D28
   1 H_CPU1_MSMI_G_N      A @BASEBOARD_FAB2_LIB.BASEBOARD_FAB2(SCH_1):H_CPU1_MSMI_G_N
   2 H_CPU_MSMI_G_N      B @BASEBOARD_FAB2_LIB.BASEBOARD_FAB2(SCH_1):H_CPU_MSMI_G_N

RES_0402-0.0,5%,1/16W,CHIP,G21A  I68  R7D27
   1 H_CPU0_MSMI_G_N      A @BASEBOARD_FAB2_LIB.BASEBOARD_FAB2(SCH_1):H_CPU0_MSMI_G_N
   2 H_CPU_MSMI_G_N      B @BASEBOARD_FAB2_LIB.BASEBOARD_FAB2(SCH_1):H_CPU_MSMI_G_N

RES_0402-33.2,1%,1/16W,CHIP,G2A  I70  R7D25
   1 FM_CPU_MSMI_LVT3_R_N      A @BASEBOARD_FAB2_LIB.BASEBOARD_FAB2(SCH_1):FM_CPU_MSMI_LVT3_R_N
   2 FM_CPU_MSMI_LVT3_N      B @BASEBOARD_FAB2_LIB.BASEBOARD_FAB2(SCH_1):FM_CPU_MSMI_LVT3_N

RES_0402-1.00K,1%,1/16W,CHIP,GA  I75  R3R2
   1 H_CPU1_FIVR_FAULT_G      A @BASEBOARD_FAB2_LIB.BASEBOARD_FAB2(SCH_1):H_CPU1_FIVR_FAULT_G
   2    GND      B @BASEBOARD_FAB2_LIB.BASEBOARD_FAB2(SCH_1):GND

CAP_0402-1.0UF,16V,10%,X6S,D97A  I79  C7D4
   1   P3V3      A @BASEBOARD_FAB2_LIB.BASEBOARD_FAB2(SCH_1):P3V3
   2    GND      B @BASEBOARD_FAB2_LIB.BASEBOARD_FAB2(SCH_1):GND

CAP_0402-1.0UF,16V,10%,X6S,D97A  I84  C3P50
   1   P3V3      A @BASEBOARD_FAB2_LIB.BASEBOARD_FAB2(SCH_1):P3V3
   2    GND      B @BASEBOARD_FAB2_LIB.BASEBOARD_FAB2(SCH_1):GND

RES_0402-0.0,5%,1/16W,CHIP,G21A  I92  R2T44
   1 H_CPU1_ERR2_G_N      A @BASEBOARD_FAB2_LIB.BASEBOARD_FAB2(SCH_1):H_CPU1_ERR2_G_N
   2 H_CPU_ERR2_G_R_N      B @BASEBOARD_FAB2_LIB.BASEBOARD_FAB2(SCH_1):H_CPU_ERR2_G_R_N

RES_0402-0.0,5%,1/16W,CHIP,G21A  I93  R2T40
   1 H_CPU0_ERR2_G_N      A @BASEBOARD_FAB2_LIB.BASEBOARD_FAB2(SCH_1):H_CPU0_ERR2_G_N
   2 H_CPU_ERR2_G_R_N      B @BASEBOARD_FAB2_LIB.BASEBOARD_FAB2(SCH_1):H_CPU_ERR2_G_R_N

RES_0402-200.0,1%,1/16W,CHIP,GA  I94  R2T37
   1 PVCCIO_CPU0      A @BASEBOARD_FAB2_LIB.BASEBOARD_FAB2(SCH_1):PVCCIO_CPU0
   2 H_CPU_ERR2_G_R_N      B @BASEBOARD_FAB2_LIB.BASEBOARD_FAB2(SCH_1):H_CPU_ERR2_G_R_N

RES_0402-75,1.0%,1/16W,CHIP,G2A  I96  R2T43
   1 H_CPU_ERR2_G_R_N      A @BASEBOARD_FAB2_LIB.BASEBOARD_FAB2(SCH_1):H_CPU_ERR2_G_R_N
   2 H_CPU_ERR2_GTL_N      B @BASEBOARD_FAB2_LIB.BASEBOARD_FAB2(SCH_1):H_CPU_ERR2_GTL_N

RES_0402-0.0,5%,1/16W,CHIP,G21A  I97  R3P59
   1 H_CPU0_CATERR_G_N      A @BASEBOARD_FAB2_LIB.BASEBOARD_FAB2(SCH_1):H_CPU0_CATERR_G_N
   2 H_CPU_CATERR_G_N      B @BASEBOARD_FAB2_LIB.BASEBOARD_FAB2(SCH_1):H_CPU_CATERR_G_N

RES_0402-0.0,5%,1/16W,CHIP,G21A  I98  R3P58
   1 H_CPU1_CATERR_G_N      A @BASEBOARD_FAB2_LIB.BASEBOARD_FAB2(SCH_1):H_CPU1_CATERR_G_N
   2 H_CPU_CATERR_G_N      B @BASEBOARD_FAB2_LIB.BASEBOARD_FAB2(SCH_1):H_CPU_CATERR_G_N

RES_0402-150.0,1%,1/16W,CHIP,GA  I100  R7P18
   1 PVCCIO_CPU0      A @BASEBOARD_FAB2_LIB.BASEBOARD_FAB2(SCH_1):PVCCIO_CPU0
   2 H_CPU1_CATERR_G_N      B @BASEBOARD_FAB2_LIB.BASEBOARD_FAB2(SCH_1):H_CPU1_CATERR_G_N

RES_0402-150.0,1%,1/16W,CHIP,GA  I101  R4R2
   1 PVCCIO_CPU0      A @BASEBOARD_FAB2_LIB.BASEBOARD_FAB2(SCH_1):PVCCIO_CPU0
   2 H_CPU0_CATERR_G_N      B @BASEBOARD_FAB2_LIB.BASEBOARD_FAB2(SCH_1):H_CPU0_CATERR_G_N

RES_0402-49.9,1%,1/16W,EMPTY,GA  I106  R7W4
   1 PVCCIO_CPU0      A @BASEBOARD_FAB2_LIB.BASEBOARD_FAB2(SCH_1):PVCCIO_CPU0
   2 P0V7_GTL2104_VREF_0      B @BASEBOARD_FAB2_LIB.BASEBOARD_FAB2(SCH_1):P0V7_GTL2104_VREF_0

RES_0402-49.9,1%,1/16W,EMPTY,GA  I108  R3W10
   1 PVCCIO_CPU0      A @BASEBOARD_FAB2_LIB.BASEBOARD_FAB2(SCH_1):PVCCIO_CPU0
   2 P0V7_GTL2104_VREF_1      B @BASEBOARD_FAB2_LIB.BASEBOARD_FAB2(SCH_1):P0V7_GTL2104_VREF_1

374R2F-1-GP_SMD-RG-374R2F-1-GPA  I110  R3P45
   1   P3V3      1 @BASEBOARD_FAB2_LIB.BASEBOARD_FAB2(SCH_1):P3V3
   2 P0V7_GTL2104_VREF_1      2 @BASEBOARD_FAB2_LIB.BASEBOARD_FAB2(SCH_1):P0V7_GTL2104_VREF_1

374R2F-1-GP_SMD-RG-374R2F-1-GPA  I111  R7D33
   1   P3V3      1 @BASEBOARD_FAB2_LIB.BASEBOARD_FAB2(SCH_1):P3V3
   2 P0V7_GTL2104_VREF_0      2 @BASEBOARD_FAB2_LIB.BASEBOARD_FAB2(SCH_1):P0V7_GTL2104_VREF_0


DRAWING: @BASEBOARD_FAB2_LIB.BASEBOARD_FAB2(SCH_1):PAGE93 

RES_0402-0.0,5%,1/16W,CHIP,G21A  I13  R2T27
   1 H_CPU1_ERR1_G_N      A @BASEBOARD_FAB2_LIB.BASEBOARD_FAB2(SCH_1):H_CPU1_ERR1_G_N
   2 H_CPU_ERR1_GTL_R_N      B @BASEBOARD_FAB2_LIB.BASEBOARD_FAB2(SCH_1):H_CPU_ERR1_GTL_R_N

RES_0402-0.0,5%,1/16W,CHIP,G21A  I15  R2T32
   1 H_CPU0_ERR1_G_N      A @BASEBOARD_FAB2_LIB.BASEBOARD_FAB2(SCH_1):H_CPU0_ERR1_G_N
   2 H_CPU_ERR1_GTL_R_N      B @BASEBOARD_FAB2_LIB.BASEBOARD_FAB2(SCH_1):H_CPU_ERR1_GTL_R_N

RES_0402-0.0,5%,1/16W,CHIP,G21A  I16  R2T20
   1 H_CPU1_ERR0_G_N      A @BASEBOARD_FAB2_LIB.BASEBOARD_FAB2(SCH_1):H_CPU1_ERR0_G_N
   2 H_CPU_ERR0_GTL_R_N      B @BASEBOARD_FAB2_LIB.BASEBOARD_FAB2(SCH_1):H_CPU_ERR0_GTL_R_N

RES_0402-0.0,5%,1/16W,CHIP,G21A  I23  R2T17
   1 H_CPU0_ERR0_G_N      A @BASEBOARD_FAB2_LIB.BASEBOARD_FAB2(SCH_1):H_CPU0_ERR0_G_N
   2 H_CPU_ERR0_GTL_R_N      B @BASEBOARD_FAB2_LIB.BASEBOARD_FAB2(SCH_1):H_CPU_ERR0_GTL_R_N

GTL2014_SM-IC,D66151-001  I30  U2T4
  13 FM_CPU1_PROCHOT_LVT3_R_N     A0 @BASEBOARD_FAB2_LIB.BASEBOARD_FAB2(SCH_1):FM_CPU1_PROCHOT_LVT3_R_N
  12 FM_CPU0_PROCHOT_LVT3_R_N     A1 @BASEBOARD_FAB2_LIB.BASEBOARD_FAB2(SCH_1):FM_CPU0_PROCHOT_LVT3_R_N
  10 FM_CPU_ERR1_LVT3_R_N     A2 @BASEBOARD_FAB2_LIB.BASEBOARD_FAB2(SCH_1):FM_CPU_ERR1_LVT3_R_N
   9 FM_CPU_ERR0_LVT3_R_N     A3 @BASEBOARD_FAB2_LIB.BASEBOARD_FAB2(SCH_1):FM_CPU_ERR0_LVT3_R_N
   2 H_CPU1_PROCHOT_G_R_N     B0 @BASEBOARD_FAB2_LIB.BASEBOARD_FAB2(SCH_1):H_CPU1_PROCHOT_G_R_N
   3 H_CPU0_PROCHOT_G_R_N     B1 @BASEBOARD_FAB2_LIB.BASEBOARD_FAB2(SCH_1):H_CPU0_PROCHOT_G_R_N
   5 H_CPU_ERR1_GTL_N     B2 @BASEBOARD_FAB2_LIB.BASEBOARD_FAB2(SCH_1):H_CPU_ERR1_GTL_N
   6 H_CPU_ERR0_GTL_N     B3 @BASEBOARD_FAB2_LIB.BASEBOARD_FAB2(SCH_1):H_CPU_ERR0_GTL_N
   1 PD_GTL2104_4_DIR    DIR @BASEBOARD_FAB2_LIB.BASEBOARD_FAB2(SCH_1):PD_GTL2104_4_DIR
  11    GND GND<2> @BASEBOARD_FAB2_LIB.BASEBOARD_FAB2(SCH_1):GND
   8    GND GND<1> @BASEBOARD_FAB2_LIB.BASEBOARD_FAB2(SCH_1):GND
   7    GND GND<0> @BASEBOARD_FAB2_LIB.BASEBOARD_FAB2(SCH_1):GND
  14   P3V3    VCC @BASEBOARD_FAB2_LIB.BASEBOARD_FAB2(SCH_1):P3V3
   4 P0V7_GTL2104_5_VREF   VREF @BASEBOARD_FAB2_LIB.BASEBOARD_FAB2(SCH_1):P0V7_GTL2104_5_VREF

RES_0402-33.2,1%,1/16W,CHIP,G2A  I39  R2T38
   1 FM_CPU0_PROCHOT_LVT3_K_N      A @BASEBOARD_FAB2_LIB.BASEBOARD_FAB2(SCH_1):FM_CPU0_PROCHOT_LVT3_K_N
   2 FM_CPU0_PROCHOT_LVT3_N      B @BASEBOARD_FAB2_LIB.BASEBOARD_FAB2(SCH_1):FM_CPU0_PROCHOT_LVT3_N

RES_0402-33.2,1%,1/16W,CHIP,G2A  I40  R2T33
   1 FM_CPU_ERR1_LVT3_K_N      A @BASEBOARD_FAB2_LIB.BASEBOARD_FAB2(SCH_1):FM_CPU_ERR1_LVT3_K_N
   2 FM_CPU_ERR1_LVT3_N      B @BASEBOARD_FAB2_LIB.BASEBOARD_FAB2(SCH_1):FM_CPU_ERR1_LVT3_N

RES_0402-33.2,1%,1/16W,CHIP,G2A  I42  R2T30
   1 FM_CPU_ERR0_LVT3_K_N      A @BASEBOARD_FAB2_LIB.BASEBOARD_FAB2(SCH_1):FM_CPU_ERR0_LVT3_K_N
   2 FM_CPU_ERR0_LVT3_N      B @BASEBOARD_FAB2_LIB.BASEBOARD_FAB2(SCH_1):FM_CPU_ERR0_LVT3_N

RES_0402-33.2,1%,1/16W,CHIP,G2A  I62  R7D24
   1 FM_CPU1_PROCHOT_LVT3_K_N      A @BASEBOARD_FAB2_LIB.BASEBOARD_FAB2(SCH_1):FM_CPU1_PROCHOT_LVT3_K_N
   2 FM_CPU1_PROCHOT_LVT3_N      B @BASEBOARD_FAB2_LIB.BASEBOARD_FAB2(SCH_1):FM_CPU1_PROCHOT_LVT3_N

RES_0402-200.0,1%,1/16W,CHIP,GA  I63  R2T19
   1 PVCCIO_CPU0      A @BASEBOARD_FAB2_LIB.BASEBOARD_FAB2(SCH_1):PVCCIO_CPU0
   2 H_CPU_ERR0_GTL_R_N      B @BASEBOARD_FAB2_LIB.BASEBOARD_FAB2(SCH_1):H_CPU_ERR0_GTL_R_N

RES_0402-75,1.0%,1/16W,CHIP,G2A  I67  R2T16
   1 H_CPU_ERR0_GTL_R_N      A @BASEBOARD_FAB2_LIB.BASEBOARD_FAB2(SCH_1):H_CPU_ERR0_GTL_R_N
   2 H_CPU_ERR0_GTL_N      B @BASEBOARD_FAB2_LIB.BASEBOARD_FAB2(SCH_1):H_CPU_ERR0_GTL_N

RES_0402-75,1.0%,1/16W,CHIP,G2A  I68  R2T31
   1 H_CPU_ERR1_GTL_R_N      A @BASEBOARD_FAB2_LIB.BASEBOARD_FAB2(SCH_1):H_CPU_ERR1_GTL_R_N
   2 H_CPU_ERR1_GTL_N      B @BASEBOARD_FAB2_LIB.BASEBOARD_FAB2(SCH_1):H_CPU_ERR1_GTL_N

CAP_A_0402V-1.0UF,6.3V,10%,X6SA  I72  C2T33
   1   P3V3      A @BASEBOARD_FAB2_LIB.BASEBOARD_FAB2(SCH_1):P3V3
   2    GND      B @BASEBOARD_FAB2_LIB.BASEBOARD_FAB2(SCH_1):GND

RES_0402-150.0,1%,1/16W,CHIP,GA  I79  R4R3
   1 PVCCIO_CPU0      A @BASEBOARD_FAB2_LIB.BASEBOARD_FAB2(SCH_1):PVCCIO_CPU0
   2 H_CPU0_PROCHOT_G_N      B @BASEBOARD_FAB2_LIB.BASEBOARD_FAB2(SCH_1):H_CPU0_PROCHOT_G_N

RES_0402-200.0,1%,1/16W,CHIP,GA  I87  R2T26
   1 PVCCIO_CPU0      A @BASEBOARD_FAB2_LIB.BASEBOARD_FAB2(SCH_1):PVCCIO_CPU0
   2 H_CPU_ERR1_GTL_R_N      B @BASEBOARD_FAB2_LIB.BASEBOARD_FAB2(SCH_1):H_CPU_ERR1_GTL_R_N

RES_0402-0.0,5%,1/16W,EMPTY,G2A  I88  R2T57
   1 H_CPU_ERR0_PCH_N      A @BASEBOARD_FAB2_LIB.BASEBOARD_FAB2(SCH_1):H_CPU_ERR0_PCH_N
   2 H_CPU_ERR0_GTL_R_N      B @BASEBOARD_FAB2_LIB.BASEBOARD_FAB2(SCH_1):H_CPU_ERR0_GTL_R_N

RES_0402-0.0,5%,1/16W,EMPTY,G2A  I89  R2T61
   1 H_CPU_ERR1_PCH_N      A @BASEBOARD_FAB2_LIB.BASEBOARD_FAB2(SCH_1):H_CPU_ERR1_PCH_N
   2 H_CPU_ERR1_GTL_R_N      B @BASEBOARD_FAB2_LIB.BASEBOARD_FAB2(SCH_1):H_CPU_ERR1_GTL_R_N

RES_0402-0.0,5%,1/16W,EMPTY,G2A  I93  R2T62
   1 H_CPU_ERR1_PCH_N      A @BASEBOARD_FAB2_LIB.BASEBOARD_FAB2(SCH_1):H_CPU_ERR1_PCH_N
   2 FM_CPU_ERR1_LVT3_K_N      B @BASEBOARD_FAB2_LIB.BASEBOARD_FAB2(SCH_1):FM_CPU_ERR1_LVT3_K_N

RES_0402-0.0,5%,1/16W,EMPTY,G2A  I94  R2T58
   1 H_CPU_ERR0_PCH_N      A @BASEBOARD_FAB2_LIB.BASEBOARD_FAB2(SCH_1):H_CPU_ERR0_PCH_N
   2 FM_CPU_ERR0_LVT3_K_N      B @BASEBOARD_FAB2_LIB.BASEBOARD_FAB2(SCH_1):FM_CPU_ERR0_LVT3_K_N

CAP_A_0402V-0.1UF,16V,10%,X7R,A  I95  C2T32
   1 P0V7_GTL2104_5_VREF      A @BASEBOARD_FAB2_LIB.BASEBOARD_FAB2(SCH_1):P0V7_GTL2104_5_VREF
   2    GND      B @BASEBOARD_FAB2_LIB.BASEBOARD_FAB2(SCH_1):GND

RES_0402-100.0,1%,1/16W,CHIP,GA  I98  R2T39
   1 P0V7_GTL2104_5_VREF      A @BASEBOARD_FAB2_LIB.BASEBOARD_FAB2(SCH_1):P0V7_GTL2104_5_VREF
   2    GND      B @BASEBOARD_FAB2_LIB.BASEBOARD_FAB2(SCH_1):GND

RES_0402-0.0,5%,1/16W,CHIP,G21A  I102  R2T68
   1 H_CPU1_PROCHOT_G_N      A @BASEBOARD_FAB2_LIB.BASEBOARD_FAB2(SCH_1):H_CPU1_PROCHOT_G_N
   2 H_CPU1_PROCHOT_G_R_N      B @BASEBOARD_FAB2_LIB.BASEBOARD_FAB2(SCH_1):H_CPU1_PROCHOT_G_R_N

RES_0402-0.0,5%,1/16W,CHIP,G21A  I103  R2T60
   1 H_CPU0_PROCHOT_G_N      A @BASEBOARD_FAB2_LIB.BASEBOARD_FAB2(SCH_1):H_CPU0_PROCHOT_G_N
   2 H_CPU0_PROCHOT_G_R_N      B @BASEBOARD_FAB2_LIB.BASEBOARD_FAB2(SCH_1):H_CPU0_PROCHOT_G_R_N

RES_0402-150.0,1%,1/16W,CHIP,GA  I106  R7P28
   1 PVCCIO_CPU1      A @BASEBOARD_FAB2_LIB.BASEBOARD_FAB2(SCH_1):PVCCIO_CPU1
   2 H_CPU1_PROCHOT_G_N      B @BASEBOARD_FAB2_LIB.BASEBOARD_FAB2(SCH_1):H_CPU1_PROCHOT_G_N

RES_0402-0.0,5%,1/16W,EMPTY,G2A  I107  R2T59
   1 H_CPU0_PROCHOT_G_N      A @BASEBOARD_FAB2_LIB.BASEBOARD_FAB2(SCH_1):H_CPU0_PROCHOT_G_N
   2 H_CPU0_PROCHOT_G_PCH_N      B @BASEBOARD_FAB2_LIB.BASEBOARD_FAB2(SCH_1):H_CPU0_PROCHOT_G_PCH_N

RES_0402-0.0,5%,1/16W,EMPTY,G2A  I108  R2T69
   1 H_CPU1_PROCHOT_G_N      A @BASEBOARD_FAB2_LIB.BASEBOARD_FAB2(SCH_1):H_CPU1_PROCHOT_G_N
   2 H_CPU1_PROCHOT_G_PCH_N      B @BASEBOARD_FAB2_LIB.BASEBOARD_FAB2(SCH_1):H_CPU1_PROCHOT_G_PCH_N

RES_0402-0.0,5%,1/16W,EMPTY,G2A  I109  R2T71
   1 FM_CPU0_PROCHOT_LVT3_K_N      A @BASEBOARD_FAB2_LIB.BASEBOARD_FAB2(SCH_1):FM_CPU0_PROCHOT_LVT3_K_N
   2 H_CPU0_PROCHOT_G_PCH_N      B @BASEBOARD_FAB2_LIB.BASEBOARD_FAB2(SCH_1):H_CPU0_PROCHOT_G_PCH_N

RES_0402-0.0,5%,1/16W,EMPTY,G2A  I110  R7D43
   1 FM_CPU1_PROCHOT_LVT3_K_N      A @BASEBOARD_FAB2_LIB.BASEBOARD_FAB2(SCH_1):FM_CPU1_PROCHOT_LVT3_K_N
   2 H_CPU1_PROCHOT_G_PCH_N      B @BASEBOARD_FAB2_LIB.BASEBOARD_FAB2(SCH_1):H_CPU1_PROCHOT_G_PCH_N

RES_0402-0.0,5%,1/16W,CHIP,G21A  I111  R2T65
   1 FM_CPU_ERR0_LVT3_R_N      A @BASEBOARD_FAB2_LIB.BASEBOARD_FAB2(SCH_1):FM_CPU_ERR0_LVT3_R_N
   2 FM_CPU_ERR0_LVT3_K_N      B @BASEBOARD_FAB2_LIB.BASEBOARD_FAB2(SCH_1):FM_CPU_ERR0_LVT3_K_N

RES_0402-0.0,5%,1/16W,CHIP,G21A  I112  R2T66
   1 FM_CPU_ERR1_LVT3_R_N      A @BASEBOARD_FAB2_LIB.BASEBOARD_FAB2(SCH_1):FM_CPU_ERR1_LVT3_R_N
   2 FM_CPU_ERR1_LVT3_K_N      B @BASEBOARD_FAB2_LIB.BASEBOARD_FAB2(SCH_1):FM_CPU_ERR1_LVT3_K_N

RES_0402-0.0,5%,1/16W,CHIP,G21A  I113  R2T67
   1 FM_CPU0_PROCHOT_LVT3_R_N      A @BASEBOARD_FAB2_LIB.BASEBOARD_FAB2(SCH_1):FM_CPU0_PROCHOT_LVT3_R_N
   2 FM_CPU0_PROCHOT_LVT3_K_N      B @BASEBOARD_FAB2_LIB.BASEBOARD_FAB2(SCH_1):FM_CPU0_PROCHOT_LVT3_K_N

RES_0402-0.0,5%,1/16W,CHIP,G21A  I114  R7D41
   1 FM_CPU1_PROCHOT_LVT3_R_N      A @BASEBOARD_FAB2_LIB.BASEBOARD_FAB2(SCH_1):FM_CPU1_PROCHOT_LVT3_R_N
   2 FM_CPU1_PROCHOT_LVT3_K_N      B @BASEBOARD_FAB2_LIB.BASEBOARD_FAB2(SCH_1):FM_CPU1_PROCHOT_LVT3_K_N

RES_0402-0.0,5%,1/16W,CHIP,G21A  I119  R8F38
   1 FM_CPU_ERR0_LVT3_N      A @BASEBOARD_FAB2_LIB.BASEBOARD_FAB2(SCH_1):FM_CPU_ERR0_LVT3_N
   2 FM_CPU_ERR0_LVT3_BMC_N      B @BASEBOARD_FAB2_LIB.BASEBOARD_FAB2(SCH_1):FM_CPU_ERR0_LVT3_BMC_N

RES_0402-0.0,5%,1/16W,CHIP,G21A  I121  R2T64
   1 FM_CPU_ERR1_LVT3_N      A @BASEBOARD_FAB2_LIB.BASEBOARD_FAB2(SCH_1):FM_CPU_ERR1_LVT3_N
   2 FM_CPU_ERR1_LVT3_BMC_N      B @BASEBOARD_FAB2_LIB.BASEBOARD_FAB2(SCH_1):FM_CPU_ERR1_LVT3_BMC_N

RES_0402-0.0,5%,1/16W,CHIP,G21A  I122  R1T36
   1 FM_CPU0_PROCHOT_LVT3_N      A @BASEBOARD_FAB2_LIB.BASEBOARD_FAB2(SCH_1):FM_CPU0_PROCHOT_LVT3_N
   2 FM_CPU0_PROCHOT_LVT3_BMC_N      B @BASEBOARD_FAB2_LIB.BASEBOARD_FAB2(SCH_1):FM_CPU0_PROCHOT_LVT3_BMC_N

RES_0402-0.0,5%,1/16W,CHIP,G21A  I123  R1T37
   1 FM_CPU1_PROCHOT_LVT3_N      A @BASEBOARD_FAB2_LIB.BASEBOARD_FAB2(SCH_1):FM_CPU1_PROCHOT_LVT3_N
   2 FM_CPU1_PROCHOT_LVT3_BMC_N      B @BASEBOARD_FAB2_LIB.BASEBOARD_FAB2(SCH_1):FM_CPU1_PROCHOT_LVT3_BMC_N

RES_0402-1.00K,1%,1/16W,CHIP,GA  I127  R2T50
   1 PD_GTL2104_4_DIR      A @BASEBOARD_FAB2_LIB.BASEBOARD_FAB2(SCH_1):PD_GTL2104_4_DIR
   2    GND      B @BASEBOARD_FAB2_LIB.BASEBOARD_FAB2(SCH_1):GND

RES_0402-0.0,5%,1/16W,EMPTY,G2A  I131  R8F37
   1 FM_CPU_ERR0_LVT3_N      A @BASEBOARD_FAB2_LIB.BASEBOARD_FAB2(SCH_1):FM_CPU_ERR0_LVT3_N
   2 FM_CPU_ERR0_PCH_N      B @BASEBOARD_FAB2_LIB.BASEBOARD_FAB2(SCH_1):FM_CPU_ERR0_PCH_N

RES_0402-0.0,5%,1/16W,EMPTY,G2A  I133  R2T63
   1 FM_CPU_ERR1_LVT3_N      A @BASEBOARD_FAB2_LIB.BASEBOARD_FAB2(SCH_1):FM_CPU_ERR1_LVT3_N
   2 FM_CPU_ERR1_PCH_N      B @BASEBOARD_FAB2_LIB.BASEBOARD_FAB2(SCH_1):FM_CPU_ERR1_PCH_N

RES_0402-0.0,5%,1/16W,EMPTY,G2A  I135  R1T35
   1 FM_CPU0_PROCHOT_LVT3_N      A @BASEBOARD_FAB2_LIB.BASEBOARD_FAB2(SCH_1):FM_CPU0_PROCHOT_LVT3_N
   2 FM_CPU0_PROCHOT_PCH_N      B @BASEBOARD_FAB2_LIB.BASEBOARD_FAB2(SCH_1):FM_CPU0_PROCHOT_PCH_N

RES_0402-0.0,5%,1/16W,EMPTY,G2A  I137  R1T38
   1 FM_CPU1_PROCHOT_LVT3_N      A @BASEBOARD_FAB2_LIB.BASEBOARD_FAB2(SCH_1):FM_CPU1_PROCHOT_LVT3_N
   2 FM_CPU1_PROCHOT_PCH_N      B @BASEBOARD_FAB2_LIB.BASEBOARD_FAB2(SCH_1):FM_CPU1_PROCHOT_PCH_N

RES_0402-150.0,1%,1/16W,CHIP,GA  I143  R2T72
   1 PVCCIO_CPU0      A @BASEBOARD_FAB2_LIB.BASEBOARD_FAB2(SCH_1):PVCCIO_CPU0
   2 H_CPU0_PROCHOT_G_N      B @BASEBOARD_FAB2_LIB.BASEBOARD_FAB2(SCH_1):H_CPU0_PROCHOT_G_N

RES_0402-150.0,1%,1/16W,CHIP,GA  I144  R2T73
   1 PVCCIO_CPU1      A @BASEBOARD_FAB2_LIB.BASEBOARD_FAB2(SCH_1):PVCCIO_CPU1
   2 H_CPU1_PROCHOT_G_N      B @BASEBOARD_FAB2_LIB.BASEBOARD_FAB2(SCH_1):H_CPU1_PROCHOT_G_N

RES_0402-49.9,1%,1/16W,EMPTY,GA  I147  R2W2
   1 PVCCIO_CPU0      A @BASEBOARD_FAB2_LIB.BASEBOARD_FAB2(SCH_1):PVCCIO_CPU0
   2 P0V7_GTL2104_5_VREF      B @BASEBOARD_FAB2_LIB.BASEBOARD_FAB2(SCH_1):P0V7_GTL2104_5_VREF

374R2F-1-GP_SMD-RG-374R2F-1-GPA  I148  R2T36
   1   P3V3      1 @BASEBOARD_FAB2_LIB.BASEBOARD_FAB2(SCH_1):P3V3
   2 P0V7_GTL2104_5_VREF      2 @BASEBOARD_FAB2_LIB.BASEBOARD_FAB2(SCH_1):P0V7_GTL2104_5_VREF


DRAWING: @BASEBOARD_FAB2_LIB.BASEBOARD_FAB2(SCH_1):PAGE94 

FET_N_DUAL_SMLF-NTJD4001N,FET,A  I49  Q3U1
   2 IRQ_PVDDQ_ABC_VRHOT_LVT3_N GATE<0> @BASEBOARD_FAB2_LIB.BASEBOARD_FAB2(SCH_1):IRQ_PVDDQ_ABC_VRHOT_LVT3_N
   1    GND SOURCE<0> @BASEBOARD_FAB2_LIB.BASEBOARD_FAB2(SCH_1):GND
   6 H_CPU0_MEMABC_MEMHOT DRAIN<0> @BASEBOARD_FAB2_LIB.BASEBOARD_FAB2(SCH_1):H_CPU0_MEMABC_MEMHOT

RES_0402-4.75K,1%,1/16W,CHIP,GA  I51  R7G7
   1   P3V3      A @BASEBOARD_FAB2_LIB.BASEBOARD_FAB2(SCH_1):P3V3
   2 H_CPU0_MEMABC_MEMHOT      B @BASEBOARD_FAB2_LIB.BASEBOARD_FAB2(SCH_1):H_CPU0_MEMABC_MEMHOT

FET_N_DUAL_SMLF-NTJD4001N,FET,A  I60  Q7E1
   2 IRQ_PVDDQ_DEF_VRHOT_LVT3_N GATE<0> @BASEBOARD_FAB2_LIB.BASEBOARD_FAB2(SCH_1):IRQ_PVDDQ_DEF_VRHOT_LVT3_N
   1    GND SOURCE<0> @BASEBOARD_FAB2_LIB.BASEBOARD_FAB2(SCH_1):GND
   6 H_CPU0_MEMDEF_MEMHOT DRAIN<0> @BASEBOARD_FAB2_LIB.BASEBOARD_FAB2(SCH_1):H_CPU0_MEMDEF_MEMHOT

FET_N_DUAL_SMLF-NTJD4001N,FET,A  I64  Q7E1
   5 H_CPU0_MEMDEF_MEMHOT GATE<0> @BASEBOARD_FAB2_LIB.BASEBOARD_FAB2(SCH_1):H_CPU0_MEMDEF_MEMHOT
   4    GND SOURCE<0> @BASEBOARD_FAB2_LIB.BASEBOARD_FAB2(SCH_1):GND
   3 H_CPU0_MEMDEF_MEMHOT_G_N DRAIN<0> @BASEBOARD_FAB2_LIB.BASEBOARD_FAB2(SCH_1):H_CPU0_MEMDEF_MEMHOT_G_N

RES_0402-4.75K,1%,1/16W,CHIP,GA  I66  R3R4
   1   P3V3      A @BASEBOARD_FAB2_LIB.BASEBOARD_FAB2(SCH_1):P3V3
   2 H_CPU0_MEMDEF_MEMHOT      B @BASEBOARD_FAB2_LIB.BASEBOARD_FAB2(SCH_1):H_CPU0_MEMDEF_MEMHOT

FET_N_DUAL_SMLF-NTJD4001N,FET,A  I69  Q7E2
   2 IRQ_PVDDQ_GHJ_VRHOT_LVT3_N GATE<0> @BASEBOARD_FAB2_LIB.BASEBOARD_FAB2(SCH_1):IRQ_PVDDQ_GHJ_VRHOT_LVT3_N
   1    GND SOURCE<0> @BASEBOARD_FAB2_LIB.BASEBOARD_FAB2(SCH_1):GND
   6 H_CPU1_MEMGHJ_MEMHOT DRAIN<0> @BASEBOARD_FAB2_LIB.BASEBOARD_FAB2(SCH_1):H_CPU1_MEMGHJ_MEMHOT

FET_N_DUAL_SMLF-NTJD4001N,FET,A  I75  Q7E2
   5 H_CPU1_MEMGHJ_MEMHOT GATE<0> @BASEBOARD_FAB2_LIB.BASEBOARD_FAB2(SCH_1):H_CPU1_MEMGHJ_MEMHOT
   4    GND SOURCE<0> @BASEBOARD_FAB2_LIB.BASEBOARD_FAB2(SCH_1):GND
   3 H_CPU1_MEMGHJ_MEMHOT_G_N DRAIN<0> @BASEBOARD_FAB2_LIB.BASEBOARD_FAB2(SCH_1):H_CPU1_MEMGHJ_MEMHOT_G_N

FET_N_DUAL_SMLF-NTJD4001N,FET,A  I77  Q4B1
   5 H_CPU1_MEMKLM_MEMHOT GATE<0> @BASEBOARD_FAB2_LIB.BASEBOARD_FAB2(SCH_1):H_CPU1_MEMKLM_MEMHOT
   4    GND SOURCE<0> @BASEBOARD_FAB2_LIB.BASEBOARD_FAB2(SCH_1):GND
   3 H_CPU1_MEMKLM_MEMHOT_G_N DRAIN<0> @BASEBOARD_FAB2_LIB.BASEBOARD_FAB2(SCH_1):H_CPU1_MEMKLM_MEMHOT_G_N

RES_0402-4.75K,1%,1/16W,CHIP,GA  I79  R3R10
   1   P3V3      A @BASEBOARD_FAB2_LIB.BASEBOARD_FAB2(SCH_1):P3V3
   2 H_CPU1_MEMGHJ_MEMHOT      B @BASEBOARD_FAB2_LIB.BASEBOARD_FAB2(SCH_1):H_CPU1_MEMGHJ_MEMHOT

RES_0402-4.75K,1%,1/16W,CHIP,GA  I82  R6M4
   1   P3V3      A @BASEBOARD_FAB2_LIB.BASEBOARD_FAB2(SCH_1):P3V3
   2 H_CPU1_MEMKLM_MEMHOT      B @BASEBOARD_FAB2_LIB.BASEBOARD_FAB2(SCH_1):H_CPU1_MEMKLM_MEMHOT

FET_N_DUAL_SMLF-NTJD4001N,FET,A  I84  Q4B1
   2 IRQ_PVDDQ_KLM_VRHOT_LVT3_N GATE<0> @BASEBOARD_FAB2_LIB.BASEBOARD_FAB2(SCH_1):IRQ_PVDDQ_KLM_VRHOT_LVT3_N
   1    GND SOURCE<0> @BASEBOARD_FAB2_LIB.BASEBOARD_FAB2(SCH_1):GND
   6 H_CPU1_MEMKLM_MEMHOT DRAIN<0> @BASEBOARD_FAB2_LIB.BASEBOARD_FAB2(SCH_1):H_CPU1_MEMKLM_MEMHOT

FET_N_DUAL_SMLF-NTJD4001N,FET,A  I89  Q3U1
   5 H_CPU0_MEMABC_MEMHOT GATE<0> @BASEBOARD_FAB2_LIB.BASEBOARD_FAB2(SCH_1):H_CPU0_MEMABC_MEMHOT
   4    GND SOURCE<0> @BASEBOARD_FAB2_LIB.BASEBOARD_FAB2(SCH_1):GND
   3 H_CPU0_MEMABC_MEMHOT_G_N DRAIN<0> @BASEBOARD_FAB2_LIB.BASEBOARD_FAB2(SCH_1):H_CPU0_MEMABC_MEMHOT_G_N

RES_0402-4.75K,1%,1/16W,CHIP,GA  I91  R4U1
   1 P3V3_STBY      A @BASEBOARD_FAB2_LIB.BASEBOARD_FAB2(SCH_1):P3V3_STBY
   2 FM_MEM_THERM_EVENT_LVT3_N      B @BASEBOARD_FAB2_LIB.BASEBOARD_FAB2(SCH_1):FM_MEM_THERM_EVENT_LVT3_N

RES_0402-4.75K,1%,1/16W,CHIP,GA  I94  R4U3
   1 PVPP_ABC      A @BASEBOARD_FAB2_LIB.BASEBOARD_FAB2(SCH_1):PVPP_ABC
   2 FM_DIMM_EVENT_FET      B @BASEBOARD_FAB2_LIB.BASEBOARD_FAB2(SCH_1):FM_DIMM_EVENT_FET

FET_N_DUAL_SMLF-NTJD4001N,FET,A  I98  Q4U1
   2 FM_DIMM_EVENT_COD_N GATE<0> @BASEBOARD_FAB2_LIB.BASEBOARD_FAB2(SCH_1):FM_DIMM_EVENT_COD_N
   1    GND SOURCE<0> @BASEBOARD_FAB2_LIB.BASEBOARD_FAB2(SCH_1):GND
   6 FM_DIMM_EVENT_FET DRAIN<0> @BASEBOARD_FAB2_LIB.BASEBOARD_FAB2(SCH_1):FM_DIMM_EVENT_FET

RES_0402-2.21K,1%,1/16W,CHIP,GA  I100  R4U2
   1 PVPP_ABC      A @BASEBOARD_FAB2_LIB.BASEBOARD_FAB2(SCH_1):PVPP_ABC
   2 FM_DIMM_EVENT_COD_N      B @BASEBOARD_FAB2_LIB.BASEBOARD_FAB2(SCH_1):FM_DIMM_EVENT_COD_N

FET_N_DUAL_SMLF-NTJD4001N,FET,A  I102  Q4U1
   5 FM_DIMM_EVENT_FET GATE<0> @BASEBOARD_FAB2_LIB.BASEBOARD_FAB2(SCH_1):FM_DIMM_EVENT_FET
   4    GND SOURCE<0> @BASEBOARD_FAB2_LIB.BASEBOARD_FAB2(SCH_1):GND
   3 FM_MEM_THERM_EVENT_LVT3_N DRAIN<0> @BASEBOARD_FAB2_LIB.BASEBOARD_FAB2(SCH_1):FM_MEM_THERM_EVENT_LVT3_N

RES_0402-33.0K,5%,1/16W,CHIP,GA  I104  R4U4
   1 FM_DIMM_EVENT_FET      A @BASEBOARD_FAB2_LIB.BASEBOARD_FAB2(SCH_1):FM_DIMM_EVENT_FET
   2    GND      B @BASEBOARD_FAB2_LIB.BASEBOARD_FAB2(SCH_1):GND


DRAWING: @BASEBOARD_FAB2_LIB.BASEBOARD_FAB2(SCH_1):PAGE95 

FET_N_DUAL_SMLF-NTJD4001N,FET,A  I28  Q2U1
   2 FM_SYS_THROTTLE_LVC3 GATE<0> @BASEBOARD_FAB2_LIB.BASEBOARD_FAB2(SCH_1):FM_SYS_THROTTLE_LVC3
   1    GND SOURCE<0> @BASEBOARD_FAB2_LIB.BASEBOARD_FAB2(SCH_1):GND
   6 H_CPU0_MEMABC_MEMHOT_G_N DRAIN<0> @BASEBOARD_FAB2_LIB.BASEBOARD_FAB2(SCH_1):H_CPU0_MEMABC_MEMHOT_G_N

FET_N_DUAL_SMLF-NTJD4001N,FET,A  I32  Q4B2
   2 FM_SYS_THROTTLE_LVC3 GATE<0> @BASEBOARD_FAB2_LIB.BASEBOARD_FAB2(SCH_1):FM_SYS_THROTTLE_LVC3
   1    GND SOURCE<0> @BASEBOARD_FAB2_LIB.BASEBOARD_FAB2(SCH_1):GND
   6 H_CPU1_MEMGHJ_MEMHOT_G_N DRAIN<0> @BASEBOARD_FAB2_LIB.BASEBOARD_FAB2(SCH_1):H_CPU1_MEMGHJ_MEMHOT_G_N

FET_N_DUAL_SMLF-NTJD4001N,FET,A  I33  Q4B2
   5 FM_SYS_THROTTLE_LVC3 GATE<0> @BASEBOARD_FAB2_LIB.BASEBOARD_FAB2(SCH_1):FM_SYS_THROTTLE_LVC3
   4    GND SOURCE<0> @BASEBOARD_FAB2_LIB.BASEBOARD_FAB2(SCH_1):GND
   3 H_CPU1_MEMKLM_MEMHOT_G_N DRAIN<0> @BASEBOARD_FAB2_LIB.BASEBOARD_FAB2(SCH_1):H_CPU1_MEMKLM_MEMHOT_G_N

FET_N_DUAL_SMLF-NTJD4001N,FET,A  I51  Q7E3
   5 FM_SYS_THROTTLE_LVC3 GATE<0> @BASEBOARD_FAB2_LIB.BASEBOARD_FAB2(SCH_1):FM_SYS_THROTTLE_LVC3
   4    GND SOURCE<0> @BASEBOARD_FAB2_LIB.BASEBOARD_FAB2(SCH_1):GND
   3 H_CPU1_PROCHOT_G_N DRAIN<0> @BASEBOARD_FAB2_LIB.BASEBOARD_FAB2(SCH_1):H_CPU1_PROCHOT_G_N

FET_N_DUAL_SMLF-NTJD4001N,FET,A  I52  Q7E3
   2 FM_SYS_THROTTLE_LVC3 GATE<0> @BASEBOARD_FAB2_LIB.BASEBOARD_FAB2(SCH_1):FM_SYS_THROTTLE_LVC3
   1    GND SOURCE<0> @BASEBOARD_FAB2_LIB.BASEBOARD_FAB2(SCH_1):GND
   6 H_CPU0_PROCHOT_G_N DRAIN<0> @BASEBOARD_FAB2_LIB.BASEBOARD_FAB2(SCH_1):H_CPU0_PROCHOT_G_N

FET_N_DUAL_SMLF-NTJD4001N,FET,A  I59  Q7E5
   5 IRQ_CPU0_VRHOT GATE<0> @BASEBOARD_FAB2_LIB.BASEBOARD_FAB2(SCH_1):IRQ_CPU0_VRHOT
   4    GND SOURCE<0> @BASEBOARD_FAB2_LIB.BASEBOARD_FAB2(SCH_1):GND
   3 H_CPU0_PROCHOT_G_N DRAIN<0> @BASEBOARD_FAB2_LIB.BASEBOARD_FAB2(SCH_1):H_CPU0_PROCHOT_G_N

RES_0402-4.75K,1%,1/16W,CHIP,GA  I62  R7E10
   1   P3V3      A @BASEBOARD_FAB2_LIB.BASEBOARD_FAB2(SCH_1):P3V3
   2 IRQ_CPU0_VRHOT      B @BASEBOARD_FAB2_LIB.BASEBOARD_FAB2(SCH_1):IRQ_CPU0_VRHOT

FET_N_DUAL_SMLF-NTJD4001N,FET,A  I69  Q7E6
   5 IRQ_CPU1_VRHOT GATE<0> @BASEBOARD_FAB2_LIB.BASEBOARD_FAB2(SCH_1):IRQ_CPU1_VRHOT
   4    GND SOURCE<0> @BASEBOARD_FAB2_LIB.BASEBOARD_FAB2(SCH_1):GND
   3 H_CPU1_PROCHOT_G_N DRAIN<0> @BASEBOARD_FAB2_LIB.BASEBOARD_FAB2(SCH_1):H_CPU1_PROCHOT_G_N

RES_0402-4.75K,1%,1/16W,CHIP,GA  I72  R7E11
   1   P3V3      A @BASEBOARD_FAB2_LIB.BASEBOARD_FAB2(SCH_1):P3V3
   2 IRQ_CPU1_VRHOT      B @BASEBOARD_FAB2_LIB.BASEBOARD_FAB2(SCH_1):IRQ_CPU1_VRHOT

CAP_A_0402V-0.1UF,16V,10%,X7R,A  I92  C7E3
   1 P3V3_STBY      A @BASEBOARD_FAB2_LIB.BASEBOARD_FAB2(SCH_1):P3V3_STBY
   2    GND      B @BASEBOARD_FAB2_LIB.BASEBOARD_FAB2(SCH_1):GND

RES_0402-4.75K,1%,1/16W,CHIP,GA  I106  R7E7
   1   P3V3      A @BASEBOARD_FAB2_LIB.BASEBOARD_FAB2(SCH_1):P3V3
   2 FM_SYS_THROTTLE_LVC3      B @BASEBOARD_FAB2_LIB.BASEBOARD_FAB2(SCH_1):FM_SYS_THROTTLE_LVC3

RES_0402-0.0,5%,1/16W,CHIP,G21A  I108  R7E9
   1 FM_THROTTLE_N      A @BASEBOARD_FAB2_LIB.BASEBOARD_FAB2(SCH_1):FM_THROTTLE_N
   2 FM_THROTTLE_R_N      B @BASEBOARD_FAB2_LIB.BASEBOARD_FAB2(SCH_1):FM_THROTTLE_R_N

FET_N_DUAL_SMLF-NTJD4001N,FET,A  I111  Q7E5
   2 IRQ_CPU0_PROCHOT_G_N GATE<0> @BASEBOARD_FAB2_LIB.BASEBOARD_FAB2(SCH_1):IRQ_CPU0_PROCHOT_G_N
   1    GND SOURCE<0> @BASEBOARD_FAB2_LIB.BASEBOARD_FAB2(SCH_1):GND
   6 IRQ_CPU0_VRHOT DRAIN<0> @BASEBOARD_FAB2_LIB.BASEBOARD_FAB2(SCH_1):IRQ_CPU0_VRHOT

FET_N_DUAL_SMLF-NTJD4001N,FET,A  I112  Q7E6
   2 IRQ_CPU1_PROCHOT_G_N GATE<0> @BASEBOARD_FAB2_LIB.BASEBOARD_FAB2(SCH_1):IRQ_CPU1_PROCHOT_G_N
   1    GND SOURCE<0> @BASEBOARD_FAB2_LIB.BASEBOARD_FAB2(SCH_1):GND
   6 IRQ_CPU1_VRHOT DRAIN<0> @BASEBOARD_FAB2_LIB.BASEBOARD_FAB2(SCH_1):IRQ_CPU1_VRHOT

FET_N_DUAL_SMLF-NTJD4001N,FET,A  I113  Q2U1
   5 FM_SYS_THROTTLE_LVC3 GATE<0> @BASEBOARD_FAB2_LIB.BASEBOARD_FAB2(SCH_1):FM_SYS_THROTTLE_LVC3
   4    GND SOURCE<0> @BASEBOARD_FAB2_LIB.BASEBOARD_FAB2(SCH_1):GND
   3 H_CPU0_MEMDEF_MEMHOT_G_N DRAIN<0> @BASEBOARD_FAB2_LIB.BASEBOARD_FAB2(SCH_1):H_CPU0_MEMDEF_MEMHOT_G_N

CAP_A_0402V-0.1UF,16V,10%,X7R,A  I115  C7E4
   1 P3V3_STBY      A @BASEBOARD_FAB2_LIB.BASEBOARD_FAB2(SCH_1):P3V3_STBY
   2    GND      B @BASEBOARD_FAB2_LIB.BASEBOARD_FAB2(SCH_1):GND

TTL1G08_SOTLF-NC7SZ08,IC,D1032B  I117  U7E2
   4 IRQ_CPU0_PROCHOT_G_N   Y<0> @BASEBOARD_FAB2_LIB.BASEBOARD_FAB2(SCH_1):IRQ_CPU0_PROCHOT_G_N
   1 FM_PVCCIN_CPU0_PWR_IN_ALERT_N   A<0> @BASEBOARD_FAB2_LIB.BASEBOARD_FAB2(SCH_1):FM_PVCCIN_CPU0_PWR_IN_ALERT_N
   2 IRQ_PVCCIN_CPU0_VRHOT_LVC3_N   B<0> @BASEBOARD_FAB2_LIB.BASEBOARD_FAB2(SCH_1):IRQ_PVCCIN_CPU0_VRHOT_LVC3_N

TTL1G08_SOTLF-NC7SZ08,IC,D1032B  I118  U7E3
   4 IRQ_CPU1_PROCHOT_G_N   Y<0> @BASEBOARD_FAB2_LIB.BASEBOARD_FAB2(SCH_1):IRQ_CPU1_PROCHOT_G_N
   1 FM_PVCCIN_CPU1_PWR_IN_ALERT_N   A<0> @BASEBOARD_FAB2_LIB.BASEBOARD_FAB2(SCH_1):FM_PVCCIN_CPU1_PWR_IN_ALERT_N
   2 IRQ_PVCCIN_CPU1_VRHOT_LVC3_N   B<0> @BASEBOARD_FAB2_LIB.BASEBOARD_FAB2(SCH_1):IRQ_PVCCIN_CPU1_VRHOT_LVC3_N

FET_N_SOT23LF-2N7002,FET,C7925A  I122  Q7E4
   1 FM_THROTTLE_R_N   GATE @BASEBOARD_FAB2_LIB.BASEBOARD_FAB2(SCH_1):FM_THROTTLE_R_N
   2    GND    SRC @BASEBOARD_FAB2_LIB.BASEBOARD_FAB2(SCH_1):GND
   3 FM_SYS_THROTTLE_LVC3    DRN @BASEBOARD_FAB2_LIB.BASEBOARD_FAB2(SCH_1):FM_SYS_THROTTLE_LVC3

FET_N_SOT23LF-2N7002,FET,C7925A  I123  Q7E8
   1 FM_SYS_THROTTLE_LVC3   GATE @BASEBOARD_FAB2_LIB.BASEBOARD_FAB2(SCH_1):FM_SYS_THROTTLE_LVC3
   2    GND    SRC @BASEBOARD_FAB2_LIB.BASEBOARD_FAB2(SCH_1):GND
   3 FM_PWRBRK_N    DRN @BASEBOARD_FAB2_LIB.BASEBOARD_FAB2(SCH_1):FM_PWRBRK_N


DRAWING: @BASEBOARD_FAB2_LIB.BASEBOARD_FAB2(SCH_1):PAGE96 

RES_0402-49.9,1%,1/16W,CHIP,G2A  I2  R6D12
   1 PVCCIO_CPU0      A @BASEBOARD_FAB2_LIB.BASEBOARD_FAB2(SCH_1):PVCCIO_CPU0
   2 RST_CPU0_G_N      B @BASEBOARD_FAB2_LIB.BASEBOARD_FAB2(SCH_1):RST_CPU0_G_N

RES_0402-49.9,1%,1/16W,CHIP,G2A  I3  R6D8
   1 PVCCIO_CPU0      A @BASEBOARD_FAB2_LIB.BASEBOARD_FAB2(SCH_1):PVCCIO_CPU0
   2 PWRGD_CPU0_G      B @BASEBOARD_FAB2_LIB.BASEBOARD_FAB2(SCH_1):PWRGD_CPU0_G

RES_0402-64.9,1.0%,1/16W,CHIP,A  I5  R3P29
   1 PVDDQ_DEF      A @BASEBOARD_FAB2_LIB.BASEBOARD_FAB2(SCH_1):PVDDQ_DEF
   2 PWRGD_CPU0_DRAMPWROK_DEF_G      B @BASEBOARD_FAB2_LIB.BASEBOARD_FAB2(SCH_1):PWRGD_CPU0_DRAMPWROK_DEF_G

RES_0402-64.9,1.0%,1/16W,CHIP,A  I7  R3P38
   1 PVDDQ_ABC      A @BASEBOARD_FAB2_LIB.BASEBOARD_FAB2(SCH_1):PVDDQ_ABC
   2 PWRGD_CPU0_DRAMPWROK_ABC_G      B @BASEBOARD_FAB2_LIB.BASEBOARD_FAB2(SCH_1):PWRGD_CPU0_DRAMPWROK_ABC_G

RES_0402-49.9,1%,1/16W,CHIP,G2A  I25  R3D20
   1 PVCCIO_CPU1      A @BASEBOARD_FAB2_LIB.BASEBOARD_FAB2(SCH_1):PVCCIO_CPU1
   2 RST_CPU1_G_N      B @BASEBOARD_FAB2_LIB.BASEBOARD_FAB2(SCH_1):RST_CPU1_G_N

RES_0402-49.9,1%,1/16W,CHIP,G2A  I26  R3D15
   1 PVCCIO_CPU1      A @BASEBOARD_FAB2_LIB.BASEBOARD_FAB2(SCH_1):PVCCIO_CPU1
   2 PWRGD_CPU1_G      B @BASEBOARD_FAB2_LIB.BASEBOARD_FAB2(SCH_1):PWRGD_CPU1_G

RES_0402-64.9,1.0%,1/16W,CHIP,A  I28  R7M9
   1 PVDDQ_KLM      A @BASEBOARD_FAB2_LIB.BASEBOARD_FAB2(SCH_1):PVDDQ_KLM
   2 PWRGD_CPU1_DRAMPWROK_KLM_G      B @BASEBOARD_FAB2_LIB.BASEBOARD_FAB2(SCH_1):PWRGD_CPU1_DRAMPWROK_KLM_G

RES_0402-64.9,1.0%,1/16W,CHIP,A  I30  R3D21
   1 PVDDQ_GHJ      A @BASEBOARD_FAB2_LIB.BASEBOARD_FAB2(SCH_1):PVDDQ_GHJ
   2 PWRGD_CPU1_DRAMPWROK_GHJ_G      B @BASEBOARD_FAB2_LIB.BASEBOARD_FAB2(SCH_1):PWRGD_CPU1_DRAMPWROK_GHJ_G

RES_0402-1.00K,1%,1/16W,CHIP,GA  I36  R3P36
   1 P3V3_STBY      A @BASEBOARD_FAB2_LIB.BASEBOARD_FAB2(SCH_1):P3V3_STBY
   2 PU_GTL2014_1_DIR      B @BASEBOARD_FAB2_LIB.BASEBOARD_FAB2(SCH_1):PU_GTL2014_1_DIR

GTL2014_SM-IC,D66151-001  I42  U3P1
  13 PWRGD_DRAMPWRGD     A0 @BASEBOARD_FAB2_LIB.BASEBOARD_FAB2(SCH_1):PWRGD_DRAMPWRGD
  12 PWRGD_DRAMPWRGD     A1 @BASEBOARD_FAB2_LIB.BASEBOARD_FAB2(SCH_1):PWRGD_DRAMPWRGD
  10 RST_CPU0_LVC3_N     A2 @BASEBOARD_FAB2_LIB.BASEBOARD_FAB2(SCH_1):RST_CPU0_LVC3_N
   9 PWRGD_CPU0_LVC3     A3 @BASEBOARD_FAB2_LIB.BASEBOARD_FAB2(SCH_1):PWRGD_CPU0_LVC3
   2 PWRGD_CPU0_DRAMPWROK_DEF_G     B0 @BASEBOARD_FAB2_LIB.BASEBOARD_FAB2(SCH_1):PWRGD_CPU0_DRAMPWROK_DEF_G
   3 PWRGD_CPU0_DRAMPWROK_ABC_G     B1 @BASEBOARD_FAB2_LIB.BASEBOARD_FAB2(SCH_1):PWRGD_CPU0_DRAMPWROK_ABC_G
   5 RST_CPU0_G_N     B2 @BASEBOARD_FAB2_LIB.BASEBOARD_FAB2(SCH_1):RST_CPU0_G_N
   6 PWRGD_CPU0_G     B3 @BASEBOARD_FAB2_LIB.BASEBOARD_FAB2(SCH_1):PWRGD_CPU0_G
   1 PU_GTL2014_1_DIR    DIR @BASEBOARD_FAB2_LIB.BASEBOARD_FAB2(SCH_1):PU_GTL2014_1_DIR
  11    GND GND<2> @BASEBOARD_FAB2_LIB.BASEBOARD_FAB2(SCH_1):GND
   8    GND GND<1> @BASEBOARD_FAB2_LIB.BASEBOARD_FAB2(SCH_1):GND
   7    GND GND<0> @BASEBOARD_FAB2_LIB.BASEBOARD_FAB2(SCH_1):GND
  14 P3V3_STBY    VCC @BASEBOARD_FAB2_LIB.BASEBOARD_FAB2(SCH_1):P3V3_STBY
   4 PD_GTL2014_1_VREF   VREF @BASEBOARD_FAB2_LIB.BASEBOARD_FAB2(SCH_1):PD_GTL2014_1_VREF

GTL2014_SM-IC,D66151-001  I46  U4C2
  13 PWRGD_DRAMPWRGD     A0 @BASEBOARD_FAB2_LIB.BASEBOARD_FAB2(SCH_1):PWRGD_DRAMPWRGD
  12 PWRGD_DRAMPWRGD     A1 @BASEBOARD_FAB2_LIB.BASEBOARD_FAB2(SCH_1):PWRGD_DRAMPWRGD
  10 RST_CPU1_LVC3_N     A2 @BASEBOARD_FAB2_LIB.BASEBOARD_FAB2(SCH_1):RST_CPU1_LVC3_N
   9 PWRGD_CPU1_LVC3     A3 @BASEBOARD_FAB2_LIB.BASEBOARD_FAB2(SCH_1):PWRGD_CPU1_LVC3
   2 PWRGD_CPU1_DRAMPWROK_KLM_G     B0 @BASEBOARD_FAB2_LIB.BASEBOARD_FAB2(SCH_1):PWRGD_CPU1_DRAMPWROK_KLM_G
   3 PWRGD_CPU1_DRAMPWROK_GHJ_G     B1 @BASEBOARD_FAB2_LIB.BASEBOARD_FAB2(SCH_1):PWRGD_CPU1_DRAMPWROK_GHJ_G
   5 RST_CPU1_G_N     B2 @BASEBOARD_FAB2_LIB.BASEBOARD_FAB2(SCH_1):RST_CPU1_G_N
   6 PWRGD_CPU1_G     B3 @BASEBOARD_FAB2_LIB.BASEBOARD_FAB2(SCH_1):PWRGD_CPU1_G
   1 PU_GTL2014_2_DIR    DIR @BASEBOARD_FAB2_LIB.BASEBOARD_FAB2(SCH_1):PU_GTL2014_2_DIR
  11    GND GND<2> @BASEBOARD_FAB2_LIB.BASEBOARD_FAB2(SCH_1):GND
   8    GND GND<1> @BASEBOARD_FAB2_LIB.BASEBOARD_FAB2(SCH_1):GND
   7    GND GND<0> @BASEBOARD_FAB2_LIB.BASEBOARD_FAB2(SCH_1):GND
  14 P3V3_STBY    VCC @BASEBOARD_FAB2_LIB.BASEBOARD_FAB2(SCH_1):P3V3_STBY
   4 PD_GTL2014_2_VREF   VREF @BASEBOARD_FAB2_LIB.BASEBOARD_FAB2(SCH_1):PD_GTL2014_2_VREF

RES_0402-1.00K,1%,1/16W,CHIP,GA  I55  R4C8
   1 P3V3_STBY      A @BASEBOARD_FAB2_LIB.BASEBOARD_FAB2(SCH_1):P3V3_STBY
   2 PU_GTL2014_2_DIR      B @BASEBOARD_FAB2_LIB.BASEBOARD_FAB2(SCH_1):PU_GTL2014_2_DIR

RES_0402-1.00K,1%,1/16W,CHIP,GA  I69  R4C9
   1    GND      A @BASEBOARD_FAB2_LIB.BASEBOARD_FAB2(SCH_1):GND
   2 PD_GTL2014_2_VREF      B @BASEBOARD_FAB2_LIB.BASEBOARD_FAB2(SCH_1):PD_GTL2014_2_VREF

RES_0402-1.00K,1%,1/16W,CHIP,GA  I71  R3P32
   1    GND      A @BASEBOARD_FAB2_LIB.BASEBOARD_FAB2(SCH_1):GND
   2 PD_GTL2014_1_VREF      B @BASEBOARD_FAB2_LIB.BASEBOARD_FAB2(SCH_1):PD_GTL2014_1_VREF

CAP_A_0402V-1.0UF,6.3V,10%,X6SA  I73  C3P42
   1 P3V3_STBY      A @BASEBOARD_FAB2_LIB.BASEBOARD_FAB2(SCH_1):P3V3_STBY
   2    GND      B @BASEBOARD_FAB2_LIB.BASEBOARD_FAB2(SCH_1):GND

CAP_A_0402V-1.0UF,6.3V,10%,X6SA  I75  C4C3
   1 P3V3_STBY      A @BASEBOARD_FAB2_LIB.BASEBOARD_FAB2(SCH_1):P3V3_STBY
   2    GND      B @BASEBOARD_FAB2_LIB.BASEBOARD_FAB2(SCH_1):GND


DRAWING: @BASEBOARD_FAB2_LIB.BASEBOARD_FAB2(SCH_1):PAGE97 

RES_0402-0.0,5%,1/16W,CHIP,G21A  I33  R3D18
   1 H_CPU0_FAST_WAKE_N      A @BASEBOARD_FAB2_LIB.BASEBOARD_FAB2(SCH_1):H_CPU0_FAST_WAKE_N
   2 H_CPU1_FAST_WAKE_N      B @BASEBOARD_FAB2_LIB.BASEBOARD_FAB2(SCH_1):H_CPU1_FAST_WAKE_N

RES_0402-150.0,1%,1/16W,CHIP,GA  I42  R4R4
   1 PVCCIO_CPU0      A @BASEBOARD_FAB2_LIB.BASEBOARD_FAB2(SCH_1):PVCCIO_CPU0
   2 H_CPU0_FAST_WAKE_N      B @BASEBOARD_FAB2_LIB.BASEBOARD_FAB2(SCH_1):H_CPU0_FAST_WAKE_N

RES_0402-150.0,1%,1/16W,CHIP,GA  I44  R7P20
   1 PVCCIO_CPU0      A @BASEBOARD_FAB2_LIB.BASEBOARD_FAB2(SCH_1):PVCCIO_CPU0
   2 H_CPU1_FAST_WAKE_N      B @BASEBOARD_FAB2_LIB.BASEBOARD_FAB2(SCH_1):H_CPU1_FAST_WAKE_N

RES_0402-240,1.0%,1/16W,CHIP,GA  I72  R4P21
   1 PVCCIO_CPU0      A @BASEBOARD_FAB2_LIB.BASEBOARD_FAB2(SCH_1):PVCCIO_CPU0
   2 PU_CPU0_TSC_SYNC      B @BASEBOARD_FAB2_LIB.BASEBOARD_FAB2(SCH_1):PU_CPU0_TSC_SYNC

RES_0402-240,1.0%,1/16W,CHIP,GA  I76  R4C10
   1 PVCCIO_CPU1      A @BASEBOARD_FAB2_LIB.BASEBOARD_FAB2(SCH_1):PVCCIO_CPU1
   2 PU_CPU1_TSC_SYNC      B @BASEBOARD_FAB2_LIB.BASEBOARD_FAB2(SCH_1):PU_CPU1_TSC_SYNC

RES_0402-10.0K,1%,1/16W,CHIP,GA  I80  R4P5
   1    GND      A @BASEBOARD_FAB2_LIB.BASEBOARD_FAB2(SCH_1):GND
   2 PD_CPU0_MCP01_DMON      B @BASEBOARD_FAB2_LIB.BASEBOARD_FAB2(SCH_1):PD_CPU0_MCP01_DMON

RES_0402-10.0K,1%,1/16W,CHIP,GA  I81  R7P13
   1    GND      A @BASEBOARD_FAB2_LIB.BASEBOARD_FAB2(SCH_1):GND
   2 PD_CPU1_MCP01_DMON      B @BASEBOARD_FAB2_LIB.BASEBOARD_FAB2(SCH_1):PD_CPU1_MCP01_DMON


DRAWING: @BASEBOARD_FAB2_LIB.BASEBOARD_FAB2(SCH_1):PAGE98 

RES_0402-1.00K,1%,1/16W,CHIP,GA  I4  R4F5
   1 M_A_VREF      A @BASEBOARD_FAB2_LIB.BASEBOARD_FAB2(SCH_1):M_A_VREF
   2    GND      B @BASEBOARD_FAB2_LIB.BASEBOARD_FAB2(SCH_1):GND

RES_0402-2,1.0%,1/16W,CHIP,G21A  I5  R4F3
   1 M_A_CPU_VREF      A @BASEBOARD_FAB2_LIB.BASEBOARD_FAB2(SCH_1):M_A_CPU_VREF
   2 M_A_VREF      B @BASEBOARD_FAB2_LIB.BASEBOARD_FAB2(SCH_1):M_A_VREF

CAP_A_0402V-0.01UF,25V,10%,X7RA  I7  C4F9
   1 M_A_CPU_VREF      A @BASEBOARD_FAB2_LIB.BASEBOARD_FAB2(SCH_1):M_A_CPU_VREF
   2    GND      B @BASEBOARD_FAB2_LIB.BASEBOARD_FAB2(SCH_1):GND

RES_0402-1.00K,1%,1/16W,CHIP,GA  I9  R6M1
   1 PVDDQ_DEF      A @BASEBOARD_FAB2_LIB.BASEBOARD_FAB2(SCH_1):PVDDQ_DEF
   2 M_D_VREF      B @BASEBOARD_FAB2_LIB.BASEBOARD_FAB2(SCH_1):M_D_VREF

RES_0402-1.00K,1%,1/16W,CHIP,GA  I12  R6L16
   1 M_D_VREF      A @BASEBOARD_FAB2_LIB.BASEBOARD_FAB2(SCH_1):M_D_VREF
   2    GND      B @BASEBOARD_FAB2_LIB.BASEBOARD_FAB2(SCH_1):GND

RES_0402-2,1.0%,1/16W,CHIP,G21A  I14  R6M2
   1 M_D_CPU_VREF      A @BASEBOARD_FAB2_LIB.BASEBOARD_FAB2(SCH_1):M_D_CPU_VREF
   2 M_D_VREF      B @BASEBOARD_FAB2_LIB.BASEBOARD_FAB2(SCH_1):M_D_VREF

CAP_A_0402V-0.01UF,25V,10%,X7RA  I33  C6M2
   1 M_D_CPU_VREF      A @BASEBOARD_FAB2_LIB.BASEBOARD_FAB2(SCH_1):M_D_CPU_VREF
   2    GND      B @BASEBOARD_FAB2_LIB.BASEBOARD_FAB2(SCH_1):GND

RES_0402-1.00K,1%,1/16W,CHIP,GA  I36  R4F4
   1 PVDDQ_ABC      A @BASEBOARD_FAB2_LIB.BASEBOARD_FAB2(SCH_1):PVDDQ_ABC
   2 M_A_VREF      B @BASEBOARD_FAB2_LIB.BASEBOARD_FAB2(SCH_1):M_A_VREF

RES_0402-1.00K,1%,1/16W,CHIP,GA  I38  R4G2
   1 PVDDQ_ABC      A @BASEBOARD_FAB2_LIB.BASEBOARD_FAB2(SCH_1):PVDDQ_ABC
   2 M_B_VREF      B @BASEBOARD_FAB2_LIB.BASEBOARD_FAB2(SCH_1):M_B_VREF

RES_0402-1.00K,1%,1/16W,CHIP,GA  I40  R4G3
   1 M_B_VREF      A @BASEBOARD_FAB2_LIB.BASEBOARD_FAB2(SCH_1):M_B_VREF
   2    GND      B @BASEBOARD_FAB2_LIB.BASEBOARD_FAB2(SCH_1):GND

RES_0402-2,1.0%,1/16W,CHIP,G21A  I42  R4G1
   1 M_B_CPU_VREF      A @BASEBOARD_FAB2_LIB.BASEBOARD_FAB2(SCH_1):M_B_CPU_VREF
   2 M_B_VREF      B @BASEBOARD_FAB2_LIB.BASEBOARD_FAB2(SCH_1):M_B_VREF

CAP_A_0402V-0.01UF,25V,10%,X7RA  I43  C4G1
   1 M_B_CPU_VREF      A @BASEBOARD_FAB2_LIB.BASEBOARD_FAB2(SCH_1):M_B_CPU_VREF
   2    GND      B @BASEBOARD_FAB2_LIB.BASEBOARD_FAB2(SCH_1):GND

RES_0402-1.00K,1%,1/16W,CHIP,GA  I46  R4G21
   1 PVDDQ_ABC      A @BASEBOARD_FAB2_LIB.BASEBOARD_FAB2(SCH_1):PVDDQ_ABC
   2 M_C_VREF      B @BASEBOARD_FAB2_LIB.BASEBOARD_FAB2(SCH_1):M_C_VREF

RES_0402-1.00K,1%,1/16W,CHIP,GA  I48  R4G22
   1 M_C_VREF      A @BASEBOARD_FAB2_LIB.BASEBOARD_FAB2(SCH_1):M_C_VREF
   2    GND      B @BASEBOARD_FAB2_LIB.BASEBOARD_FAB2(SCH_1):GND

RES_0402-2,1.0%,1/16W,CHIP,G21A  I50  R4G20
   1 M_C_CPU_VREF      A @BASEBOARD_FAB2_LIB.BASEBOARD_FAB2(SCH_1):M_C_CPU_VREF
   2 M_C_VREF      B @BASEBOARD_FAB2_LIB.BASEBOARD_FAB2(SCH_1):M_C_VREF

CAP_A_0402V-0.01UF,25V,10%,X7RA  I51  C4G17
   1 M_C_CPU_VREF      A @BASEBOARD_FAB2_LIB.BASEBOARD_FAB2(SCH_1):M_C_CPU_VREF
   2    GND      B @BASEBOARD_FAB2_LIB.BASEBOARD_FAB2(SCH_1):GND

RES_0402-1.00K,1%,1/16W,CHIP,GA  I54  R6L13
   1 PVDDQ_DEF      A @BASEBOARD_FAB2_LIB.BASEBOARD_FAB2(SCH_1):PVDDQ_DEF
   2 M_E_VREF      B @BASEBOARD_FAB2_LIB.BASEBOARD_FAB2(SCH_1):M_E_VREF

RES_0402-1.00K,1%,1/16W,CHIP,GA  I56  R6L12
   1 M_E_VREF      A @BASEBOARD_FAB2_LIB.BASEBOARD_FAB2(SCH_1):M_E_VREF
   2    GND      B @BASEBOARD_FAB2_LIB.BASEBOARD_FAB2(SCH_1):GND

RES_0402-2,1.0%,1/16W,CHIP,G21A  I58  R6L14
   1 M_E_CPU_VREF      A @BASEBOARD_FAB2_LIB.BASEBOARD_FAB2(SCH_1):M_E_CPU_VREF
   2 M_E_VREF      B @BASEBOARD_FAB2_LIB.BASEBOARD_FAB2(SCH_1):M_E_VREF

CAP_A_0402V-0.01UF,25V,10%,X7RA  I59  C6L7
   1 M_E_CPU_VREF      A @BASEBOARD_FAB2_LIB.BASEBOARD_FAB2(SCH_1):M_E_CPU_VREF
   2    GND      B @BASEBOARD_FAB2_LIB.BASEBOARD_FAB2(SCH_1):GND

RES_0402-1.00K,1%,1/16W,CHIP,GA  I62  R6L2
   1 PVDDQ_DEF      A @BASEBOARD_FAB2_LIB.BASEBOARD_FAB2(SCH_1):PVDDQ_DEF
   2 M_F_VREF      B @BASEBOARD_FAB2_LIB.BASEBOARD_FAB2(SCH_1):M_F_VREF

RES_0402-1.00K,1%,1/16W,CHIP,GA  I64  R6L1
   1 M_F_VREF      A @BASEBOARD_FAB2_LIB.BASEBOARD_FAB2(SCH_1):M_F_VREF
   2    GND      B @BASEBOARD_FAB2_LIB.BASEBOARD_FAB2(SCH_1):GND

RES_0402-2,1.0%,1/16W,CHIP,G21A  I66  R6L3
   1 M_F_CPU_VREF      A @BASEBOARD_FAB2_LIB.BASEBOARD_FAB2(SCH_1):M_F_CPU_VREF
   2 M_F_VREF      B @BASEBOARD_FAB2_LIB.BASEBOARD_FAB2(SCH_1):M_F_VREF

CAP_A_0402V-0.01UF,25V,10%,X7RA  I67  C6L2
   1 M_F_CPU_VREF      A @BASEBOARD_FAB2_LIB.BASEBOARD_FAB2(SCH_1):M_F_CPU_VREF
   2    GND      B @BASEBOARD_FAB2_LIB.BASEBOARD_FAB2(SCH_1):GND


DRAWING: @BASEBOARD_FAB2_LIB.BASEBOARD_FAB2(SCH_1):PAGE99 

CAP_A_0402V-0.1UF,16V,10%,X7R,A  I2  C6F2
   1 PVCCIO_CPU0      A @BASEBOARD_FAB2_LIB.BASEBOARD_FAB2(SCH_1):PVCCIO_CPU0
   2    GND      B @BASEBOARD_FAB2_LIB.BASEBOARD_FAB2(SCH_1):GND

CAP_A_0402V-0.1UF,16V,10%,X7R,A  I7  C6F3
   1 PVPP_ABC      A @BASEBOARD_FAB2_LIB.BASEBOARD_FAB2(SCH_1):PVPP_ABC
   2    GND      B @BASEBOARD_FAB2_LIB.BASEBOARD_FAB2(SCH_1):GND

RES_0402-20.0,1%,1/16W,CHIP,G2A  I9  R4T9
   1 SMB_DDR_ABC_VPP_SCL_R      A @BASEBOARD_FAB2_LIB.BASEBOARD_FAB2(SCH_1):SMB_DDR_ABC_VPP_SCL_R
   2 SMB_DDR_ABC_VPP_SCL      B @BASEBOARD_FAB2_LIB.BASEBOARD_FAB2(SCH_1):SMB_DDR_ABC_VPP_SCL

RES_0402-20.0,1%,1/16W,CHIP,G2A  I10  R4T10
   1 SMB_DDR_ABC_VPP_SDA_R      A @BASEBOARD_FAB2_LIB.BASEBOARD_FAB2(SCH_1):SMB_DDR_ABC_VPP_SDA_R
   2 SMB_DDR_ABC_VPP_SDA      B @BASEBOARD_FAB2_LIB.BASEBOARD_FAB2(SCH_1):SMB_DDR_ABC_VPP_SDA

RES_0402-665,1.0%,1/16W,CHIP,GA  I11  R4T8
   1 PVPP_ABC      A @BASEBOARD_FAB2_LIB.BASEBOARD_FAB2(SCH_1):PVPP_ABC
   2 SMB_DDR_ABC_VPP_SDA_R      B @BASEBOARD_FAB2_LIB.BASEBOARD_FAB2(SCH_1):SMB_DDR_ABC_VPP_SDA_R

RES_0402-665,1.0%,1/16W,CHIP,GA  I13  R4T7
   1 PVPP_ABC      A @BASEBOARD_FAB2_LIB.BASEBOARD_FAB2(SCH_1):PVPP_ABC
   2 SMB_DDR_ABC_VPP_SCL_R      B @BASEBOARD_FAB2_LIB.BASEBOARD_FAB2(SCH_1):SMB_DDR_ABC_VPP_SCL_R

PCA9617_SSOP-IC,G81764-001-GNDA  I15  U6F1
   5 TP_SMB_DDR_ABC_EN     EN @BASEBOARD_FAB2_LIB.BASEBOARD_FAB2(SCH_1):TP_SMB_DDR_ABC_EN
   2 SMB_DDR_ABC_SCL_G   SCLA @BASEBOARD_FAB2_LIB.BASEBOARD_FAB2(SCH_1):SMB_DDR_ABC_SCL_G
   7 SMB_DDR_ABC_VPP_SCL_R   SCLB @BASEBOARD_FAB2_LIB.BASEBOARD_FAB2(SCH_1):SMB_DDR_ABC_VPP_SCL_R
   3 SMB_DDR_ABC_SDA_G   SDAA @BASEBOARD_FAB2_LIB.BASEBOARD_FAB2(SCH_1):SMB_DDR_ABC_SDA_G
   6 SMB_DDR_ABC_VPP_SDA_R   SDAB @BASEBOARD_FAB2_LIB.BASEBOARD_FAB2(SCH_1):SMB_DDR_ABC_VPP_SDA_R
   1 PVCCIO_CPU0   VCCA @BASEBOARD_FAB2_LIB.BASEBOARD_FAB2(SCH_1):PVCCIO_CPU0
   8 PVPP_ABC   VCCB @BASEBOARD_FAB2_LIB.BASEBOARD_FAB2(SCH_1):PVPP_ABC

RES_0402-240,1.0%,1/16W,CHIP,GA  I17  R4T6
   1 PVCCIO_CPU0      A @BASEBOARD_FAB2_LIB.BASEBOARD_FAB2(SCH_1):PVCCIO_CPU0
   2 SMB_DDR_ABC_SDA_G      B @BASEBOARD_FAB2_LIB.BASEBOARD_FAB2(SCH_1):SMB_DDR_ABC_SDA_G

RES_0402-240,1.0%,1/16W,CHIP,GA  I19  R4T5
   1 PVCCIO_CPU0      A @BASEBOARD_FAB2_LIB.BASEBOARD_FAB2(SCH_1):PVCCIO_CPU0
   2 SMB_DDR_ABC_SCL_G      B @BASEBOARD_FAB2_LIB.BASEBOARD_FAB2(SCH_1):SMB_DDR_ABC_SCL_G

RES_0402-10.0,1%,1/16W,CHIP,G2A  I20  R4T4
   1 SMB_DDR_ABC_SDA_G_R      A @BASEBOARD_FAB2_LIB.BASEBOARD_FAB2(SCH_1):SMB_DDR_ABC_SDA_G_R
   2 SMB_DDR_ABC_SDA_G      B @BASEBOARD_FAB2_LIB.BASEBOARD_FAB2(SCH_1):SMB_DDR_ABC_SDA_G

CAP_A_0402V-0.1UF,16V,10%,X7R,A  I23  C7E1
   1 PVCCIO_CPU0      A @BASEBOARD_FAB2_LIB.BASEBOARD_FAB2(SCH_1):PVCCIO_CPU0
   2    GND      B @BASEBOARD_FAB2_LIB.BASEBOARD_FAB2(SCH_1):GND

CAP_A_0402V-0.1UF,16V,10%,X7R,A  I27  C4G22
   1 PVCCIO_CPU1      A @BASEBOARD_FAB2_LIB.BASEBOARD_FAB2(SCH_1):PVCCIO_CPU1
   2    GND      B @BASEBOARD_FAB2_LIB.BASEBOARD_FAB2(SCH_1):GND

CAP_A_0402V-0.1UF,16V,10%,X7R,A  I32  C7E2
   1 PVPP_DEF      A @BASEBOARD_FAB2_LIB.BASEBOARD_FAB2(SCH_1):PVPP_DEF
   2    GND      B @BASEBOARD_FAB2_LIB.BASEBOARD_FAB2(SCH_1):GND

RES_0402-20.0,1%,1/16W,CHIP,G2A  I34  R3R9
   1 SMB_DDR_DEF_VPP_SDA_R      A @BASEBOARD_FAB2_LIB.BASEBOARD_FAB2(SCH_1):SMB_DDR_DEF_VPP_SDA_R
   2 SMB_DDR_DEF_VPP_SDA      B @BASEBOARD_FAB2_LIB.BASEBOARD_FAB2(SCH_1):SMB_DDR_DEF_VPP_SDA

RES_0402-20.0,1%,1/16W,CHIP,G2A  I35  R3R8
   1 SMB_DDR_DEF_VPP_SCL_R      A @BASEBOARD_FAB2_LIB.BASEBOARD_FAB2(SCH_1):SMB_DDR_DEF_VPP_SCL_R
   2 SMB_DDR_DEF_VPP_SCL      B @BASEBOARD_FAB2_LIB.BASEBOARD_FAB2(SCH_1):SMB_DDR_DEF_VPP_SCL

CAP_A_0402V-0.1UF,16V,10%,X7R,A  I41  C4G25
   1 PVPP_GHJ      A @BASEBOARD_FAB2_LIB.BASEBOARD_FAB2(SCH_1):PVPP_GHJ
   2    GND      B @BASEBOARD_FAB2_LIB.BASEBOARD_FAB2(SCH_1):GND

RES_0402-20.0,1%,1/16W,CHIP,G2A  I42  R6U13
   1 SMB_DDR_GHJ_VPP_SCL_R      A @BASEBOARD_FAB2_LIB.BASEBOARD_FAB2(SCH_1):SMB_DDR_GHJ_VPP_SCL_R
   2 SMB_DDR_GHJ_VPP_SCL      B @BASEBOARD_FAB2_LIB.BASEBOARD_FAB2(SCH_1):SMB_DDR_GHJ_VPP_SCL

CAP_A_0402V-0.1UF,16V,10%,X7R,A  I47  C3B4
   1 PVCCIO_CPU1      A @BASEBOARD_FAB2_LIB.BASEBOARD_FAB2(SCH_1):PVCCIO_CPU1
   2    GND      B @BASEBOARD_FAB2_LIB.BASEBOARD_FAB2(SCH_1):GND

CAP_A_0402V-0.1UF,16V,10%,X7R,A  I53  C3B5
   1 PVPP_KLM      A @BASEBOARD_FAB2_LIB.BASEBOARD_FAB2(SCH_1):PVPP_KLM
   2    GND      B @BASEBOARD_FAB2_LIB.BASEBOARD_FAB2(SCH_1):GND

RES_0402-20.0,1%,1/16W,CHIP,G2A  I55  R7M5
   1 SMB_DDR_KLM_VPP_SDA_R      A @BASEBOARD_FAB2_LIB.BASEBOARD_FAB2(SCH_1):SMB_DDR_KLM_VPP_SDA_R
   2 SMB_DDR_KLM_VPP_SDA      B @BASEBOARD_FAB2_LIB.BASEBOARD_FAB2(SCH_1):SMB_DDR_KLM_VPP_SDA

RES_0402-20.0,1%,1/16W,CHIP,G2A  I56  R7M4
   1 SMB_DDR_KLM_VPP_SCL_R      A @BASEBOARD_FAB2_LIB.BASEBOARD_FAB2(SCH_1):SMB_DDR_KLM_VPP_SCL_R
   2 SMB_DDR_KLM_VPP_SCL      B @BASEBOARD_FAB2_LIB.BASEBOARD_FAB2(SCH_1):SMB_DDR_KLM_VPP_SCL

PCA9617_SSOP-IC,G81764-001-GNDA  I61  U7E1
   5 TP_SMB_DDR_DEF_EN     EN @BASEBOARD_FAB2_LIB.BASEBOARD_FAB2(SCH_1):TP_SMB_DDR_DEF_EN
   2 SMB_DDR_DEF_SCL_G   SCLA @BASEBOARD_FAB2_LIB.BASEBOARD_FAB2(SCH_1):SMB_DDR_DEF_SCL_G
   7 SMB_DDR_DEF_VPP_SCL_R   SCLB @BASEBOARD_FAB2_LIB.BASEBOARD_FAB2(SCH_1):SMB_DDR_DEF_VPP_SCL_R
   3 SMB_DDR_DEF_SDA_G   SDAA @BASEBOARD_FAB2_LIB.BASEBOARD_FAB2(SCH_1):SMB_DDR_DEF_SDA_G
   6 SMB_DDR_DEF_VPP_SDA_R   SDAB @BASEBOARD_FAB2_LIB.BASEBOARD_FAB2(SCH_1):SMB_DDR_DEF_VPP_SDA_R
   1 PVCCIO_CPU0   VCCA @BASEBOARD_FAB2_LIB.BASEBOARD_FAB2(SCH_1):PVCCIO_CPU0
   8 PVPP_DEF   VCCB @BASEBOARD_FAB2_LIB.BASEBOARD_FAB2(SCH_1):PVPP_DEF

PCA9617_SSOP-IC,G81764-001-GNDA  I63  U4G1
   5 TP_SMB_DDR_GHJ_EN     EN @BASEBOARD_FAB2_LIB.BASEBOARD_FAB2(SCH_1):TP_SMB_DDR_GHJ_EN
   2 SMB_DDR_GHJ_SCL_G   SCLA @BASEBOARD_FAB2_LIB.BASEBOARD_FAB2(SCH_1):SMB_DDR_GHJ_SCL_G
   7 SMB_DDR_GHJ_VPP_SCL_R   SCLB @BASEBOARD_FAB2_LIB.BASEBOARD_FAB2(SCH_1):SMB_DDR_GHJ_VPP_SCL_R
   3 SMB_DDR_GHJ_SDA_G   SDAA @BASEBOARD_FAB2_LIB.BASEBOARD_FAB2(SCH_1):SMB_DDR_GHJ_SDA_G
   6 SMB_DDR_GHJ_VPP_SDA_R   SDAB @BASEBOARD_FAB2_LIB.BASEBOARD_FAB2(SCH_1):SMB_DDR_GHJ_VPP_SDA_R
   1 PVCCIO_CPU1   VCCA @BASEBOARD_FAB2_LIB.BASEBOARD_FAB2(SCH_1):PVCCIO_CPU1
   8 PVPP_GHJ   VCCB @BASEBOARD_FAB2_LIB.BASEBOARD_FAB2(SCH_1):PVPP_GHJ

RES_0402-240,1.0%,1/16W,CHIP,GA  I65  R3R13
   1 PVCCIO_CPU0      A @BASEBOARD_FAB2_LIB.BASEBOARD_FAB2(SCH_1):PVCCIO_CPU0
   2 SMB_DDR_DEF_SDA_G      B @BASEBOARD_FAB2_LIB.BASEBOARD_FAB2(SCH_1):SMB_DDR_DEF_SDA_G

RES_0402-240,1.0%,1/16W,CHIP,GA  I67  R3P60
   1 PVCCIO_CPU0      A @BASEBOARD_FAB2_LIB.BASEBOARD_FAB2(SCH_1):PVCCIO_CPU0
   2 SMB_DDR_DEF_SCL_G      B @BASEBOARD_FAB2_LIB.BASEBOARD_FAB2(SCH_1):SMB_DDR_DEF_SCL_G

RES_0402-240,1.0%,1/16W,CHIP,GA  I70  R6T1
   1 PVCCIO_CPU1      A @BASEBOARD_FAB2_LIB.BASEBOARD_FAB2(SCH_1):PVCCIO_CPU1
   2 SMB_DDR_GHJ_SDA_G      B @BASEBOARD_FAB2_LIB.BASEBOARD_FAB2(SCH_1):SMB_DDR_GHJ_SDA_G

RES_0402-240,1.0%,1/16W,CHIP,GA  I72  R6T2
   1 PVCCIO_CPU1      A @BASEBOARD_FAB2_LIB.BASEBOARD_FAB2(SCH_1):PVCCIO_CPU1
   2 SMB_DDR_GHJ_SCL_G      B @BASEBOARD_FAB2_LIB.BASEBOARD_FAB2(SCH_1):SMB_DDR_GHJ_SCL_G

PCA9617_SSOP-IC,G81764-001-GNDA  I75  U3B1
   5 TP_SMB_DDR_KLM_EN     EN @BASEBOARD_FAB2_LIB.BASEBOARD_FAB2(SCH_1):TP_SMB_DDR_KLM_EN
   2 SMB_DDR_KLM_SCL_G   SCLA @BASEBOARD_FAB2_LIB.BASEBOARD_FAB2(SCH_1):SMB_DDR_KLM_SCL_G
   7 SMB_DDR_KLM_VPP_SCL_R   SCLB @BASEBOARD_FAB2_LIB.BASEBOARD_FAB2(SCH_1):SMB_DDR_KLM_VPP_SCL_R
   3 SMB_DDR_KLM_SDA_G   SDAA @BASEBOARD_FAB2_LIB.BASEBOARD_FAB2(SCH_1):SMB_DDR_KLM_SDA_G
   6 SMB_DDR_KLM_VPP_SDA_R   SDAB @BASEBOARD_FAB2_LIB.BASEBOARD_FAB2(SCH_1):SMB_DDR_KLM_VPP_SDA_R
   1 PVCCIO_CPU1   VCCA @BASEBOARD_FAB2_LIB.BASEBOARD_FAB2(SCH_1):PVCCIO_CPU1
   8 PVPP_KLM   VCCB @BASEBOARD_FAB2_LIB.BASEBOARD_FAB2(SCH_1):PVPP_KLM

RES_0402-240,1.0%,1/16W,CHIP,GA  I77  R7M7
   1 PVCCIO_CPU1      A @BASEBOARD_FAB2_LIB.BASEBOARD_FAB2(SCH_1):PVCCIO_CPU1
   2 SMB_DDR_KLM_SDA_G      B @BASEBOARD_FAB2_LIB.BASEBOARD_FAB2(SCH_1):SMB_DDR_KLM_SDA_G

RES_0402-240,1.0%,1/16W,CHIP,GA  I79  R7M2
   1 PVCCIO_CPU1      A @BASEBOARD_FAB2_LIB.BASEBOARD_FAB2(SCH_1):PVCCIO_CPU1
   2 SMB_DDR_KLM_SCL_G      B @BASEBOARD_FAB2_LIB.BASEBOARD_FAB2(SCH_1):SMB_DDR_KLM_SCL_G

RES_0402-10.0,1%,1/16W,CHIP,G2A  I83  R4T3
   1 SMB_DDR_ABC_SCL_G_R      A @BASEBOARD_FAB2_LIB.BASEBOARD_FAB2(SCH_1):SMB_DDR_ABC_SCL_G_R
   2 SMB_DDR_ABC_SCL_G      B @BASEBOARD_FAB2_LIB.BASEBOARD_FAB2(SCH_1):SMB_DDR_ABC_SCL_G

RES_0402-10.0,1%,1/16W,CHIP,G2A  I88  R3R7
   1 SMB_DDR_DEF_SCL_G_R      A @BASEBOARD_FAB2_LIB.BASEBOARD_FAB2(SCH_1):SMB_DDR_DEF_SCL_G_R
   2 SMB_DDR_DEF_SCL_G      B @BASEBOARD_FAB2_LIB.BASEBOARD_FAB2(SCH_1):SMB_DDR_DEF_SCL_G

RES_0402-10.0,1%,1/16W,CHIP,G2A  I92  R6T3
   1 SMB_DDR_GHJ_SCL_G_R      A @BASEBOARD_FAB2_LIB.BASEBOARD_FAB2(SCH_1):SMB_DDR_GHJ_SCL_G_R
   2 SMB_DDR_GHJ_SCL_G      B @BASEBOARD_FAB2_LIB.BASEBOARD_FAB2(SCH_1):SMB_DDR_GHJ_SCL_G

RES_0402-10.0,1%,1/16W,CHIP,G2A  I98  R7M3
   1 SMB_DDR_KLM_SCL_G_R      A @BASEBOARD_FAB2_LIB.BASEBOARD_FAB2(SCH_1):SMB_DDR_KLM_SCL_G_R
   2 SMB_DDR_KLM_SCL_G      B @BASEBOARD_FAB2_LIB.BASEBOARD_FAB2(SCH_1):SMB_DDR_KLM_SCL_G

RES_0402-665,1.0%,1/16W,CHIP,GA  I101  R3R12
   1 PVPP_DEF      A @BASEBOARD_FAB2_LIB.BASEBOARD_FAB2(SCH_1):PVPP_DEF
   2 SMB_DDR_DEF_VPP_SDA_R      B @BASEBOARD_FAB2_LIB.BASEBOARD_FAB2(SCH_1):SMB_DDR_DEF_VPP_SDA_R

RES_0402-665,1.0%,1/16W,CHIP,GA  I103  R3R5
   1 PVPP_DEF      A @BASEBOARD_FAB2_LIB.BASEBOARD_FAB2(SCH_1):PVPP_DEF
   2 SMB_DDR_DEF_VPP_SCL_R      B @BASEBOARD_FAB2_LIB.BASEBOARD_FAB2(SCH_1):SMB_DDR_DEF_VPP_SCL_R

RES_0402-665,1.0%,1/16W,CHIP,GA  I104  R6U18
   1 PVPP_GHJ      A @BASEBOARD_FAB2_LIB.BASEBOARD_FAB2(SCH_1):PVPP_GHJ
   2 SMB_DDR_GHJ_VPP_SDA_R      B @BASEBOARD_FAB2_LIB.BASEBOARD_FAB2(SCH_1):SMB_DDR_GHJ_VPP_SDA_R

RES_0402-665,1.0%,1/16W,CHIP,GA  I106  R6U17
   1 PVPP_GHJ      A @BASEBOARD_FAB2_LIB.BASEBOARD_FAB2(SCH_1):PVPP_GHJ
   2 SMB_DDR_GHJ_VPP_SCL_R      B @BASEBOARD_FAB2_LIB.BASEBOARD_FAB2(SCH_1):SMB_DDR_GHJ_VPP_SCL_R

RES_0402-665,1.0%,1/16W,CHIP,GA  I107  R7M6
   1 PVPP_KLM      A @BASEBOARD_FAB2_LIB.BASEBOARD_FAB2(SCH_1):PVPP_KLM
   2 SMB_DDR_KLM_VPP_SDA_R      B @BASEBOARD_FAB2_LIB.BASEBOARD_FAB2(SCH_1):SMB_DDR_KLM_VPP_SDA_R

RES_0402-665,1.0%,1/16W,CHIP,GA  I109  R7M1
   1 PVPP_KLM      A @BASEBOARD_FAB2_LIB.BASEBOARD_FAB2(SCH_1):PVPP_KLM
   2 SMB_DDR_KLM_VPP_SCL_R      B @BASEBOARD_FAB2_LIB.BASEBOARD_FAB2(SCH_1):SMB_DDR_KLM_VPP_SCL_R

RES_0402-10.0,1%,1/16W,CHIP,G2A  I110  R3R14
   1 SMB_DDR_DEF_SDA_G_R      A @BASEBOARD_FAB2_LIB.BASEBOARD_FAB2(SCH_1):SMB_DDR_DEF_SDA_G_R
   2 SMB_DDR_DEF_SDA_G      B @BASEBOARD_FAB2_LIB.BASEBOARD_FAB2(SCH_1):SMB_DDR_DEF_SDA_G

RES_0402-10.0,1%,1/16W,CHIP,G2A  I111  R6T4
   1 SMB_DDR_GHJ_SDA_G_R      A @BASEBOARD_FAB2_LIB.BASEBOARD_FAB2(SCH_1):SMB_DDR_GHJ_SDA_G_R
   2 SMB_DDR_GHJ_SDA_G      B @BASEBOARD_FAB2_LIB.BASEBOARD_FAB2(SCH_1):SMB_DDR_GHJ_SDA_G

RES_0402-10.0,1%,1/16W,CHIP,G2A  I112  R7M8
   1 SMB_DDR_KLM_SDA_G_R      A @BASEBOARD_FAB2_LIB.BASEBOARD_FAB2(SCH_1):SMB_DDR_KLM_SDA_G_R
   2 SMB_DDR_KLM_SDA_G      B @BASEBOARD_FAB2_LIB.BASEBOARD_FAB2(SCH_1):SMB_DDR_KLM_SDA_G

RES_0402-20.0,1%,1/16W,CHIP,G2A  I115  R6U14
   1 SMB_DDR_GHJ_VPP_SDA_R      A @BASEBOARD_FAB2_LIB.BASEBOARD_FAB2(SCH_1):SMB_DDR_GHJ_VPP_SDA_R
   2 SMB_DDR_GHJ_VPP_SDA      B @BASEBOARD_FAB2_LIB.BASEBOARD_FAB2(SCH_1):SMB_DDR_GHJ_VPP_SDA


DRAWING: @BASEBOARD_FAB2_LIB.BASEBOARD_FAB2(SCH_1):PAGE100 

RES_0402-1.00K,1%,1/16W,CHIP,GA  I2  R1F6
   1 M_G_VREF      A @BASEBOARD_FAB2_LIB.BASEBOARD_FAB2(SCH_1):M_G_VREF
   2    GND      B @BASEBOARD_FAB2_LIB.BASEBOARD_FAB2(SCH_1):GND

RES_0402-1.00K,1%,1/16W,CHIP,GA  I4  R9L11
   1 M_K_VREF      A @BASEBOARD_FAB2_LIB.BASEBOARD_FAB2(SCH_1):M_K_VREF
   2    GND      B @BASEBOARD_FAB2_LIB.BASEBOARD_FAB2(SCH_1):GND

RES_0402-1.00K,1%,1/16W,CHIP,GA  I6  R1F5
   1 PVDDQ_GHJ      A @BASEBOARD_FAB2_LIB.BASEBOARD_FAB2(SCH_1):PVDDQ_GHJ
   2 M_G_VREF      B @BASEBOARD_FAB2_LIB.BASEBOARD_FAB2(SCH_1):M_G_VREF

RES_0402-2,1.0%,1/16W,CHIP,G21A  I7  R1F4
   1 M_G_CPU_VREF      A @BASEBOARD_FAB2_LIB.BASEBOARD_FAB2(SCH_1):M_G_CPU_VREF
   2 M_G_VREF      B @BASEBOARD_FAB2_LIB.BASEBOARD_FAB2(SCH_1):M_G_VREF

CAP_A_0402V-0.01UF,25V,10%,X7RA  I8  C1F19
   1 M_G_CPU_VREF      A @BASEBOARD_FAB2_LIB.BASEBOARD_FAB2(SCH_1):M_G_CPU_VREF
   2    GND      B @BASEBOARD_FAB2_LIB.BASEBOARD_FAB2(SCH_1):GND

RES_0402-1.00K,1%,1/16W,CHIP,GA  I11  R9M1
   1 PVDDQ_KLM      A @BASEBOARD_FAB2_LIB.BASEBOARD_FAB2(SCH_1):PVDDQ_KLM
   2 M_K_VREF      B @BASEBOARD_FAB2_LIB.BASEBOARD_FAB2(SCH_1):M_K_VREF

RES_0402-2,1.0%,1/16W,CHIP,G21A  I13  R9M2
   1 M_K_CPU_VREF      A @BASEBOARD_FAB2_LIB.BASEBOARD_FAB2(SCH_1):M_K_CPU_VREF
   2 M_K_VREF      B @BASEBOARD_FAB2_LIB.BASEBOARD_FAB2(SCH_1):M_K_VREF

CAP_A_0402V-0.01UF,25V,10%,X7RA  I15  C9M2
   1 M_K_CPU_VREF      A @BASEBOARD_FAB2_LIB.BASEBOARD_FAB2(SCH_1):M_K_CPU_VREF
   2    GND      B @BASEBOARD_FAB2_LIB.BASEBOARD_FAB2(SCH_1):GND

RES_0402-1.00K,1%,1/16W,CHIP,GA  I19  R1G2
   1 PVDDQ_GHJ      A @BASEBOARD_FAB2_LIB.BASEBOARD_FAB2(SCH_1):PVDDQ_GHJ
   2 M_H_VREF      B @BASEBOARD_FAB2_LIB.BASEBOARD_FAB2(SCH_1):M_H_VREF

RES_0402-1.00K,1%,1/16W,CHIP,GA  I20  R1G3
   1 M_H_VREF      A @BASEBOARD_FAB2_LIB.BASEBOARD_FAB2(SCH_1):M_H_VREF
   2    GND      B @BASEBOARD_FAB2_LIB.BASEBOARD_FAB2(SCH_1):GND

RES_0402-1.00K,1%,1/16W,CHIP,GA  I22  R9L7
   1 PVDDQ_KLM      A @BASEBOARD_FAB2_LIB.BASEBOARD_FAB2(SCH_1):PVDDQ_KLM
   2 M_L_VREF      B @BASEBOARD_FAB2_LIB.BASEBOARD_FAB2(SCH_1):M_L_VREF

RES_0402-1.00K,1%,1/16W,CHIP,GA  I24  R9L6
   1 M_L_VREF      A @BASEBOARD_FAB2_LIB.BASEBOARD_FAB2(SCH_1):M_L_VREF
   2    GND      B @BASEBOARD_FAB2_LIB.BASEBOARD_FAB2(SCH_1):GND

RES_0402-2,1.0%,1/16W,CHIP,G21A  I25  R1G1
   1 M_H_CPU_VREF      A @BASEBOARD_FAB2_LIB.BASEBOARD_FAB2(SCH_1):M_H_CPU_VREF
   2 M_H_VREF      B @BASEBOARD_FAB2_LIB.BASEBOARD_FAB2(SCH_1):M_H_VREF

CAP_A_0402V-0.01UF,25V,10%,X7RA  I26  C1G8
   1 M_H_CPU_VREF      A @BASEBOARD_FAB2_LIB.BASEBOARD_FAB2(SCH_1):M_H_CPU_VREF
   2    GND      B @BASEBOARD_FAB2_LIB.BASEBOARD_FAB2(SCH_1):GND

RES_0402-2,1.0%,1/16W,CHIP,G21A  I29  R9L8
   1 M_L_CPU_VREF      A @BASEBOARD_FAB2_LIB.BASEBOARD_FAB2(SCH_1):M_L_CPU_VREF
   2 M_L_VREF      B @BASEBOARD_FAB2_LIB.BASEBOARD_FAB2(SCH_1):M_L_VREF

CAP_A_0402V-0.01UF,25V,10%,X7RA  I30  C9L8
   1 M_L_CPU_VREF      A @BASEBOARD_FAB2_LIB.BASEBOARD_FAB2(SCH_1):M_L_CPU_VREF
   2    GND      B @BASEBOARD_FAB2_LIB.BASEBOARD_FAB2(SCH_1):GND

RES_0402-1.00K,1%,1/16W,CHIP,GA  I35  R1G15
   1 PVDDQ_GHJ      A @BASEBOARD_FAB2_LIB.BASEBOARD_FAB2(SCH_1):PVDDQ_GHJ
   2 M_J_VREF      B @BASEBOARD_FAB2_LIB.BASEBOARD_FAB2(SCH_1):M_J_VREF

RES_0402-1.00K,1%,1/16W,CHIP,GA  I36  R1G17
   1 M_J_VREF      A @BASEBOARD_FAB2_LIB.BASEBOARD_FAB2(SCH_1):M_J_VREF
   2    GND      B @BASEBOARD_FAB2_LIB.BASEBOARD_FAB2(SCH_1):GND

RES_0402-1.00K,1%,1/16W,CHIP,GA  I38  R9L2
   1 PVDDQ_KLM      A @BASEBOARD_FAB2_LIB.BASEBOARD_FAB2(SCH_1):PVDDQ_KLM
   2 M_M_VREF      B @BASEBOARD_FAB2_LIB.BASEBOARD_FAB2(SCH_1):M_M_VREF

RES_0402-1.00K,1%,1/16W,CHIP,GA  I40  R9L1
   1 M_M_VREF      A @BASEBOARD_FAB2_LIB.BASEBOARD_FAB2(SCH_1):M_M_VREF
   2    GND      B @BASEBOARD_FAB2_LIB.BASEBOARD_FAB2(SCH_1):GND

RES_0402-2,1.0%,1/16W,CHIP,G21A  I41  R1G14
   1 M_J_CPU_VREF      A @BASEBOARD_FAB2_LIB.BASEBOARD_FAB2(SCH_1):M_J_CPU_VREF
   2 M_J_VREF      B @BASEBOARD_FAB2_LIB.BASEBOARD_FAB2(SCH_1):M_J_VREF

CAP_A_0402V-0.01UF,25V,10%,X7RA  I42  C1G18
   1 M_J_CPU_VREF      A @BASEBOARD_FAB2_LIB.BASEBOARD_FAB2(SCH_1):M_J_CPU_VREF
   2    GND      B @BASEBOARD_FAB2_LIB.BASEBOARD_FAB2(SCH_1):GND

RES_0402-2,1.0%,1/16W,CHIP,G21A  I45  R9L3
   1 M_M_CPU_VREF      A @BASEBOARD_FAB2_LIB.BASEBOARD_FAB2(SCH_1):M_M_CPU_VREF
   2 M_M_VREF      B @BASEBOARD_FAB2_LIB.BASEBOARD_FAB2(SCH_1):M_M_VREF

CAP_A_0402V-0.01UF,25V,10%,X7RA  I46  C9L3
   1 M_M_CPU_VREF      A @BASEBOARD_FAB2_LIB.BASEBOARD_FAB2(SCH_1):M_M_CPU_VREF
   2    GND      B @BASEBOARD_FAB2_LIB.BASEBOARD_FAB2(SCH_1):GND


DRAWING: @BASEBOARD_FAB2_LIB.BASEBOARD_FAB2(SCH_1):PAGE101 

RES_0402-33.2,1%,1/16W,CHIP,G2A  I20  R8F29
   1 CLK_25M_BMC_R      A @BASEBOARD_FAB2_LIB.BASEBOARD_FAB2(SCH_1):CLK_25M_BMC_R
   2 CLK_25M_BMC      B @BASEBOARD_FAB2_LIB.BASEBOARD_FAB2(SCH_1):CLK_25M_BMC

RES_0402-475.0,1%,1/16W,CHIP,GA  I28  R8F25
   1 A_COMP_CKMNG      A @BASEBOARD_FAB2_LIB.BASEBOARD_FAB2(SCH_1):A_COMP_CKMNG
   2    GND      B @BASEBOARD_FAB2_LIB.BASEBOARD_FAB2(SCH_1):GND

ICS9FGP204_MLFP-IC,E95226-001  I34  EU8F2
  12 P3V3_STBY_MNG VDD32K @BASEBOARD_FAB2_LIB.BASEBOARD_FAB2(SCH_1):P3V3_STBY_MNG
  13 CLK_32K_SUSCLK_PLD_R  32KHZ @BASEBOARD_FAB2_LIB.BASEBOARD_FAB2(SCH_1):CLK_32K_SUSCLK_PLD_R
  14    GND GND32K @BASEBOARD_FAB2_LIB.BASEBOARD_FAB2(SCH_1):GND
  16 CLK_25M_BMC_R 25MHZ_0 @BASEBOARD_FAB2_LIB.BASEBOARD_FAB2(SCH_1):CLK_25M_BMC_R
  17 CLK_25M_CPLD_R 25MHZ_1 @BASEBOARD_FAB2_LIB.BASEBOARD_FAB2(SCH_1):CLK_25M_CPLD_R
  32 CLK_50M_CKMNG_BMC_1_R RMII<1> @BASEBOARD_FAB2_LIB.BASEBOARD_FAB2(SCH_1):CLK_50M_CKMNG_BMC_1_R
  29 CLK_50M_CKMNG_BMC_2_R RMII<2> @BASEBOARD_FAB2_LIB.BASEBOARD_FAB2(SCH_1):CLK_50M_CKMNG_BMC_2_R
  24 TP_CLK5_50M_CKMNG RMII<5> @BASEBOARD_FAB2_LIB.BASEBOARD_FAB2(SCH_1):TP_CLK5_50M_CKMNG
  25 CLK_50M_CKMNG_PCH_10GBE_R RMII<4> @BASEBOARD_FAB2_LIB.BASEBOARD_FAB2(SCH_1):CLK_50M_CKMNG_PCH_10GBE_R
  28 CLK_50M_CKMNG_SPRVLLE_R RMII<3> @BASEBOARD_FAB2_LIB.BASEBOARD_FAB2(SCH_1):CLK_50M_CKMNG_SPRVLLE_R
  33 CLK_50M_CKMNG_OCP_R RMII<0> @BASEBOARD_FAB2_LIB.BASEBOARD_FAB2(SCH_1):CLK_50M_CKMNG_OCP_R
  41    GND GND<1> @BASEBOARD_FAB2_LIB.BASEBOARD_FAB2(SCH_1):GND
  21    GND  GND33 @BASEBOARD_FAB2_LIB.BASEBOARD_FAB2(SCH_1):GND
   1    GND GND<0> @BASEBOARD_FAB2_LIB.BASEBOARD_FAB2(SCH_1):GND
   4 TP_CLK_96M_CKMNG_N DOT96SSC @BASEBOARD_FAB2_LIB.BASEBOARD_FAB2(SCH_1):TP_CLK_96M_CKMNG_N
   3 TP_CLK_96M_CKMNG_P DOT96SST @BASEBOARD_FAB2_LIB.BASEBOARD_FAB2(SCH_1):TP_CLK_96M_CKMNG_P
   8 TP_CLK_100M_R_DN CPUCLKC0 @BASEBOARD_FAB2_LIB.BASEBOARD_FAB2(SCH_1):TP_CLK_100M_R_DN
  18    GND GNDREF @BASEBOARD_FAB2_LIB.BASEBOARD_FAB2(SCH_1):GND
   7 TP_CLK_100M_R_DP CPUCLKT0 @BASEBOARD_FAB2_LIB.BASEBOARD_FAB2(SCH_1):TP_CLK_100M_R_DP
  15 P3V3_STBY_MNG VDDREF @BASEBOARD_FAB2_LIB.BASEBOARD_FAB2(SCH_1):P3V3_STBY_MNG
  11 A_COMP_CKMNG   IREF @BASEBOARD_FAB2_LIB.BASEBOARD_FAB2(SCH_1):A_COMP_CKMNG
  19 XTAL_CK_MNG_IN  X1_25 @BASEBOARD_FAB2_LIB.BASEBOARD_FAB2(SCH_1):XTAL_CK_MNG_IN
  27    GND GNDRMII<0> @BASEBOARD_FAB2_LIB.BASEBOARD_FAB2(SCH_1):GND
  26 P3V3_STBY_MNG_RMII VDDRMII<0> @BASEBOARD_FAB2_LIB.BASEBOARD_FAB2(SCH_1):P3V3_STBY_MNG_RMII
  31 P3V3_STBY_MNG_RMII VDDRMII<1> @BASEBOARD_FAB2_LIB.BASEBOARD_FAB2(SCH_1):P3V3_STBY_MNG_RMII
  30    GND GNDRMII<1> @BASEBOARD_FAB2_LIB.BASEBOARD_FAB2(SCH_1):GND
  22 PU_33P_33M_SMBADR 33MHZ_SMBADR @BASEBOARD_FAB2_LIB.BASEBOARD_FAB2(SCH_1):PU_33P_33M_SMBADR
  23 P3V3_STBY_MNG  VDD33 @BASEBOARD_FAB2_LIB.BASEBOARD_FAB2(SCH_1):P3V3_STBY_MNG
   5 PD_CKMNG_OE  OE_96 @BASEBOARD_FAB2_LIB.BASEBOARD_FAB2(SCH_1):PD_CKMNG_OE
   2 P3V3_STBY_MNG  VDD96 @BASEBOARD_FAB2_LIB.BASEBOARD_FAB2(SCH_1):P3V3_STBY_MNG
   6 PD_CKMNG_OE OE_CPU @BASEBOARD_FAB2_LIB.BASEBOARD_FAB2(SCH_1):PD_CKMNG_OE
  10    GND GNDCPU @BASEBOARD_FAB2_LIB.BASEBOARD_FAB2(SCH_1):GND
   9 P3V3_STBY_MNG_CPU VDDCPU @BASEBOARD_FAB2_LIB.BASEBOARD_FAB2(SCH_1):P3V3_STBY_MNG_CPU
  40 PWRGD_P3V3_STBY VTTPWR_GD_PD_N @BASEBOARD_FAB2_LIB.BASEBOARD_FAB2(SCH_1):PWRGD_P3V3_STBY
  38 SMB_HOST_STBY_LVC3_SCL_R4 SMBCLK @BASEBOARD_FAB2_LIB.BASEBOARD_FAB2(SCH_1):SMB_HOST_STBY_LVC3_SCL_R4
  20 XTAL_CK_MNG_OUT_R  X2_25 @BASEBOARD_FAB2_LIB.BASEBOARD_FAB2(SCH_1):XTAL_CK_MNG_OUT_R
  39 SMB_HOST_STBY_LVC3_SDA_R4 SMBDAT @BASEBOARD_FAB2_LIB.BASEBOARD_FAB2(SCH_1):SMB_HOST_STBY_LVC3_SDA_R4
  34 P3V3_STBY_MNG_RGMII VDD_RGMII @BASEBOARD_FAB2_LIB.BASEBOARD_FAB2(SCH_1):P3V3_STBY_MNG_RGMII
  35    GND GND_RGMII @BASEBOARD_FAB2_LIB.BASEBOARD_FAB2(SCH_1):GND
  37 TP_CLK_125M_BMCA RGMII<0> @BASEBOARD_FAB2_LIB.BASEBOARD_FAB2(SCH_1):TP_CLK_125M_BMCA
  36 TP_CLK_125M RGMII<1> @BASEBOARD_FAB2_LIB.BASEBOARD_FAB2(SCH_1):TP_CLK_125M

RES_0402-1.00K,1%,1/16W,CHIP,GA  I48  R2T25
   1 PD_CKMNG_OE      A @BASEBOARD_FAB2_LIB.BASEBOARD_FAB2(SCH_1):PD_CKMNG_OE
   2    GND      B @BASEBOARD_FAB2_LIB.BASEBOARD_FAB2(SCH_1):GND

CRYSTAL_2013LF-25.000MHZ,IC,D7B  I52  Y8F1
   1 XTAL_CK_MNG_IN      A @BASEBOARD_FAB2_LIB.BASEBOARD_FAB2(SCH_1):XTAL_CK_MNG_IN
   3 XTAL_CK_MNG_OUT      B @BASEBOARD_FAB2_LIB.BASEBOARD_FAB2(SCH_1):XTAL_CK_MNG_OUT

CAP_A_0402V-1.0UF,6.3V,10%,X6SA  I89  C2T31
   1 P3V3_STBY_MNG_RGMII      A @BASEBOARD_FAB2_LIB.BASEBOARD_FAB2(SCH_1):P3V3_STBY_MNG_RGMII
   2    GND      B @BASEBOARD_FAB2_LIB.BASEBOARD_FAB2(SCH_1):GND

CAP_A_0402V-0.01UF,25V,10%,X7RA  I90  C2T27
   1 P3V3_STBY_MNG_RGMII      A @BASEBOARD_FAB2_LIB.BASEBOARD_FAB2(SCH_1):P3V3_STBY_MNG_RGMII
   2    GND      B @BASEBOARD_FAB2_LIB.BASEBOARD_FAB2(SCH_1):GND

RES_0603-2.2,1.0%,1/10W,CHIP,GA  I94  R2T23
   1 P3V3_STBY_MNG      A @BASEBOARD_FAB2_LIB.BASEBOARD_FAB2(SCH_1):P3V3_STBY_MNG
   2 P3V3_STBY_MNG_RGMII      B @BASEBOARD_FAB2_LIB.BASEBOARD_FAB2(SCH_1):P3V3_STBY_MNG_RGMII

RES_0603-2.2,1.0%,1/10W,CHIP,GA  I95  R2T52
   1 P3V3_STBY_MNG      A @BASEBOARD_FAB2_LIB.BASEBOARD_FAB2(SCH_1):P3V3_STBY_MNG
   2 P3V3_STBY_MNG_RMII      B @BASEBOARD_FAB2_LIB.BASEBOARD_FAB2(SCH_1):P3V3_STBY_MNG_RMII

CAP_A_0402V-1.0UF,6.3V,10%,X6SA  I97  C2T38
   1 P3V3_STBY_MNG_RMII      A @BASEBOARD_FAB2_LIB.BASEBOARD_FAB2(SCH_1):P3V3_STBY_MNG_RMII
   2    GND      B @BASEBOARD_FAB2_LIB.BASEBOARD_FAB2(SCH_1):GND

CAP_A_0402V-0.01UF,25V,10%,X7RA  I99  C2T37
   1 P3V3_STBY_MNG_RMII      A @BASEBOARD_FAB2_LIB.BASEBOARD_FAB2(SCH_1):P3V3_STBY_MNG_RMII
   2    GND      B @BASEBOARD_FAB2_LIB.BASEBOARD_FAB2(SCH_1):GND

CAP_A_0402V-0.01UF,25V,10%,X7RA  I104  C2T18
   1 P3V3_STBY_MNG_CPU      A @BASEBOARD_FAB2_LIB.BASEBOARD_FAB2(SCH_1):P3V3_STBY_MNG_CPU
   2    GND      B @BASEBOARD_FAB2_LIB.BASEBOARD_FAB2(SCH_1):GND

RES_0603-2.2,1.0%,1/10W,CHIP,GA  I105  R2T21
   1 P3V3_STBY_MNG      A @BASEBOARD_FAB2_LIB.BASEBOARD_FAB2(SCH_1):P3V3_STBY_MNG
   2 P3V3_STBY_MNG_CPU      B @BASEBOARD_FAB2_LIB.BASEBOARD_FAB2(SCH_1):P3V3_STBY_MNG_CPU

CAP_A_0402V-1.0UF,6.3V,10%,X6SA  I106  C2T19
   1 P3V3_STBY_MNG_CPU      A @BASEBOARD_FAB2_LIB.BASEBOARD_FAB2(SCH_1):P3V3_STBY_MNG_CPU
   2    GND      B @BASEBOARD_FAB2_LIB.BASEBOARD_FAB2(SCH_1):GND

CAP_A_0402V-0.1UF,16V,10%,X7R,A  I109  C2T34
   1 P3V3_STBY_MNG      A @BASEBOARD_FAB2_LIB.BASEBOARD_FAB2(SCH_1):P3V3_STBY_MNG
   2    GND      B @BASEBOARD_FAB2_LIB.BASEBOARD_FAB2(SCH_1):GND

CAP_A_0402V-0.1UF,16V,10%,X7R,A  I110  C2T30
   1 P3V3_STBY_MNG      A @BASEBOARD_FAB2_LIB.BASEBOARD_FAB2(SCH_1):P3V3_STBY_MNG
   2    GND      B @BASEBOARD_FAB2_LIB.BASEBOARD_FAB2(SCH_1):GND

CAP_A_0402V-0.1UF,16V,10%,X7R,A  I111  C2T25
   1 P3V3_STBY_MNG      A @BASEBOARD_FAB2_LIB.BASEBOARD_FAB2(SCH_1):P3V3_STBY_MNG
   2    GND      B @BASEBOARD_FAB2_LIB.BASEBOARD_FAB2(SCH_1):GND

CAP_A_0402V-0.1UF,16V,10%,X7R,A  I112  C2T17
   1 P3V3_STBY_MNG      A @BASEBOARD_FAB2_LIB.BASEBOARD_FAB2(SCH_1):P3V3_STBY_MNG
   2    GND      B @BASEBOARD_FAB2_LIB.BASEBOARD_FAB2(SCH_1):GND

CAP_0805-10UF,16V,10%,X6S,C953A  I113  C2T22
   1 P3V3_STBY_MNG      A @BASEBOARD_FAB2_LIB.BASEBOARD_FAB2(SCH_1):P3V3_STBY_MNG
   2    GND      B @BASEBOARD_FAB2_LIB.BASEBOARD_FAB2(SCH_1):GND

FERRITE_SMLF-600,FB,656554-043  I114  FB2T2
   1 P3V3_STBY      A @BASEBOARD_FAB2_LIB.BASEBOARD_FAB2(SCH_1):P3V3_STBY
   2 P3V3_STBY_MNG      B @BASEBOARD_FAB2_LIB.BASEBOARD_FAB2(SCH_1):P3V3_STBY_MNG

CAP_A_0402V-1.0UF,6.3V,10%,X6SA  I116  C2T28
   1 P3V3_STBY      A @BASEBOARD_FAB2_LIB.BASEBOARD_FAB2(SCH_1):P3V3_STBY
   2    GND      B @BASEBOARD_FAB2_LIB.BASEBOARD_FAB2(SCH_1):GND

RES_0402-22.1,1.0%,1/16W,CHIP,A  I124  R2T42
   1 CLK_50M_CKMNG_OCP_R      A @BASEBOARD_FAB2_LIB.BASEBOARD_FAB2(SCH_1):CLK_50M_CKMNG_OCP_R
   2 CLK_50M_CKMNG_OCP      B @BASEBOARD_FAB2_LIB.BASEBOARD_FAB2(SCH_1):CLK_50M_CKMNG_OCP

RES_0402-22.1,1.0%,1/16W,CHIP,A  I125  R2T46
   1 CLK_50M_CKMNG_BMC_1_R      A @BASEBOARD_FAB2_LIB.BASEBOARD_FAB2(SCH_1):CLK_50M_CKMNG_BMC_1_R
   2 CLK_50M_CKMNG_BMC_1      B @BASEBOARD_FAB2_LIB.BASEBOARD_FAB2(SCH_1):CLK_50M_CKMNG_BMC_1

RES_0402-33.2,1%,1/16W,CHIP,G2A  I130  R2T47
   1 CLK_25M_CPLD_R      A @BASEBOARD_FAB2_LIB.BASEBOARD_FAB2(SCH_1):CLK_25M_CPLD_R
   2 CLK_25M_CPLD      B @BASEBOARD_FAB2_LIB.BASEBOARD_FAB2(SCH_1):CLK_25M_CPLD

RES_0402-0.0,5%,1/16W,CHIP,G21A  I134  R1W22
   1 SMB_HOST_STBY_LVC3_SCL      A @BASEBOARD_FAB2_LIB.BASEBOARD_FAB2(SCH_1):SMB_HOST_STBY_LVC3_SCL
   2 SMB_HOST_STBY_LVC3_SCL_R4      B @BASEBOARD_FAB2_LIB.BASEBOARD_FAB2(SCH_1):SMB_HOST_STBY_LVC3_SCL_R4

RES_0402-0.0,5%,1/16W,CHIP,G21A  I135  R1W23
   1 SMB_HOST_STBY_LVC3_SDA      A @BASEBOARD_FAB2_LIB.BASEBOARD_FAB2(SCH_1):SMB_HOST_STBY_LVC3_SDA
   2 SMB_HOST_STBY_LVC3_SDA_R4      B @BASEBOARD_FAB2_LIB.BASEBOARD_FAB2(SCH_1):SMB_HOST_STBY_LVC3_SDA_R4

RES_0402-0.0,5%,1/16W,CHIP,G21A  I138  R1W24
   1 XTAL_CK_MNG_OUT      A @BASEBOARD_FAB2_LIB.BASEBOARD_FAB2(SCH_1):XTAL_CK_MNG_OUT
   2 XTAL_CK_MNG_OUT_R      B @BASEBOARD_FAB2_LIB.BASEBOARD_FAB2(SCH_1):XTAL_CK_MNG_OUT_R

CAP_0805-10UF,16V,10%,EMPTY,C9A  I139  C1W17
   1 P3V3_STBY_MNG_RMII      A @BASEBOARD_FAB2_LIB.BASEBOARD_FAB2(SCH_1):P3V3_STBY_MNG_RMII
   2    GND      B @BASEBOARD_FAB2_LIB.BASEBOARD_FAB2(SCH_1):GND

RES_0402-1.00K,1%,1/16W,CHIP,GA  I140  R1W25
   1 PU_33P_33M_SMBADR      A @BASEBOARD_FAB2_LIB.BASEBOARD_FAB2(SCH_1):PU_33P_33M_SMBADR
   2    GND      B @BASEBOARD_FAB2_LIB.BASEBOARD_FAB2(SCH_1):GND

RES_0402-33.2,1%,1/16W,CHIP,G2A  I142  R8F27
   1 CLK_32K_SUSCLK_PLD_R      A @BASEBOARD_FAB2_LIB.BASEBOARD_FAB2(SCH_1):CLK_32K_SUSCLK_PLD_R
   2 CLK_32K_SUSCLK_PLD      B @BASEBOARD_FAB2_LIB.BASEBOARD_FAB2(SCH_1):CLK_32K_SUSCLK_PLD

RES_0402-22.1,1.0%,1/16W,CHIP,A  I143  R8G24
   1 CLK_50M_CKMNG_PCH_10GBE_R      A @BASEBOARD_FAB2_LIB.BASEBOARD_FAB2(SCH_1):CLK_50M_CKMNG_PCH_10GBE_R
   2 CLK_50M_CKMNG_PCH_10GBE      B @BASEBOARD_FAB2_LIB.BASEBOARD_FAB2(SCH_1):CLK_50M_CKMNG_PCH_10GBE

RES_0402-22.1,1.0%,1/16W,CHIP,A  I144  R8G25
   1 CLK_50M_CKMNG_SPRVLLE_R      A @BASEBOARD_FAB2_LIB.BASEBOARD_FAB2(SCH_1):CLK_50M_CKMNG_SPRVLLE_R
   2 CLK_50M_CKMNG_SPRVLLE      B @BASEBOARD_FAB2_LIB.BASEBOARD_FAB2(SCH_1):CLK_50M_CKMNG_SPRVLLE

RES_0402-22.1,1.0%,1/16W,CHIP,A  I145  R8G1
   1 CLK_50M_CKMNG_BMC_2_R      A @BASEBOARD_FAB2_LIB.BASEBOARD_FAB2(SCH_1):CLK_50M_CKMNG_BMC_2_R
   2 CLK_50M_CKMNG_BMC_2      B @BASEBOARD_FAB2_LIB.BASEBOARD_FAB2(SCH_1):CLK_50M_CKMNG_BMC_2

CAP_0402LF-15.0PF,50V,5%,COG,AA  I146  C8F19
   1 XTAL_CK_MNG_OUT      A @BASEBOARD_FAB2_LIB.BASEBOARD_FAB2(SCH_1):XTAL_CK_MNG_OUT
   2    GND      B @BASEBOARD_FAB2_LIB.BASEBOARD_FAB2(SCH_1):GND

CAP_0402LF-15.0PF,50V,5%,COG,AA  I147  C8F18
   1 XTAL_CK_MNG_IN      A @BASEBOARD_FAB2_LIB.BASEBOARD_FAB2(SCH_1):XTAL_CK_MNG_IN
   2    GND      B @BASEBOARD_FAB2_LIB.BASEBOARD_FAB2(SCH_1):GND


DRAWING: @BASEBOARD_FAB2_LIB.BASEBOARD_FAB2(SCH_1):PAGE102 

NB3W1200L_LCC-IC,H13585-001  I1  EU4D2
   1 P3V3_DB1200_A   VDDA @BASEBOARD_FAB2_LIB.BASEBOARD_FAB2(SCH_1):P3V3_DB1200_A
   2    GND   GNDA @BASEBOARD_FAB2_LIB.BASEBOARD_FAB2(SCH_1):GND
   3     NC  NC<0>     NC
   4 FM_100M_N 100M_133M_N @BASEBOARD_FAB2_LIB.BASEBOARD_FAB2(SCH_1):FM_100M_N
   5 FM_HBW_BYPASS_LOWBW_N HBW_BYPASS_LOBW_N @BASEBOARD_FAB2_LIB.BASEBOARD_FAB2(SCH_1):FM_HBW_BYPASS_LOWBW_N
   6 FM_DB1200_PWRGD_R PWRGD_PWRDN_N @BASEBOARD_FAB2_LIB.BASEBOARD_FAB2(SCH_1):FM_DB1200_PWRGD_R
   7    GND GND<0> @BASEBOARD_FAB2_LIB.BASEBOARD_FAB2(SCH_1):GND
   8 P3V3_DB1200_R   VDDR @BASEBOARD_FAB2_LIB.BASEBOARD_FAB2(SCH_1):P3V3_DB1200_R
   9 CLK_100M_DB1200_DP CLK_INP @BASEBOARD_FAB2_LIB.BASEBOARD_FAB2(SCH_1):CLK_100M_DB1200_DP
  10 CLK_100M_DB1200_DN CLK_INN @BASEBOARD_FAB2_LIB.BASEBOARD_FAB2(SCH_1):CLK_100M_DB1200_DN
  11 FM_DB1200_SMB_SA0   SA_0 @BASEBOARD_FAB2_LIB.BASEBOARD_FAB2(SCH_1):FM_DB1200_SMB_SA0
  12 SMB_HOST_STBY_LVC3_SDA_R2    SDA @BASEBOARD_FAB2_LIB.BASEBOARD_FAB2(SCH_1):SMB_HOST_STBY_LVC3_SDA_R2
  13 SMB_HOST_STBY_LVC3_SCL_R2    SCL @BASEBOARD_FAB2_LIB.BASEBOARD_FAB2(SCH_1):SMB_HOST_STBY_LVC3_SCL_R2
  14 FM_DB1200_SMB_SA1   SA_1 @BASEBOARD_FAB2_LIB.BASEBOARD_FAB2(SCH_1):FM_DB1200_SMB_SA1
  15     NC  NC<2>     NC
  16     NC  NC<1>     NC
  17 CLK_100M_CPU0_BCLK0_R_DP DIF_0P @BASEBOARD_FAB2_LIB.BASEBOARD_FAB2(SCH_1):CLK_100M_CPU0_BCLK0_R_DP
  18 CLK_100M_CPU0_BCLK0_R_DN DIF_0N @BASEBOARD_FAB2_LIB.BASEBOARD_FAB2(SCH_1):CLK_100M_CPU0_BCLK0_R_DN
  19 FM_DB1200ZL_BCLKS_EN_N OE_0_N @BASEBOARD_FAB2_LIB.BASEBOARD_FAB2(SCH_1):FM_DB1200ZL_BCLKS_EN_N
  20 FM_DB1200ZL_BCLKS_EN_N OE_1_N @BASEBOARD_FAB2_LIB.BASEBOARD_FAB2(SCH_1):FM_DB1200ZL_BCLKS_EN_N
  21 CLK_100M_CPU0_BCLK1_R_DP DIF_1P @BASEBOARD_FAB2_LIB.BASEBOARD_FAB2(SCH_1):CLK_100M_CPU0_BCLK1_R_DP
  22 CLK_100M_CPU0_BCLK1_R_DN DIF_1N @BASEBOARD_FAB2_LIB.BASEBOARD_FAB2(SCH_1):CLK_100M_CPU0_BCLK1_R_DN
  23    GND GND<1> @BASEBOARD_FAB2_LIB.BASEBOARD_FAB2(SCH_1):GND
  24 P3V3_DB1200 VDD<0> @BASEBOARD_FAB2_LIB.BASEBOARD_FAB2(SCH_1):P3V3_DB1200
  25 P3V3_DB1200 VDDIO<0> @BASEBOARD_FAB2_LIB.BASEBOARD_FAB2(SCH_1):P3V3_DB1200
  26 CLK_100M_CPU0_BCLK2_R_DP DIF_2P @BASEBOARD_FAB2_LIB.BASEBOARD_FAB2(SCH_1):CLK_100M_CPU0_BCLK2_R_DP
  27 CLK_100M_CPU0_BCLK2_R_DN DIF_2N @BASEBOARD_FAB2_LIB.BASEBOARD_FAB2(SCH_1):CLK_100M_CPU0_BCLK2_R_DN
  28 FM_DB1200ZL_BCLKS_EN_N OE_2_N @BASEBOARD_FAB2_LIB.BASEBOARD_FAB2(SCH_1):FM_DB1200ZL_BCLKS_EN_N
  29 FM_CPU0_MCP_CLK_EN_N OE_3_N @BASEBOARD_FAB2_LIB.BASEBOARD_FAB2(SCH_1):FM_CPU0_MCP_CLK_EN_N
  30 CLK_100M_CPU0_PE_REFCLK_R_DP DIF_3P @BASEBOARD_FAB2_LIB.BASEBOARD_FAB2(SCH_1):CLK_100M_CPU0_PE_REFCLK_R_DP
  31 CLK_100M_CPU0_PE_REFCLK_R_DN DIF_3N @BASEBOARD_FAB2_LIB.BASEBOARD_FAB2(SCH_1):CLK_100M_CPU0_PE_REFCLK_R_DN
  32 P3V3_DB1200 VDDIO<1> @BASEBOARD_FAB2_LIB.BASEBOARD_FAB2(SCH_1):P3V3_DB1200
  33    GND GND<2> @BASEBOARD_FAB2_LIB.BASEBOARD_FAB2(SCH_1):GND
  34 CLK_100M_CPU0_RC_REFCLK0_R_DP DIF_4P @BASEBOARD_FAB2_LIB.BASEBOARD_FAB2(SCH_1):CLK_100M_CPU0_RC_REFCLK0_R_DP
  35 CLK_100M_CPU0_RC_REFCLK0_R_DN DIF_4N @BASEBOARD_FAB2_LIB.BASEBOARD_FAB2(SCH_1):CLK_100M_CPU0_RC_REFCLK0_R_DN
  36 FM_CPU0_MCP_CLK_EN_N OE_4_N @BASEBOARD_FAB2_LIB.BASEBOARD_FAB2(SCH_1):FM_CPU0_MCP_CLK_EN_N
  37 FM_CPU0_MCP_CLK_EN_N OE_5_N @BASEBOARD_FAB2_LIB.BASEBOARD_FAB2(SCH_1):FM_CPU0_MCP_CLK_EN_N
  38 CLK_100M_CPU0_RC_REFCLK1_R_DP DIF_5P @BASEBOARD_FAB2_LIB.BASEBOARD_FAB2(SCH_1):CLK_100M_CPU0_RC_REFCLK1_R_DP
  39 CLK_100M_CPU0_RC_REFCLK1_R_DN DIF_5N @BASEBOARD_FAB2_LIB.BASEBOARD_FAB2(SCH_1):CLK_100M_CPU0_RC_REFCLK1_R_DN
  40 P3V3_DB1200 VDD<1> @BASEBOARD_FAB2_LIB.BASEBOARD_FAB2(SCH_1):P3V3_DB1200
  41    GND GND<3> @BASEBOARD_FAB2_LIB.BASEBOARD_FAB2(SCH_1):GND
  42 CLK_100M_CPU1_BCLK0_R_DP DIF_6P @BASEBOARD_FAB2_LIB.BASEBOARD_FAB2(SCH_1):CLK_100M_CPU1_BCLK0_R_DP
  43 CLK_100M_CPU1_BCLK0_R_DN DIF_6N @BASEBOARD_FAB2_LIB.BASEBOARD_FAB2(SCH_1):CLK_100M_CPU1_BCLK0_R_DN
  44 FM_DB1200ZL_BCLKS_EN_N OE_6_N @BASEBOARD_FAB2_LIB.BASEBOARD_FAB2(SCH_1):FM_DB1200ZL_BCLKS_EN_N
  45 FM_DB1200ZL_BCLKS_EN_N OE_7_N @BASEBOARD_FAB2_LIB.BASEBOARD_FAB2(SCH_1):FM_DB1200ZL_BCLKS_EN_N
  46 CLK_100M_CPU1_BCLK1_R_DP DIF_7P @BASEBOARD_FAB2_LIB.BASEBOARD_FAB2(SCH_1):CLK_100M_CPU1_BCLK1_R_DP
  47 CLK_100M_CPU1_BCLK1_R_DN DIF_7N @BASEBOARD_FAB2_LIB.BASEBOARD_FAB2(SCH_1):CLK_100M_CPU1_BCLK1_R_DN
  48    GND GND<4> @BASEBOARD_FAB2_LIB.BASEBOARD_FAB2(SCH_1):GND
  49 P3V3_DB1200 VDDIO<2> @BASEBOARD_FAB2_LIB.BASEBOARD_FAB2(SCH_1):P3V3_DB1200
  50 CLK_100M_CPU1_BCLK2_R_DP DIF_8P @BASEBOARD_FAB2_LIB.BASEBOARD_FAB2(SCH_1):CLK_100M_CPU1_BCLK2_R_DP
  51 CLK_100M_CPU1_BCLK2_R_DN DIF_8N @BASEBOARD_FAB2_LIB.BASEBOARD_FAB2(SCH_1):CLK_100M_CPU1_BCLK2_R_DN
  52 FM_DB1200ZL_BCLKS_EN_N OE_8_N @BASEBOARD_FAB2_LIB.BASEBOARD_FAB2(SCH_1):FM_DB1200ZL_BCLKS_EN_N
  53 FM_CPU1_MCP_CLK_EN_N OE_9_N @BASEBOARD_FAB2_LIB.BASEBOARD_FAB2(SCH_1):FM_CPU1_MCP_CLK_EN_N
  54 CLK_100M_CPU1_PE_REFCLK_R_DP DIF_9P @BASEBOARD_FAB2_LIB.BASEBOARD_FAB2(SCH_1):CLK_100M_CPU1_PE_REFCLK_R_DP
  55 CLK_100M_CPU1_PE_REFCLK_R_DN DIF_9N @BASEBOARD_FAB2_LIB.BASEBOARD_FAB2(SCH_1):CLK_100M_CPU1_PE_REFCLK_R_DN
  56 P3V3_DB1200 VDDIO<3> @BASEBOARD_FAB2_LIB.BASEBOARD_FAB2(SCH_1):P3V3_DB1200
  57 P3V3_DB1200 VDD<2> @BASEBOARD_FAB2_LIB.BASEBOARD_FAB2(SCH_1):P3V3_DB1200
  58    GND GND<5> @BASEBOARD_FAB2_LIB.BASEBOARD_FAB2(SCH_1):GND
  59 CLK_100M_CPU1_RC_REFCLK0_R_DP DIF_10P @BASEBOARD_FAB2_LIB.BASEBOARD_FAB2(SCH_1):CLK_100M_CPU1_RC_REFCLK0_R_DP
  60 CLK_100M_CPU1_RC_REFCLK0_R_DN DIF_10N @BASEBOARD_FAB2_LIB.BASEBOARD_FAB2(SCH_1):CLK_100M_CPU1_RC_REFCLK0_R_DN
  61 FM_CPU1_MCP_CLK_EN_N OE_10_N @BASEBOARD_FAB2_LIB.BASEBOARD_FAB2(SCH_1):FM_CPU1_MCP_CLK_EN_N
  62 FM_CPU1_MCP_CLK_EN_N OE_11_N @BASEBOARD_FAB2_LIB.BASEBOARD_FAB2(SCH_1):FM_CPU1_MCP_CLK_EN_N
  63 CLK_100M_CPU1_RC_REFCLK1_R_DP DIF_11P @BASEBOARD_FAB2_LIB.BASEBOARD_FAB2(SCH_1):CLK_100M_CPU1_RC_REFCLK1_R_DP
  64 CLK_100M_CPU1_RC_REFCLK1_R_DN DIF_11N @BASEBOARD_FAB2_LIB.BASEBOARD_FAB2(SCH_1):CLK_100M_CPU1_RC_REFCLK1_R_DN
  65    GND  THPAD @BASEBOARD_FAB2_LIB.BASEBOARD_FAB2(SCH_1):GND

FERRITE_SMLF-600,FB,656554-043  I8  FB6P1
   1   P3V3      A @BASEBOARD_FAB2_LIB.BASEBOARD_FAB2(SCH_1):P3V3
   2 P3V3_DB1200      B @BASEBOARD_FAB2_LIB.BASEBOARD_FAB2(SCH_1):P3V3_DB1200

CAP_0805-10UF,16V,10%,X7R,G106A  I10  C3D22
   1 P3V3_DB1200      A @BASEBOARD_FAB2_LIB.BASEBOARD_FAB2(SCH_1):P3V3_DB1200
   2    GND      B @BASEBOARD_FAB2_LIB.BASEBOARD_FAB2(SCH_1):GND

CAP_A_0402V-0.1UF,16V,10%,X7R,A  I11  C6P4
   1 P3V3_DB1200      A @BASEBOARD_FAB2_LIB.BASEBOARD_FAB2(SCH_1):P3V3_DB1200
   2    GND      B @BASEBOARD_FAB2_LIB.BASEBOARD_FAB2(SCH_1):GND

CAP_A_0402V-0.1UF,16V,10%,X7R,A  I12  C6P6
   1 P3V3_DB1200      A @BASEBOARD_FAB2_LIB.BASEBOARD_FAB2(SCH_1):P3V3_DB1200
   2    GND      B @BASEBOARD_FAB2_LIB.BASEBOARD_FAB2(SCH_1):GND

CAP_A_0402V-0.1UF,16V,10%,X7R,A  I13  C6P10
   1 P3V3_DB1200      A @BASEBOARD_FAB2_LIB.BASEBOARD_FAB2(SCH_1):P3V3_DB1200
   2    GND      B @BASEBOARD_FAB2_LIB.BASEBOARD_FAB2(SCH_1):GND

CAP_A_0402V-0.1UF,16V,10%,X7R,A  I14  C6P5
   1 P3V3_DB1200      A @BASEBOARD_FAB2_LIB.BASEBOARD_FAB2(SCH_1):P3V3_DB1200
   2    GND      B @BASEBOARD_FAB2_LIB.BASEBOARD_FAB2(SCH_1):GND

CAP_A_0402V-0.1UF,16V,10%,X7R,A  I15  C6P12
   1 P3V3_DB1200      A @BASEBOARD_FAB2_LIB.BASEBOARD_FAB2(SCH_1):P3V3_DB1200
   2    GND      B @BASEBOARD_FAB2_LIB.BASEBOARD_FAB2(SCH_1):GND

CAP_A_0402V-0.1UF,16V,10%,X7R,A  I16  C6P11
   1 P3V3_DB1200      A @BASEBOARD_FAB2_LIB.BASEBOARD_FAB2(SCH_1):P3V3_DB1200
   2    GND      B @BASEBOARD_FAB2_LIB.BASEBOARD_FAB2(SCH_1):GND

CAP_A_0402V-0.1UF,16V,10%,X7R,A  I18  C4D24
   1 P3V3_DB1200_A      A @BASEBOARD_FAB2_LIB.BASEBOARD_FAB2(SCH_1):P3V3_DB1200_A
   2    GND      B @BASEBOARD_FAB2_LIB.BASEBOARD_FAB2(SCH_1):GND

CAP_A_0402V-1.0UF,6.3V,10%,X6SA  I19  C4D23
   1 P3V3_DB1200_A      A @BASEBOARD_FAB2_LIB.BASEBOARD_FAB2(SCH_1):P3V3_DB1200_A
   2    GND      B @BASEBOARD_FAB2_LIB.BASEBOARD_FAB2(SCH_1):GND

RES_0603-2.2,1.0%,1/10W,CHIP,GA  I21  R3D14
   1 P3V3_DB1200      A @BASEBOARD_FAB2_LIB.BASEBOARD_FAB2(SCH_1):P3V3_DB1200
   2 P3V3_DB1200_A      B @BASEBOARD_FAB2_LIB.BASEBOARD_FAB2(SCH_1):P3V3_DB1200_A

RES_0603-2.2,1.0%,1/10W,CHIP,GA  I26  R6P25
   1 P3V3_DB1200      A @BASEBOARD_FAB2_LIB.BASEBOARD_FAB2(SCH_1):P3V3_DB1200
   2 P3V3_DB1200_R      B @BASEBOARD_FAB2_LIB.BASEBOARD_FAB2(SCH_1):P3V3_DB1200_R

CAP_A_0402V-0.1UF,16V,10%,X7R,A  I28  C4D22
   1 P3V3_DB1200_R      A @BASEBOARD_FAB2_LIB.BASEBOARD_FAB2(SCH_1):P3V3_DB1200_R
   2    GND      B @BASEBOARD_FAB2_LIB.BASEBOARD_FAB2(SCH_1):GND

CAP_A_0402V-1.0UF,6.3V,10%,X6SA  I30  C4D27
   1 P3V3_DB1200_R      A @BASEBOARD_FAB2_LIB.BASEBOARD_FAB2(SCH_1):P3V3_DB1200_R
   2    GND      B @BASEBOARD_FAB2_LIB.BASEBOARD_FAB2(SCH_1):GND

RES_0402-10.0K,1%,1/16W,EMPTY,A  I37  R4D38
   1 P3V3_DB1200      A @BASEBOARD_FAB2_LIB.BASEBOARD_FAB2(SCH_1):P3V3_DB1200
   2 FM_DB1200_SMB_SA1      B @BASEBOARD_FAB2_LIB.BASEBOARD_FAB2(SCH_1):FM_DB1200_SMB_SA1

RES_0402-10.0K,1%,1/16W,EMPTY,A  I38  R4D35
   1 P3V3_DB1200      A @BASEBOARD_FAB2_LIB.BASEBOARD_FAB2(SCH_1):P3V3_DB1200
   2 FM_DB1200_SMB_SA0      B @BASEBOARD_FAB2_LIB.BASEBOARD_FAB2(SCH_1):FM_DB1200_SMB_SA0

RES_0402-4.75K,1%,1/16W,CHIP,GA  I45  R4D40
   1 P3V3_DB1200      A @BASEBOARD_FAB2_LIB.BASEBOARD_FAB2(SCH_1):P3V3_DB1200
   2 FM_100M_N      B @BASEBOARD_FAB2_LIB.BASEBOARD_FAB2(SCH_1):FM_100M_N

RES_0402-4.75K,1%,1/16W,EMPTY,A  I46  R6P23
   1 FM_100M_N      A @BASEBOARD_FAB2_LIB.BASEBOARD_FAB2(SCH_1):FM_100M_N
   2    GND      B @BASEBOARD_FAB2_LIB.BASEBOARD_FAB2(SCH_1):GND

RES_0402-4.75K,1%,1/16W,EMPTY,A  I47  R6P22
   1 FM_HBW_BYPASS_LOWBW_N      A @BASEBOARD_FAB2_LIB.BASEBOARD_FAB2(SCH_1):FM_HBW_BYPASS_LOWBW_N
   2    GND      B @BASEBOARD_FAB2_LIB.BASEBOARD_FAB2(SCH_1):GND

RES_0402-4.75K,1%,1/16W,CHIP,GA  I53  R4D41
   1 P3V3_DB1200      A @BASEBOARD_FAB2_LIB.BASEBOARD_FAB2(SCH_1):P3V3_DB1200
   2 FM_HBW_BYPASS_LOWBW_N      B @BASEBOARD_FAB2_LIB.BASEBOARD_FAB2(SCH_1):FM_HBW_BYPASS_LOWBW_N

CAP_A_0402V-0.1UF,16V,10%,X7R,A  I79  C6P9
   1 P3V3_DB1200      A @BASEBOARD_FAB2_LIB.BASEBOARD_FAB2(SCH_1):P3V3_DB1200
   2    GND      B @BASEBOARD_FAB2_LIB.BASEBOARD_FAB2(SCH_1):GND

RES_0402-1.00K,1%,1/16W,CHIP,GA  I80  R6P21
   1 FM_DB1200_SMB_SA0      A @BASEBOARD_FAB2_LIB.BASEBOARD_FAB2(SCH_1):FM_DB1200_SMB_SA0
   2    GND      B @BASEBOARD_FAB2_LIB.BASEBOARD_FAB2(SCH_1):GND

RES_0402-1.00K,1%,1/16W,CHIP,GA  I81  R6P20
   1 FM_DB1200_SMB_SA1      A @BASEBOARD_FAB2_LIB.BASEBOARD_FAB2(SCH_1):FM_DB1200_SMB_SA1
   2    GND      B @BASEBOARD_FAB2_LIB.BASEBOARD_FAB2(SCH_1):GND

RES_0402-4.75K,1%,1/16W,CHIP,GA  I93  R4D69
   1   P3V3      A @BASEBOARD_FAB2_LIB.BASEBOARD_FAB2(SCH_1):P3V3
   2 FM_CPU1_MCP_CLK_EN_N      B @BASEBOARD_FAB2_LIB.BASEBOARD_FAB2(SCH_1):FM_CPU1_MCP_CLK_EN_N

RES_0402-4.75K,1%,1/16W,CHIP,GA  I94  R4D70
   1   P3V3      A @BASEBOARD_FAB2_LIB.BASEBOARD_FAB2(SCH_1):P3V3
   2 FM_CPU0_MCP_CLK_EN_N      B @BASEBOARD_FAB2_LIB.BASEBOARD_FAB2(SCH_1):FM_CPU0_MCP_CLK_EN_N

FET_N_DUAL_SMLF-2N7002DW,FET,DA  I101  Q4W1
   5 P3V3_DB1200_R1 GATE<0> @BASEBOARD_FAB2_LIB.BASEBOARD_FAB2(SCH_1):P3V3_DB1200_R1
   4 SMB_HOST_STBY_LVC3_SCL_R2 SOURCE<0> @BASEBOARD_FAB2_LIB.BASEBOARD_FAB2(SCH_1):SMB_HOST_STBY_LVC3_SCL_R2
   3 SMB_HOST_STBY_LVC3_SCL DRAIN<0> @BASEBOARD_FAB2_LIB.BASEBOARD_FAB2(SCH_1):SMB_HOST_STBY_LVC3_SCL

FET_N_DUAL_SMLF-2N7002DW,FET,DA  I102  Q4W1
   2 P3V3_DB1200_R1 GATE<0> @BASEBOARD_FAB2_LIB.BASEBOARD_FAB2(SCH_1):P3V3_DB1200_R1
   1 SMB_HOST_STBY_LVC3_SDA_R2 SOURCE<0> @BASEBOARD_FAB2_LIB.BASEBOARD_FAB2(SCH_1):SMB_HOST_STBY_LVC3_SDA_R2
   6 SMB_HOST_STBY_LVC3_SDA DRAIN<0> @BASEBOARD_FAB2_LIB.BASEBOARD_FAB2(SCH_1):SMB_HOST_STBY_LVC3_SDA

RES_0402-1.00K,1%,1/16W,CHIP,GA  I103  R4W2
   1 P3V3_DB1200      A @BASEBOARD_FAB2_LIB.BASEBOARD_FAB2(SCH_1):P3V3_DB1200
   2 P3V3_DB1200_R1      B @BASEBOARD_FAB2_LIB.BASEBOARD_FAB2(SCH_1):P3V3_DB1200_R1

RES_0402-3.3K,5%,1/16W,CHIP,G2A  I105  R4W3
   1 P3V3_DB1200      A @BASEBOARD_FAB2_LIB.BASEBOARD_FAB2(SCH_1):P3V3_DB1200
   2 SMB_HOST_STBY_LVC3_SDA_R2      B @BASEBOARD_FAB2_LIB.BASEBOARD_FAB2(SCH_1):SMB_HOST_STBY_LVC3_SDA_R2

RES_0402-3.3K,5%,1/16W,CHIP,G2A  I106  R4W4
   1 P3V3_DB1200      A @BASEBOARD_FAB2_LIB.BASEBOARD_FAB2(SCH_1):P3V3_DB1200
   2 SMB_HOST_STBY_LVC3_SCL_R2      B @BASEBOARD_FAB2_LIB.BASEBOARD_FAB2(SCH_1):SMB_HOST_STBY_LVC3_SCL_R2

RES_0402-4.75K,1%,1/16W,CHIP,GA  I109  R4W6
   1 P3V3_DB1200      A @BASEBOARD_FAB2_LIB.BASEBOARD_FAB2(SCH_1):P3V3_DB1200
   2 FM_DB1200_PWRGD_R      B @BASEBOARD_FAB2_LIB.BASEBOARD_FAB2(SCH_1):FM_DB1200_PWRGD_R

FET_N_SOT23LF-2N7002,FET,C7925A  I112  Q4W2
   1 FM_DB1200_PWRGD   GATE @BASEBOARD_FAB2_LIB.BASEBOARD_FAB2(SCH_1):FM_DB1200_PWRGD
   2    GND    SRC @BASEBOARD_FAB2_LIB.BASEBOARD_FAB2(SCH_1):GND
   3 FM_DB1200_PWRGD_R    DRN @BASEBOARD_FAB2_LIB.BASEBOARD_FAB2(SCH_1):FM_DB1200_PWRGD_R

RES_0402-0.0,5%,1/16W,EMPTY,G2A  I114  R4W5
   1 FM_DB1200_PWRGD      A @BASEBOARD_FAB2_LIB.BASEBOARD_FAB2(SCH_1):FM_DB1200_PWRGD
   2 FM_DB1200_PWRGD_R      B @BASEBOARD_FAB2_LIB.BASEBOARD_FAB2(SCH_1):FM_DB1200_PWRGD_R

RES_0402-1.00K,1%,1/16W,CHIP,GA  I115  R6P48
   1   P3V3      A @BASEBOARD_FAB2_LIB.BASEBOARD_FAB2(SCH_1):P3V3
   2 FM_DB1200ZL_BCLKS_EN_N      B @BASEBOARD_FAB2_LIB.BASEBOARD_FAB2(SCH_1):FM_DB1200ZL_BCLKS_EN_N


DRAWING: @BASEBOARD_FAB2_LIB.BASEBOARD_FAB2(SCH_1):PAGE103 

RES_0402-27.4,1%,1/16W,CHIP,G2A  I1  R4D25
   1 CLK_100M_CPU0_BCLK0_R_DN      A @BASEBOARD_FAB2_LIB.BASEBOARD_FAB2(SCH_1):CLK_100M_CPU0_BCLK0_R_DN
   2 CLK_100M_CPU0_BCLK0_DN      B @BASEBOARD_FAB2_LIB.BASEBOARD_FAB2(SCH_1):CLK_100M_CPU0_BCLK0_DN

RES_0402-27.4,1%,1/16W,CHIP,G2A  I9  R4D23
   1 CLK_100M_CPU1_RC_REFCLK1_R_DP      A @BASEBOARD_FAB2_LIB.BASEBOARD_FAB2(SCH_1):CLK_100M_CPU1_RC_REFCLK1_R_DP
   2 CLK_100M_CPU1_RC_REFCLK1_DP      B @BASEBOARD_FAB2_LIB.BASEBOARD_FAB2(SCH_1):CLK_100M_CPU1_RC_REFCLK1_DP

RES_0402-27.4,1%,1/16W,CHIP,G2A  I14  R4D28
   1 CLK_100M_CPU1_RC_REFCLK1_R_DN      A @BASEBOARD_FAB2_LIB.BASEBOARD_FAB2(SCH_1):CLK_100M_CPU1_RC_REFCLK1_R_DN
   2 CLK_100M_CPU1_RC_REFCLK1_DN      B @BASEBOARD_FAB2_LIB.BASEBOARD_FAB2(SCH_1):CLK_100M_CPU1_RC_REFCLK1_DN

RES_0402-27.4,1%,1/16W,CHIP,G2A  I19  R4D19
   1 CLK_100M_CPU1_RC_REFCLK0_R_DP      A @BASEBOARD_FAB2_LIB.BASEBOARD_FAB2(SCH_1):CLK_100M_CPU1_RC_REFCLK0_R_DP
   2 CLK_100M_CPU1_RC_REFCLK0_DP      B @BASEBOARD_FAB2_LIB.BASEBOARD_FAB2(SCH_1):CLK_100M_CPU1_RC_REFCLK0_DP

RES_0402-27.4,1%,1/16W,CHIP,G2A  I24  R4D21
   1 CLK_100M_CPU1_RC_REFCLK0_R_DN      A @BASEBOARD_FAB2_LIB.BASEBOARD_FAB2(SCH_1):CLK_100M_CPU1_RC_REFCLK0_R_DN
   2 CLK_100M_CPU1_RC_REFCLK0_DN      B @BASEBOARD_FAB2_LIB.BASEBOARD_FAB2(SCH_1):CLK_100M_CPU1_RC_REFCLK0_DN

RES_0402-27.4,1%,1/16W,CHIP,G2A  I29  R4D13
   1 CLK_100M_CPU1_PE_REFCLK_R_DP      A @BASEBOARD_FAB2_LIB.BASEBOARD_FAB2(SCH_1):CLK_100M_CPU1_PE_REFCLK_R_DP
   2 CLK_100M_CPU1_PE_REFCLK_DP      B @BASEBOARD_FAB2_LIB.BASEBOARD_FAB2(SCH_1):CLK_100M_CPU1_PE_REFCLK_DP

RES_0402-27.4,1%,1/16W,CHIP,G2A  I34  R4D16
   1 CLK_100M_CPU1_PE_REFCLK_R_DN      A @BASEBOARD_FAB2_LIB.BASEBOARD_FAB2(SCH_1):CLK_100M_CPU1_PE_REFCLK_R_DN
   2 CLK_100M_CPU1_PE_REFCLK_DN      B @BASEBOARD_FAB2_LIB.BASEBOARD_FAB2(SCH_1):CLK_100M_CPU1_PE_REFCLK_DN

RES_0402-27.4,1%,1/16W,CHIP,G2A  I39  R4D9
   1 CLK_100M_CPU1_BCLK2_R_DP      A @BASEBOARD_FAB2_LIB.BASEBOARD_FAB2(SCH_1):CLK_100M_CPU1_BCLK2_R_DP
   2 CLK_100M_CPU1_BCLK2_DP      B @BASEBOARD_FAB2_LIB.BASEBOARD_FAB2(SCH_1):CLK_100M_CPU1_BCLK2_DP

RES_0402-27.4,1%,1/16W,CHIP,G2A  I44  R4D11
   1 CLK_100M_CPU1_BCLK2_R_DN      A @BASEBOARD_FAB2_LIB.BASEBOARD_FAB2(SCH_1):CLK_100M_CPU1_BCLK2_R_DN
   2 CLK_100M_CPU1_BCLK2_DN      B @BASEBOARD_FAB2_LIB.BASEBOARD_FAB2(SCH_1):CLK_100M_CPU1_BCLK2_DN

RES_0402-27.4,1%,1/16W,CHIP,G2A  I49  R4D2
   1 CLK_100M_CPU1_BCLK1_R_DP      A @BASEBOARD_FAB2_LIB.BASEBOARD_FAB2(SCH_1):CLK_100M_CPU1_BCLK1_R_DP
   2 CLK_100M_CPU1_BCLK1_DP      B @BASEBOARD_FAB2_LIB.BASEBOARD_FAB2(SCH_1):CLK_100M_CPU1_BCLK1_DP

RES_0402-27.4,1%,1/16W,CHIP,G2A  I54  R4D1
   1 CLK_100M_CPU1_BCLK1_R_DN      A @BASEBOARD_FAB2_LIB.BASEBOARD_FAB2(SCH_1):CLK_100M_CPU1_BCLK1_R_DN
   2 CLK_100M_CPU1_BCLK1_DN      B @BASEBOARD_FAB2_LIB.BASEBOARD_FAB2(SCH_1):CLK_100M_CPU1_BCLK1_DN

RES_0402-27.4,1%,1/16W,CHIP,G2A  I59  R4D4
   1 CLK_100M_CPU1_BCLK0_R_DP      A @BASEBOARD_FAB2_LIB.BASEBOARD_FAB2(SCH_1):CLK_100M_CPU1_BCLK0_R_DP
   2 CLK_100M_CPU1_BCLK0_DP      B @BASEBOARD_FAB2_LIB.BASEBOARD_FAB2(SCH_1):CLK_100M_CPU1_BCLK0_DP

RES_0402-27.4,1%,1/16W,CHIP,G2A  I64  R4D3
   1 CLK_100M_CPU1_BCLK0_R_DN      A @BASEBOARD_FAB2_LIB.BASEBOARD_FAB2(SCH_1):CLK_100M_CPU1_BCLK0_R_DN
   2 CLK_100M_CPU1_BCLK0_DN      B @BASEBOARD_FAB2_LIB.BASEBOARD_FAB2(SCH_1):CLK_100M_CPU1_BCLK0_DN

RES_0402-27.4,1%,1/16W,CHIP,G2A  I69  R4D29
   1 CLK_100M_CPU0_BCLK0_R_DP      A @BASEBOARD_FAB2_LIB.BASEBOARD_FAB2(SCH_1):CLK_100M_CPU0_BCLK0_R_DP
   2 CLK_100M_CPU0_BCLK0_DP      B @BASEBOARD_FAB2_LIB.BASEBOARD_FAB2(SCH_1):CLK_100M_CPU0_BCLK0_DP

RES_0402-27.4,1%,1/16W,CHIP,G2A  I74  R4D6
   1 CLK_100M_CPU0_RC_REFCLK1_R_DP      A @BASEBOARD_FAB2_LIB.BASEBOARD_FAB2(SCH_1):CLK_100M_CPU0_RC_REFCLK1_R_DP
   2 CLK_100M_CPU0_RC_REFCLK1_DP      B @BASEBOARD_FAB2_LIB.BASEBOARD_FAB2(SCH_1):CLK_100M_CPU0_RC_REFCLK1_DP

RES_0402-27.4,1%,1/16W,CHIP,G2A  I79  R4D5
   1 CLK_100M_CPU0_RC_REFCLK1_R_DN      A @BASEBOARD_FAB2_LIB.BASEBOARD_FAB2(SCH_1):CLK_100M_CPU0_RC_REFCLK1_R_DN
   2 CLK_100M_CPU0_RC_REFCLK1_DN      B @BASEBOARD_FAB2_LIB.BASEBOARD_FAB2(SCH_1):CLK_100M_CPU0_RC_REFCLK1_DN

RES_0402-27.4,1%,1/16W,CHIP,G2A  I84  R4D8
   1 CLK_100M_CPU0_RC_REFCLK0_R_DP      A @BASEBOARD_FAB2_LIB.BASEBOARD_FAB2(SCH_1):CLK_100M_CPU0_RC_REFCLK0_R_DP
   2 CLK_100M_CPU0_RC_REFCLK0_DP      B @BASEBOARD_FAB2_LIB.BASEBOARD_FAB2(SCH_1):CLK_100M_CPU0_RC_REFCLK0_DP

RES_0402-27.4,1%,1/16W,CHIP,G2A  I89  R4D7
   1 CLK_100M_CPU0_RC_REFCLK0_R_DN      A @BASEBOARD_FAB2_LIB.BASEBOARD_FAB2(SCH_1):CLK_100M_CPU0_RC_REFCLK0_R_DN
   2 CLK_100M_CPU0_RC_REFCLK0_DN      B @BASEBOARD_FAB2_LIB.BASEBOARD_FAB2(SCH_1):CLK_100M_CPU0_RC_REFCLK0_DN

RES_0402-27.4,1%,1/16W,CHIP,G2A  I94  R4D12
   1 CLK_100M_CPU0_PE_REFCLK_R_DP      A @BASEBOARD_FAB2_LIB.BASEBOARD_FAB2(SCH_1):CLK_100M_CPU0_PE_REFCLK_R_DP
   2 CLK_100M_CPU0_PE_REFCLK_DP      B @BASEBOARD_FAB2_LIB.BASEBOARD_FAB2(SCH_1):CLK_100M_CPU0_PE_REFCLK_DP

RES_0402-27.4,1%,1/16W,CHIP,G2A  I99  R4D10
   1 CLK_100M_CPU0_PE_REFCLK_R_DN      A @BASEBOARD_FAB2_LIB.BASEBOARD_FAB2(SCH_1):CLK_100M_CPU0_PE_REFCLK_R_DN
   2 CLK_100M_CPU0_PE_REFCLK_DN      B @BASEBOARD_FAB2_LIB.BASEBOARD_FAB2(SCH_1):CLK_100M_CPU0_PE_REFCLK_DN

RES_0402-27.4,1%,1/16W,CHIP,G2A  I104  R4D17
   1 CLK_100M_CPU0_BCLK2_R_DP      A @BASEBOARD_FAB2_LIB.BASEBOARD_FAB2(SCH_1):CLK_100M_CPU0_BCLK2_R_DP
   2 CLK_100M_CPU0_BCLK2_DP      B @BASEBOARD_FAB2_LIB.BASEBOARD_FAB2(SCH_1):CLK_100M_CPU0_BCLK2_DP

RES_0402-27.4,1%,1/16W,CHIP,G2A  I109  R4D14
   1 CLK_100M_CPU0_BCLK2_R_DN      A @BASEBOARD_FAB2_LIB.BASEBOARD_FAB2(SCH_1):CLK_100M_CPU0_BCLK2_R_DN
   2 CLK_100M_CPU0_BCLK2_DN      B @BASEBOARD_FAB2_LIB.BASEBOARD_FAB2(SCH_1):CLK_100M_CPU0_BCLK2_DN

RES_0402-27.4,1%,1/16W,CHIP,G2A  I114  R4D22
   1 CLK_100M_CPU0_BCLK1_R_DP      A @BASEBOARD_FAB2_LIB.BASEBOARD_FAB2(SCH_1):CLK_100M_CPU0_BCLK1_R_DP
   2 CLK_100M_CPU0_BCLK1_DP      B @BASEBOARD_FAB2_LIB.BASEBOARD_FAB2(SCH_1):CLK_100M_CPU0_BCLK1_DP

RES_0402-27.4,1%,1/16W,CHIP,G2A  I119  R4D20
   1 CLK_100M_CPU0_BCLK1_R_DN      A @BASEBOARD_FAB2_LIB.BASEBOARD_FAB2(SCH_1):CLK_100M_CPU0_BCLK1_R_DN
   2 CLK_100M_CPU0_BCLK1_DN      B @BASEBOARD_FAB2_LIB.BASEBOARD_FAB2(SCH_1):CLK_100M_CPU0_BCLK1_DN

RES_0402-42.2,1.0%,1/16W,EMPTYA  I121  R7P9
   1 CLK_100M_CPU1_RC_REFCLK1_DP      A @BASEBOARD_FAB2_LIB.BASEBOARD_FAB2(SCH_1):CLK_100M_CPU1_RC_REFCLK1_DP
   2    GND      B @BASEBOARD_FAB2_LIB.BASEBOARD_FAB2(SCH_1):GND

RES_0402-42.2,1.0%,1/16W,EMPTYA  I123  R7P12
   1 CLK_100M_CPU1_RC_REFCLK1_DN      A @BASEBOARD_FAB2_LIB.BASEBOARD_FAB2(SCH_1):CLK_100M_CPU1_RC_REFCLK1_DN
   2    GND      B @BASEBOARD_FAB2_LIB.BASEBOARD_FAB2(SCH_1):GND

RES_0402-42.2,1.0%,1/16W,EMPTYA  I125  R7P6
   1 CLK_100M_CPU1_RC_REFCLK0_DP      A @BASEBOARD_FAB2_LIB.BASEBOARD_FAB2(SCH_1):CLK_100M_CPU1_RC_REFCLK0_DP
   2    GND      B @BASEBOARD_FAB2_LIB.BASEBOARD_FAB2(SCH_1):GND

RES_0402-42.2,1.0%,1/16W,EMPTYA  I127  R7P7
   1 CLK_100M_CPU1_RC_REFCLK0_DN      A @BASEBOARD_FAB2_LIB.BASEBOARD_FAB2(SCH_1):CLK_100M_CPU1_RC_REFCLK0_DN
   2    GND      B @BASEBOARD_FAB2_LIB.BASEBOARD_FAB2(SCH_1):GND

RES_0402-42.2,1.0%,1/16W,EMPTYA  I129  R7P3
   1 CLK_100M_CPU1_PE_REFCLK_DP      A @BASEBOARD_FAB2_LIB.BASEBOARD_FAB2(SCH_1):CLK_100M_CPU1_PE_REFCLK_DP
   2    GND      B @BASEBOARD_FAB2_LIB.BASEBOARD_FAB2(SCH_1):GND

RES_0402-42.2,1.0%,1/16W,EMPTYA  I131  R7P4
   1 CLK_100M_CPU1_PE_REFCLK_DN      A @BASEBOARD_FAB2_LIB.BASEBOARD_FAB2(SCH_1):CLK_100M_CPU1_PE_REFCLK_DN
   2    GND      B @BASEBOARD_FAB2_LIB.BASEBOARD_FAB2(SCH_1):GND

RES_0402-42.2,1.0%,1/16W,EMPTYA  I133  R7P1
   1 CLK_100M_CPU1_BCLK2_DP      A @BASEBOARD_FAB2_LIB.BASEBOARD_FAB2(SCH_1):CLK_100M_CPU1_BCLK2_DP
   2    GND      B @BASEBOARD_FAB2_LIB.BASEBOARD_FAB2(SCH_1):GND

RES_0402-42.2,1.0%,1/16W,EMPTYA  I135  R7P2
   1 CLK_100M_CPU1_BCLK2_DN      A @BASEBOARD_FAB2_LIB.BASEBOARD_FAB2(SCH_1):CLK_100M_CPU1_BCLK2_DN
   2    GND      B @BASEBOARD_FAB2_LIB.BASEBOARD_FAB2(SCH_1):GND

RES_0402-42.2,1.0%,1/16W,EMPTYA  I137  R6P7
   1 CLK_100M_CPU1_BCLK1_DP      A @BASEBOARD_FAB2_LIB.BASEBOARD_FAB2(SCH_1):CLK_100M_CPU1_BCLK1_DP
   2    GND      B @BASEBOARD_FAB2_LIB.BASEBOARD_FAB2(SCH_1):GND

RES_0402-42.2,1.0%,1/16W,EMPTYA  I139  R6P8
   1 CLK_100M_CPU1_BCLK1_DN      A @BASEBOARD_FAB2_LIB.BASEBOARD_FAB2(SCH_1):CLK_100M_CPU1_BCLK1_DN
   2    GND      B @BASEBOARD_FAB2_LIB.BASEBOARD_FAB2(SCH_1):GND

RES_0402-42.2,1.0%,1/16W,EMPTYA  I141  R6P5
   1 CLK_100M_CPU1_BCLK0_DP      A @BASEBOARD_FAB2_LIB.BASEBOARD_FAB2(SCH_1):CLK_100M_CPU1_BCLK0_DP
   2    GND      B @BASEBOARD_FAB2_LIB.BASEBOARD_FAB2(SCH_1):GND

RES_0402-42.2,1.0%,1/16W,EMPTYA  I143  R6P6
   1 CLK_100M_CPU1_BCLK0_DN      A @BASEBOARD_FAB2_LIB.BASEBOARD_FAB2(SCH_1):CLK_100M_CPU1_BCLK0_DN
   2    GND      B @BASEBOARD_FAB2_LIB.BASEBOARD_FAB2(SCH_1):GND

RES_0402-42.2,1.0%,1/16W,EMPTYA  I145  R6P3
   1 CLK_100M_CPU0_RC_REFCLK1_DP      A @BASEBOARD_FAB2_LIB.BASEBOARD_FAB2(SCH_1):CLK_100M_CPU0_RC_REFCLK1_DP
   2    GND      B @BASEBOARD_FAB2_LIB.BASEBOARD_FAB2(SCH_1):GND

RES_0402-42.2,1.0%,1/16W,EMPTYA  I147  R6P4
   1 CLK_100M_CPU0_RC_REFCLK1_DN      A @BASEBOARD_FAB2_LIB.BASEBOARD_FAB2(SCH_1):CLK_100M_CPU0_RC_REFCLK1_DN
   2    GND      B @BASEBOARD_FAB2_LIB.BASEBOARD_FAB2(SCH_1):GND

RES_0402-42.2,1.0%,1/16W,EMPTYA  I149  R6P1
   1 CLK_100M_CPU0_RC_REFCLK0_DP      A @BASEBOARD_FAB2_LIB.BASEBOARD_FAB2(SCH_1):CLK_100M_CPU0_RC_REFCLK0_DP
   2    GND      B @BASEBOARD_FAB2_LIB.BASEBOARD_FAB2(SCH_1):GND

RES_0402-42.2,1.0%,1/16W,EMPTYA  I151  R6P2
   1 CLK_100M_CPU0_RC_REFCLK0_DN      A @BASEBOARD_FAB2_LIB.BASEBOARD_FAB2(SCH_1):CLK_100M_CPU0_RC_REFCLK0_DN
   2    GND      B @BASEBOARD_FAB2_LIB.BASEBOARD_FAB2(SCH_1):GND

RES_0402-42.2,1.0%,1/16W,EMPTYA  I153  R6P11
   1 CLK_100M_CPU0_PE_REFCLK_DP      A @BASEBOARD_FAB2_LIB.BASEBOARD_FAB2(SCH_1):CLK_100M_CPU0_PE_REFCLK_DP
   2    GND      B @BASEBOARD_FAB2_LIB.BASEBOARD_FAB2(SCH_1):GND

RES_0402-42.2,1.0%,1/16W,EMPTYA  I155  R6P9
   1 CLK_100M_CPU0_PE_REFCLK_DN      A @BASEBOARD_FAB2_LIB.BASEBOARD_FAB2(SCH_1):CLK_100M_CPU0_PE_REFCLK_DN
   2    GND      B @BASEBOARD_FAB2_LIB.BASEBOARD_FAB2(SCH_1):GND

RES_0402-42.2,1.0%,1/16W,EMPTYA  I157  R6P13
   1 CLK_100M_CPU0_BCLK2_DP      A @BASEBOARD_FAB2_LIB.BASEBOARD_FAB2(SCH_1):CLK_100M_CPU0_BCLK2_DP
   2    GND      B @BASEBOARD_FAB2_LIB.BASEBOARD_FAB2(SCH_1):GND

RES_0402-42.2,1.0%,1/16W,EMPTYA  I159  R6P12
   1 CLK_100M_CPU0_BCLK2_DN      A @BASEBOARD_FAB2_LIB.BASEBOARD_FAB2(SCH_1):CLK_100M_CPU0_BCLK2_DN
   2    GND      B @BASEBOARD_FAB2_LIB.BASEBOARD_FAB2(SCH_1):GND

RES_0402-42.2,1.0%,1/16W,EMPTYA  I161  R4D24
   1 CLK_100M_CPU0_BCLK1_DP      A @BASEBOARD_FAB2_LIB.BASEBOARD_FAB2(SCH_1):CLK_100M_CPU0_BCLK1_DP
   2    GND      B @BASEBOARD_FAB2_LIB.BASEBOARD_FAB2(SCH_1):GND

RES_0402-42.2,1.0%,1/16W,EMPTYA  I163  R4D18
   1 CLK_100M_CPU0_BCLK1_DN      A @BASEBOARD_FAB2_LIB.BASEBOARD_FAB2(SCH_1):CLK_100M_CPU0_BCLK1_DN
   2    GND      B @BASEBOARD_FAB2_LIB.BASEBOARD_FAB2(SCH_1):GND

RES_0402-42.2,1.0%,1/16W,EMPTYA  I165  R6P17
   1 CLK_100M_CPU0_BCLK0_DP      A @BASEBOARD_FAB2_LIB.BASEBOARD_FAB2(SCH_1):CLK_100M_CPU0_BCLK0_DP
   2    GND      B @BASEBOARD_FAB2_LIB.BASEBOARD_FAB2(SCH_1):GND

RES_0402-42.2,1.0%,1/16W,EMPTYA  I167  R6P15
   1 CLK_100M_CPU0_BCLK0_DN      A @BASEBOARD_FAB2_LIB.BASEBOARD_FAB2(SCH_1):CLK_100M_CPU0_BCLK0_DN
   2    GND      B @BASEBOARD_FAB2_LIB.BASEBOARD_FAB2(SCH_1):GND


DRAWING: @BASEBOARD_FAB2_LIB.BASEBOARD_FAB2(SCH_1):PAGE104 

CAP_A_0402V-0.1UF,16V,10%,X7R,A  I25  C6F1
   1   P3V3      A @BASEBOARD_FAB2_LIB.BASEBOARD_FAB2(SCH_1):P3V3
   2    GND      B @BASEBOARD_FAB2_LIB.BASEBOARD_FAB2(SCH_1):GND

CAP_A_0402V-0.1UF,16V,10%,X7R,A  I34  C3F2
   1   P3V3      A @BASEBOARD_FAB2_LIB.BASEBOARD_FAB2(SCH_1):P3V3
   2    GND      B @BASEBOARD_FAB2_LIB.BASEBOARD_FAB2(SCH_1):GND

RES_0402-0.0,5%,1/16W,EMPTY,G2A  I37  R6F8
   1 CLK_322M_156M_CPU0_OSC_VRM_DP      A @BASEBOARD_FAB2_LIB.BASEBOARD_FAB2(SCH_1):CLK_322M_156M_CPU0_OSC_VRM_DP
   2 CLK_156M_OSC_CPU0_HFI_DP      B @BASEBOARD_FAB2_LIB.BASEBOARD_FAB2(SCH_1):CLK_156M_OSC_CPU0_HFI_DP

RES_0402-0.0,5%,1/16W,EMPTY,G2A  I41  R6F6
   1 CLK_322M_156M_CPU0_OSC_VRM_DN      A @BASEBOARD_FAB2_LIB.BASEBOARD_FAB2(SCH_1):CLK_322M_156M_CPU0_OSC_VRM_DN
   2 CLK_156M_OSC_CPU0_HFI_DN      B @BASEBOARD_FAB2_LIB.BASEBOARD_FAB2(SCH_1):CLK_156M_OSC_CPU0_HFI_DN

RES_0402-0.0,5%,1/16W,EMPTY,G2A  I51  R3F1
   1 CLK_322M_156M_CPU1_OSC_VRM_DN      A @BASEBOARD_FAB2_LIB.BASEBOARD_FAB2(SCH_1):CLK_322M_156M_CPU1_OSC_VRM_DN
   2 CLK_156M_OSC_CPU1_HFI_DN      B @BASEBOARD_FAB2_LIB.BASEBOARD_FAB2(SCH_1):CLK_156M_OSC_CPU1_HFI_DN

RES_0402-0.0,5%,1/16W,EMPTY,G2A  I53  R3F3
   1 CLK_322M_156M_CPU1_OSC_VRM_DP      A @BASEBOARD_FAB2_LIB.BASEBOARD_FAB2(SCH_1):CLK_322M_156M_CPU1_OSC_VRM_DP
   2 CLK_156M_OSC_CPU1_HFI_DP      B @BASEBOARD_FAB2_LIB.BASEBOARD_FAB2(SCH_1):CLK_156M_OSC_CPU1_HFI_DP

RES_0402-0.0,5%,1/16W,CHIP,G21A  I67  R6F7
   1 CLK_156M_OSC_BRD_CPU0_DN      A @BASEBOARD_FAB2_LIB.BASEBOARD_FAB2(SCH_1):CLK_156M_OSC_BRD_CPU0_DN
   2 CLK_156M_OSC_CPU0_HFI_DN      B @BASEBOARD_FAB2_LIB.BASEBOARD_FAB2(SCH_1):CLK_156M_OSC_CPU0_HFI_DN

RES_0402-0.0,5%,1/16W,CHIP,G21A  I68  R6F9
   1 CLK_156M_OSC_BRD_CPU0_DP      A @BASEBOARD_FAB2_LIB.BASEBOARD_FAB2(SCH_1):CLK_156M_OSC_BRD_CPU0_DP
   2 CLK_156M_OSC_CPU0_HFI_DP      B @BASEBOARD_FAB2_LIB.BASEBOARD_FAB2(SCH_1):CLK_156M_OSC_CPU0_HFI_DP

RES_0402-0.0,5%,1/16W,CHIP,G21A  I69  R3F2
   1 CLK_156M_OSC_BRD_CPU1_DN      A @BASEBOARD_FAB2_LIB.BASEBOARD_FAB2(SCH_1):CLK_156M_OSC_BRD_CPU1_DN
   2 CLK_156M_OSC_CPU1_HFI_DN      B @BASEBOARD_FAB2_LIB.BASEBOARD_FAB2(SCH_1):CLK_156M_OSC_CPU1_HFI_DN

RES_0402-0.0,5%,1/16W,CHIP,G21A  I70  R3F4
   1 CLK_156M_OSC_BRD_CPU1_DP      A @BASEBOARD_FAB2_LIB.BASEBOARD_FAB2(SCH_1):CLK_156M_OSC_BRD_CPU1_DP
   2 CLK_156M_OSC_CPU1_HFI_DP      B @BASEBOARD_FAB2_LIB.BASEBOARD_FAB2(SCH_1):CLK_156M_OSC_CPU1_HFI_DP

OSC_C_6P10-156.25MHZ,OSC,G6383A  I71  Y6F1
   1 FM_CPU0_STL_BRD_OSC_EN ENABLE_DISABLE @BASEBOARD_FAB2_LIB.BASEBOARD_FAB2(SCH_1):FM_CPU0_STL_BRD_OSC_EN
   2 NC_CLK_156M_CPU0_OSC NC_GND @BASEBOARD_FAB2_LIB.BASEBOARD_FAB2(SCH_1):NC_CLK_156M_CPU0_OSC
   3    GND    GND @BASEBOARD_FAB2_LIB.BASEBOARD_FAB2(SCH_1):GND
   4 CLK_156M_OSC_BRD_CPU0_DP    OUT @BASEBOARD_FAB2_LIB.BASEBOARD_FAB2(SCH_1):CLK_156M_OSC_BRD_CPU0_DP
   5 CLK_156M_OSC_BRD_CPU0_DN  OUT_N @BASEBOARD_FAB2_LIB.BASEBOARD_FAB2(SCH_1):CLK_156M_OSC_BRD_CPU0_DN
   6   P3V3    VCC @BASEBOARD_FAB2_LIB.BASEBOARD_FAB2(SCH_1):P3V3

OSC_C_6P10-156.25MHZ,OSC,G6383A  I72  Y3F1
   1 FM_CPU1_STL_BRD_OSC_EN ENABLE_DISABLE @BASEBOARD_FAB2_LIB.BASEBOARD_FAB2(SCH_1):FM_CPU1_STL_BRD_OSC_EN
   2 NC_CLK_156M_CPU1_OSC NC_GND @BASEBOARD_FAB2_LIB.BASEBOARD_FAB2(SCH_1):NC_CLK_156M_CPU1_OSC
   3    GND    GND @BASEBOARD_FAB2_LIB.BASEBOARD_FAB2(SCH_1):GND
   4 CLK_156M_OSC_BRD_CPU1_DP    OUT @BASEBOARD_FAB2_LIB.BASEBOARD_FAB2(SCH_1):CLK_156M_OSC_BRD_CPU1_DP
   5 CLK_156M_OSC_BRD_CPU1_DN  OUT_N @BASEBOARD_FAB2_LIB.BASEBOARD_FAB2(SCH_1):CLK_156M_OSC_BRD_CPU1_DN
   6   P3V3    VCC @BASEBOARD_FAB2_LIB.BASEBOARD_FAB2(SCH_1):P3V3

RES_0402-0.0,5%,1/16W,EMPTY,G2A  I78  R6F10
   1 CLK_322M_156M_CPU0_OSC_VRM_DN      A @BASEBOARD_FAB2_LIB.BASEBOARD_FAB2(SCH_1):CLK_322M_156M_CPU0_OSC_VRM_DN
   2 CLK_322M_OSC_CPU0_RC_DN      B @BASEBOARD_FAB2_LIB.BASEBOARD_FAB2(SCH_1):CLK_322M_OSC_CPU0_RC_DN

RES_0402-0.0,5%,1/16W,EMPTY,G2A  I79  R6F11
   1 CLK_322M_156M_CPU0_OSC_VRM_DP      A @BASEBOARD_FAB2_LIB.BASEBOARD_FAB2(SCH_1):CLK_322M_156M_CPU0_OSC_VRM_DP
   2 CLK_322M_OSC_CPU0_RC_DP      B @BASEBOARD_FAB2_LIB.BASEBOARD_FAB2(SCH_1):CLK_322M_OSC_CPU0_RC_DP

RES_0402-0.0,5%,1/16W,EMPTY,G2A  I84  R3F5
   1 CLK_322M_156M_CPU1_OSC_VRM_DN      A @BASEBOARD_FAB2_LIB.BASEBOARD_FAB2(SCH_1):CLK_322M_156M_CPU1_OSC_VRM_DN
   2 CLK_322M_OSC_CPU1_RC_DN      B @BASEBOARD_FAB2_LIB.BASEBOARD_FAB2(SCH_1):CLK_322M_OSC_CPU1_RC_DN

RES_0402-0.0,5%,1/16W,EMPTY,G2A  I88  R3F6
   1 CLK_322M_156M_CPU1_OSC_VRM_DP      A @BASEBOARD_FAB2_LIB.BASEBOARD_FAB2(SCH_1):CLK_322M_156M_CPU1_OSC_VRM_DP
   2 CLK_322M_OSC_CPU1_RC_DP      B @BASEBOARD_FAB2_LIB.BASEBOARD_FAB2(SCH_1):CLK_322M_OSC_CPU1_RC_DP

RES_0402-0.0,5%,1/16W,CHIP,G21A  I93  R8D43
   1 FM_156M_CPU0_BRD_OSC_EN      A @BASEBOARD_FAB2_LIB.BASEBOARD_FAB2(SCH_1):FM_156M_CPU0_BRD_OSC_EN
   2 FM_CPU0_STL_BRD_OSC_EN      B @BASEBOARD_FAB2_LIB.BASEBOARD_FAB2(SCH_1):FM_CPU0_STL_BRD_OSC_EN

RES_0402-0.0,5%,1/16W,EMPTY,G2A  I94  R7D40
   1 FM_CPU0_VRM_OSC_EN      A @BASEBOARD_FAB2_LIB.BASEBOARD_FAB2(SCH_1):FM_CPU0_VRM_OSC_EN
   2 FM_CPU0_STL_BRD_OSC_EN      B @BASEBOARD_FAB2_LIB.BASEBOARD_FAB2(SCH_1):FM_CPU0_STL_BRD_OSC_EN

RES_0402-0.0,5%,1/16W,CHIP,G21A  I96  R7D36
   1 FM_156M_CPU1_BRD_OSC_EN      A @BASEBOARD_FAB2_LIB.BASEBOARD_FAB2(SCH_1):FM_156M_CPU1_BRD_OSC_EN
   2 FM_CPU1_STL_BRD_OSC_EN      B @BASEBOARD_FAB2_LIB.BASEBOARD_FAB2(SCH_1):FM_CPU1_STL_BRD_OSC_EN

RES_0402-0.0,5%,1/16W,EMPTY,G2A  I97  R7D38
   1 FM_CPU1_VRM_OSC_EN      A @BASEBOARD_FAB2_LIB.BASEBOARD_FAB2(SCH_1):FM_CPU1_VRM_OSC_EN
   2 FM_CPU1_STL_BRD_OSC_EN      B @BASEBOARD_FAB2_LIB.BASEBOARD_FAB2(SCH_1):FM_CPU1_STL_BRD_OSC_EN

RES_0402-0.0,5%,1/16W,CHIP,G21A  I103  R7D39
   1 FM_CPU0_VRM_OSC_EN      A @BASEBOARD_FAB2_LIB.BASEBOARD_FAB2(SCH_1):FM_CPU0_VRM_OSC_EN
   2 FM_CPU0_VRM_322M_156M_OSC_EN      B @BASEBOARD_FAB2_LIB.BASEBOARD_FAB2(SCH_1):FM_CPU0_VRM_322M_156M_OSC_EN

RES_0402-0.0,5%,1/16W,CHIP,G21A  I104  R7D37
   1 FM_CPU1_VRM_OSC_EN      A @BASEBOARD_FAB2_LIB.BASEBOARD_FAB2(SCH_1):FM_CPU1_VRM_OSC_EN
   2 FM_CPU1_VRM_322M_156M_OSC_EN      B @BASEBOARD_FAB2_LIB.BASEBOARD_FAB2(SCH_1):FM_CPU1_VRM_322M_156M_OSC_EN


DRAWING: @BASEBOARD_FAB2_LIB.BASEBOARD_FAB2(SCH_1):PAGE105 

CAP_0402-0.22UF,16V,10%,X7R,A3A  I1  C7G24
   1 P3E_CPU0_PE2_SS_TXN<6>      A @BASEBOARD_FAB2_LIB.BASEBOARD_FAB2(SCH_1):P3E_CPU0_PE2_SS_TXN(6)
   2 P3E_CPU0_PE2_SS_C_TXN<6>      B @BASEBOARD_FAB2_LIB.BASEBOARD_FAB2(SCH_1):P3E_CPU0_PE2_SS_C_TXN(6)

CAP_0402-0.22UF,16V,10%,X7R,A3A  I6  C7G6
   1 P3E_CPU0_PE2_SS_TXN<15>      A @BASEBOARD_FAB2_LIB.BASEBOARD_FAB2(SCH_1):P3E_CPU0_PE2_SS_TXN(15)
   2 P3E_CPU0_PE2_SS_C_TXN<15>      B @BASEBOARD_FAB2_LIB.BASEBOARD_FAB2(SCH_1):P3E_CPU0_PE2_SS_C_TXN(15)

CAP_0402-0.22UF,16V,10%,X7R,A3A  I7  C7G7
   1 P3E_CPU0_PE2_SS_TXN<14>      A @BASEBOARD_FAB2_LIB.BASEBOARD_FAB2(SCH_1):P3E_CPU0_PE2_SS_TXN(14)
   2 P3E_CPU0_PE2_SS_C_TXN<14>      B @BASEBOARD_FAB2_LIB.BASEBOARD_FAB2(SCH_1):P3E_CPU0_PE2_SS_C_TXN(14)

CAP_0402-0.22UF,16V,10%,X7R,A3A  I8  C7G10
   1 P3E_CPU0_PE2_SS_TXN<13>      A @BASEBOARD_FAB2_LIB.BASEBOARD_FAB2(SCH_1):P3E_CPU0_PE2_SS_TXN(13)
   2 P3E_CPU0_PE2_SS_C_TXN<13>      B @BASEBOARD_FAB2_LIB.BASEBOARD_FAB2(SCH_1):P3E_CPU0_PE2_SS_C_TXN(13)

CAP_0402-0.22UF,16V,10%,X7R,A3A  I12  C7G12
   1 P3E_CPU0_PE2_SS_TXN<12>      A @BASEBOARD_FAB2_LIB.BASEBOARD_FAB2(SCH_1):P3E_CPU0_PE2_SS_TXN(12)
   2 P3E_CPU0_PE2_SS_C_TXN<12>      B @BASEBOARD_FAB2_LIB.BASEBOARD_FAB2(SCH_1):P3E_CPU0_PE2_SS_C_TXN(12)

CAP_0402-0.22UF,16V,10%,X7R,A3A  I13  C7G13
   1 P3E_CPU0_PE2_SS_TXN<11>      A @BASEBOARD_FAB2_LIB.BASEBOARD_FAB2(SCH_1):P3E_CPU0_PE2_SS_TXN(11)
   2 P3E_CPU0_PE2_SS_C_TXN<11>      B @BASEBOARD_FAB2_LIB.BASEBOARD_FAB2(SCH_1):P3E_CPU0_PE2_SS_C_TXN(11)

CAP_0402-0.22UF,16V,10%,X7R,A3A  I20  C7G5
   1 P3E_CPU0_PE2_SS_TXP<15>      A @BASEBOARD_FAB2_LIB.BASEBOARD_FAB2(SCH_1):P3E_CPU0_PE2_SS_TXP(15)
   2 P3E_CPU0_PE2_SS_C_TXP<15>      B @BASEBOARD_FAB2_LIB.BASEBOARD_FAB2(SCH_1):P3E_CPU0_PE2_SS_C_TXP(15)

CAP_0402-0.22UF,16V,10%,X7R,A3A  I21  C7G9
   1 P3E_CPU0_PE2_SS_TXP<13>      A @BASEBOARD_FAB2_LIB.BASEBOARD_FAB2(SCH_1):P3E_CPU0_PE2_SS_TXP(13)
   2 P3E_CPU0_PE2_SS_C_TXP<13>      B @BASEBOARD_FAB2_LIB.BASEBOARD_FAB2(SCH_1):P3E_CPU0_PE2_SS_C_TXP(13)

CAP_0402-0.22UF,16V,10%,X7R,A3A  I22  C7G8
   1 P3E_CPU0_PE2_SS_TXP<14>      A @BASEBOARD_FAB2_LIB.BASEBOARD_FAB2(SCH_1):P3E_CPU0_PE2_SS_TXP(14)
   2 P3E_CPU0_PE2_SS_C_TXP<14>      B @BASEBOARD_FAB2_LIB.BASEBOARD_FAB2(SCH_1):P3E_CPU0_PE2_SS_C_TXP(14)

CAP_0402-0.22UF,16V,10%,X7R,A3A  I27  C7G11
   1 P3E_CPU0_PE2_SS_TXP<12>      A @BASEBOARD_FAB2_LIB.BASEBOARD_FAB2(SCH_1):P3E_CPU0_PE2_SS_TXP(12)
   2 P3E_CPU0_PE2_SS_C_TXP<12>      B @BASEBOARD_FAB2_LIB.BASEBOARD_FAB2(SCH_1):P3E_CPU0_PE2_SS_C_TXP(12)

CAP_0402-0.22UF,16V,10%,X7R,A3A  I28  C7G14
   1 P3E_CPU0_PE2_SS_TXP<11>      A @BASEBOARD_FAB2_LIB.BASEBOARD_FAB2(SCH_1):P3E_CPU0_PE2_SS_TXP(11)
   2 P3E_CPU0_PE2_SS_C_TXP<11>      B @BASEBOARD_FAB2_LIB.BASEBOARD_FAB2(SCH_1):P3E_CPU0_PE2_SS_C_TXP(11)

CAP_0402-0.22UF,16V,10%,X7R,A3A  I31  C7G16
   1 P3E_CPU0_PE2_SS_TXN<10>      A @BASEBOARD_FAB2_LIB.BASEBOARD_FAB2(SCH_1):P3E_CPU0_PE2_SS_TXN(10)
   2 P3E_CPU0_PE2_SS_C_TXN<10>      B @BASEBOARD_FAB2_LIB.BASEBOARD_FAB2(SCH_1):P3E_CPU0_PE2_SS_C_TXN(10)

CAP_0402-0.22UF,16V,10%,X7R,A3A  I32  C7G18
   1 P3E_CPU0_PE2_SS_TXN<9>      A @BASEBOARD_FAB2_LIB.BASEBOARD_FAB2(SCH_1):P3E_CPU0_PE2_SS_TXN(9)
   2 P3E_CPU0_PE2_SS_C_TXN<9>      B @BASEBOARD_FAB2_LIB.BASEBOARD_FAB2(SCH_1):P3E_CPU0_PE2_SS_C_TXN(9)

CAP_0402-0.22UF,16V,10%,X7R,A3A  I37  C7G22
   1 P3E_CPU0_PE2_SS_TXN<7>      A @BASEBOARD_FAB2_LIB.BASEBOARD_FAB2(SCH_1):P3E_CPU0_PE2_SS_TXN(7)
   2 P3E_CPU0_PE2_SS_C_TXN<7>      B @BASEBOARD_FAB2_LIB.BASEBOARD_FAB2(SCH_1):P3E_CPU0_PE2_SS_C_TXN(7)

CAP_0402-0.22UF,16V,10%,X7R,A3A  I44  C7G17
   1 P3E_CPU0_PE2_SS_TXP<9>      A @BASEBOARD_FAB2_LIB.BASEBOARD_FAB2(SCH_1):P3E_CPU0_PE2_SS_TXP(9)
   2 P3E_CPU0_PE2_SS_C_TXP<9>      B @BASEBOARD_FAB2_LIB.BASEBOARD_FAB2(SCH_1):P3E_CPU0_PE2_SS_C_TXP(9)

CAP_0402-0.22UF,16V,10%,X7R,A3A  I45  C7G15
   1 P3E_CPU0_PE2_SS_TXP<10>      A @BASEBOARD_FAB2_LIB.BASEBOARD_FAB2(SCH_1):P3E_CPU0_PE2_SS_TXP(10)
   2 P3E_CPU0_PE2_SS_C_TXP<10>      B @BASEBOARD_FAB2_LIB.BASEBOARD_FAB2(SCH_1):P3E_CPU0_PE2_SS_C_TXP(10)

CAP_0402-0.22UF,16V,10%,X7R,A3A  I51  C7G21
   1 P3E_CPU0_PE2_SS_TXP<7>      A @BASEBOARD_FAB2_LIB.BASEBOARD_FAB2(SCH_1):P3E_CPU0_PE2_SS_TXP(7)
   2 P3E_CPU0_PE2_SS_C_TXP<7>      B @BASEBOARD_FAB2_LIB.BASEBOARD_FAB2(SCH_1):P3E_CPU0_PE2_SS_C_TXP(7)

CAP_0402-0.22UF,16V,10%,X7R,A3A  I52  C7G23
   1 P3E_CPU0_PE2_SS_TXP<6>      A @BASEBOARD_FAB2_LIB.BASEBOARD_FAB2(SCH_1):P3E_CPU0_PE2_SS_TXP(6)
   2 P3E_CPU0_PE2_SS_C_TXP<6>      B @BASEBOARD_FAB2_LIB.BASEBOARD_FAB2(SCH_1):P3E_CPU0_PE2_SS_C_TXP(6)

CAP_0402-0.22UF,16V,10%,X7R,A3A  I55  C7G26
   1 P3E_CPU0_PE2_SS_TXN<5>      A @BASEBOARD_FAB2_LIB.BASEBOARD_FAB2(SCH_1):P3E_CPU0_PE2_SS_TXN(5)
   2 P3E_CPU0_PE2_SS_C_TXN<5>      B @BASEBOARD_FAB2_LIB.BASEBOARD_FAB2(SCH_1):P3E_CPU0_PE2_SS_C_TXN(5)

CAP_0402-0.22UF,16V,10%,X7R,A3A  I56  C8G4
   1 P3E_CPU0_PE2_SS_TXN<3>      A @BASEBOARD_FAB2_LIB.BASEBOARD_FAB2(SCH_1):P3E_CPU0_PE2_SS_TXN(3)
   2 P3E_CPU0_PE2_SS_C_TXN<3>      B @BASEBOARD_FAB2_LIB.BASEBOARD_FAB2(SCH_1):P3E_CPU0_PE2_SS_C_TXN(3)

CAP_0402-0.22UF,16V,10%,X7R,A3A  I58  C8G2
   1 P3E_CPU0_PE2_SS_TXN<4>      A @BASEBOARD_FAB2_LIB.BASEBOARD_FAB2(SCH_1):P3E_CPU0_PE2_SS_TXN(4)
   2 P3E_CPU0_PE2_SS_C_TXN<4>      B @BASEBOARD_FAB2_LIB.BASEBOARD_FAB2(SCH_1):P3E_CPU0_PE2_SS_C_TXN(4)

CAP_0402-0.22UF,16V,10%,X7R,A3A  I61  C8G6
   1 P3E_CPU0_PE2_SS_TXN<2>      A @BASEBOARD_FAB2_LIB.BASEBOARD_FAB2(SCH_1):P3E_CPU0_PE2_SS_TXN(2)
   2 P3E_CPU0_PE2_SS_C_TXN<2>      B @BASEBOARD_FAB2_LIB.BASEBOARD_FAB2(SCH_1):P3E_CPU0_PE2_SS_C_TXN(2)

CAP_0402-0.22UF,16V,10%,X7R,A3A  I62  C8G7
   1 P3E_CPU0_PE2_SS_TXN<1>      A @BASEBOARD_FAB2_LIB.BASEBOARD_FAB2(SCH_1):P3E_CPU0_PE2_SS_TXN(1)
   2 P3E_CPU0_PE2_SS_C_TXN<1>      B @BASEBOARD_FAB2_LIB.BASEBOARD_FAB2(SCH_1):P3E_CPU0_PE2_SS_C_TXN(1)

CAP_0402-0.22UF,16V,10%,X7R,A3A  I69  C7G25
   1 P3E_CPU0_PE2_SS_TXP<5>      A @BASEBOARD_FAB2_LIB.BASEBOARD_FAB2(SCH_1):P3E_CPU0_PE2_SS_TXP(5)
   2 P3E_CPU0_PE2_SS_C_TXP<5>      B @BASEBOARD_FAB2_LIB.BASEBOARD_FAB2(SCH_1):P3E_CPU0_PE2_SS_C_TXP(5)

CAP_0402-0.22UF,16V,10%,X7R,A3A  I70  C8G1
   1 P3E_CPU0_PE2_SS_TXP<4>      A @BASEBOARD_FAB2_LIB.BASEBOARD_FAB2(SCH_1):P3E_CPU0_PE2_SS_TXP(4)
   2 P3E_CPU0_PE2_SS_C_TXP<4>      B @BASEBOARD_FAB2_LIB.BASEBOARD_FAB2(SCH_1):P3E_CPU0_PE2_SS_C_TXP(4)

CAP_0402-0.22UF,16V,10%,X7R,A3A  I71  C8G3
   1 P3E_CPU0_PE2_SS_TXP<3>      A @BASEBOARD_FAB2_LIB.BASEBOARD_FAB2(SCH_1):P3E_CPU0_PE2_SS_TXP(3)
   2 P3E_CPU0_PE2_SS_C_TXP<3>      B @BASEBOARD_FAB2_LIB.BASEBOARD_FAB2(SCH_1):P3E_CPU0_PE2_SS_C_TXP(3)

CAP_0402-0.22UF,16V,10%,X7R,A3A  I75  C8G5
   1 P3E_CPU0_PE2_SS_TXP<2>      A @BASEBOARD_FAB2_LIB.BASEBOARD_FAB2(SCH_1):P3E_CPU0_PE2_SS_TXP(2)
   2 P3E_CPU0_PE2_SS_C_TXP<2>      B @BASEBOARD_FAB2_LIB.BASEBOARD_FAB2(SCH_1):P3E_CPU0_PE2_SS_C_TXP(2)

CAP_0402-0.22UF,16V,10%,X7R,A3A  I76  C8G8
   1 P3E_CPU0_PE2_SS_TXP<1>      A @BASEBOARD_FAB2_LIB.BASEBOARD_FAB2(SCH_1):P3E_CPU0_PE2_SS_TXP(1)
   2 P3E_CPU0_PE2_SS_C_TXP<1>      B @BASEBOARD_FAB2_LIB.BASEBOARD_FAB2(SCH_1):P3E_CPU0_PE2_SS_C_TXP(1)

CAP_0402-0.22UF,16V,10%,X7R,A3A  I93  C8G9
   1 P3E_CPU0_PE2_SS_TXP<0>      A @BASEBOARD_FAB2_LIB.BASEBOARD_FAB2(SCH_1):P3E_CPU0_PE2_SS_TXP(0)
   2 P3E_CPU0_PE2_SS_C_TXP<0>      B @BASEBOARD_FAB2_LIB.BASEBOARD_FAB2(SCH_1):P3E_CPU0_PE2_SS_C_TXP(0)

CAP_0402-0.22UF,16V,10%,X7R,A3A  I96  C8G10
   1 P3E_CPU0_PE2_SS_TXN<0>      A @BASEBOARD_FAB2_LIB.BASEBOARD_FAB2(SCH_1):P3E_CPU0_PE2_SS_TXN(0)
   2 P3E_CPU0_PE2_SS_C_TXN<0>      B @BASEBOARD_FAB2_LIB.BASEBOARD_FAB2(SCH_1):P3E_CPU0_PE2_SS_C_TXN(0)

CAP_0402-0.22UF,16V,10%,X7R,A3A  I153  C6B18
   1 P3E_CPU0_PE1_PCH_TXP<9>      A @BASEBOARD_FAB2_LIB.BASEBOARD_FAB2(SCH_1):P3E_CPU0_PE1_PCH_TXP(9)
   2 P3E_CPU0_PE1_PCH_C_TXP<9>      B @BASEBOARD_FAB2_LIB.BASEBOARD_FAB2(SCH_1):P3E_CPU0_PE1_PCH_C_TXP(9)

CAP_0402-0.22UF,16V,10%,X7R,A3A  I160  C6B19
   1 P3E_CPU0_PE1_PCH_TXN<8>      A @BASEBOARD_FAB2_LIB.BASEBOARD_FAB2(SCH_1):P3E_CPU0_PE1_PCH_TXN(8)
   2 P3E_CPU0_PE1_PCH_C_TXN<8>      B @BASEBOARD_FAB2_LIB.BASEBOARD_FAB2(SCH_1):P3E_CPU0_PE1_PCH_C_TXN(8)

CAP_0402-0.22UF,16V,10%,X7R,A3A  I163  C6B15
   1 P3E_CPU0_PE1_PCH_TXN<10>      A @BASEBOARD_FAB2_LIB.BASEBOARD_FAB2(SCH_1):P3E_CPU0_PE1_PCH_TXN(10)
   2 P3E_CPU0_PE1_PCH_C_TXN<10>      B @BASEBOARD_FAB2_LIB.BASEBOARD_FAB2(SCH_1):P3E_CPU0_PE1_PCH_C_TXN(10)

CAP_0402-0.22UF,16V,10%,X7R,A3A  I166  C6B11
   1 P3E_CPU0_PE1_PCH_TXN<12>      A @BASEBOARD_FAB2_LIB.BASEBOARD_FAB2(SCH_1):P3E_CPU0_PE1_PCH_TXN(12)
   2 P3E_CPU0_PE1_PCH_C_TXN<12>      B @BASEBOARD_FAB2_LIB.BASEBOARD_FAB2(SCH_1):P3E_CPU0_PE1_PCH_C_TXN(12)

CAP_0402-0.22UF,16V,10%,X7R,A3A  I169  C6B6
   1 P3E_CPU0_PE1_PCH_TXN<14>      A @BASEBOARD_FAB2_LIB.BASEBOARD_FAB2(SCH_1):P3E_CPU0_PE1_PCH_TXN(14)
   2 P3E_CPU0_PE1_PCH_C_TXN<14>      B @BASEBOARD_FAB2_LIB.BASEBOARD_FAB2(SCH_1):P3E_CPU0_PE1_PCH_C_TXN(14)

CAP_0402-0.22UF,16V,10%,X7R,A3A  I173  C6B20
   1 P3E_CPU0_PE1_PCH_TXP<8>      A @BASEBOARD_FAB2_LIB.BASEBOARD_FAB2(SCH_1):P3E_CPU0_PE1_PCH_TXP(8)
   2 P3E_CPU0_PE1_PCH_C_TXP<8>      B @BASEBOARD_FAB2_LIB.BASEBOARD_FAB2(SCH_1):P3E_CPU0_PE1_PCH_C_TXP(8)

CAP_0402-0.22UF,16V,10%,X7R,A3A  I175  C6B17
   1 P3E_CPU0_PE1_PCH_TXN<9>      A @BASEBOARD_FAB2_LIB.BASEBOARD_FAB2(SCH_1):P3E_CPU0_PE1_PCH_TXN(9)
   2 P3E_CPU0_PE1_PCH_C_TXN<9>      B @BASEBOARD_FAB2_LIB.BASEBOARD_FAB2(SCH_1):P3E_CPU0_PE1_PCH_C_TXN(9)

CAP_0402-0.22UF,16V,10%,X7R,A3A  I180  C6B16
   1 P3E_CPU0_PE1_PCH_TXP<10>      A @BASEBOARD_FAB2_LIB.BASEBOARD_FAB2(SCH_1):P3E_CPU0_PE1_PCH_TXP(10)
   2 P3E_CPU0_PE1_PCH_C_TXP<10>      B @BASEBOARD_FAB2_LIB.BASEBOARD_FAB2(SCH_1):P3E_CPU0_PE1_PCH_C_TXP(10)

CAP_0402-0.22UF,16V,10%,X7R,A3A  I181  C6B14
   1 P3E_CPU0_PE1_PCH_TXN<11>      A @BASEBOARD_FAB2_LIB.BASEBOARD_FAB2(SCH_1):P3E_CPU0_PE1_PCH_TXN(11)
   2 P3E_CPU0_PE1_PCH_C_TXN<11>      B @BASEBOARD_FAB2_LIB.BASEBOARD_FAB2(SCH_1):P3E_CPU0_PE1_PCH_C_TXN(11)

CAP_0402-0.22UF,16V,10%,X7R,A3A  I185  C6B9
   1 P3E_CPU0_PE1_PCH_TXN<13>      A @BASEBOARD_FAB2_LIB.BASEBOARD_FAB2(SCH_1):P3E_CPU0_PE1_PCH_TXN(13)
   2 P3E_CPU0_PE1_PCH_C_TXN<13>      B @BASEBOARD_FAB2_LIB.BASEBOARD_FAB2(SCH_1):P3E_CPU0_PE1_PCH_C_TXN(13)

CAP_0402-0.22UF,16V,10%,X7R,A3A  I187  C6B12
   1 P3E_CPU0_PE1_PCH_TXP<12>      A @BASEBOARD_FAB2_LIB.BASEBOARD_FAB2(SCH_1):P3E_CPU0_PE1_PCH_TXP(12)
   2 P3E_CPU0_PE1_PCH_C_TXP<12>      B @BASEBOARD_FAB2_LIB.BASEBOARD_FAB2(SCH_1):P3E_CPU0_PE1_PCH_C_TXP(12)

CAP_0402-0.22UF,16V,10%,X7R,A3A  I189  C6B13
   1 P3E_CPU0_PE1_PCH_TXP<11>      A @BASEBOARD_FAB2_LIB.BASEBOARD_FAB2(SCH_1):P3E_CPU0_PE1_PCH_TXP(11)
   2 P3E_CPU0_PE1_PCH_C_TXP<11>      B @BASEBOARD_FAB2_LIB.BASEBOARD_FAB2(SCH_1):P3E_CPU0_PE1_PCH_C_TXP(11)

CAP_0402-0.22UF,16V,10%,X7R,A3A  I193  C6B10
   1 P3E_CPU0_PE1_PCH_TXP<13>      A @BASEBOARD_FAB2_LIB.BASEBOARD_FAB2(SCH_1):P3E_CPU0_PE1_PCH_TXP(13)
   2 P3E_CPU0_PE1_PCH_C_TXP<13>      B @BASEBOARD_FAB2_LIB.BASEBOARD_FAB2(SCH_1):P3E_CPU0_PE1_PCH_C_TXP(13)

CAP_0402-0.22UF,16V,10%,X7R,A3A  I196  C6B4
   1 P3E_CPU0_PE1_PCH_TXN<15>      A @BASEBOARD_FAB2_LIB.BASEBOARD_FAB2(SCH_1):P3E_CPU0_PE1_PCH_TXN(15)
   2 P3E_CPU0_PE1_PCH_C_TXN<15>      B @BASEBOARD_FAB2_LIB.BASEBOARD_FAB2(SCH_1):P3E_CPU0_PE1_PCH_C_TXN(15)

CAP_0402-0.22UF,16V,10%,X7R,A3A  I198  C6B8
   1 P3E_CPU0_PE1_PCH_TXP<14>      A @BASEBOARD_FAB2_LIB.BASEBOARD_FAB2(SCH_1):P3E_CPU0_PE1_PCH_TXP(14)
   2 P3E_CPU0_PE1_PCH_C_TXP<14>      B @BASEBOARD_FAB2_LIB.BASEBOARD_FAB2(SCH_1):P3E_CPU0_PE1_PCH_C_TXP(14)

CAP_0402-0.22UF,16V,10%,X7R,A3A  I201  C6B5
   1 P3E_CPU0_PE1_PCH_TXP<15>      A @BASEBOARD_FAB2_LIB.BASEBOARD_FAB2(SCH_1):P3E_CPU0_PE1_PCH_TXP(15)
   2 P3E_CPU0_PE1_PCH_C_TXP<15>      B @BASEBOARD_FAB2_LIB.BASEBOARD_FAB2(SCH_1):P3E_CPU0_PE1_PCH_C_TXP(15)

CAP_0402-0.22UF,16V,10%,X7R,A3A  I205  C3M25
   1 P3E_CPU0_PE1_PCH_R_RXP<11>      A @BASEBOARD_FAB2_LIB.BASEBOARD_FAB2(SCH_1):P3E_CPU0_PE1_PCH_R_RXP(11)
   2 P3E_CPU0_PE1_PCH_RXP<11>      B @BASEBOARD_FAB2_LIB.BASEBOARD_FAB2(SCH_1):P3E_CPU0_PE1_PCH_RXP(11)

CAP_0402-0.22UF,16V,10%,X7R,A3A  I206  C3M34
   1 P3E_CPU0_PE1_PCH_R_RXP<8>      A @BASEBOARD_FAB2_LIB.BASEBOARD_FAB2(SCH_1):P3E_CPU0_PE1_PCH_R_RXP(8)
   2 P3E_CPU0_PE1_PCH_RXP<8>      B @BASEBOARD_FAB2_LIB.BASEBOARD_FAB2(SCH_1):P3E_CPU0_PE1_PCH_RXP(8)

CAP_0402-0.22UF,16V,10%,X7R,A3A  I212  C3M28
   1 P3E_CPU0_PE1_PCH_R_RXP<10>      A @BASEBOARD_FAB2_LIB.BASEBOARD_FAB2(SCH_1):P3E_CPU0_PE1_PCH_R_RXP(10)
   2 P3E_CPU0_PE1_PCH_RXP<10>      B @BASEBOARD_FAB2_LIB.BASEBOARD_FAB2(SCH_1):P3E_CPU0_PE1_PCH_RXP(10)

CAP_0402-0.22UF,16V,10%,X7R,A3A  I217  C3M33
   1 P3E_CPU0_PE1_PCH_R_RXN<8>      A @BASEBOARD_FAB2_LIB.BASEBOARD_FAB2(SCH_1):P3E_CPU0_PE1_PCH_R_RXN(8)
   2 P3E_CPU0_PE1_PCH_RXN<8>      B @BASEBOARD_FAB2_LIB.BASEBOARD_FAB2(SCH_1):P3E_CPU0_PE1_PCH_RXN(8)

CAP_0402-0.22UF,16V,10%,X7R,A3A  I218  C3M36
   1 P3E_CPU0_PE1_PCH_R_RXP<9>      A @BASEBOARD_FAB2_LIB.BASEBOARD_FAB2(SCH_1):P3E_CPU0_PE1_PCH_R_RXP(9)
   2 P3E_CPU0_PE1_PCH_RXP<9>      B @BASEBOARD_FAB2_LIB.BASEBOARD_FAB2(SCH_1):P3E_CPU0_PE1_PCH_RXP(9)

CAP_0402-0.22UF,16V,10%,X7R,A3A  I223  C3M32
   1 P3E_CPU0_PE1_PCH_R_RXN<10>      A @BASEBOARD_FAB2_LIB.BASEBOARD_FAB2(SCH_1):P3E_CPU0_PE1_PCH_R_RXN(10)
   2 P3E_CPU0_PE1_PCH_RXN<10>      B @BASEBOARD_FAB2_LIB.BASEBOARD_FAB2(SCH_1):P3E_CPU0_PE1_PCH_RXN(10)

CAP_0402-0.22UF,16V,10%,X7R,A3A  I225  C3M35
   1 P3E_CPU0_PE1_PCH_R_RXN<9>      A @BASEBOARD_FAB2_LIB.BASEBOARD_FAB2(SCH_1):P3E_CPU0_PE1_PCH_R_RXN(9)
   2 P3E_CPU0_PE1_PCH_RXN<9>      B @BASEBOARD_FAB2_LIB.BASEBOARD_FAB2(SCH_1):P3E_CPU0_PE1_PCH_RXN(9)

CAP_0402-0.22UF,16V,10%,X7R,A3A  I229  C3M26
   1 P3E_CPU0_PE1_PCH_R_RXN<11>      A @BASEBOARD_FAB2_LIB.BASEBOARD_FAB2(SCH_1):P3E_CPU0_PE1_PCH_R_RXN(11)
   2 P3E_CPU0_PE1_PCH_RXN<11>      B @BASEBOARD_FAB2_LIB.BASEBOARD_FAB2(SCH_1):P3E_CPU0_PE1_PCH_RXN(11)

CAP_0402-0.22UF,16V,10%,X7R,A3A  I232  C3M3
   1 P3E_CPU0_PE1_PCH_R_RXP<12>      A @BASEBOARD_FAB2_LIB.BASEBOARD_FAB2(SCH_1):P3E_CPU0_PE1_PCH_R_RXP(12)
   2 P3E_CPU0_PE1_PCH_RXP<12>      B @BASEBOARD_FAB2_LIB.BASEBOARD_FAB2(SCH_1):P3E_CPU0_PE1_PCH_RXP(12)

CAP_0402-0.22UF,16V,10%,X7R,A3A  I234  C3M11
   1 P3E_CPU0_PE1_PCH_R_RXP<14>      A @BASEBOARD_FAB2_LIB.BASEBOARD_FAB2(SCH_1):P3E_CPU0_PE1_PCH_R_RXP(14)
   2 P3E_CPU0_PE1_PCH_RXP<14>      B @BASEBOARD_FAB2_LIB.BASEBOARD_FAB2(SCH_1):P3E_CPU0_PE1_PCH_RXP(14)

CAP_0402-0.22UF,16V,10%,X7R,A3A  I239  C3M13
   1 P3E_CPU0_PE1_PCH_R_RXP<13>      A @BASEBOARD_FAB2_LIB.BASEBOARD_FAB2(SCH_1):P3E_CPU0_PE1_PCH_R_RXP(13)
   2 P3E_CPU0_PE1_PCH_RXP<13>      B @BASEBOARD_FAB2_LIB.BASEBOARD_FAB2(SCH_1):P3E_CPU0_PE1_PCH_RXP(13)

CAP_0402-0.22UF,16V,10%,X7R,A3A  I244  C3M4
   1 P3E_CPU0_PE1_PCH_R_RXN<12>      A @BASEBOARD_FAB2_LIB.BASEBOARD_FAB2(SCH_1):P3E_CPU0_PE1_PCH_R_RXN(12)
   2 P3E_CPU0_PE1_PCH_RXN<12>      B @BASEBOARD_FAB2_LIB.BASEBOARD_FAB2(SCH_1):P3E_CPU0_PE1_PCH_RXN(12)

CAP_0402-0.22UF,16V,10%,X7R,A3A  I246  C3M12
   1 P3E_CPU0_PE1_PCH_R_RXN<14>      A @BASEBOARD_FAB2_LIB.BASEBOARD_FAB2(SCH_1):P3E_CPU0_PE1_PCH_R_RXN(14)
   2 P3E_CPU0_PE1_PCH_RXN<14>      B @BASEBOARD_FAB2_LIB.BASEBOARD_FAB2(SCH_1):P3E_CPU0_PE1_PCH_RXN(14)

CAP_0402-0.22UF,16V,10%,X7R,A3A  I247  C3M2
   1 P3E_CPU0_PE1_PCH_R_RXP<15>      A @BASEBOARD_FAB2_LIB.BASEBOARD_FAB2(SCH_1):P3E_CPU0_PE1_PCH_R_RXP(15)
   2 P3E_CPU0_PE1_PCH_RXP<15>      B @BASEBOARD_FAB2_LIB.BASEBOARD_FAB2(SCH_1):P3E_CPU0_PE1_PCH_RXP(15)

CAP_0402-0.22UF,16V,10%,X7R,A3A  I253  C3M14
   1 P3E_CPU0_PE1_PCH_R_RXN<13>      A @BASEBOARD_FAB2_LIB.BASEBOARD_FAB2(SCH_1):P3E_CPU0_PE1_PCH_R_RXN(13)
   2 P3E_CPU0_PE1_PCH_RXN<13>      B @BASEBOARD_FAB2_LIB.BASEBOARD_FAB2(SCH_1):P3E_CPU0_PE1_PCH_RXN(13)

CAP_0402-0.22UF,16V,10%,X7R,A3A  I255  C3M1
   1 P3E_CPU0_PE1_PCH_R_RXN<15>      A @BASEBOARD_FAB2_LIB.BASEBOARD_FAB2(SCH_1):P3E_CPU0_PE1_PCH_R_RXN(15)
   2 P3E_CPU0_PE1_PCH_RXN<15>      B @BASEBOARD_FAB2_LIB.BASEBOARD_FAB2(SCH_1):P3E_CPU0_PE1_PCH_RXN(15)

CAP_0402-0.22UF,16V,10%,X7R,A3A  I257  C7G19
   1 P3E_CPU0_PE2_SS_TXN<8>      A @BASEBOARD_FAB2_LIB.BASEBOARD_FAB2(SCH_1):P3E_CPU0_PE2_SS_TXN(8)
   2 P3E_CPU0_PE2_SS_C_TXN<8>      B @BASEBOARD_FAB2_LIB.BASEBOARD_FAB2(SCH_1):P3E_CPU0_PE2_SS_C_TXN(8)

CAP_0402-0.22UF,16V,10%,X7R,A3A  I258  C7G20
   1 P3E_CPU0_PE2_SS_TXP<8>      A @BASEBOARD_FAB2_LIB.BASEBOARD_FAB2(SCH_1):P3E_CPU0_PE2_SS_TXP(8)
   2 P3E_CPU0_PE2_SS_C_TXP<8>      B @BASEBOARD_FAB2_LIB.BASEBOARD_FAB2(SCH_1):P3E_CPU0_PE2_SS_C_TXP(8)


DRAWING: @BASEBOARD_FAB2_LIB.BASEBOARD_FAB2(SCH_1):PAGE106 

CAP_0402-0.22UF,16V,10%,X7R,A3A  I10  C1R2
   1 P3E_CPU0_PE3_OCP_TXP<0>      A @BASEBOARD_FAB2_LIB.BASEBOARD_FAB2(SCH_1):P3E_CPU0_PE3_OCP_TXP(0)
   2 P3E_OCP_CPU0_PE3_C_TXP<0>      B @BASEBOARD_FAB2_LIB.BASEBOARD_FAB2(SCH_1):P3E_OCP_CPU0_PE3_C_TXP(0)

CAP_0402-0.22UF,16V,10%,X7R,A3A  I26  C1R4
   1 P3E_CPU0_PE3_OCP_TXP<1>      A @BASEBOARD_FAB2_LIB.BASEBOARD_FAB2(SCH_1):P3E_CPU0_PE3_OCP_TXP(1)
   2 P3E_OCP_CPU0_PE3_C_TXP<1>      B @BASEBOARD_FAB2_LIB.BASEBOARD_FAB2(SCH_1):P3E_OCP_CPU0_PE3_C_TXP(1)

CAP_0402-0.22UF,16V,10%,X7R,A3A  I29  C1R1
   1 P3E_CPU0_PE3_OCP_TXN<0>      A @BASEBOARD_FAB2_LIB.BASEBOARD_FAB2(SCH_1):P3E_CPU0_PE3_OCP_TXN(0)
   2 P3E_OCP_CPU0_PE3_C_TXN<0>      B @BASEBOARD_FAB2_LIB.BASEBOARD_FAB2(SCH_1):P3E_OCP_CPU0_PE3_C_TXN(0)

CAP_0402-0.22UF,16V,10%,X7R,A3A  I37  C1R3
   1 P3E_CPU0_PE3_OCP_TXN<1>      A @BASEBOARD_FAB2_LIB.BASEBOARD_FAB2(SCH_1):P3E_CPU0_PE3_OCP_TXN(1)
   2 P3E_OCP_CPU0_PE3_C_TXN<1>      B @BASEBOARD_FAB2_LIB.BASEBOARD_FAB2(SCH_1):P3E_OCP_CPU0_PE3_C_TXN(1)

CAP_0402-0.22UF,16V,10%,X7R,A3A  I40  C1R6
   1 P3E_CPU0_PE3_OCP_TXP<2>      A @BASEBOARD_FAB2_LIB.BASEBOARD_FAB2(SCH_1):P3E_CPU0_PE3_OCP_TXP(2)
   2 P3E_OCP_CPU0_PE3_C_TXP<2>      B @BASEBOARD_FAB2_LIB.BASEBOARD_FAB2(SCH_1):P3E_OCP_CPU0_PE3_C_TXP(2)

CAP_0402-0.22UF,16V,10%,X7R,A3A  I55  C1R8
   1 P3E_CPU0_PE3_OCP_TXP<3>      A @BASEBOARD_FAB2_LIB.BASEBOARD_FAB2(SCH_1):P3E_CPU0_PE3_OCP_TXP(3)
   2 P3E_OCP_CPU0_PE3_C_TXP<3>      B @BASEBOARD_FAB2_LIB.BASEBOARD_FAB2(SCH_1):P3E_OCP_CPU0_PE3_C_TXP(3)

CAP_0402-0.22UF,16V,10%,X7R,A3A  I59  C1R5
   1 P3E_CPU0_PE3_OCP_TXN<2>      A @BASEBOARD_FAB2_LIB.BASEBOARD_FAB2(SCH_1):P3E_CPU0_PE3_OCP_TXN(2)
   2 P3E_OCP_CPU0_PE3_C_TXN<2>      B @BASEBOARD_FAB2_LIB.BASEBOARD_FAB2(SCH_1):P3E_OCP_CPU0_PE3_C_TXN(2)

CAP_0402-0.22UF,16V,10%,X7R,A3A  I70  C1R7
   1 P3E_CPU0_PE3_OCP_TXN<3>      A @BASEBOARD_FAB2_LIB.BASEBOARD_FAB2(SCH_1):P3E_CPU0_PE3_OCP_TXN(3)
   2 P3E_OCP_CPU0_PE3_C_TXN<3>      B @BASEBOARD_FAB2_LIB.BASEBOARD_FAB2(SCH_1):P3E_OCP_CPU0_PE3_C_TXN(3)

CAP_0402-0.22UF,16V,10%,X7R,A3A  I76  C2M14
   1 P3E_CPU0_PE3_OCP_TXP<8>      A @BASEBOARD_FAB2_LIB.BASEBOARD_FAB2(SCH_1):P3E_CPU0_PE3_OCP_TXP(8)
   2 P3E_OCP_CPU0_PE3_C_TXP<8>      B @BASEBOARD_FAB2_LIB.BASEBOARD_FAB2(SCH_1):P3E_OCP_CPU0_PE3_C_TXP(8)

CAP_0402-0.22UF,16V,10%,X7R,A3A  I78  C1M18
   1 P3E_CPU0_PE3_OCP_TXP<9>      A @BASEBOARD_FAB2_LIB.BASEBOARD_FAB2(SCH_1):P3E_CPU0_PE3_OCP_TXP(9)
   2 P3E_OCP_CPU0_PE3_C_TXP<9>      B @BASEBOARD_FAB2_LIB.BASEBOARD_FAB2(SCH_1):P3E_OCP_CPU0_PE3_C_TXP(9)

CAP_0402-0.22UF,16V,10%,X7R,A3A  I82  C1M16
   1 P3E_CPU0_PE3_OCP_TXP<10>      A @BASEBOARD_FAB2_LIB.BASEBOARD_FAB2(SCH_1):P3E_CPU0_PE3_OCP_TXP(10)
   2 P3E_OCP_CPU0_PE3_C_TXP<10>      B @BASEBOARD_FAB2_LIB.BASEBOARD_FAB2(SCH_1):P3E_OCP_CPU0_PE3_C_TXP(10)

CAP_0402-0.22UF,16V,10%,X7R,A3A  I85  C1M14
   1 P3E_CPU0_PE3_OCP_TXP<11>      A @BASEBOARD_FAB2_LIB.BASEBOARD_FAB2(SCH_1):P3E_CPU0_PE3_OCP_TXP(11)
   2 P3E_OCP_CPU0_PE3_C_TXP<11>      B @BASEBOARD_FAB2_LIB.BASEBOARD_FAB2(SCH_1):P3E_OCP_CPU0_PE3_C_TXP(11)

CAP_0402-0.22UF,16V,10%,X7R,A3A  I86  C2M15
   1 P3E_CPU0_PE3_OCP_TXN<8>      A @BASEBOARD_FAB2_LIB.BASEBOARD_FAB2(SCH_1):P3E_CPU0_PE3_OCP_TXN(8)
   2 P3E_OCP_CPU0_PE3_C_TXN<8>      B @BASEBOARD_FAB2_LIB.BASEBOARD_FAB2(SCH_1):P3E_OCP_CPU0_PE3_C_TXN(8)

CAP_0402-0.22UF,16V,10%,X7R,A3A  I90  C1M19
   1 P3E_CPU0_PE3_OCP_TXN<9>      A @BASEBOARD_FAB2_LIB.BASEBOARD_FAB2(SCH_1):P3E_CPU0_PE3_OCP_TXN(9)
   2 P3E_OCP_CPU0_PE3_C_TXN<9>      B @BASEBOARD_FAB2_LIB.BASEBOARD_FAB2(SCH_1):P3E_OCP_CPU0_PE3_C_TXN(9)

CAP_0402-0.22UF,16V,10%,X7R,A3A  I92  C1M17
   1 P3E_CPU0_PE3_OCP_TXN<10>      A @BASEBOARD_FAB2_LIB.BASEBOARD_FAB2(SCH_1):P3E_CPU0_PE3_OCP_TXN(10)
   2 P3E_OCP_CPU0_PE3_C_TXN<10>      B @BASEBOARD_FAB2_LIB.BASEBOARD_FAB2(SCH_1):P3E_OCP_CPU0_PE3_C_TXN(10)

CAP_0402-0.22UF,16V,10%,X7R,A3A  I95  C1M15
   1 P3E_CPU0_PE3_OCP_TXN<11>      A @BASEBOARD_FAB2_LIB.BASEBOARD_FAB2(SCH_1):P3E_CPU0_PE3_OCP_TXN(11)
   2 P3E_OCP_CPU0_PE3_C_TXN<11>      B @BASEBOARD_FAB2_LIB.BASEBOARD_FAB2(SCH_1):P3E_OCP_CPU0_PE3_C_TXN(11)

CAP_0402-0.22UF,16V,10%,X7R,A3A  I100  C1M12
   1 P3E_CPU0_PE3_OCP_TXP<12>      A @BASEBOARD_FAB2_LIB.BASEBOARD_FAB2(SCH_1):P3E_CPU0_PE3_OCP_TXP(12)
   2 P3E_OCP_CPU0_PE3_C_TXP<12>      B @BASEBOARD_FAB2_LIB.BASEBOARD_FAB2(SCH_1):P3E_OCP_CPU0_PE3_C_TXP(12)

CAP_0402-0.22UF,16V,10%,X7R,A3A  I102  C1M10
   1 P3E_CPU0_PE3_OCP_TXP<13>      A @BASEBOARD_FAB2_LIB.BASEBOARD_FAB2(SCH_1):P3E_CPU0_PE3_OCP_TXP(13)
   2 P3E_OCP_CPU0_PE3_C_TXP<13>      B @BASEBOARD_FAB2_LIB.BASEBOARD_FAB2(SCH_1):P3E_OCP_CPU0_PE3_C_TXP(13)

CAP_0402-0.22UF,16V,10%,X7R,A3A  I105  C1M8
   1 P3E_CPU0_PE3_OCP_TXP<14>      A @BASEBOARD_FAB2_LIB.BASEBOARD_FAB2(SCH_1):P3E_CPU0_PE3_OCP_TXP(14)
   2 P3E_OCP_CPU0_PE3_C_TXP<14>      B @BASEBOARD_FAB2_LIB.BASEBOARD_FAB2(SCH_1):P3E_OCP_CPU0_PE3_C_TXP(14)

CAP_0402-0.22UF,16V,10%,X7R,A3A  I109  C1M6
   1 P3E_CPU0_PE3_OCP_TXP<15>      A @BASEBOARD_FAB2_LIB.BASEBOARD_FAB2(SCH_1):P3E_CPU0_PE3_OCP_TXP(15)
   2 P3E_OCP_CPU0_PE3_C_TXP<15>      B @BASEBOARD_FAB2_LIB.BASEBOARD_FAB2(SCH_1):P3E_OCP_CPU0_PE3_C_TXP(15)

CAP_0402-0.22UF,16V,10%,X7R,A3A  I111  C1M13
   1 P3E_CPU0_PE3_OCP_TXN<12>      A @BASEBOARD_FAB2_LIB.BASEBOARD_FAB2(SCH_1):P3E_CPU0_PE3_OCP_TXN(12)
   2 P3E_OCP_CPU0_PE3_C_TXN<12>      B @BASEBOARD_FAB2_LIB.BASEBOARD_FAB2(SCH_1):P3E_OCP_CPU0_PE3_C_TXN(12)

CAP_0402-0.22UF,16V,10%,X7R,A3A  I114  C1M9
   1 P3E_CPU0_PE3_OCP_TXN<14>      A @BASEBOARD_FAB2_LIB.BASEBOARD_FAB2(SCH_1):P3E_CPU0_PE3_OCP_TXN(14)
   2 P3E_OCP_CPU0_PE3_C_TXN<14>      B @BASEBOARD_FAB2_LIB.BASEBOARD_FAB2(SCH_1):P3E_OCP_CPU0_PE3_C_TXN(14)

CAP_0402-0.22UF,16V,10%,X7R,A3A  I117  C1M11
   1 P3E_CPU0_PE3_OCP_TXN<13>      A @BASEBOARD_FAB2_LIB.BASEBOARD_FAB2(SCH_1):P3E_CPU0_PE3_OCP_TXN(13)
   2 P3E_OCP_CPU0_PE3_C_TXN<13>      B @BASEBOARD_FAB2_LIB.BASEBOARD_FAB2(SCH_1):P3E_OCP_CPU0_PE3_C_TXN(13)

CAP_0402-0.22UF,16V,10%,X7R,A3A  I122  C1M7
   1 P3E_CPU0_PE3_OCP_TXN<15>      A @BASEBOARD_FAB2_LIB.BASEBOARD_FAB2(SCH_1):P3E_CPU0_PE3_OCP_TXN(15)
   2 P3E_OCP_CPU0_PE3_C_TXN<15>      B @BASEBOARD_FAB2_LIB.BASEBOARD_FAB2(SCH_1):P3E_OCP_CPU0_PE3_C_TXN(15)

CAP_0402-0.22UF,16V,10%,X7R,A3A  I123  C2R7
   1 P3E_CPU0_PE3_OCP_TXN<6>      A @BASEBOARD_FAB2_LIB.BASEBOARD_FAB2(SCH_1):P3E_CPU0_PE3_OCP_TXN(6)
   2 P3E_OCP_CPU0_PE3_C_TXN<6>      B @BASEBOARD_FAB2_LIB.BASEBOARD_FAB2(SCH_1):P3E_OCP_CPU0_PE3_C_TXN(6)

CAP_0402-0.22UF,16V,10%,X7R,A3A  I128  C1R10
   1 P3E_CPU0_PE3_OCP_TXP<4>      A @BASEBOARD_FAB2_LIB.BASEBOARD_FAB2(SCH_1):P3E_CPU0_PE3_OCP_TXP(4)
   2 P3E_OCP_CPU0_PE3_C_TXP<4>      B @BASEBOARD_FAB2_LIB.BASEBOARD_FAB2(SCH_1):P3E_OCP_CPU0_PE3_C_TXP(4)

CAP_0402-0.22UF,16V,10%,X7R,A3A  I130  C2R14
   1 P3E_CPU0_PE3_OCP_TXP<5>      A @BASEBOARD_FAB2_LIB.BASEBOARD_FAB2(SCH_1):P3E_CPU0_PE3_OCP_TXP(5)
   2 P3E_OCP_CPU0_PE3_C_TXP<5>      B @BASEBOARD_FAB2_LIB.BASEBOARD_FAB2(SCH_1):P3E_OCP_CPU0_PE3_C_TXP(5)

CAP_0402-0.22UF,16V,10%,X7R,A3A  I134  C1R9
   1 P3E_CPU0_PE3_OCP_TXN<4>      A @BASEBOARD_FAB2_LIB.BASEBOARD_FAB2(SCH_1):P3E_CPU0_PE3_OCP_TXN(4)
   2 P3E_OCP_CPU0_PE3_C_TXN<4>      B @BASEBOARD_FAB2_LIB.BASEBOARD_FAB2(SCH_1):P3E_OCP_CPU0_PE3_C_TXN(4)

CAP_0402-0.22UF,16V,10%,X7R,A3A  I137  C2R13
   1 P3E_CPU0_PE3_OCP_TXN<5>      A @BASEBOARD_FAB2_LIB.BASEBOARD_FAB2(SCH_1):P3E_CPU0_PE3_OCP_TXN(5)
   2 P3E_OCP_CPU0_PE3_C_TXN<5>      B @BASEBOARD_FAB2_LIB.BASEBOARD_FAB2(SCH_1):P3E_OCP_CPU0_PE3_C_TXN(5)

CAP_0402-0.22UF,16V,10%,X7R,A3A  I141  C2R8
   1 P3E_CPU0_PE3_OCP_TXP<6>      A @BASEBOARD_FAB2_LIB.BASEBOARD_FAB2(SCH_1):P3E_CPU0_PE3_OCP_TXP(6)
   2 P3E_OCP_CPU0_PE3_C_TXP<6>      B @BASEBOARD_FAB2_LIB.BASEBOARD_FAB2(SCH_1):P3E_OCP_CPU0_PE3_C_TXP(6)

CAP_0402-0.22UF,16V,10%,X7R,A3A  I142  C2R10
   1 P3E_CPU0_PE3_OCP_TXP<7>      A @BASEBOARD_FAB2_LIB.BASEBOARD_FAB2(SCH_1):P3E_CPU0_PE3_OCP_TXP(7)
   2 P3E_OCP_CPU0_PE3_C_TXP<7>      B @BASEBOARD_FAB2_LIB.BASEBOARD_FAB2(SCH_1):P3E_OCP_CPU0_PE3_C_TXP(7)

CAP_0402-0.22UF,16V,10%,X7R,A3A  I147  C2R9
   1 P3E_CPU0_PE3_OCP_TXN<7>      A @BASEBOARD_FAB2_LIB.BASEBOARD_FAB2(SCH_1):P3E_CPU0_PE3_OCP_TXN(7)
   2 P3E_OCP_CPU0_PE3_C_TXN<7>      B @BASEBOARD_FAB2_LIB.BASEBOARD_FAB2(SCH_1):P3E_OCP_CPU0_PE3_C_TXN(7)


DRAWING: @BASEBOARD_FAB2_LIB.BASEBOARD_FAB2(SCH_1):PAGE107 

CAP_0402-0.22UF,16V,10%,X7R,A3A  I207  C3P13
   1 P3E_CPU0_PE1_SS_TXN<0>      A @BASEBOARD_FAB2_LIB.BASEBOARD_FAB2(SCH_1):P3E_CPU0_PE1_SS_TXN(0)
   2 P3E_CPU0_PE1_PCH_TXN<0>      B @BASEBOARD_FAB2_LIB.BASEBOARD_FAB2(SCH_1):P3E_CPU0_PE1_PCH_TXN(0)

CAP_0402-0.22UF,16V,10%,X7R,A3A  I208  C3P17
   1 P3E_CPU0_PE1_SS_TXN<1>      A @BASEBOARD_FAB2_LIB.BASEBOARD_FAB2(SCH_1):P3E_CPU0_PE1_SS_TXN(1)
   2 P3E_CPU0_PE1_PCH_TXN<1>      B @BASEBOARD_FAB2_LIB.BASEBOARD_FAB2(SCH_1):P3E_CPU0_PE1_PCH_TXN(1)

CAP_0402-0.22UF,16V,10%,X7R,A3A  I212  C3P11
   1 P3E_CPU0_PE1_SS_TXP<0>      A @BASEBOARD_FAB2_LIB.BASEBOARD_FAB2(SCH_1):P3E_CPU0_PE1_SS_TXP(0)
   2 P3E_CPU0_PE1_PCH_TXP<0>      B @BASEBOARD_FAB2_LIB.BASEBOARD_FAB2(SCH_1):P3E_CPU0_PE1_PCH_TXP(0)

CAP_0402-0.22UF,16V,10%,X7R,A3A  I215  C3P20
   1 P3E_CPU0_PE1_SS_TXN<2>      A @BASEBOARD_FAB2_LIB.BASEBOARD_FAB2(SCH_1):P3E_CPU0_PE1_SS_TXN(2)
   2 P3E_CPU0_PE1_PCH_TXN<2>      B @BASEBOARD_FAB2_LIB.BASEBOARD_FAB2(SCH_1):P3E_CPU0_PE1_PCH_TXN(2)

CAP_0402-0.22UF,16V,10%,X7R,A3A  I216  C3P25
   1 P3E_CPU0_PE1_SS_TXN<3>      A @BASEBOARD_FAB2_LIB.BASEBOARD_FAB2(SCH_1):P3E_CPU0_PE1_SS_TXN(3)
   2 P3E_CPU0_PE1_PCH_TXN<3>      B @BASEBOARD_FAB2_LIB.BASEBOARD_FAB2(SCH_1):P3E_CPU0_PE1_PCH_TXN(3)

CAP_0402-0.22UF,16V,10%,X7R,A3A  I219  C3P18
   1 P3E_CPU0_PE1_SS_TXP<2>      A @BASEBOARD_FAB2_LIB.BASEBOARD_FAB2(SCH_1):P3E_CPU0_PE1_SS_TXP(2)
   2 P3E_CPU0_PE1_PCH_TXP<2>      B @BASEBOARD_FAB2_LIB.BASEBOARD_FAB2(SCH_1):P3E_CPU0_PE1_PCH_TXP(2)

CAP_0402-0.22UF,16V,10%,X7R,A3A  I223  C3P27
   1 P3E_CPU0_PE1_SS_TXP<4>      A @BASEBOARD_FAB2_LIB.BASEBOARD_FAB2(SCH_1):P3E_CPU0_PE1_SS_TXP(4)
   2 P3E_CPU0_PE1_PCH_TXP<4>      B @BASEBOARD_FAB2_LIB.BASEBOARD_FAB2(SCH_1):P3E_CPU0_PE1_PCH_TXP(4)

CAP_0402-0.22UF,16V,10%,X7R,A3A  I226  C3P15
   1 P3E_CPU0_PE1_SS_TXP<1>      A @BASEBOARD_FAB2_LIB.BASEBOARD_FAB2(SCH_1):P3E_CPU0_PE1_SS_TXP(1)
   2 P3E_CPU0_PE1_PCH_TXP<1>      B @BASEBOARD_FAB2_LIB.BASEBOARD_FAB2(SCH_1):P3E_CPU0_PE1_PCH_TXP(1)

CAP_0402-0.22UF,16V,10%,X7R,A3A  I229  C3P23
   1 P3E_CPU0_PE1_SS_TXP<3>      A @BASEBOARD_FAB2_LIB.BASEBOARD_FAB2(SCH_1):P3E_CPU0_PE1_SS_TXP(3)
   2 P3E_CPU0_PE1_PCH_TXP<3>      B @BASEBOARD_FAB2_LIB.BASEBOARD_FAB2(SCH_1):P3E_CPU0_PE1_PCH_TXP(3)

CAP_0402-0.22UF,16V,10%,X7R,A3A  I232  C3P28
   1 P3E_CPU0_PE1_SS_TXN<4>      A @BASEBOARD_FAB2_LIB.BASEBOARD_FAB2(SCH_1):P3E_CPU0_PE1_SS_TXN(4)
   2 P3E_CPU0_PE1_PCH_TXN<4>      B @BASEBOARD_FAB2_LIB.BASEBOARD_FAB2(SCH_1):P3E_CPU0_PE1_PCH_TXN(4)

CAP_0402-0.22UF,16V,10%,X7R,A3A  I234  C3P32
   1 P3E_CPU0_PE1_SS_TXN<5>      A @BASEBOARD_FAB2_LIB.BASEBOARD_FAB2(SCH_1):P3E_CPU0_PE1_SS_TXN(5)
   2 P3E_CPU0_PE1_PCH_TXN<5>      B @BASEBOARD_FAB2_LIB.BASEBOARD_FAB2(SCH_1):P3E_CPU0_PE1_PCH_TXN(5)

CAP_0402-0.22UF,16V,10%,X7R,A3A  I235  C3P37
   1 P3E_CPU0_PE1_SS_TXN<6>      A @BASEBOARD_FAB2_LIB.BASEBOARD_FAB2(SCH_1):P3E_CPU0_PE1_SS_TXN(6)
   2 P3E_CPU0_PE1_PCH_TXN<6>      B @BASEBOARD_FAB2_LIB.BASEBOARD_FAB2(SCH_1):P3E_CPU0_PE1_PCH_TXN(6)

CAP_0402-0.22UF,16V,10%,X7R,A3A  I240  C3P35
   1 P3E_CPU0_PE1_SS_TXP<6>      A @BASEBOARD_FAB2_LIB.BASEBOARD_FAB2(SCH_1):P3E_CPU0_PE1_SS_TXP(6)
   2 P3E_CPU0_PE1_PCH_TXP<6>      B @BASEBOARD_FAB2_LIB.BASEBOARD_FAB2(SCH_1):P3E_CPU0_PE1_PCH_TXP(6)

CAP_0402-0.22UF,16V,10%,X7R,A3A  I241  C3P40
   1 P3E_CPU0_PE1_SS_TXN<7>      A @BASEBOARD_FAB2_LIB.BASEBOARD_FAB2(SCH_1):P3E_CPU0_PE1_SS_TXN(7)
   2 P3E_CPU0_PE1_PCH_TXN<7>      B @BASEBOARD_FAB2_LIB.BASEBOARD_FAB2(SCH_1):P3E_CPU0_PE1_PCH_TXN(7)

CAP_0402-0.22UF,16V,10%,X7R,A3A  I245  C3P30
   1 P3E_CPU0_PE1_SS_TXP<5>      A @BASEBOARD_FAB2_LIB.BASEBOARD_FAB2(SCH_1):P3E_CPU0_PE1_SS_TXP(5)
   2 P3E_CPU0_PE1_PCH_TXP<5>      B @BASEBOARD_FAB2_LIB.BASEBOARD_FAB2(SCH_1):P3E_CPU0_PE1_PCH_TXP(5)

CAP_0402-0.22UF,16V,10%,X7R,A3A  I248  C3P39
   1 P3E_CPU0_PE1_SS_TXP<7>      A @BASEBOARD_FAB2_LIB.BASEBOARD_FAB2(SCH_1):P3E_CPU0_PE1_SS_TXP(7)
   2 P3E_CPU0_PE1_PCH_TXP<7>      B @BASEBOARD_FAB2_LIB.BASEBOARD_FAB2(SCH_1):P3E_CPU0_PE1_PCH_TXP(7)

CAP_0402-0.22UF,16V,10%,X7R,A3A  I257  C2U4
   1 P3E_CPU0_PE1_PCH_RXN<0>      A @BASEBOARD_FAB2_LIB.BASEBOARD_FAB2(SCH_1):P3E_CPU0_PE1_PCH_RXN(0)
   2 P3E_CPU0_PE1_SS_RXN<0>      B @BASEBOARD_FAB2_LIB.BASEBOARD_FAB2(SCH_1):P3E_CPU0_PE1_SS_RXN(0)

CAP_0402-0.22UF,16V,10%,X7R,A3A  I260  C2U6
   1 P3E_CPU0_PE1_PCH_RXN<1>      A @BASEBOARD_FAB2_LIB.BASEBOARD_FAB2(SCH_1):P3E_CPU0_PE1_PCH_RXN(1)
   2 P3E_CPU0_PE1_SS_RXN<1>      B @BASEBOARD_FAB2_LIB.BASEBOARD_FAB2(SCH_1):P3E_CPU0_PE1_SS_RXN(1)

CAP_0402-0.22UF,16V,10%,X7R,A3A  I264  C2U8
   1 P3E_CPU0_PE1_PCH_RXN<2>      A @BASEBOARD_FAB2_LIB.BASEBOARD_FAB2(SCH_1):P3E_CPU0_PE1_PCH_RXN(2)
   2 P3E_CPU0_PE1_SS_RXN<2>      B @BASEBOARD_FAB2_LIB.BASEBOARD_FAB2(SCH_1):P3E_CPU0_PE1_SS_RXN(2)

CAP_0402-0.22UF,16V,10%,X7R,A3A  I265  C2U12
   1 P3E_CPU0_PE1_PCH_RXN<4>      A @BASEBOARD_FAB2_LIB.BASEBOARD_FAB2(SCH_1):P3E_CPU0_PE1_PCH_RXN(4)
   2 P3E_CPU0_PE1_SS_RXN<4>      B @BASEBOARD_FAB2_LIB.BASEBOARD_FAB2(SCH_1):P3E_CPU0_PE1_SS_RXN(4)

CAP_0402-0.22UF,16V,10%,X7R,A3A  I267  C2U10
   1 P3E_CPU0_PE1_PCH_RXN<3>      A @BASEBOARD_FAB2_LIB.BASEBOARD_FAB2(SCH_1):P3E_CPU0_PE1_PCH_RXN(3)
   2 P3E_CPU0_PE1_SS_RXN<3>      B @BASEBOARD_FAB2_LIB.BASEBOARD_FAB2(SCH_1):P3E_CPU0_PE1_SS_RXN(3)

CAP_0402-0.22UF,16V,10%,X7R,A3A  I272  C2U3
   1 P3E_CPU0_PE1_PCH_RXP<0>      A @BASEBOARD_FAB2_LIB.BASEBOARD_FAB2(SCH_1):P3E_CPU0_PE1_PCH_RXP(0)
   2 P3E_CPU0_PE1_SS_RXP<0>      B @BASEBOARD_FAB2_LIB.BASEBOARD_FAB2(SCH_1):P3E_CPU0_PE1_SS_RXP(0)

CAP_0402-0.22UF,16V,10%,X7R,A3A  I274  C2U5
   1 P3E_CPU0_PE1_PCH_RXP<1>      A @BASEBOARD_FAB2_LIB.BASEBOARD_FAB2(SCH_1):P3E_CPU0_PE1_PCH_RXP(1)
   2 P3E_CPU0_PE1_SS_RXP<1>      B @BASEBOARD_FAB2_LIB.BASEBOARD_FAB2(SCH_1):P3E_CPU0_PE1_SS_RXP(1)

CAP_0402-0.22UF,16V,10%,X7R,A3A  I277  C2U7
   1 P3E_CPU0_PE1_PCH_RXP<2>      A @BASEBOARD_FAB2_LIB.BASEBOARD_FAB2(SCH_1):P3E_CPU0_PE1_PCH_RXP(2)
   2 P3E_CPU0_PE1_SS_RXP<2>      B @BASEBOARD_FAB2_LIB.BASEBOARD_FAB2(SCH_1):P3E_CPU0_PE1_SS_RXP(2)

CAP_0402-0.22UF,16V,10%,X7R,A3A  I278  C2U11
   1 P3E_CPU0_PE1_PCH_RXP<4>      A @BASEBOARD_FAB2_LIB.BASEBOARD_FAB2(SCH_1):P3E_CPU0_PE1_PCH_RXP(4)
   2 P3E_CPU0_PE1_SS_RXP<4>      B @BASEBOARD_FAB2_LIB.BASEBOARD_FAB2(SCH_1):P3E_CPU0_PE1_SS_RXP(4)

CAP_0402-0.22UF,16V,10%,X7R,A3A  I279  C2U9
   1 P3E_CPU0_PE1_PCH_RXP<3>      A @BASEBOARD_FAB2_LIB.BASEBOARD_FAB2(SCH_1):P3E_CPU0_PE1_PCH_RXP(3)
   2 P3E_CPU0_PE1_SS_RXP<3>      B @BASEBOARD_FAB2_LIB.BASEBOARD_FAB2(SCH_1):P3E_CPU0_PE1_SS_RXP(3)

CAP_0402-0.22UF,16V,10%,X7R,A3A  I286  C2U16
   1 P3E_CPU0_PE1_PCH_RXN<6>      A @BASEBOARD_FAB2_LIB.BASEBOARD_FAB2(SCH_1):P3E_CPU0_PE1_PCH_RXN(6)
   2 P3E_CPU0_PE1_SS_RXN<6>      B @BASEBOARD_FAB2_LIB.BASEBOARD_FAB2(SCH_1):P3E_CPU0_PE1_SS_RXN(6)

CAP_0402-0.22UF,16V,10%,X7R,A3A  I287  C2U14
   1 P3E_CPU0_PE1_PCH_RXN<5>      A @BASEBOARD_FAB2_LIB.BASEBOARD_FAB2(SCH_1):P3E_CPU0_PE1_PCH_RXN(5)
   2 P3E_CPU0_PE1_SS_RXN<5>      B @BASEBOARD_FAB2_LIB.BASEBOARD_FAB2(SCH_1):P3E_CPU0_PE1_SS_RXN(5)

CAP_0402-0.22UF,16V,10%,X7R,A3A  I294  C2U18
   1 P3E_CPU0_PE1_PCH_RXN<7>      A @BASEBOARD_FAB2_LIB.BASEBOARD_FAB2(SCH_1):P3E_CPU0_PE1_PCH_RXN(7)
   2 P3E_CPU0_PE1_SS_RXN<7>      B @BASEBOARD_FAB2_LIB.BASEBOARD_FAB2(SCH_1):P3E_CPU0_PE1_SS_RXN(7)

CAP_0402-0.22UF,16V,10%,X7R,A3A  I296  C2U15
   1 P3E_CPU0_PE1_PCH_RXP<6>      A @BASEBOARD_FAB2_LIB.BASEBOARD_FAB2(SCH_1):P3E_CPU0_PE1_PCH_RXP(6)
   2 P3E_CPU0_PE1_SS_RXP<6>      B @BASEBOARD_FAB2_LIB.BASEBOARD_FAB2(SCH_1):P3E_CPU0_PE1_SS_RXP(6)

CAP_0402-0.22UF,16V,10%,X7R,A3A  I297  C2U13
   1 P3E_CPU0_PE1_PCH_RXP<5>      A @BASEBOARD_FAB2_LIB.BASEBOARD_FAB2(SCH_1):P3E_CPU0_PE1_PCH_RXP(5)
   2 P3E_CPU0_PE1_SS_RXP<5>      B @BASEBOARD_FAB2_LIB.BASEBOARD_FAB2(SCH_1):P3E_CPU0_PE1_SS_RXP(5)

CAP_0402-0.22UF,16V,10%,X7R,A3A  I300  C2U17
   1 P3E_CPU0_PE1_PCH_RXP<7>      A @BASEBOARD_FAB2_LIB.BASEBOARD_FAB2(SCH_1):P3E_CPU0_PE1_PCH_RXP(7)
   2 P3E_CPU0_PE1_SS_RXP<7>      B @BASEBOARD_FAB2_LIB.BASEBOARD_FAB2(SCH_1):P3E_CPU0_PE1_SS_RXP(7)

CAP_0402-0.22UF,16V,10%,X7R,A3A  I474  C3P41
   1 P3E_CPU0_PE1_SS_TXN<7>      A @BASEBOARD_FAB2_LIB.BASEBOARD_FAB2(SCH_1):P3E_CPU0_PE1_SS_TXN(7)
   2 P3E_CPU0_PE1_SS_C_TXN<7>      B @BASEBOARD_FAB2_LIB.BASEBOARD_FAB2(SCH_1):P3E_CPU0_PE1_SS_C_TXN(7)

CAP_0402-0.22UF,16V,10%,X7R,A3A  I475  C3P36
   1 P3E_CPU0_PE1_SS_TXN<6>      A @BASEBOARD_FAB2_LIB.BASEBOARD_FAB2(SCH_1):P3E_CPU0_PE1_SS_TXN(6)
   2 P3E_CPU0_PE1_SS_C_TXN<6>      B @BASEBOARD_FAB2_LIB.BASEBOARD_FAB2(SCH_1):P3E_CPU0_PE1_SS_C_TXN(6)

CAP_0402-0.22UF,16V,10%,X7R,A3A  I476  C3P16
   1 P3E_CPU0_PE1_SS_TXN<1>      A @BASEBOARD_FAB2_LIB.BASEBOARD_FAB2(SCH_1):P3E_CPU0_PE1_SS_TXN(1)
   2 P3E_CPU0_PE1_SS_C_TXN<1>      B @BASEBOARD_FAB2_LIB.BASEBOARD_FAB2(SCH_1):P3E_CPU0_PE1_SS_C_TXN(1)

CAP_0402-0.22UF,16V,10%,X7R,A3A  I477  C3P33
   1 P3E_CPU0_PE1_SS_TXN<5>      A @BASEBOARD_FAB2_LIB.BASEBOARD_FAB2(SCH_1):P3E_CPU0_PE1_SS_TXN(5)
   2 P3E_CPU0_PE1_SS_C_TXN<5>      B @BASEBOARD_FAB2_LIB.BASEBOARD_FAB2(SCH_1):P3E_CPU0_PE1_SS_C_TXN(5)

CAP_0402-0.22UF,16V,10%,X7R,A3A  I478  C3P29
   1 P3E_CPU0_PE1_SS_TXN<4>      A @BASEBOARD_FAB2_LIB.BASEBOARD_FAB2(SCH_1):P3E_CPU0_PE1_SS_TXN(4)
   2 P3E_CPU0_PE1_SS_C_TXN<4>      B @BASEBOARD_FAB2_LIB.BASEBOARD_FAB2(SCH_1):P3E_CPU0_PE1_SS_C_TXN(4)

CAP_0402-0.22UF,16V,10%,X7R,A3A  I479  C3P24
   1 P3E_CPU0_PE1_SS_TXN<3>      A @BASEBOARD_FAB2_LIB.BASEBOARD_FAB2(SCH_1):P3E_CPU0_PE1_SS_TXN(3)
   2 P3E_CPU0_PE1_SS_C_TXN<3>      B @BASEBOARD_FAB2_LIB.BASEBOARD_FAB2(SCH_1):P3E_CPU0_PE1_SS_C_TXN(3)

CAP_0402-0.22UF,16V,10%,X7R,A3A  I480  C3P21
   1 P3E_CPU0_PE1_SS_TXN<2>      A @BASEBOARD_FAB2_LIB.BASEBOARD_FAB2(SCH_1):P3E_CPU0_PE1_SS_TXN(2)
   2 P3E_CPU0_PE1_SS_C_TXN<2>      B @BASEBOARD_FAB2_LIB.BASEBOARD_FAB2(SCH_1):P3E_CPU0_PE1_SS_C_TXN(2)

CAP_0402-0.22UF,16V,10%,X7R,A3A  I481  C3P12
   1 P3E_CPU0_PE1_SS_TXN<0>      A @BASEBOARD_FAB2_LIB.BASEBOARD_FAB2(SCH_1):P3E_CPU0_PE1_SS_TXN(0)
   2 P3E_CPU0_PE1_SS_C_TXN<0>      B @BASEBOARD_FAB2_LIB.BASEBOARD_FAB2(SCH_1):P3E_CPU0_PE1_SS_C_TXN(0)

CAP_0402-0.22UF,16V,10%,X7R,A3A  I482  C3P10
   1 P3E_CPU0_PE1_SS_TXP<0>      A @BASEBOARD_FAB2_LIB.BASEBOARD_FAB2(SCH_1):P3E_CPU0_PE1_SS_TXP(0)
   2 P3E_CPU0_PE1_SS_C_TXP<0>      B @BASEBOARD_FAB2_LIB.BASEBOARD_FAB2(SCH_1):P3E_CPU0_PE1_SS_C_TXP(0)

CAP_0402-0.22UF,16V,10%,X7R,A3A  I483  C3P14
   1 P3E_CPU0_PE1_SS_TXP<1>      A @BASEBOARD_FAB2_LIB.BASEBOARD_FAB2(SCH_1):P3E_CPU0_PE1_SS_TXP(1)
   2 P3E_CPU0_PE1_SS_C_TXP<1>      B @BASEBOARD_FAB2_LIB.BASEBOARD_FAB2(SCH_1):P3E_CPU0_PE1_SS_C_TXP(1)

CAP_0402-0.22UF,16V,10%,X7R,A3A  I484  C3P22
   1 P3E_CPU0_PE1_SS_TXP<3>      A @BASEBOARD_FAB2_LIB.BASEBOARD_FAB2(SCH_1):P3E_CPU0_PE1_SS_TXP(3)
   2 P3E_CPU0_PE1_SS_C_TXP<3>      B @BASEBOARD_FAB2_LIB.BASEBOARD_FAB2(SCH_1):P3E_CPU0_PE1_SS_C_TXP(3)

CAP_0402-0.22UF,16V,10%,X7R,A3A  I485  C3P19
   1 P3E_CPU0_PE1_SS_TXP<2>      A @BASEBOARD_FAB2_LIB.BASEBOARD_FAB2(SCH_1):P3E_CPU0_PE1_SS_TXP(2)
   2 P3E_CPU0_PE1_SS_C_TXP<2>      B @BASEBOARD_FAB2_LIB.BASEBOARD_FAB2(SCH_1):P3E_CPU0_PE1_SS_C_TXP(2)

CAP_0402-0.22UF,16V,10%,X7R,A3A  I486  C3P38
   1 P3E_CPU0_PE1_SS_TXP<7>      A @BASEBOARD_FAB2_LIB.BASEBOARD_FAB2(SCH_1):P3E_CPU0_PE1_SS_TXP(7)
   2 P3E_CPU0_PE1_SS_C_TXP<7>      B @BASEBOARD_FAB2_LIB.BASEBOARD_FAB2(SCH_1):P3E_CPU0_PE1_SS_C_TXP(7)

CAP_0402-0.22UF,16V,10%,X7R,A3A  I487  C3P26
   1 P3E_CPU0_PE1_SS_TXP<4>      A @BASEBOARD_FAB2_LIB.BASEBOARD_FAB2(SCH_1):P3E_CPU0_PE1_SS_TXP(4)
   2 P3E_CPU0_PE1_SS_C_TXP<4>      B @BASEBOARD_FAB2_LIB.BASEBOARD_FAB2(SCH_1):P3E_CPU0_PE1_SS_C_TXP(4)

CAP_0402-0.22UF,16V,10%,X7R,A3A  I488  C3P31
   1 P3E_CPU0_PE1_SS_TXP<5>      A @BASEBOARD_FAB2_LIB.BASEBOARD_FAB2(SCH_1):P3E_CPU0_PE1_SS_TXP(5)
   2 P3E_CPU0_PE1_SS_C_TXP<5>      B @BASEBOARD_FAB2_LIB.BASEBOARD_FAB2(SCH_1):P3E_CPU0_PE1_SS_C_TXP(5)

CAP_0402-0.22UF,16V,10%,X7R,A3A  I489  C3P34
   1 P3E_CPU0_PE1_SS_TXP<6>      A @BASEBOARD_FAB2_LIB.BASEBOARD_FAB2(SCH_1):P3E_CPU0_PE1_SS_TXP(6)
   2 P3E_CPU0_PE1_SS_C_TXP<6>      B @BASEBOARD_FAB2_LIB.BASEBOARD_FAB2(SCH_1):P3E_CPU0_PE1_SS_C_TXP(6)

RES_0402-0.0,5%,1/16W,CHIP,G21A  I490  R2U15
   1 P3E_CPU0_PE1_SS_RXN<0>      A @BASEBOARD_FAB2_LIB.BASEBOARD_FAB2(SCH_1):P3E_CPU0_PE1_SS_RXN(0)
   2 P3E_CPU0_PE1_SS_R_RXN<0>      B @BASEBOARD_FAB2_LIB.BASEBOARD_FAB2(SCH_1):P3E_CPU0_PE1_SS_R_RXN(0)

RES_0402-0.0,5%,1/16W,CHIP,G21A  I491  R2U21
   1 P3E_CPU0_PE1_SS_RXN<3>      A @BASEBOARD_FAB2_LIB.BASEBOARD_FAB2(SCH_1):P3E_CPU0_PE1_SS_RXN(3)
   2 P3E_CPU0_PE1_SS_R_RXN<3>      B @BASEBOARD_FAB2_LIB.BASEBOARD_FAB2(SCH_1):P3E_CPU0_PE1_SS_R_RXN(3)

RES_0402-0.0,5%,1/16W,CHIP,G21A  I492  R2U17
   1 P3E_CPU0_PE1_SS_RXN<1>      A @BASEBOARD_FAB2_LIB.BASEBOARD_FAB2(SCH_1):P3E_CPU0_PE1_SS_RXN(1)
   2 P3E_CPU0_PE1_SS_R_RXN<1>      B @BASEBOARD_FAB2_LIB.BASEBOARD_FAB2(SCH_1):P3E_CPU0_PE1_SS_R_RXN(1)

RES_0402-0.0,5%,1/16W,CHIP,G21A  I493  R2U19
   1 P3E_CPU0_PE1_SS_RXN<2>      A @BASEBOARD_FAB2_LIB.BASEBOARD_FAB2(SCH_1):P3E_CPU0_PE1_SS_RXN(2)
   2 P3E_CPU0_PE1_SS_R_RXN<2>      B @BASEBOARD_FAB2_LIB.BASEBOARD_FAB2(SCH_1):P3E_CPU0_PE1_SS_R_RXN(2)

RES_0402-0.0,5%,1/16W,CHIP,G21A  I494  R2U29
   1 P3E_CPU0_PE1_SS_RXN<7>      A @BASEBOARD_FAB2_LIB.BASEBOARD_FAB2(SCH_1):P3E_CPU0_PE1_SS_RXN(7)
   2 P3E_CPU0_PE1_SS_R_RXN<7>      B @BASEBOARD_FAB2_LIB.BASEBOARD_FAB2(SCH_1):P3E_CPU0_PE1_SS_R_RXN(7)

RES_0402-0.0,5%,1/16W,CHIP,G21A  I495  R2U23
   1 P3E_CPU0_PE1_SS_RXN<4>      A @BASEBOARD_FAB2_LIB.BASEBOARD_FAB2(SCH_1):P3E_CPU0_PE1_SS_RXN(4)
   2 P3E_CPU0_PE1_SS_R_RXN<4>      B @BASEBOARD_FAB2_LIB.BASEBOARD_FAB2(SCH_1):P3E_CPU0_PE1_SS_R_RXN(4)

RES_0402-0.0,5%,1/16W,CHIP,G21A  I496  R2U25
   1 P3E_CPU0_PE1_SS_RXN<5>      A @BASEBOARD_FAB2_LIB.BASEBOARD_FAB2(SCH_1):P3E_CPU0_PE1_SS_RXN(5)
   2 P3E_CPU0_PE1_SS_R_RXN<5>      B @BASEBOARD_FAB2_LIB.BASEBOARD_FAB2(SCH_1):P3E_CPU0_PE1_SS_R_RXN(5)

RES_0402-0.0,5%,1/16W,CHIP,G21A  I497  R2U27
   1 P3E_CPU0_PE1_SS_RXN<6>      A @BASEBOARD_FAB2_LIB.BASEBOARD_FAB2(SCH_1):P3E_CPU0_PE1_SS_RXN(6)
   2 P3E_CPU0_PE1_SS_R_RXN<6>      B @BASEBOARD_FAB2_LIB.BASEBOARD_FAB2(SCH_1):P3E_CPU0_PE1_SS_R_RXN(6)

RES_0402-0.0,5%,1/16W,CHIP,G21A  I498  R2U26
   1 P3E_CPU0_PE1_SS_RXP<6>      A @BASEBOARD_FAB2_LIB.BASEBOARD_FAB2(SCH_1):P3E_CPU0_PE1_SS_RXP(6)
   2 P3E_CPU0_PE1_SS_R_RXP<6>      B @BASEBOARD_FAB2_LIB.BASEBOARD_FAB2(SCH_1):P3E_CPU0_PE1_SS_R_RXP(6)

RES_0402-0.0,5%,1/16W,CHIP,G21A  I499  R2U14
   1 P3E_CPU0_PE1_SS_RXP<0>      A @BASEBOARD_FAB2_LIB.BASEBOARD_FAB2(SCH_1):P3E_CPU0_PE1_SS_RXP(0)
   2 P3E_CPU0_PE1_SS_R_RXP<0>      B @BASEBOARD_FAB2_LIB.BASEBOARD_FAB2(SCH_1):P3E_CPU0_PE1_SS_R_RXP(0)

RES_0402-0.0,5%,1/16W,CHIP,G21A  I500  R2U28
   1 P3E_CPU0_PE1_SS_RXP<7>      A @BASEBOARD_FAB2_LIB.BASEBOARD_FAB2(SCH_1):P3E_CPU0_PE1_SS_RXP(7)
   2 P3E_CPU0_PE1_SS_R_RXP<7>      B @BASEBOARD_FAB2_LIB.BASEBOARD_FAB2(SCH_1):P3E_CPU0_PE1_SS_R_RXP(7)

RES_0402-0.0,5%,1/16W,CHIP,G21A  I501  R2U16
   1 P3E_CPU0_PE1_SS_RXP<1>      A @BASEBOARD_FAB2_LIB.BASEBOARD_FAB2(SCH_1):P3E_CPU0_PE1_SS_RXP(1)
   2 P3E_CPU0_PE1_SS_R_RXP<1>      B @BASEBOARD_FAB2_LIB.BASEBOARD_FAB2(SCH_1):P3E_CPU0_PE1_SS_R_RXP(1)

RES_0402-0.0,5%,1/16W,CHIP,G21A  I502  R2U18
   1 P3E_CPU0_PE1_SS_RXP<2>      A @BASEBOARD_FAB2_LIB.BASEBOARD_FAB2(SCH_1):P3E_CPU0_PE1_SS_RXP(2)
   2 P3E_CPU0_PE1_SS_R_RXP<2>      B @BASEBOARD_FAB2_LIB.BASEBOARD_FAB2(SCH_1):P3E_CPU0_PE1_SS_R_RXP(2)

RES_0402-0.0,5%,1/16W,CHIP,G21A  I503  R2U20
   1 P3E_CPU0_PE1_SS_RXP<3>      A @BASEBOARD_FAB2_LIB.BASEBOARD_FAB2(SCH_1):P3E_CPU0_PE1_SS_RXP(3)
   2 P3E_CPU0_PE1_SS_R_RXP<3>      B @BASEBOARD_FAB2_LIB.BASEBOARD_FAB2(SCH_1):P3E_CPU0_PE1_SS_R_RXP(3)

RES_0402-0.0,5%,1/16W,CHIP,G21A  I504  R2U22
   1 P3E_CPU0_PE1_SS_RXP<4>      A @BASEBOARD_FAB2_LIB.BASEBOARD_FAB2(SCH_1):P3E_CPU0_PE1_SS_RXP(4)
   2 P3E_CPU0_PE1_SS_R_RXP<4>      B @BASEBOARD_FAB2_LIB.BASEBOARD_FAB2(SCH_1):P3E_CPU0_PE1_SS_R_RXP(4)

RES_0402-0.0,5%,1/16W,CHIP,G21A  I505  R2U24
   1 P3E_CPU0_PE1_SS_RXP<5>      A @BASEBOARD_FAB2_LIB.BASEBOARD_FAB2(SCH_1):P3E_CPU0_PE1_SS_RXP(5)
   2 P3E_CPU0_PE1_SS_R_RXP<5>      B @BASEBOARD_FAB2_LIB.BASEBOARD_FAB2(SCH_1):P3E_CPU0_PE1_SS_R_RXP(5)


DRAWING: @BASEBOARD_FAB2_LIB.BASEBOARD_FAB2(SCH_1):PAGE108 

CAP_A_0402V-0.1UF,16V,10%,X7R,A  I1  C2U20
   1   P12V      A @BASEBOARD_FAB2_LIB.BASEBOARD_FAB2(SCH_1):P12V
   2    GND      B @BASEBOARD_FAB2_LIB.BASEBOARD_FAB2(SCH_1):GND

CAP_A_0402V-0.1UF,16V,10%,X7R,A  I2  C2U24
   1   P12V      A @BASEBOARD_FAB2_LIB.BASEBOARD_FAB2(SCH_1):P12V
   2    GND      B @BASEBOARD_FAB2_LIB.BASEBOARD_FAB2(SCH_1):GND

CAP_A_0402V-0.1UF,16V,10%,X7R,A  I5  C2U21
   1   P3V3      A @BASEBOARD_FAB2_LIB.BASEBOARD_FAB2(SCH_1):P3V3
   2    GND      B @BASEBOARD_FAB2_LIB.BASEBOARD_FAB2(SCH_1):GND

CAP_A_0402V-0.1UF,16V,10%,X7R,A  I7  C2U25
   1   P3V3      A @BASEBOARD_FAB2_LIB.BASEBOARD_FAB2(SCH_1):P3V3
   2    GND      B @BASEBOARD_FAB2_LIB.BASEBOARD_FAB2(SCH_1):GND

RES_0402-0.0,5%,1/16W,CHIP,G21A  I173  R2U37
   1 RST_PCIE_RISER1_PERST_N      A @BASEBOARD_FAB2_LIB.BASEBOARD_FAB2(SCH_1):RST_PCIE_RISER1_PERST_N
   2 RST_PCIE_RISER1_PERST_R_N      B @BASEBOARD_FAB2_LIB.BASEBOARD_FAB2(SCH_1):RST_PCIE_RISER1_PERST_R_N

SCONN200_H68296001_SM-CONN,H68A  I258  J8G1
   1   P12V    IO1 @BASEBOARD_FAB2_LIB.BASEBOARD_FAB2(SCH_1):P12V
   2   P12V    IO2 @BASEBOARD_FAB2_LIB.BASEBOARD_FAB2(SCH_1):P12V
   3   P12V    IO3 @BASEBOARD_FAB2_LIB.BASEBOARD_FAB2(SCH_1):P12V
   4   P12V    IO4 @BASEBOARD_FAB2_LIB.BASEBOARD_FAB2(SCH_1):P12V
   5   P12V    IO5 @BASEBOARD_FAB2_LIB.BASEBOARD_FAB2(SCH_1):P12V
   6   P12V    IO6 @BASEBOARD_FAB2_LIB.BASEBOARD_FAB2(SCH_1):P12V
   7   P12V    IO7 @BASEBOARD_FAB2_LIB.BASEBOARD_FAB2(SCH_1):P12V
   8   P12V    IO8 @BASEBOARD_FAB2_LIB.BASEBOARD_FAB2(SCH_1):P12V
   9   P12V    IO9 @BASEBOARD_FAB2_LIB.BASEBOARD_FAB2(SCH_1):P12V
  10   P12V   IO10 @BASEBOARD_FAB2_LIB.BASEBOARD_FAB2(SCH_1):P12V
  11   P12V   IO11 @BASEBOARD_FAB2_LIB.BASEBOARD_FAB2(SCH_1):P12V
  12   P12V   IO12 @BASEBOARD_FAB2_LIB.BASEBOARD_FAB2(SCH_1):P12V
  13    GND   IO13 @BASEBOARD_FAB2_LIB.BASEBOARD_FAB2(SCH_1):GND
  14    GND   IO14 @BASEBOARD_FAB2_LIB.BASEBOARD_FAB2(SCH_1):GND
  15 SMB_SLOTX24_STBY_LVC3_SDA_R2   IO15 @BASEBOARD_FAB2_LIB.BASEBOARD_FAB2(SCH_1):SMB_SLOTX24_STBY_LVC3_SDA_R2
  16 IRQ_OOB_MGMT_RISER_ALERT_N   IO16 @BASEBOARD_FAB2_LIB.BASEBOARD_FAB2(SCH_1):IRQ_OOB_MGMT_RISER_ALERT_N
  17 SMB_SLOTX24_STBY_LVC3_SCL_R2   IO17 @BASEBOARD_FAB2_LIB.BASEBOARD_FAB2(SCH_1):SMB_SLOTX24_STBY_LVC3_SCL_R2
  18 FM_SLT_CFG1   IO18 @BASEBOARD_FAB2_LIB.BASEBOARD_FAB2(SCH_1):FM_SLT_CFG1
  19 FM_SLT_CFG0   IO19 @BASEBOARD_FAB2_LIB.BASEBOARD_FAB2(SCH_1):FM_SLT_CFG0
  20 FM_PWRBRK_SLOT_N   IO20 @BASEBOARD_FAB2_LIB.BASEBOARD_FAB2(SCH_1):FM_PWRBRK_SLOT_N
  21   P3V3   IO21 @BASEBOARD_FAB2_LIB.BASEBOARD_FAB2(SCH_1):P3V3
  22   P3V3   IO22 @BASEBOARD_FAB2_LIB.BASEBOARD_FAB2(SCH_1):P3V3
  23   P3V3   IO23 @BASEBOARD_FAB2_LIB.BASEBOARD_FAB2(SCH_1):P3V3
  24   P3V3   IO24 @BASEBOARD_FAB2_LIB.BASEBOARD_FAB2(SCH_1):P3V3
  25 P3V3_STBY   IO25 @BASEBOARD_FAB2_LIB.BASEBOARD_FAB2(SCH_1):P3V3_STBY
  26    GND   IO26 @BASEBOARD_FAB2_LIB.BASEBOARD_FAB2(SCH_1):GND
  27 PU_PCH_TLS_ENABLE_STRAP   IO27 @BASEBOARD_FAB2_LIB.BASEBOARD_FAB2(SCH_1):PU_PCH_TLS_ENABLE_STRAP
  28 FM_PE_SLOTX24_WAKE_N   IO28 @BASEBOARD_FAB2_LIB.BASEBOARD_FAB2(SCH_1):FM_PE_SLOTX24_WAKE_N
  29 RST_PCIE_RISER1_PERST_R_N   IO29 @BASEBOARD_FAB2_LIB.BASEBOARD_FAB2(SCH_1):RST_PCIE_RISER1_PERST_R_N
  30 SMB_HOST_STBY_LVC3_SDA_R5   IO30 @BASEBOARD_FAB2_LIB.BASEBOARD_FAB2(SCH_1):SMB_HOST_STBY_LVC3_SDA_R5
  31    GND   IO31 @BASEBOARD_FAB2_LIB.BASEBOARD_FAB2(SCH_1):GND
  32 SMB_HOST_STBY_LVC3_SCL_R5   IO32 @BASEBOARD_FAB2_LIB.BASEBOARD_FAB2(SCH_1):SMB_HOST_STBY_LVC3_SCL_R5
  33 CLK_100M_PCH_SLOTX24_S5_DP   IO33 @BASEBOARD_FAB2_LIB.BASEBOARD_FAB2(SCH_1):CLK_100M_PCH_SLOTX24_S5_DP
  34    GND   IO34 @BASEBOARD_FAB2_LIB.BASEBOARD_FAB2(SCH_1):GND
  35 CLK_100M_PCH_SLOTX24_S5_DN   IO35 @BASEBOARD_FAB2_LIB.BASEBOARD_FAB2(SCH_1):CLK_100M_PCH_SLOTX24_S5_DN
  36 CLK_100M_PCH_SLOTX24_S4_DP   IO36 @BASEBOARD_FAB2_LIB.BASEBOARD_FAB2(SCH_1):CLK_100M_PCH_SLOTX24_S4_DP
  37    GND   IO37 @BASEBOARD_FAB2_LIB.BASEBOARD_FAB2(SCH_1):GND
  38 CLK_100M_PCH_SLOTX24_S4_DN   IO38 @BASEBOARD_FAB2_LIB.BASEBOARD_FAB2(SCH_1):CLK_100M_PCH_SLOTX24_S4_DN
  39 CLK_100M_PCH_SLOTX24_S0_DP   IO39 @BASEBOARD_FAB2_LIB.BASEBOARD_FAB2(SCH_1):CLK_100M_PCH_SLOTX24_S0_DP
  40    GND   IO40 @BASEBOARD_FAB2_LIB.BASEBOARD_FAB2(SCH_1):GND
  41 CLK_100M_PCH_SLOTX24_S0_DN   IO41 @BASEBOARD_FAB2_LIB.BASEBOARD_FAB2(SCH_1):CLK_100M_PCH_SLOTX24_S0_DN
  42 CLK_100M_PCH_SLOTX24_S1_DP   IO42 @BASEBOARD_FAB2_LIB.BASEBOARD_FAB2(SCH_1):CLK_100M_PCH_SLOTX24_S1_DP
  43    GND   IO43 @BASEBOARD_FAB2_LIB.BASEBOARD_FAB2(SCH_1):GND
  44 CLK_100M_PCH_SLOTX24_S1_DN   IO44 @BASEBOARD_FAB2_LIB.BASEBOARD_FAB2(SCH_1):CLK_100M_PCH_SLOTX24_S1_DN
  45 CLK_100M_PCH_SLOTX24_S3_DP   IO45 @BASEBOARD_FAB2_LIB.BASEBOARD_FAB2(SCH_1):CLK_100M_PCH_SLOTX24_S3_DP
  46    GND   IO46 @BASEBOARD_FAB2_LIB.BASEBOARD_FAB2(SCH_1):GND
  47 CLK_100M_PCH_SLOTX24_S3_DN   IO47 @BASEBOARD_FAB2_LIB.BASEBOARD_FAB2(SCH_1):CLK_100M_PCH_SLOTX24_S3_DN
  48 CLK_100M_PCH_SLOTX24_S2_DP   IO48 @BASEBOARD_FAB2_LIB.BASEBOARD_FAB2(SCH_1):CLK_100M_PCH_SLOTX24_S2_DP
  49    GND   IO49 @BASEBOARD_FAB2_LIB.BASEBOARD_FAB2(SCH_1):GND
  50 CLK_100M_PCH_SLOTX24_S2_DN   IO50 @BASEBOARD_FAB2_LIB.BASEBOARD_FAB2(SCH_1):CLK_100M_PCH_SLOTX24_S2_DN
  51 P3E_CPU0_PE1_PCH_CON_TXN<15>   IO51 @BASEBOARD_FAB2_LIB.BASEBOARD_FAB2(SCH_1):P3E_CPU0_PE1_PCH_CON_TXN(15)
  52    GND   IO52 @BASEBOARD_FAB2_LIB.BASEBOARD_FAB2(SCH_1):GND
  53 P3E_CPU0_PE1_PCH_CON_TXP<15>   IO53 @BASEBOARD_FAB2_LIB.BASEBOARD_FAB2(SCH_1):P3E_CPU0_PE1_PCH_CON_TXP(15)
  54 P3E_CPU0_PE1_PCH_CON_RXN<15>   IO54 @BASEBOARD_FAB2_LIB.BASEBOARD_FAB2(SCH_1):P3E_CPU0_PE1_PCH_CON_RXN(15)
  55    GND   IO55 @BASEBOARD_FAB2_LIB.BASEBOARD_FAB2(SCH_1):GND
  56 P3E_CPU0_PE1_PCH_CON_RXP<15>   IO56 @BASEBOARD_FAB2_LIB.BASEBOARD_FAB2(SCH_1):P3E_CPU0_PE1_PCH_CON_RXP(15)
  57 P3E_CPU0_PE1_PCH_CON_TXP<14>   IO57 @BASEBOARD_FAB2_LIB.BASEBOARD_FAB2(SCH_1):P3E_CPU0_PE1_PCH_CON_TXP(14)
  58    GND   IO58 @BASEBOARD_FAB2_LIB.BASEBOARD_FAB2(SCH_1):GND
  59 P3E_CPU0_PE1_PCH_CON_TXN<14>   IO59 @BASEBOARD_FAB2_LIB.BASEBOARD_FAB2(SCH_1):P3E_CPU0_PE1_PCH_CON_TXN(14)
  60 P3E_CPU0_PE1_PCH_CON_RXN<14>   IO60 @BASEBOARD_FAB2_LIB.BASEBOARD_FAB2(SCH_1):P3E_CPU0_PE1_PCH_CON_RXN(14)
  61    GND   IO61 @BASEBOARD_FAB2_LIB.BASEBOARD_FAB2(SCH_1):GND
  62 P3E_CPU0_PE1_PCH_CON_RXP<14>   IO62 @BASEBOARD_FAB2_LIB.BASEBOARD_FAB2(SCH_1):P3E_CPU0_PE1_PCH_CON_RXP(14)
  63 TP_SLOTX24_RSVD63   IO63 @BASEBOARD_FAB2_LIB.BASEBOARD_FAB2(SCH_1):TP_SLOTX24_RSVD63
  64    GND   IO64 @BASEBOARD_FAB2_LIB.BASEBOARD_FAB2(SCH_1):GND
  65    GND   IO65 @BASEBOARD_FAB2_LIB.BASEBOARD_FAB2(SCH_1):GND
  66 TP_SLOTX24_RSVD66   IO66 @BASEBOARD_FAB2_LIB.BASEBOARD_FAB2(SCH_1):TP_SLOTX24_RSVD66
  67 P3E_CPU0_PE1_PCH_CON_TXN<13>   IO67 @BASEBOARD_FAB2_LIB.BASEBOARD_FAB2(SCH_1):P3E_CPU0_PE1_PCH_CON_TXN(13)
  68    GND   IO68 @BASEBOARD_FAB2_LIB.BASEBOARD_FAB2(SCH_1):GND
  69 P3E_CPU0_PE1_PCH_CON_TXP<13>   IO69 @BASEBOARD_FAB2_LIB.BASEBOARD_FAB2(SCH_1):P3E_CPU0_PE1_PCH_CON_TXP(13)
  70 P3E_CPU0_PE1_PCH_CON_RXN<13>   IO70 @BASEBOARD_FAB2_LIB.BASEBOARD_FAB2(SCH_1):P3E_CPU0_PE1_PCH_CON_RXN(13)
  71    GND   IO71 @BASEBOARD_FAB2_LIB.BASEBOARD_FAB2(SCH_1):GND
  72 P3E_CPU0_PE1_PCH_CON_RXP<13>   IO72 @BASEBOARD_FAB2_LIB.BASEBOARD_FAB2(SCH_1):P3E_CPU0_PE1_PCH_CON_RXP(13)
  73 P3E_CPU0_PE1_PCH_CON_TXN<12>   IO73 @BASEBOARD_FAB2_LIB.BASEBOARD_FAB2(SCH_1):P3E_CPU0_PE1_PCH_CON_TXN(12)
  74    GND   IO74 @BASEBOARD_FAB2_LIB.BASEBOARD_FAB2(SCH_1):GND
  75 P3E_CPU0_PE1_PCH_CON_TXP<12>   IO75 @BASEBOARD_FAB2_LIB.BASEBOARD_FAB2(SCH_1):P3E_CPU0_PE1_PCH_CON_TXP(12)
  76 P3E_CPU0_PE1_PCH_CON_RXN<12>   IO76 @BASEBOARD_FAB2_LIB.BASEBOARD_FAB2(SCH_1):P3E_CPU0_PE1_PCH_CON_RXN(12)
  77    GND   IO77 @BASEBOARD_FAB2_LIB.BASEBOARD_FAB2(SCH_1):GND
  78 P3E_CPU0_PE1_PCH_CON_RXP<12>   IO78 @BASEBOARD_FAB2_LIB.BASEBOARD_FAB2(SCH_1):P3E_CPU0_PE1_PCH_CON_RXP(12)
  79 P3E_CPU0_PE1_PCH_CON_TXN<11>   IO79 @BASEBOARD_FAB2_LIB.BASEBOARD_FAB2(SCH_1):P3E_CPU0_PE1_PCH_CON_TXN(11)
  80    GND   IO80 @BASEBOARD_FAB2_LIB.BASEBOARD_FAB2(SCH_1):GND
  81 P3E_CPU0_PE1_PCH_CON_TXP<11>   IO81 @BASEBOARD_FAB2_LIB.BASEBOARD_FAB2(SCH_1):P3E_CPU0_PE1_PCH_CON_TXP(11)
  82 P3E_CPU0_PE1_PCH_CON_RXN<11>   IO82 @BASEBOARD_FAB2_LIB.BASEBOARD_FAB2(SCH_1):P3E_CPU0_PE1_PCH_CON_RXN(11)
  83    GND   IO83 @BASEBOARD_FAB2_LIB.BASEBOARD_FAB2(SCH_1):GND
  84 P3E_CPU0_PE1_PCH_CON_RXP<11>   IO84 @BASEBOARD_FAB2_LIB.BASEBOARD_FAB2(SCH_1):P3E_CPU0_PE1_PCH_CON_RXP(11)
  85 P3E_CPU0_PE1_PCH_CON_TXN<10>   IO85 @BASEBOARD_FAB2_LIB.BASEBOARD_FAB2(SCH_1):P3E_CPU0_PE1_PCH_CON_TXN(10)
  86    GND   IO86 @BASEBOARD_FAB2_LIB.BASEBOARD_FAB2(SCH_1):GND
  87 P3E_CPU0_PE1_PCH_CON_TXP<10>   IO87 @BASEBOARD_FAB2_LIB.BASEBOARD_FAB2(SCH_1):P3E_CPU0_PE1_PCH_CON_TXP(10)
  88 P3E_CPU0_PE1_PCH_CON_RXN<10>   IO88 @BASEBOARD_FAB2_LIB.BASEBOARD_FAB2(SCH_1):P3E_CPU0_PE1_PCH_CON_RXN(10)
  89    GND   IO89 @BASEBOARD_FAB2_LIB.BASEBOARD_FAB2(SCH_1):GND
  90 P3E_CPU0_PE1_PCH_CON_RXP<10>   IO90 @BASEBOARD_FAB2_LIB.BASEBOARD_FAB2(SCH_1):P3E_CPU0_PE1_PCH_CON_RXP(10)
  91 P3E_CPU0_PE1_PCH_CON_TXN<9>   IO91 @BASEBOARD_FAB2_LIB.BASEBOARD_FAB2(SCH_1):P3E_CPU0_PE1_PCH_CON_TXN(9)
  92    GND   IO92 @BASEBOARD_FAB2_LIB.BASEBOARD_FAB2(SCH_1):GND
  93 P3E_CPU0_PE1_PCH_CON_TXP<9>   IO93 @BASEBOARD_FAB2_LIB.BASEBOARD_FAB2(SCH_1):P3E_CPU0_PE1_PCH_CON_TXP(9)
  94 P3E_CPU0_PE1_PCH_CON_RXN<9>   IO94 @BASEBOARD_FAB2_LIB.BASEBOARD_FAB2(SCH_1):P3E_CPU0_PE1_PCH_CON_RXN(9)
  95    GND   IO95 @BASEBOARD_FAB2_LIB.BASEBOARD_FAB2(SCH_1):GND
  96 P3E_CPU0_PE1_PCH_CON_RXP<9>   IO96 @BASEBOARD_FAB2_LIB.BASEBOARD_FAB2(SCH_1):P3E_CPU0_PE1_PCH_CON_RXP(9)
  97 P3E_CPU0_PE1_PCH_CON_TXN<8>   IO97 @BASEBOARD_FAB2_LIB.BASEBOARD_FAB2(SCH_1):P3E_CPU0_PE1_PCH_CON_TXN(8)
  98    GND   IO98 @BASEBOARD_FAB2_LIB.BASEBOARD_FAB2(SCH_1):GND
  99 P3E_CPU0_PE1_PCH_CON_TXP<8>   IO99 @BASEBOARD_FAB2_LIB.BASEBOARD_FAB2(SCH_1):P3E_CPU0_PE1_PCH_CON_TXP(8)
 100 P3E_CPU0_PE1_PCH_CON_RXN<8>  IO100 @BASEBOARD_FAB2_LIB.BASEBOARD_FAB2(SCH_1):P3E_CPU0_PE1_PCH_CON_RXN(8)
 MH1    GND    MH1 @BASEBOARD_FAB2_LIB.BASEBOARD_FAB2(SCH_1):GND
 MH2    GND    MH2 @BASEBOARD_FAB2_LIB.BASEBOARD_FAB2(SCH_1):GND

CAP_A_0402V-0.1UF,16V,10%,X7R,A  I315  C2U23
   1 P3V3_STBY      A @BASEBOARD_FAB2_LIB.BASEBOARD_FAB2(SCH_1):P3V3_STBY
   2    GND      B @BASEBOARD_FAB2_LIB.BASEBOARD_FAB2(SCH_1):GND

CAP_A_0402V-0.1UF,16V,10%,X7R,A  I318  C2U22
   1 P3V3_STBY      A @BASEBOARD_FAB2_LIB.BASEBOARD_FAB2(SCH_1):P3V3_STBY
   2    GND      B @BASEBOARD_FAB2_LIB.BASEBOARD_FAB2(SCH_1):GND

RES_0402-20.0,1%,1/16W,CHIP,G2A  I330  R2U31
   1 SMB_SLOTX24_BMC_STBY_LVC3_SDA      A @BASEBOARD_FAB2_LIB.BASEBOARD_FAB2(SCH_1):SMB_SLOTX24_BMC_STBY_LVC3_SDA
   2 SMB_SLOTX24_STBY_LVC3_SDA_R2      B @BASEBOARD_FAB2_LIB.BASEBOARD_FAB2(SCH_1):SMB_SLOTX24_STBY_LVC3_SDA_R2

RES_0402-20.0,1%,1/16W,CHIP,G2A  I339  R2U32
   1 SMB_SLOTX24_BMC_STBY_LVC3_SCL      A @BASEBOARD_FAB2_LIB.BASEBOARD_FAB2(SCH_1):SMB_SLOTX24_BMC_STBY_LVC3_SCL
   2 SMB_SLOTX24_STBY_LVC3_SCL_R2      B @BASEBOARD_FAB2_LIB.BASEBOARD_FAB2(SCH_1):SMB_SLOTX24_STBY_LVC3_SCL_R2

RES_0402-0.0,5%,1/16W,CHIP,G21A  I341  R7E22
   1 FM_PWRBRK_N      A @BASEBOARD_FAB2_LIB.BASEBOARD_FAB2(SCH_1):FM_PWRBRK_N
   2 FM_PWRBRK_SLOT_N      B @BASEBOARD_FAB2_LIB.BASEBOARD_FAB2(SCH_1):FM_PWRBRK_SLOT_N

RES_0402-4.75K,1%,1/16W,CHIP,GA  I343  R7E21
   1   P3V3      A @BASEBOARD_FAB2_LIB.BASEBOARD_FAB2(SCH_1):P3V3
   2 FM_PWRBRK_N      B @BASEBOARD_FAB2_LIB.BASEBOARD_FAB2(SCH_1):FM_PWRBRK_N

RES_0402-20.0,1%,1/16W,EMPTY,GA  I350  R2U35
   1 SMB_SLOTX24_PCH_STBY_LVC3_SDA      A @BASEBOARD_FAB2_LIB.BASEBOARD_FAB2(SCH_1):SMB_SLOTX24_PCH_STBY_LVC3_SDA
   2 SMB_SLOTX24_STBY_LVC3_SDA_R2      B @BASEBOARD_FAB2_LIB.BASEBOARD_FAB2(SCH_1):SMB_SLOTX24_STBY_LVC3_SDA_R2

RES_0402-20.0,1%,1/16W,EMPTY,GA  I351  R2U36
   1 SMB_SLOTX24_PCH_STBY_LVC3_SCL      A @BASEBOARD_FAB2_LIB.BASEBOARD_FAB2(SCH_1):SMB_SLOTX24_PCH_STBY_LVC3_SCL
   2 SMB_SLOTX24_STBY_LVC3_SCL_R2      B @BASEBOARD_FAB2_LIB.BASEBOARD_FAB2(SCH_1):SMB_SLOTX24_STBY_LVC3_SCL_R2


DRAWING: @BASEBOARD_FAB2_LIB.BASEBOARD_FAB2(SCH_1):PAGE111 

RES_0402-1.00K,1%,1/16W,CHIP,GA  I6  R1L13
   1 XDP_SYSPWROK      A @BASEBOARD_FAB2_LIB.BASEBOARD_FAB2(SCH_1):XDP_SYSPWROK
   2 P3V3_STBY      B @BASEBOARD_FAB2_LIB.BASEBOARD_FAB2(SCH_1):P3V3_STBY

CAP_A_0402V-0.1UF,16V,10%,X7R,A  I10  C9A2
   1 XDP_SYSPWROK      A @BASEBOARD_FAB2_LIB.BASEBOARD_FAB2(SCH_1):XDP_SYSPWROK
   2    GND      B @BASEBOARD_FAB2_LIB.BASEBOARD_FAB2(SCH_1):GND

RES_0402-1.00K,1%,1/16W,CHIP,GA  I11  R9A14
   1 XDP_RST_CO_N      A @BASEBOARD_FAB2_LIB.BASEBOARD_FAB2(SCH_1):XDP_RST_CO_N
   2 P3V3_STBY      B @BASEBOARD_FAB2_LIB.BASEBOARD_FAB2(SCH_1):P3V3_STBY

CAP_A_0402V-0.1UF,16V,10%,X7R,A  I12  C9A5
   1 XDP_RST_CO_N      A @BASEBOARD_FAB2_LIB.BASEBOARD_FAB2(SCH_1):XDP_RST_CO_N
   2    GND      B @BASEBOARD_FAB2_LIB.BASEBOARD_FAB2(SCH_1):GND

RES_0402-1.00K,1%,1/16W,CHIP,GA  I13  R1L23
   1 XDP_PWRGD_RST_N      A @BASEBOARD_FAB2_LIB.BASEBOARD_FAB2(SCH_1):XDP_PWRGD_RST_N
   2 P3V3_STBY      B @BASEBOARD_FAB2_LIB.BASEBOARD_FAB2(SCH_1):P3V3_STBY

CAP_A_0402V-0.1UF,16V,10%,X7R,A  I14  C1L8
   1 XDP_PWRGD_RST_N      A @BASEBOARD_FAB2_LIB.BASEBOARD_FAB2(SCH_1):XDP_PWRGD_RST_N
   2    GND      B @BASEBOARD_FAB2_LIB.BASEBOARD_FAB2(SCH_1):GND

CAP_A_0402V-1.0UF,6.3V,10%,X6SA  I25  C9A6
   1 P1V05_PCH_STBY      A @BASEBOARD_FAB2_LIB.BASEBOARD_FAB2(SCH_1):P1V05_PCH_STBY
   2    GND      B @BASEBOARD_FAB2_LIB.BASEBOARD_FAB2(SCH_1):GND

SCONN60_C21100002_SMLF-CONN,C2A  I26  J9A3
   1 XDP_DEBUG_CONSENT_N    IO1 @BASEBOARD_FAB2_LIB.BASEBOARD_FAB2(SCH_1):XDP_DEBUG_CONSENT_N
   3 XDP_PREQ_N    IO3 @BASEBOARD_FAB2_LIB.BASEBOARD_FAB2(SCH_1):XDP_PREQ_N
   5 XDP_PRDY_N    IO5 @BASEBOARD_FAB2_LIB.BASEBOARD_FAB2(SCH_1):XDP_PRDY_N
   7    GND    IO7 @BASEBOARD_FAB2_LIB.BASEBOARD_FAB2(SCH_1):GND
   9 TP_XDP_OBSDATA_A0    IO9 @BASEBOARD_FAB2_LIB.BASEBOARD_FAB2(SCH_1):TP_XDP_OBSDATA_A0
  11 TP_XDP_OBSDATA_A1   IO11 @BASEBOARD_FAB2_LIB.BASEBOARD_FAB2(SCH_1):TP_XDP_OBSDATA_A1
  13    GND   IO13 @BASEBOARD_FAB2_LIB.BASEBOARD_FAB2(SCH_1):GND
  15 TP_XDP_OBSDATA_A2   IO15 @BASEBOARD_FAB2_LIB.BASEBOARD_FAB2(SCH_1):TP_XDP_OBSDATA_A2
  17 TP_XDP_OBSDATA_A3   IO17 @BASEBOARD_FAB2_LIB.BASEBOARD_FAB2(SCH_1):TP_XDP_OBSDATA_A3
  19    GND   IO19 @BASEBOARD_FAB2_LIB.BASEBOARD_FAB2(SCH_1):GND
  21 TP_XDP_OBSFN_B0   IO21 @BASEBOARD_FAB2_LIB.BASEBOARD_FAB2(SCH_1):TP_XDP_OBSFN_B0
  23 TP_XDP_OBSFN_B1   IO23 @BASEBOARD_FAB2_LIB.BASEBOARD_FAB2(SCH_1):TP_XDP_OBSFN_B1
  25    GND   IO25 @BASEBOARD_FAB2_LIB.BASEBOARD_FAB2(SCH_1):GND
  27 TP_XDP_OBSDATA_B0   IO27 @BASEBOARD_FAB2_LIB.BASEBOARD_FAB2(SCH_1):TP_XDP_OBSDATA_B0
  29 TP_XDP_OBSDATA_B1   IO29 @BASEBOARD_FAB2_LIB.BASEBOARD_FAB2(SCH_1):TP_XDP_OBSDATA_B1
  31    GND   IO31 @BASEBOARD_FAB2_LIB.BASEBOARD_FAB2(SCH_1):GND
  33 TP_XDP_OBSDATA_B2   IO33 @BASEBOARD_FAB2_LIB.BASEBOARD_FAB2(SCH_1):TP_XDP_OBSDATA_B2
  35 TP_XDP_OBSDATA_B3   IO35 @BASEBOARD_FAB2_LIB.BASEBOARD_FAB2(SCH_1):TP_XDP_OBSDATA_B3
  37    GND   IO37 @BASEBOARD_FAB2_LIB.BASEBOARD_FAB2(SCH_1):GND
  39 XDP_RSMRST_N   IO39 @BASEBOARD_FAB2_LIB.BASEBOARD_FAB2(SCH_1):XDP_RSMRST_N
  41 XDP_PWRGD_RST_N   IO41 @BASEBOARD_FAB2_LIB.BASEBOARD_FAB2(SCH_1):XDP_PWRGD_RST_N
  43 P1V05_PCH_STBY   IO43 @BASEBOARD_FAB2_LIB.BASEBOARD_FAB2(SCH_1):P1V05_PCH_STBY
  45 XDP_CPU_PWR_DEBUG_N   IO45 @BASEBOARD_FAB2_LIB.BASEBOARD_FAB2(SCH_1):XDP_CPU_PWR_DEBUG_N
  47 XDP_SYSPWROK   IO47 @BASEBOARD_FAB2_LIB.BASEBOARD_FAB2(SCH_1):XDP_SYSPWROK
  49    GND   IO49 @BASEBOARD_FAB2_LIB.BASEBOARD_FAB2(SCH_1):GND
   2    GND    IO2 @BASEBOARD_FAB2_LIB.BASEBOARD_FAB2(SCH_1):GND
   4 TP_XDP_CPU_OBSFN_C0    IO4 @BASEBOARD_FAB2_LIB.BASEBOARD_FAB2(SCH_1):TP_XDP_CPU_OBSFN_C0
   6 XDP_SPI_PCH_MOSI_BOOT_HALT_N    IO6 @BASEBOARD_FAB2_LIB.BASEBOARD_FAB2(SCH_1):XDP_SPI_PCH_MOSI_BOOT_HALT_N
   8    GND    IO8 @BASEBOARD_FAB2_LIB.BASEBOARD_FAB2(SCH_1):GND
  10 TP_XDP_CPU_OBSDATA_C0   IO10 @BASEBOARD_FAB2_LIB.BASEBOARD_FAB2(SCH_1):TP_XDP_CPU_OBSDATA_C0
  12 TP_XDP_CPU_OBSDATA_C1   IO12 @BASEBOARD_FAB2_LIB.BASEBOARD_FAB2(SCH_1):TP_XDP_CPU_OBSDATA_C1
  14    GND   IO14 @BASEBOARD_FAB2_LIB.BASEBOARD_FAB2(SCH_1):GND
  16 TP_XDP_CPU_OBSDATA_C2   IO16 @BASEBOARD_FAB2_LIB.BASEBOARD_FAB2(SCH_1):TP_XDP_CPU_OBSDATA_C2
  18 TP_XDP_CPU_OBSDATA_C3   IO18 @BASEBOARD_FAB2_LIB.BASEBOARD_FAB2(SCH_1):TP_XDP_CPU_OBSDATA_C3
  20    GND   IO20 @BASEBOARD_FAB2_LIB.BASEBOARD_FAB2(SCH_1):GND
  22 XDP_OBSFN_B0_MBP6_N   IO22 @BASEBOARD_FAB2_LIB.BASEBOARD_FAB2(SCH_1):XDP_OBSFN_B0_MBP6_N
  24 XDP_OBSFN_B1_MBP7_N   IO24 @BASEBOARD_FAB2_LIB.BASEBOARD_FAB2(SCH_1):XDP_OBSFN_B1_MBP7_N
  26    GND   IO26 @BASEBOARD_FAB2_LIB.BASEBOARD_FAB2(SCH_1):GND
  28 TP_XDP_CPU_OBSDATA_D0   IO28 @BASEBOARD_FAB2_LIB.BASEBOARD_FAB2(SCH_1):TP_XDP_CPU_OBSDATA_D0
  30 TP_XDP_CPU_OBSDATA_D1   IO30 @BASEBOARD_FAB2_LIB.BASEBOARD_FAB2(SCH_1):TP_XDP_CPU_OBSDATA_D1
  32    GND   IO32 @BASEBOARD_FAB2_LIB.BASEBOARD_FAB2(SCH_1):GND
  34 TP_XDP_CPU_OBSDATA_D2   IO34 @BASEBOARD_FAB2_LIB.BASEBOARD_FAB2(SCH_1):TP_XDP_CPU_OBSDATA_D2
  36 TP_XDP_CPU_OBSDATA_D3   IO36 @BASEBOARD_FAB2_LIB.BASEBOARD_FAB2(SCH_1):TP_XDP_CPU_OBSDATA_D3
  38    GND   IO38 @BASEBOARD_FAB2_LIB.BASEBOARD_FAB2(SCH_1):GND
  40 CLK_100M_PCH_XDP_DP   IO40 @BASEBOARD_FAB2_LIB.BASEBOARD_FAB2(SCH_1):CLK_100M_PCH_XDP_DP
  42 CLK_100M_PCH_XDP_DN   IO42 @BASEBOARD_FAB2_LIB.BASEBOARD_FAB2(SCH_1):CLK_100M_PCH_XDP_DN
  44 P1V05_PCH_STBY   IO44 @BASEBOARD_FAB2_LIB.BASEBOARD_FAB2(SCH_1):P1V05_PCH_STBY
  46 XDP_ITP_PMODE   IO46 @BASEBOARD_FAB2_LIB.BASEBOARD_FAB2(SCH_1):XDP_ITP_PMODE
  48 XDP_RST_CO_N   IO48 @BASEBOARD_FAB2_LIB.BASEBOARD_FAB2(SCH_1):XDP_RST_CO_N
  50    GND   IO50 @BASEBOARD_FAB2_LIB.BASEBOARD_FAB2(SCH_1):GND
  51 SMB_HOST_STBY_LVC3_SDA   IO51 @BASEBOARD_FAB2_LIB.BASEBOARD_FAB2(SCH_1):SMB_HOST_STBY_LVC3_SDA
  52 XDP_TDO   IO52 @BASEBOARD_FAB2_LIB.BASEBOARD_FAB2(SCH_1):XDP_TDO
  53 SMB_HOST_STBY_LVC3_SCL   IO53 @BASEBOARD_FAB2_LIB.BASEBOARD_FAB2(SCH_1):SMB_HOST_STBY_LVC3_SCL
  54 XDP_TRST_N   IO54 @BASEBOARD_FAB2_LIB.BASEBOARD_FAB2(SCH_1):XDP_TRST_N
  55 XDP_PCH_TCK1   IO55 @BASEBOARD_FAB2_LIB.BASEBOARD_FAB2(SCH_1):XDP_PCH_TCK1
  56 XDP_TDI   IO56 @BASEBOARD_FAB2_LIB.BASEBOARD_FAB2(SCH_1):XDP_TDI
  57 XDP_CPU_TCK0   IO57 @BASEBOARD_FAB2_LIB.BASEBOARD_FAB2(SCH_1):XDP_CPU_TCK0
  58 XDP_TMS   IO58 @BASEBOARD_FAB2_LIB.BASEBOARD_FAB2(SCH_1):XDP_TMS
  59    GND   IO59 @BASEBOARD_FAB2_LIB.BASEBOARD_FAB2(SCH_1):GND
  60 XDP_PRESENT_N   IO60 @BASEBOARD_FAB2_LIB.BASEBOARD_FAB2(SCH_1):XDP_PRESENT_N

CAP_A_0402V-1.0UF,6.3V,10%,X6SA  I30  C1L5
   1 P1V05_PCH_STBY      A @BASEBOARD_FAB2_LIB.BASEBOARD_FAB2(SCH_1):P1V05_PCH_STBY
   2    GND      B @BASEBOARD_FAB2_LIB.BASEBOARD_FAB2(SCH_1):GND

RES_0402-1.00K,1%,1/16W,CHIP,GA  I37  R2P2
   1 SPI_PCH_IO2      A @BASEBOARD_FAB2_LIB.BASEBOARD_FAB2(SCH_1):SPI_PCH_IO2
   2 XDP_DEBUG_CONSENT_N      B @BASEBOARD_FAB2_LIB.BASEBOARD_FAB2(SCH_1):XDP_DEBUG_CONSENT_N

RES_0402-475.0,1%,1/16W,CHIP,GA  I55  R9A4
   1 CPU_XDP_PRESENT_N      A @BASEBOARD_FAB2_LIB.BASEBOARD_FAB2(SCH_1):CPU_XDP_PRESENT_N
   2 PVCCIO_CPU0      B @BASEBOARD_FAB2_LIB.BASEBOARD_FAB2(SCH_1):PVCCIO_CPU0

RES_0402-150.0,1%,1/16W,CHIP,GA  I56  R1L17
   1 XDP_CPU_PWR_DEBUG_N      A @BASEBOARD_FAB2_LIB.BASEBOARD_FAB2(SCH_1):XDP_CPU_PWR_DEBUG_N
   2 PVCCIO_CPU0      B @BASEBOARD_FAB2_LIB.BASEBOARD_FAB2(SCH_1):PVCCIO_CPU0

RES_0402-1.00K,1%,1/16W,CHIP,GA  I57  R9A17
   1 XDP_ITP_PMODE      A @BASEBOARD_FAB2_LIB.BASEBOARD_FAB2(SCH_1):XDP_ITP_PMODE
   2 P1V05_PCH_STBY      B @BASEBOARD_FAB2_LIB.BASEBOARD_FAB2(SCH_1):P1V05_PCH_STBY

CAP_A_0402V-0.1UF,16V,10%,X7R,A  I59  C9A4
   1 XDP_CPU_PWR_DEBUG_N      A @BASEBOARD_FAB2_LIB.BASEBOARD_FAB2(SCH_1):XDP_CPU_PWR_DEBUG_N
   2    GND      B @BASEBOARD_FAB2_LIB.BASEBOARD_FAB2(SCH_1):GND

RES_0402-1.00K,1%,1/16W,CHIP,GA  I60  R9A15
   1 RST_RSMRST_N      A @BASEBOARD_FAB2_LIB.BASEBOARD_FAB2(SCH_1):RST_RSMRST_N
   2 XDP_RSMRST_N      B @BASEBOARD_FAB2_LIB.BASEBOARD_FAB2(SCH_1):XDP_RSMRST_N

RES_0402-33.2,1%,1/16W,CHIP,G2A  I68  R1L29
   1 FM_DEBUG_RST_BTN_R1_N      A @BASEBOARD_FAB2_LIB.BASEBOARD_FAB2(SCH_1):FM_DEBUG_RST_BTN_R1_N
   2 FM_DEBUG_RST_BTN_N      B @BASEBOARD_FAB2_LIB.BASEBOARD_FAB2(SCH_1):FM_DEBUG_RST_BTN_N

RES_0402-0.0,5%,1/16W,CHIP,G21A  I74  R9A3
   1 XDP_PCH_CPU_TCK0      A @BASEBOARD_FAB2_LIB.BASEBOARD_FAB2(SCH_1):XDP_PCH_CPU_TCK0
   2 XDP_CPU_TCK0      B @BASEBOARD_FAB2_LIB.BASEBOARD_FAB2(SCH_1):XDP_CPU_TCK0

RES_0402-33.2,1%,1/16W,EMPTY,GA  I83  R9A2
   1 XDP_PCH_CPU_TCK0      A @BASEBOARD_FAB2_LIB.BASEBOARD_FAB2(SCH_1):XDP_PCH_CPU_TCK0
   2 XDP_CPU_GTL_TCK_R2      B @BASEBOARD_FAB2_LIB.BASEBOARD_FAB2(SCH_1):XDP_CPU_GTL_TCK_R2

TTL1G07_A_SOP-74LVC1G07,IC,C88B  I85  U1L4
   2 XDP_RST_CO_N      A @BASEBOARD_FAB2_LIB.BASEBOARD_FAB2(SCH_1):XDP_RST_CO_N
   4 FM_DEBUG_RST_BTN_R1_N      Y @BASEBOARD_FAB2_LIB.BASEBOARD_FAB2(SCH_1):FM_DEBUG_RST_BTN_R1_N

CAP_A_0402V-0.1UF,16V,10%,X7R,A  I87  C1L11
   1 P3V3_STBY      A @BASEBOARD_FAB2_LIB.BASEBOARD_FAB2(SCH_1):P3V3_STBY
   2    GND      B @BASEBOARD_FAB2_LIB.BASEBOARD_FAB2(SCH_1):GND

RES_0402-1.00K,1%,1/16W,CHIP,GA  I89  R8E2
   1 XDP_SPI_PCH_MOSI_BOOT_HALT_N      A @BASEBOARD_FAB2_LIB.BASEBOARD_FAB2(SCH_1):XDP_SPI_PCH_MOSI_BOOT_HALT_N
   2 SPI_PCH_MOSI      B @BASEBOARD_FAB2_LIB.BASEBOARD_FAB2(SCH_1):SPI_PCH_MOSI

NPN_DUAL_SSOPLF-MBT3904,EMPTY,A  I93  Q9A1
   2 XDP_CPU_TCK_BUF   B<0> @BASEBOARD_FAB2_LIB.BASEBOARD_FAB2(SCH_1):XDP_CPU_TCK_BUF
   6 XDP_CPU_TCK_BUF   C<0> @BASEBOARD_FAB2_LIB.BASEBOARD_FAB2(SCH_1):XDP_CPU_TCK_BUF
   1 XDP_CPU_GTL_TCK_R2   E<0> @BASEBOARD_FAB2_LIB.BASEBOARD_FAB2(SCH_1):XDP_CPU_GTL_TCK_R2

NPN_DUAL_SSOPLF-MBT3904,EMPTY,A  I94  Q9A1
   5 XDP_CPU_TCK_BUF   B<0> @BASEBOARD_FAB2_LIB.BASEBOARD_FAB2(SCH_1):XDP_CPU_TCK_BUF
   3   P3V3   C<0> @BASEBOARD_FAB2_LIB.BASEBOARD_FAB2(SCH_1):P3V3
   4 XDP_CPU_TCK0   E<0> @BASEBOARD_FAB2_LIB.BASEBOARD_FAB2(SCH_1):XDP_CPU_TCK0

RES_0402-1.00K,1%,1/16W,EMPTY,A  I95  R9A1
   1   P3V3      A @BASEBOARD_FAB2_LIB.BASEBOARD_FAB2(SCH_1):P3V3
   2 XDP_CPU_TCK_BUF      B @BASEBOARD_FAB2_LIB.BASEBOARD_FAB2(SCH_1):XDP_CPU_TCK_BUF

RES_0402-4.75K,1%,1/16W,EMPTY,A  I97  R1L28
   1 P3V3_STBY      A @BASEBOARD_FAB2_LIB.BASEBOARD_FAB2(SCH_1):P3V3_STBY
   2 FM_DEBUG_RST_BTN_R1_N      B @BASEBOARD_FAB2_LIB.BASEBOARD_FAB2(SCH_1):FM_DEBUG_RST_BTN_R1_N


DRAWING: @BASEBOARD_FAB2_LIB.BASEBOARD_FAB2(SCH_1):PAGE112 

NC7SB3157_SMLF-IC,C99406-001  I40  U1M7
   6 FM_CPU1_SKTOCC_LVT3_N      S @BASEBOARD_FAB2_LIB.BASEBOARD_FAB2(SCH_1):FM_CPU1_SKTOCC_LVT3_N
   3 XDP_CPU1_TDO     B0 @BASEBOARD_FAB2_LIB.BASEBOARD_FAB2(SCH_1):XDP_CPU1_TDO
   1 XDP_CPU0_TDO     B1 @BASEBOARD_FAB2_LIB.BASEBOARD_FAB2(SCH_1):XDP_CPU0_TDO
   4 XDP_CPU_TDO      A @BASEBOARD_FAB2_LIB.BASEBOARD_FAB2(SCH_1):XDP_CPU_TDO
   5 P3V3_STBY    VCC @BASEBOARD_FAB2_LIB.BASEBOARD_FAB2(SCH_1):P3V3_STBY
   2    GND    GND @BASEBOARD_FAB2_LIB.BASEBOARD_FAB2(SCH_1):GND

CAP_A_0402V-0.01UF,25V,10%,X7RA  I42  C1M36
   1 P3V3_STBY      A @BASEBOARD_FAB2_LIB.BASEBOARD_FAB2(SCH_1):P3V3_STBY
   2    GND      B @BASEBOARD_FAB2_LIB.BASEBOARD_FAB2(SCH_1):GND

CAP_A_0402V-1.0UF,6.3V,10%,X6SA  I47  C1M37
   1 P3V3_STBY      A @BASEBOARD_FAB2_LIB.BASEBOARD_FAB2(SCH_1):P3V3_STBY
   2    GND      B @BASEBOARD_FAB2_LIB.BASEBOARD_FAB2(SCH_1):GND

RES_0402-100.0,1%,1/16W,CHIP,GA  I49  R6P46
   1 PVCCIO_CPU0      A @BASEBOARD_FAB2_LIB.BASEBOARD_FAB2(SCH_1):PVCCIO_CPU0
   2 XDP_CPU_MBP1_N      B @BASEBOARD_FAB2_LIB.BASEBOARD_FAB2(SCH_1):XDP_CPU_MBP1_N

RES_0402-100.0,1%,1/16W,CHIP,GA  I50  R7P30
   1 PVCCIO_CPU0      A @BASEBOARD_FAB2_LIB.BASEBOARD_FAB2(SCH_1):PVCCIO_CPU0
   2 XDP_CPU_MBP0_N      B @BASEBOARD_FAB2_LIB.BASEBOARD_FAB2(SCH_1):XDP_CPU_MBP0_N

RES_0402-100.0,1%,1/16W,CHIP,GA  I51  R1M3
   1 PVCCIO_CPU0      A @BASEBOARD_FAB2_LIB.BASEBOARD_FAB2(SCH_1):PVCCIO_CPU0
   2 XDP_CPU_PRDY_N      B @BASEBOARD_FAB2_LIB.BASEBOARD_FAB2(SCH_1):XDP_CPU_PRDY_N

RES_0402-100.0,1%,1/16W,CHIP,GA  I53  R4P15
   1 PVCCIO_CPU0      A @BASEBOARD_FAB2_LIB.BASEBOARD_FAB2(SCH_1):PVCCIO_CPU0
   2 XDP_CPU_MBP1_N      B @BASEBOARD_FAB2_LIB.BASEBOARD_FAB2(SCH_1):XDP_CPU_MBP1_N

RES_0402-100.0,1%,1/16W,CHIP,GA  I54  R1M4
   1 PVCCIO_CPU0      A @BASEBOARD_FAB2_LIB.BASEBOARD_FAB2(SCH_1):PVCCIO_CPU0
   2 XDP_CPU_PREQ_N      B @BASEBOARD_FAB2_LIB.BASEBOARD_FAB2(SCH_1):XDP_CPU_PREQ_N

RES_0402-150.0,1%,1/16W,CHIP,GA  I55  R6T7
   1 PVCCIO_CPU1      A @BASEBOARD_FAB2_LIB.BASEBOARD_FAB2(SCH_1):PVCCIO_CPU1
   2 XDP_CPU1_TDO      B @BASEBOARD_FAB2_LIB.BASEBOARD_FAB2(SCH_1):XDP_CPU1_TDO

RES_0402-150.0,1%,1/16W,CHIP,GA  I56  R6T6
   1 PVCCIO_CPU1      A @BASEBOARD_FAB2_LIB.BASEBOARD_FAB2(SCH_1):PVCCIO_CPU1
   2 XDP_CPU1_TDI      B @BASEBOARD_FAB2_LIB.BASEBOARD_FAB2(SCH_1):XDP_CPU1_TDI

RES_0402-100.0,1%,1/16W,CHIP,GA  I57  R4P12
   1 PVCCIO_CPU0      A @BASEBOARD_FAB2_LIB.BASEBOARD_FAB2(SCH_1):PVCCIO_CPU0
   2 XDP_CPU_MBP0_N      B @BASEBOARD_FAB2_LIB.BASEBOARD_FAB2(SCH_1):XDP_CPU_MBP0_N

RES_0402-150.0,1%,1/16W,CHIP,GA  I58  R4P23
   1 PVCCIO_CPU0      A @BASEBOARD_FAB2_LIB.BASEBOARD_FAB2(SCH_1):PVCCIO_CPU0
   2 XDP_CPU0_TDO      B @BASEBOARD_FAB2_LIB.BASEBOARD_FAB2(SCH_1):XDP_CPU0_TDO

RES_0402-150.0,1%,1/16W,CHIP,GA  I59  R4P24
   1 PVCCIO_CPU0      A @BASEBOARD_FAB2_LIB.BASEBOARD_FAB2(SCH_1):PVCCIO_CPU0
   2 XDP_CPU_TDI      B @BASEBOARD_FAB2_LIB.BASEBOARD_FAB2(SCH_1):XDP_CPU_TDI

RES_0402-150.0,1%,1/16W,CHIP,GA  I60  R1L15
   1 PVCCIO_CPU0      A @BASEBOARD_FAB2_LIB.BASEBOARD_FAB2(SCH_1):PVCCIO_CPU0
   2 XDP_CPU_TMS      B @BASEBOARD_FAB2_LIB.BASEBOARD_FAB2(SCH_1):XDP_CPU_TMS

RES_0402-51.1,1.0%,1/16W,CHIP,A  I61  R7P29
   1 XDP_CPU_TCK0      A @BASEBOARD_FAB2_LIB.BASEBOARD_FAB2(SCH_1):XDP_CPU_TCK0
   2    GND      B @BASEBOARD_FAB2_LIB.BASEBOARD_FAB2(SCH_1):GND

RES_0402-1.00K,1%,1/16W,CHIP,GA  I62  R6T5
   1 XDP_CPU_TRST_N      A @BASEBOARD_FAB2_LIB.BASEBOARD_FAB2(SCH_1):XDP_CPU_TRST_N
   2    GND      B @BASEBOARD_FAB2_LIB.BASEBOARD_FAB2(SCH_1):GND

RES_0402-100.0,1%,1/16W,CHIP,GA  I76  R1L39
   1 P1V05_PCH_STBY      A @BASEBOARD_FAB2_LIB.BASEBOARD_FAB2(SCH_1):P1V05_PCH_STBY
   2 XDP_PRDY_N      B @BASEBOARD_FAB2_LIB.BASEBOARD_FAB2(SCH_1):XDP_PRDY_N

RES_0402-100.0,1%,1/16W,CHIP,GA  I77  R1L41
   1 P1V05_PCH_STBY      A @BASEBOARD_FAB2_LIB.BASEBOARD_FAB2(SCH_1):P1V05_PCH_STBY
   2 XDP_PREQ_N      B @BASEBOARD_FAB2_LIB.BASEBOARD_FAB2(SCH_1):XDP_PREQ_N

RES_0402-150.0,1%,1/16W,CHIP,GA  I78  R9A11
   1 P1V05_PCH_STBY      A @BASEBOARD_FAB2_LIB.BASEBOARD_FAB2(SCH_1):P1V05_PCH_STBY
   2 XDP_TDO      B @BASEBOARD_FAB2_LIB.BASEBOARD_FAB2(SCH_1):XDP_TDO

RES_0402-150.0,1%,1/16W,CHIP,GA  I79  R8A13
   1 P1V05_PCH_STBY      A @BASEBOARD_FAB2_LIB.BASEBOARD_FAB2(SCH_1):P1V05_PCH_STBY
   2 XDP_TDI      B @BASEBOARD_FAB2_LIB.BASEBOARD_FAB2(SCH_1):XDP_TDI

RES_0402-150.0,1%,1/16W,CHIP,GA  I80  R8A14
   1 P1V05_PCH_STBY      A @BASEBOARD_FAB2_LIB.BASEBOARD_FAB2(SCH_1):P1V05_PCH_STBY
   2 XDP_TMS      B @BASEBOARD_FAB2_LIB.BASEBOARD_FAB2(SCH_1):XDP_TMS

RES_0402-1.00K,1%,1/16W,CHIP,GA  I85  R3M10
   1 XDP_PCH_CPU_TCK0      A @BASEBOARD_FAB2_LIB.BASEBOARD_FAB2(SCH_1):XDP_PCH_CPU_TCK0
   2    GND      B @BASEBOARD_FAB2_LIB.BASEBOARD_FAB2(SCH_1):GND

RES_0402-1.00K,1%,1/16W,CHIP,GA  I94  R8B2
   1 XDP_TRST_N      A @BASEBOARD_FAB2_LIB.BASEBOARD_FAB2(SCH_1):XDP_TRST_N
   2    GND      B @BASEBOARD_FAB2_LIB.BASEBOARD_FAB2(SCH_1):GND

RES_0402-51.1,1.0%,1/16W,CHIP,A  I95  R8B1
   1 XDP_PCH_TCK1      A @BASEBOARD_FAB2_LIB.BASEBOARD_FAB2(SCH_1):XDP_PCH_TCK1
   2    GND      B @BASEBOARD_FAB2_LIB.BASEBOARD_FAB2(SCH_1):GND

TTL3126_QFNLF-74CBTLV3126,IC,DB  I108  SIZE=4  Summary of common pins:

  Section:  I108(3) U1L1
   1 PWRGD_PVCCIN_CPU0  OE<3> @BASEBOARD_FAB2_LIB.BASEBOARD_FAB2(SCH_1):PWRGD_PVCCIN_CPU0
   2 XDP_TRST_N   A<3> @BASEBOARD_FAB2_LIB.BASEBOARD_FAB2(SCH_1):XDP_TRST_N
   3 XDP_CPU_TRST_N   B<3> @BASEBOARD_FAB2_LIB.BASEBOARD_FAB2(SCH_1):XDP_CPU_TRST_N

  Section:  I108(2) U1L1
   4 PWRGD_PVCCIN_CPU0  OE<2> @BASEBOARD_FAB2_LIB.BASEBOARD_FAB2(SCH_1):PWRGD_PVCCIN_CPU0
   5 XDP_TMS   A<2> @BASEBOARD_FAB2_LIB.BASEBOARD_FAB2(SCH_1):XDP_TMS
   6 XDP_CPU_TMS   B<2> @BASEBOARD_FAB2_LIB.BASEBOARD_FAB2(SCH_1):XDP_CPU_TMS

  Section:  I108(1) U1L1
  10 PWRGD_PVCCIN_CPU0  OE<1> @BASEBOARD_FAB2_LIB.BASEBOARD_FAB2(SCH_1):PWRGD_PVCCIN_CPU0
   9 XDP_TDO   A<1> @BASEBOARD_FAB2_LIB.BASEBOARD_FAB2(SCH_1):XDP_TDO
   8 XDP_CPU_TDO   B<1> @BASEBOARD_FAB2_LIB.BASEBOARD_FAB2(SCH_1):XDP_CPU_TDO

  Section:  I108 U1L1
  13 PWRGD_PVCCIN_CPU0  OE<0> @BASEBOARD_FAB2_LIB.BASEBOARD_FAB2(SCH_1):PWRGD_PVCCIN_CPU0
  12 XDP_TDI   A<0> @BASEBOARD_FAB2_LIB.BASEBOARD_FAB2(SCH_1):XDP_TDI
  11 XDP_CPU_TDI   B<0> @BASEBOARD_FAB2_LIB.BASEBOARD_FAB2(SCH_1):XDP_CPU_TDI

TTL3126_QFNLF-74CBTLV3126,IC,DB  I109  SIZE=4  Summary of common pins:

  Section:  I109(3) U1L5
   1 PWRGD_PVCCIN_CPU0  OE<3> @BASEBOARD_FAB2_LIB.BASEBOARD_FAB2(SCH_1):PWRGD_PVCCIN_CPU0
   2 XDP_OBSFN_B1_MBP7_N   A<3> @BASEBOARD_FAB2_LIB.BASEBOARD_FAB2(SCH_1):XDP_OBSFN_B1_MBP7_N
   3 XDP_CPU_OBSFN_B1_MBP7_N   B<3> @BASEBOARD_FAB2_LIB.BASEBOARD_FAB2(SCH_1):XDP_CPU_OBSFN_B1_MBP7_N

  Section:  I109(2) U1L5
   4 PWRGD_PVCCIN_CPU0  OE<2> @BASEBOARD_FAB2_LIB.BASEBOARD_FAB2(SCH_1):PWRGD_PVCCIN_CPU0
   5 XDP_OBSFN_B0_MBP6_N   A<2> @BASEBOARD_FAB2_LIB.BASEBOARD_FAB2(SCH_1):XDP_OBSFN_B0_MBP6_N
   6 XDP_CPU_OBSFN_B0_MBP6_N   B<2> @BASEBOARD_FAB2_LIB.BASEBOARD_FAB2(SCH_1):XDP_CPU_OBSFN_B0_MBP6_N

  Section:  I109(1) U1L5
  10 PWRGD_PVCCIN_CPU0  OE<1> @BASEBOARD_FAB2_LIB.BASEBOARD_FAB2(SCH_1):PWRGD_PVCCIN_CPU0
   9 XDP_PRDY_N   A<1> @BASEBOARD_FAB2_LIB.BASEBOARD_FAB2(SCH_1):XDP_PRDY_N
   8 XDP_CPU_PRDY_N   B<1> @BASEBOARD_FAB2_LIB.BASEBOARD_FAB2(SCH_1):XDP_CPU_PRDY_N

  Section:  I109 U1L5
  13 PWRGD_PVCCIN_CPU0  OE<0> @BASEBOARD_FAB2_LIB.BASEBOARD_FAB2(SCH_1):PWRGD_PVCCIN_CPU0
  12 XDP_PREQ_N   A<0> @BASEBOARD_FAB2_LIB.BASEBOARD_FAB2(SCH_1):XDP_PREQ_N
  11 XDP_CPU_PREQ_N   B<0> @BASEBOARD_FAB2_LIB.BASEBOARD_FAB2(SCH_1):XDP_CPU_PREQ_N

RES_0402-100.0,1%,1/16W,CHIP,GA  I120  R6T9
   1 PVCCIO_CPU0      A @BASEBOARD_FAB2_LIB.BASEBOARD_FAB2(SCH_1):PVCCIO_CPU0
   2 XDP_CPU_OBSFN_B1_MBP7_N      B @BASEBOARD_FAB2_LIB.BASEBOARD_FAB2(SCH_1):XDP_CPU_OBSFN_B1_MBP7_N

RES_0402-100.0,1%,1/16W,CHIP,GA  I121  R6T8
   1 PVCCIO_CPU0      A @BASEBOARD_FAB2_LIB.BASEBOARD_FAB2(SCH_1):PVCCIO_CPU0
   2 XDP_CPU_OBSFN_B0_MBP6_N      B @BASEBOARD_FAB2_LIB.BASEBOARD_FAB2(SCH_1):XDP_CPU_OBSFN_B0_MBP6_N

74CBTLV1G125_SMLF-IC,C88177-00A  I127  U1M4
   4 XDP_CPU1_TDI      B @BASEBOARD_FAB2_LIB.BASEBOARD_FAB2(SCH_1):XDP_CPU1_TDI
   1 FM_CPU1_SKTOCC_LVT3_N   OE_N @BASEBOARD_FAB2_LIB.BASEBOARD_FAB2(SCH_1):FM_CPU1_SKTOCC_LVT3_N
   2 XDP_CPU0_TDO      A @BASEBOARD_FAB2_LIB.BASEBOARD_FAB2(SCH_1):XDP_CPU0_TDO

CAP_A_0402V-0.01UF,25V,10%,X7RA  I131  C1M30
   1 P3V3_STBY      A @BASEBOARD_FAB2_LIB.BASEBOARD_FAB2(SCH_1):P3V3_STBY
   2    GND      B @BASEBOARD_FAB2_LIB.BASEBOARD_FAB2(SCH_1):GND

CAP_0402-1.0UF,16V,10%,X6S,D97A  I136  C1L1
   1 P3V3_STBY      A @BASEBOARD_FAB2_LIB.BASEBOARD_FAB2(SCH_1):P3V3_STBY
   2    GND      B @BASEBOARD_FAB2_LIB.BASEBOARD_FAB2(SCH_1):GND

CAP_0402-1.0UF,16V,10%,X6S,D97A  I140  C1L19
   1 P3V3_STBY      A @BASEBOARD_FAB2_LIB.BASEBOARD_FAB2(SCH_1):P3V3_STBY
   2    GND      B @BASEBOARD_FAB2_LIB.BASEBOARD_FAB2(SCH_1):GND


DRAWING: @BASEBOARD_FAB2_LIB.BASEBOARD_FAB2(SCH_1):PAGE113 

NC7SB3157_SMLF-IC,C99406-001  I107  U1M2
   6 FM_CPU1_CD_PRES_N      S @BASEBOARD_FAB2_LIB.BASEBOARD_FAB2(SCH_1):FM_CPU1_CD_PRES_N
   3 JTAG_MCP_CPU1_TDO     B0 @BASEBOARD_FAB2_LIB.BASEBOARD_FAB2(SCH_1):JTAG_MCP_CPU1_TDO
   1 JTAG_MCP_CPU0_TDO     B1 @BASEBOARD_FAB2_LIB.BASEBOARD_FAB2(SCH_1):JTAG_MCP_CPU0_TDO
   4 JTAG_MCP_MUX_TDO      A @BASEBOARD_FAB2_LIB.BASEBOARD_FAB2(SCH_1):JTAG_MCP_MUX_TDO
   5 P3V3_STBY    VCC @BASEBOARD_FAB2_LIB.BASEBOARD_FAB2(SCH_1):P3V3_STBY
   2    GND    GND @BASEBOARD_FAB2_LIB.BASEBOARD_FAB2(SCH_1):GND

CAP_A_0402V-0.01UF,25V,10%,X7RA  I116  C1M31
   1 P3V3_STBY      A @BASEBOARD_FAB2_LIB.BASEBOARD_FAB2(SCH_1):P3V3_STBY
   2    GND      B @BASEBOARD_FAB2_LIB.BASEBOARD_FAB2(SCH_1):GND

CAP_A_0402V-1.0UF,6.3V,10%,X6SA  I117  C1M32
   1 P3V3_STBY      A @BASEBOARD_FAB2_LIB.BASEBOARD_FAB2(SCH_1):P3V3_STBY
   2    GND      B @BASEBOARD_FAB2_LIB.BASEBOARD_FAB2(SCH_1):GND

CAP_A_0402V-0.01UF,25V,10%,X7RA  I119  C1M28
   1 P3V3_STBY      A @BASEBOARD_FAB2_LIB.BASEBOARD_FAB2(SCH_1):P3V3_STBY
   2    GND      B @BASEBOARD_FAB2_LIB.BASEBOARD_FAB2(SCH_1):GND

74CBTLV1G125_SMLF-IC,C88177-00A  I127  U1M6
   4 JTAG_MCP_CPU1_TDI      B @BASEBOARD_FAB2_LIB.BASEBOARD_FAB2(SCH_1):JTAG_MCP_CPU1_TDI
   1 FM_CPU0_AND_CPU1_MCP_PRES   OE_N @BASEBOARD_FAB2_LIB.BASEBOARD_FAB2(SCH_1):FM_CPU0_AND_CPU1_MCP_PRES
   2 JTAG_MCP_CPU0_TDO      A @BASEBOARD_FAB2_LIB.BASEBOARD_FAB2(SCH_1):JTAG_MCP_CPU0_TDO

CAP_A_0402V-0.1UF,16V,10%,X7R,A  I147  C1M29
   1 P1V8_MCP_CPU0      A @BASEBOARD_FAB2_LIB.BASEBOARD_FAB2(SCH_1):P1V8_MCP_CPU0
   2    GND      B @BASEBOARD_FAB2_LIB.BASEBOARD_FAB2(SCH_1):GND

RES_0402-1.00K,1%,1/16W,CHIP,GA  I168  R9B14
   1 PWRGD_CPU0_G      A @BASEBOARD_FAB2_LIB.BASEBOARD_FAB2(SCH_1):PWRGD_CPU0_G
   2 PWRGD_CPU0_G_R      B @BASEBOARD_FAB2_LIB.BASEBOARD_FAB2(SCH_1):PWRGD_CPU0_G_R

SCONN10_C12536004_SMLF-CONN,C1A  I175  J9B4
   1 JTAG_MCP_TCK_R    IO1 @BASEBOARD_FAB2_LIB.BASEBOARD_FAB2(SCH_1):JTAG_MCP_TCK_R
   2    GND    IO2 @BASEBOARD_FAB2_LIB.BASEBOARD_FAB2(SCH_1):GND
   3 JTAG_MCP_MUX_TDO    IO3 @BASEBOARD_FAB2_LIB.BASEBOARD_FAB2(SCH_1):JTAG_MCP_MUX_TDO
   4 P1V8_MCP_CPU0    IO4 @BASEBOARD_FAB2_LIB.BASEBOARD_FAB2(SCH_1):P1V8_MCP_CPU0
   5 JTAG_MCP_TMS_R    IO5 @BASEBOARD_FAB2_LIB.BASEBOARD_FAB2(SCH_1):JTAG_MCP_TMS_R
   6 JTAG_MCP_TRST_N    IO6 @BASEBOARD_FAB2_LIB.BASEBOARD_FAB2(SCH_1):JTAG_MCP_TRST_N
   7 PWRGD_CPU0_G_R    IO7 @BASEBOARD_FAB2_LIB.BASEBOARD_FAB2(SCH_1):PWRGD_CPU0_G_R
   8 TP_JTAG_MCP_IO8_RSVD    IO8 @BASEBOARD_FAB2_LIB.BASEBOARD_FAB2(SCH_1):TP_JTAG_MCP_IO8_RSVD
   9 JTAG_MCP_MUX_TDI    IO9 @BASEBOARD_FAB2_LIB.BASEBOARD_FAB2(SCH_1):JTAG_MCP_MUX_TDI
  10    GND   IO10 @BASEBOARD_FAB2_LIB.BASEBOARD_FAB2(SCH_1):GND

RES_0402-1.00K,1%,1/16W,CHIP,GA  I179  R9B9
   1 JTAG_MCP_TCK      A @BASEBOARD_FAB2_LIB.BASEBOARD_FAB2(SCH_1):JTAG_MCP_TCK
   2    GND      B @BASEBOARD_FAB2_LIB.BASEBOARD_FAB2(SCH_1):GND

RES_0402-49.9,1%,1/16W,CHIP,G2A  I180  R9B10
   1 JTAG_MCP_TCK      A @BASEBOARD_FAB2_LIB.BASEBOARD_FAB2(SCH_1):JTAG_MCP_TCK
   2 JTAG_MCP_TCK_R1      B @BASEBOARD_FAB2_LIB.BASEBOARD_FAB2(SCH_1):JTAG_MCP_TCK_R1

74CBTLV1G125_SMLF-IC,C88177-00A  I185  U9A5
   4    GND      B @BASEBOARD_FAB2_LIB.BASEBOARD_FAB2(SCH_1):GND
   1 FM_CPU0_OR_CPU1_MCP_PRES   OE_N @BASEBOARD_FAB2_LIB.BASEBOARD_FAB2(SCH_1):FM_CPU0_OR_CPU1_MCP_PRES
   2 JTAG_MCP_TCK_R1      A @BASEBOARD_FAB2_LIB.BASEBOARD_FAB2(SCH_1):JTAG_MCP_TCK_R1

74CBTLV1G125_SMLF-IC,C88177-00A  I190  U6M1
   4 JTAG_MCP_CPU1_TDI_R      B @BASEBOARD_FAB2_LIB.BASEBOARD_FAB2(SCH_1):JTAG_MCP_CPU1_TDI_R
   1 FM_CPU1_PKGID1   OE_N @BASEBOARD_FAB2_LIB.BASEBOARD_FAB2(SCH_1):FM_CPU1_PKGID1
   2 P1V8_MCP_CPU1      A @BASEBOARD_FAB2_LIB.BASEBOARD_FAB2(SCH_1):P1V8_MCP_CPU1

RES_0402-49.9,1%,1/16W,CHIP,G2A  I195  R1M22
   1 JTAG_MCP_TMS_R1      A @BASEBOARD_FAB2_LIB.BASEBOARD_FAB2(SCH_1):JTAG_MCP_TMS_R1
   2 JTAG_MCP_TMS      B @BASEBOARD_FAB2_LIB.BASEBOARD_FAB2(SCH_1):JTAG_MCP_TMS

74CBTLV1G125_SMLF-IC,C88177-00A  I196  U1M5
   4 JTAG_MCP_TMS_R1      B @BASEBOARD_FAB2_LIB.BASEBOARD_FAB2(SCH_1):JTAG_MCP_TMS_R1
   1 FM_CPU0_OR_CPU1_MCP_PRES   OE_N @BASEBOARD_FAB2_LIB.BASEBOARD_FAB2(SCH_1):FM_CPU0_OR_CPU1_MCP_PRES
   2 P1V8_MCP_CPU0      A @BASEBOARD_FAB2_LIB.BASEBOARD_FAB2(SCH_1):P1V8_MCP_CPU0

RES_0402-1.00K,1%,1/16W,EMPTY,A  I199  R1M23
   1 JTAG_MCP_TRST_N      A @BASEBOARD_FAB2_LIB.BASEBOARD_FAB2(SCH_1):JTAG_MCP_TRST_N
   2    GND      B @BASEBOARD_FAB2_LIB.BASEBOARD_FAB2(SCH_1):GND

RES_0402-1.00K,1%,1/16W,CHIP,GA  I202  R1M19
   1 P1V8_MCP_CPU0      A @BASEBOARD_FAB2_LIB.BASEBOARD_FAB2(SCH_1):P1V8_MCP_CPU0
   2 JTAG_MCP_TMS      B @BASEBOARD_FAB2_LIB.BASEBOARD_FAB2(SCH_1):JTAG_MCP_TMS

RES_0402-1.00K,1%,1/16W,CHIP,GA  I203  R9B12
   1 P1V8_MCP_CPU0      A @BASEBOARD_FAB2_LIB.BASEBOARD_FAB2(SCH_1):P1V8_MCP_CPU0
   2 JTAG_MCP_MUX_TDO      B @BASEBOARD_FAB2_LIB.BASEBOARD_FAB2(SCH_1):JTAG_MCP_MUX_TDO

RES_0402-1.00K,1%,1/16W,CHIP,GA  I204  R1M20
   1 P1V8_MCP_CPU0      A @BASEBOARD_FAB2_LIB.BASEBOARD_FAB2(SCH_1):P1V8_MCP_CPU0
   2 JTAG_MCP_MUX_TDI      B @BASEBOARD_FAB2_LIB.BASEBOARD_FAB2(SCH_1):JTAG_MCP_MUX_TDI

RES_0402-1.00K,1%,1/16W,CHIP,GA  I205  R1M21
   1 P1V8_MCP_CPU0      A @BASEBOARD_FAB2_LIB.BASEBOARD_FAB2(SCH_1):P1V8_MCP_CPU0
   2 JTAG_MCP_TRST_N      B @BASEBOARD_FAB2_LIB.BASEBOARD_FAB2(SCH_1):JTAG_MCP_TRST_N

74CBTLV1G125_SMLF-IC,C88177-00A  I206  U4R1
   4 JTAG_MCP_CPU0_TDI_R      B @BASEBOARD_FAB2_LIB.BASEBOARD_FAB2(SCH_1):JTAG_MCP_CPU0_TDI_R
   1 FM_CPU0_PKGID1   OE_N @BASEBOARD_FAB2_LIB.BASEBOARD_FAB2(SCH_1):FM_CPU0_PKGID1
   2 P1V8_MCP_CPU0      A @BASEBOARD_FAB2_LIB.BASEBOARD_FAB2(SCH_1):P1V8_MCP_CPU0

RES_0402-0.0,5%,1/16W,CHIP,G21A  I239  R9B11
   1 JTAG_MCP_TCK      A @BASEBOARD_FAB2_LIB.BASEBOARD_FAB2(SCH_1):JTAG_MCP_TCK
   2 JTAG_MCP_TCK_R      B @BASEBOARD_FAB2_LIB.BASEBOARD_FAB2(SCH_1):JTAG_MCP_TCK_R

RES_0402-0.0,5%,1/16W,CHIP,G21A  I240  R9B13
   1 JTAG_MCP_TMS      A @BASEBOARD_FAB2_LIB.BASEBOARD_FAB2(SCH_1):JTAG_MCP_TMS
   2 JTAG_MCP_TMS_R      B @BASEBOARD_FAB2_LIB.BASEBOARD_FAB2(SCH_1):JTAG_MCP_TMS_R

CAP_A_0402V-0.1UF,16V,10%,X7R,A  I246  C4R2
   1 JTAG_MCP_CPU0_TDI_R      A @BASEBOARD_FAB2_LIB.BASEBOARD_FAB2(SCH_1):JTAG_MCP_CPU0_TDI_R
   2    GND      B @BASEBOARD_FAB2_LIB.BASEBOARD_FAB2(SCH_1):GND

CAP_A_0402V-0.1UF,16V,10%,X7R,A  I248  C1M33
   1 JTAG_MCP_TMS_R1      A @BASEBOARD_FAB2_LIB.BASEBOARD_FAB2(SCH_1):JTAG_MCP_TMS_R1
   2    GND      B @BASEBOARD_FAB2_LIB.BASEBOARD_FAB2(SCH_1):GND

CAP_A_0402V-0.1UF,16V,10%,X7R,A  I250  C6M6
   1 JTAG_MCP_CPU1_TDI_R      A @BASEBOARD_FAB2_LIB.BASEBOARD_FAB2(SCH_1):JTAG_MCP_CPU1_TDI_R
   2    GND      B @BASEBOARD_FAB2_LIB.BASEBOARD_FAB2(SCH_1):GND

NC7SB3157_SMLF-IC,C99406-001  I255  U2M1
   6 FM_CPU0_CD_PRES      S @BASEBOARD_FAB2_LIB.BASEBOARD_FAB2(SCH_1):FM_CPU0_CD_PRES
   3 JTAG_MCP_CPU1_TDI     B0 @BASEBOARD_FAB2_LIB.BASEBOARD_FAB2(SCH_1):JTAG_MCP_CPU1_TDI
   1 JTAG_MCP_CPU0_TDI     B1 @BASEBOARD_FAB2_LIB.BASEBOARD_FAB2(SCH_1):JTAG_MCP_CPU0_TDI
   4 JTAG_MCP_MUX_TDI      A @BASEBOARD_FAB2_LIB.BASEBOARD_FAB2(SCH_1):JTAG_MCP_MUX_TDI
   5 P3V3_STBY    VCC @BASEBOARD_FAB2_LIB.BASEBOARD_FAB2(SCH_1):P3V3_STBY
   2    GND    GND @BASEBOARD_FAB2_LIB.BASEBOARD_FAB2(SCH_1):GND

CAP_A_0402V-0.01UF,25V,10%,X7RA  I265  C1M34
   1 P3V3_STBY      A @BASEBOARD_FAB2_LIB.BASEBOARD_FAB2(SCH_1):P3V3_STBY
   2    GND      B @BASEBOARD_FAB2_LIB.BASEBOARD_FAB2(SCH_1):GND

CAP_A_0402V-0.01UF,25V,10%,X7RA  I266  C1M35
   1 P3V3_STBY      A @BASEBOARD_FAB2_LIB.BASEBOARD_FAB2(SCH_1):P3V3_STBY
   2    GND      B @BASEBOARD_FAB2_LIB.BASEBOARD_FAB2(SCH_1):GND

CAP_A_0402V-0.01UF,25V,10%,X7RA  I267  C1L20
   1 P3V3_STBY      A @BASEBOARD_FAB2_LIB.BASEBOARD_FAB2(SCH_1):P3V3_STBY
   2    GND      B @BASEBOARD_FAB2_LIB.BASEBOARD_FAB2(SCH_1):GND

RES_0402-1.00K,1%,1/16W,CHIP,GA  I270  R4R6
   1 JTAG_MCP_CPU0_TDI_R      A @BASEBOARD_FAB2_LIB.BASEBOARD_FAB2(SCH_1):JTAG_MCP_CPU0_TDI_R
   2 JTAG_MCP_CPU0_TDI      B @BASEBOARD_FAB2_LIB.BASEBOARD_FAB2(SCH_1):JTAG_MCP_CPU0_TDI

RES_0402-1.00K,1%,1/16W,CHIP,GA  I271  R6M8
   1 JTAG_MCP_CPU1_TDI_R      A @BASEBOARD_FAB2_LIB.BASEBOARD_FAB2(SCH_1):JTAG_MCP_CPU1_TDI_R
   2 JTAG_MCP_CPU1_TDI      B @BASEBOARD_FAB2_LIB.BASEBOARD_FAB2(SCH_1):JTAG_MCP_CPU1_TDI

RES_0402-0.0,5%,1/16W,CHIP,G21A  I272  R5W1
   1 P1V8_MCP_CPU0      A @BASEBOARD_FAB2_LIB.BASEBOARD_FAB2(SCH_1):P1V8_MCP_CPU0
   2 JTAG_MCP_CPU0_TDI_R      B @BASEBOARD_FAB2_LIB.BASEBOARD_FAB2(SCH_1):JTAG_MCP_CPU0_TDI_R

RES_0402-0.0,5%,1/16W,CHIP,G21A  I273  R5W2
   1 P1V8_MCP_CPU1      A @BASEBOARD_FAB2_LIB.BASEBOARD_FAB2(SCH_1):P1V8_MCP_CPU1
   2 JTAG_MCP_CPU1_TDI_R      B @BASEBOARD_FAB2_LIB.BASEBOARD_FAB2(SCH_1):JTAG_MCP_CPU1_TDI_R


DRAWING: @BASEBOARD_FAB2_LIB.BASEBOARD_FAB2(SCH_1):PAGE114 

LBG_CORE_QAT_EXT_D_BGA1-IC,H91A  I40  U7C1
 A39 CLK_100M_PCH_XDP_DN CLKOUT_ITPXDPN @BASEBOARD_FAB2_LIB.BASEBOARD_FAB2(SCH_1):CLK_100M_PCH_XDP_DN
 C39 CLK_100M_PCH_XDP_DP CLKOUT_ITPXDPP @BASEBOARD_FAB2_LIB.BASEBOARD_FAB2(SCH_1):CLK_100M_PCH_XDP_DP
 A32 TP_CLK_100M_NSSCC0_DN CLKOUT_NSSCCAP0N @BASEBOARD_FAB2_LIB.BASEBOARD_FAB2(SCH_1):TP_CLK_100M_NSSCC0_DN
 C32 TP_CLK_100M_NSSCC0_DP CLKOUT_NSSCCAP0P @BASEBOARD_FAB2_LIB.BASEBOARD_FAB2(SCH_1):TP_CLK_100M_NSSCC0_DP
 B38 TP_CLK_100M_NSSCC1_DN CLKOUT_NSSCCAP1N @BASEBOARD_FAB2_LIB.BASEBOARD_FAB2(SCH_1):TP_CLK_100M_NSSCC1_DN
 D38 TP_CLK_100M_NSSCC1_DP CLKOUT_NSSCCAP1P @BASEBOARD_FAB2_LIB.BASEBOARD_FAB2(SCH_1):TP_CLK_100M_NSSCC1_DP
 B29 CLK_100M_BMC_PE_DN CLKOUT_PLAT0N @BASEBOARD_FAB2_LIB.BASEBOARD_FAB2(SCH_1):CLK_100M_BMC_PE_DN
 D29 CLK_100M_BMC_PE_DP CLKOUT_PLAT0P @BASEBOARD_FAB2_LIB.BASEBOARD_FAB2(SCH_1):CLK_100M_BMC_PE_DP
 B40 TP_CLK_100M_PLAT1_DN CLKOUT_PLAT1N @BASEBOARD_FAB2_LIB.BASEBOARD_FAB2(SCH_1):TP_CLK_100M_PLAT1_DN
 D40 TP_CLK_100M_PLAT1_DP CLKOUT_PLAT1P @BASEBOARD_FAB2_LIB.BASEBOARD_FAB2(SCH_1):TP_CLK_100M_PLAT1_DP
 K27 CLK_100M_M2_DN CLKOUT_SRCN<15> @BASEBOARD_FAB2_LIB.BASEBOARD_FAB2(SCH_1):CLK_100M_M2_DN
 C20 CLK_100M_SPRV_DN CLKOUT_SRCN<14> @BASEBOARD_FAB2_LIB.BASEBOARD_FAB2(SCH_1):CLK_100M_SPRV_DN
 C24     NC CLKOUT_SRCN<13>     NC
 K24     NC CLKOUT_SRCN<12>     NC
 B21 CLK_100M_MEZZ4_DN CLKOUT_SRCN<11> @BASEBOARD_FAB2_LIB.BASEBOARD_FAB2(SCH_1):CLK_100M_MEZZ4_DN
 B23 CLK_100M_MEZZ3_DN CLKOUT_SRCN<10> @BASEBOARD_FAB2_LIB.BASEBOARD_FAB2(SCH_1):CLK_100M_MEZZ3_DN
 J26 CLK_100M_MEZZ2_DN CLKOUT_SRCN<9> @BASEBOARD_FAB2_LIB.BASEBOARD_FAB2(SCH_1):CLK_100M_MEZZ2_DN
 D31 CLK_100M_MEZZ1_DN CLKOUT_SRCN<8> @BASEBOARD_FAB2_LIB.BASEBOARD_FAB2(SCH_1):CLK_100M_MEZZ1_DN
 H31 CLK_100M_PCH_SLOTX24_S5_DN CLKOUT_SRCN<7> @BASEBOARD_FAB2_LIB.BASEBOARD_FAB2(SCH_1):CLK_100M_PCH_SLOTX24_S5_DN
 D33 CLK_100M_PCH_SLOTX24_S4_DN CLKOUT_SRCN<6> @BASEBOARD_FAB2_LIB.BASEBOARD_FAB2(SCH_1):CLK_100M_PCH_SLOTX24_S4_DN
 J40 CLK_100M_PCH_SLOTX24_S3_DN CLKOUT_SRCN<5> @BASEBOARD_FAB2_LIB.BASEBOARD_FAB2(SCH_1):CLK_100M_PCH_SLOTX24_S3_DN
 A28 CLK_100M_PCH_SLOTX24_S2_DN CLKOUT_SRCN<4> @BASEBOARD_FAB2_LIB.BASEBOARD_FAB2(SCH_1):CLK_100M_PCH_SLOTX24_S2_DN
 K42 CLK_100M_PCH_SLOTX24_S1_DN CLKOUT_SRCN<3> @BASEBOARD_FAB2_LIB.BASEBOARD_FAB2(SCH_1):CLK_100M_PCH_SLOTX24_S1_DN
 J33 CLK_100M_PCH_SLOTX24_S0_DN CLKOUT_SRCN<2> @BASEBOARD_FAB2_LIB.BASEBOARD_FAB2(SCH_1):CLK_100M_PCH_SLOTX24_S0_DN
 K35 CLK_100M_DB1200_DN CLKOUT_SRCN<1> @BASEBOARD_FAB2_LIB.BASEBOARD_FAB2(SCH_1):CLK_100M_DB1200_DN
 K38 CLK_100M_AIRMAX8_PE1_DN CLKOUT_SRCN<0> @BASEBOARD_FAB2_LIB.BASEBOARD_FAB2(SCH_1):CLK_100M_AIRMAX8_PE1_DN
 H27 CLK_100M_M2_DP CLKOUT_SRCP<15> @BASEBOARD_FAB2_LIB.BASEBOARD_FAB2(SCH_1):CLK_100M_M2_DP
 A20 CLK_100M_SPRV_DP CLKOUT_SRCP<14> @BASEBOARD_FAB2_LIB.BASEBOARD_FAB2(SCH_1):CLK_100M_SPRV_DP
 A24     NC CLKOUT_SRCP<13>     NC
 H24     NC CLKOUT_SRCP<12>     NC
 D21 CLK_100M_MEZZ4_DP CLKOUT_SRCP<11> @BASEBOARD_FAB2_LIB.BASEBOARD_FAB2(SCH_1):CLK_100M_MEZZ4_DP
 D23 CLK_100M_MEZZ3_DP CLKOUT_SRCP<10> @BASEBOARD_FAB2_LIB.BASEBOARD_FAB2(SCH_1):CLK_100M_MEZZ3_DP
 G26 CLK_100M_MEZZ2_DP CLKOUT_SRCP<9> @BASEBOARD_FAB2_LIB.BASEBOARD_FAB2(SCH_1):CLK_100M_MEZZ2_DP
 B31 CLK_100M_MEZZ1_DP CLKOUT_SRCP<8> @BASEBOARD_FAB2_LIB.BASEBOARD_FAB2(SCH_1):CLK_100M_MEZZ1_DP
 K31 CLK_100M_PCH_SLOTX24_S5_DP CLKOUT_SRCP<7> @BASEBOARD_FAB2_LIB.BASEBOARD_FAB2(SCH_1):CLK_100M_PCH_SLOTX24_S5_DP
 B33 CLK_100M_PCH_SLOTX24_S4_DP CLKOUT_SRCP<6> @BASEBOARD_FAB2_LIB.BASEBOARD_FAB2(SCH_1):CLK_100M_PCH_SLOTX24_S4_DP
 G40 CLK_100M_PCH_SLOTX24_S3_DP CLKOUT_SRCP<5> @BASEBOARD_FAB2_LIB.BASEBOARD_FAB2(SCH_1):CLK_100M_PCH_SLOTX24_S3_DP
 C28 CLK_100M_PCH_SLOTX24_S2_DP CLKOUT_SRCP<4> @BASEBOARD_FAB2_LIB.BASEBOARD_FAB2(SCH_1):CLK_100M_PCH_SLOTX24_S2_DP
 H42 CLK_100M_PCH_SLOTX24_S1_DP CLKOUT_SRCP<3> @BASEBOARD_FAB2_LIB.BASEBOARD_FAB2(SCH_1):CLK_100M_PCH_SLOTX24_S1_DP
 G33 CLK_100M_PCH_SLOTX24_S0_DP CLKOUT_SRCP<2> @BASEBOARD_FAB2_LIB.BASEBOARD_FAB2(SCH_1):CLK_100M_PCH_SLOTX24_S0_DP
 H35 CLK_100M_DB1200_DP CLKOUT_SRCP<1> @BASEBOARD_FAB2_LIB.BASEBOARD_FAB2(SCH_1):CLK_100M_DB1200_DP
 H38 CLK_100M_AIRMAX8_PE1_DP CLKOUT_SRCP<0> @BASEBOARD_FAB2_LIB.BASEBOARD_FAB2(SCH_1):CLK_100M_AIRMAX8_PE1_DP
BW50 CLK_48M_USB_BMC CLOCKSE_BMCCLK @BASEBOARD_FAB2_LIB.BASEBOARD_FAB2(SCH_1):CLK_48M_USB_BMC
BY51 H_PMSYNC_CLK_24M_R CLOCKSE_PMSYNCCLK1 @BASEBOARD_FAB2_LIB.BASEBOARD_FAB2(SCH_1):H_PMSYNC_CLK_24M_R
BV51 TP_CLK_24M_PMSYNC2 CLOCKSE_PMSYNCCLK2 @BASEBOARD_FAB2_LIB.BASEBOARD_FAB2(SCH_1):TP_CLK_24M_PMSYNC2
 A26 TP_PCH_RSVD65 RSVD<65> @BASEBOARD_FAB2_LIB.BASEBOARD_FAB2(SCH_1):TP_PCH_RSVD65
 C26 TP_PCH_RSVD64 RSVD<64> @BASEBOARD_FAB2_LIB.BASEBOARD_FAB2(SCH_1):TP_PCH_RSVD64
 K17 XTAL_33K_RTC1  RTCX1 @BASEBOARD_FAB2_LIB.BASEBOARD_FAB2(SCH_1):XTAL_33K_RTC1
 H17 XTAL_33K_RTC2  RTCX2 @BASEBOARD_FAB2_LIB.BASEBOARD_FAB2(SCH_1):XTAL_33K_RTC2
 G44 A_PCH_XCLK_BIASREF XCLK_BIASREF @BASEBOARD_FAB2_LIB.BASEBOARD_FAB2(SCH_1):A_PCH_XCLK_BIASREF
 B35 XTAL_PCH_48M_IN XTAL_IN @BASEBOARD_FAB2_LIB.BASEBOARD_FAB2(SCH_1):XTAL_PCH_48M_IN
 D35 XTAL_PCH_48M_OUT XTAL_OUT @BASEBOARD_FAB2_LIB.BASEBOARD_FAB2(SCH_1):XTAL_PCH_48M_OUT

CAP_0402LF-15.0PF,50V,5%,COG,AA  I47  C7C5
   1 XTAL_PCH_48M_OUT      A @BASEBOARD_FAB2_LIB.BASEBOARD_FAB2(SCH_1):XTAL_PCH_48M_OUT
   2    GND      B @BASEBOARD_FAB2_LIB.BASEBOARD_FAB2(SCH_1):GND

RES_0603-200K,0.1%,1/10W,CHIP,A  I48  R7C1
   1 XTAL_PCH_48M_IN      A @BASEBOARD_FAB2_LIB.BASEBOARD_FAB2(SCH_1):XTAL_PCH_48M_IN
   2 XTAL_PCH_48M_OUT      B @BASEBOARD_FAB2_LIB.BASEBOARD_FAB2(SCH_1):XTAL_PCH_48M_OUT

CRYSTAL_2013-48.000MHZ,IC,D717A  I49  Y7C1
   1 XTAL_PCH_48M_IN      A @BASEBOARD_FAB2_LIB.BASEBOARD_FAB2(SCH_1):XTAL_PCH_48M_IN
   3 XTAL_PCH_48M_OUT      B @BASEBOARD_FAB2_LIB.BASEBOARD_FAB2(SCH_1):XTAL_PCH_48M_OUT

CAP_0402LF-15.0PF,50V,5%,COG,AA  I50  C7C4
   1 XTAL_PCH_48M_IN      A @BASEBOARD_FAB2_LIB.BASEBOARD_FAB2(SCH_1):XTAL_PCH_48M_IN
   2    GND      B @BASEBOARD_FAB2_LIB.BASEBOARD_FAB2(SCH_1):GND

RES_0603-10M,1.0%,1/10W,CHIP,GA  I54  R7C6
   1 XTAL_33K_RTC1      A @BASEBOARD_FAB2_LIB.BASEBOARD_FAB2(SCH_1):XTAL_33K_RTC1
   2 XTAL_33K_RTC2      B @BASEBOARD_FAB2_LIB.BASEBOARD_FAB2(SCH_1):XTAL_33K_RTC2

CRYSTAL_SM-32.768KHZ,IC,C13544A  I55  Y7C2
   1 XTAL_33K_RTC1      A @BASEBOARD_FAB2_LIB.BASEBOARD_FAB2(SCH_1):XTAL_33K_RTC1
   2 XTAL_33K_RTC2      B @BASEBOARD_FAB2_LIB.BASEBOARD_FAB2(SCH_1):XTAL_33K_RTC2

RES_0402-10.0,1%,1/16W,CHIP,G2A  I110  R8B20
   1 H_PMSYNC_CLK_24M_R      A @BASEBOARD_FAB2_LIB.BASEBOARD_FAB2(SCH_1):H_PMSYNC_CLK_24M_R
   2 H_PMSYNC_CLK_24M      B @BASEBOARD_FAB2_LIB.BASEBOARD_FAB2(SCH_1):H_PMSYNC_CLK_24M

RES_0402-49.9,1%,1/16W,EMPTY,GA  I124  R8B21
   1 H_PMSYNC_CLK_24M      A @BASEBOARD_FAB2_LIB.BASEBOARD_FAB2(SCH_1):H_PMSYNC_CLK_24M
   2    GND      B @BASEBOARD_FAB2_LIB.BASEBOARD_FAB2(SCH_1):GND

RES_0402-169,1.0%,1/16W,CHIP,GA  I149  R3N1
   1 A_PCH_XCLK_BIASREF      A @BASEBOARD_FAB2_LIB.BASEBOARD_FAB2(SCH_1):A_PCH_XCLK_BIASREF
   2    GND      B @BASEBOARD_FAB2_LIB.BASEBOARD_FAB2(SCH_1):GND

RES_0402-0.0,5%,1/16W,CHIP,G21A  I191  R7C4
   1 CLK_100M_BMC_PE_R_DP      A @BASEBOARD_FAB2_LIB.BASEBOARD_FAB2(SCH_1):CLK_100M_BMC_PE_R_DP
   2 CLK_100M_BMC_PE_DP      B @BASEBOARD_FAB2_LIB.BASEBOARD_FAB2(SCH_1):CLK_100M_BMC_PE_DP

RES_0402-0.0,5%,1/16W,CHIP,G21A  I192  R7C2
   1 CLK_100M_BMC_PE_R_DN      A @BASEBOARD_FAB2_LIB.BASEBOARD_FAB2(SCH_1):CLK_100M_BMC_PE_R_DN
   2 CLK_100M_BMC_PE_DN      B @BASEBOARD_FAB2_LIB.BASEBOARD_FAB2(SCH_1):CLK_100M_BMC_PE_DN

CAP_0402-1.0UF,6.3V,10%,EMPTY,A  I193  C3W1
   1 A_PCH_XCLK_BIASREF      A @BASEBOARD_FAB2_LIB.BASEBOARD_FAB2(SCH_1):A_PCH_XCLK_BIASREF
   2    GND      B @BASEBOARD_FAB2_LIB.BASEBOARD_FAB2(SCH_1):GND

CAP_0402LF-15.0PF,50V,5%,COG,AA  I195  C7C13
   1 XTAL_33K_RTC1      A @BASEBOARD_FAB2_LIB.BASEBOARD_FAB2(SCH_1):XTAL_33K_RTC1
   2    GND      B @BASEBOARD_FAB2_LIB.BASEBOARD_FAB2(SCH_1):GND

CAP_0402LF-15.0PF,50V,5%,COG,AA  I196  C7C15
   1 XTAL_33K_RTC2      A @BASEBOARD_FAB2_LIB.BASEBOARD_FAB2(SCH_1):XTAL_33K_RTC2
   2    GND      B @BASEBOARD_FAB2_LIB.BASEBOARD_FAB2(SCH_1):GND


DRAWING: @BASEBOARD_FAB2_LIB.BASEBOARD_FAB2(SCH_1):PAGE115 

LBG_CORE_QAT_EXT_D_BGA1-IC,H91A  I74  U7C1
BN68 TP_PCH_RSVD55 RSVD<55> @BASEBOARD_FAB2_LIB.BASEBOARD_FAB2(SCH_1):TP_PCH_RSVD55
BY60 USB2_P01_DN USB2N_1 @BASEBOARD_FAB2_LIB.BASEBOARD_FAB2(SCH_1):USB2_P01_DN
BW65 TP_USB2_P10_DN USB2N_10 @BASEBOARD_FAB2_LIB.BASEBOARD_FAB2(SCH_1):TP_USB2_P10_DN
CA54 TP_USB2_P11_DN USB2N_11 @BASEBOARD_FAB2_LIB.BASEBOARD_FAB2(SCH_1):TP_USB2_P11_DN
BW67 TP_USB2_P12_DN USB2N_12 @BASEBOARD_FAB2_LIB.BASEBOARD_FAB2(SCH_1):TP_USB2_P12_DN
BY53 TP_USB2_P13_DN USB2N_13 @BASEBOARD_FAB2_LIB.BASEBOARD_FAB2(SCH_1):TP_USB2_P13_DN
BW68 TP_USB2_P14_DN USB2N_14 @BASEBOARD_FAB2_LIB.BASEBOARD_FAB2(SCH_1):TP_USB2_P14_DN
CA61 USB2_P02_DN_R USB2N_2 @BASEBOARD_FAB2_LIB.BASEBOARD_FAB2(SCH_1):USB2_P02_DN_R
CA59 TP_USB2_P03_DN USB2N_3 @BASEBOARD_FAB2_LIB.BASEBOARD_FAB2(SCH_1):TP_USB2_P03_DN
BY62 USB_PCH_BMC_P4_DN_R USB2N_4 @BASEBOARD_FAB2_LIB.BASEBOARD_FAB2(SCH_1):USB_PCH_BMC_P4_DN_R
BY58 USB2_PCH_BMC_P5_DN_R USB2N_5 @BASEBOARD_FAB2_LIB.BASEBOARD_FAB2(SCH_1):USB2_PCH_BMC_P5_DN_R
CA63 TP_USB2_P06_DN USB2N_6 @BASEBOARD_FAB2_LIB.BASEBOARD_FAB2(SCH_1):TP_USB2_P06_DN
CA57 TP_USB2_P07_DN USB2N_7 @BASEBOARD_FAB2_LIB.BASEBOARD_FAB2(SCH_1):TP_USB2_P07_DN
BY64 TP_USB2_P8_DN USB2N_8 @BASEBOARD_FAB2_LIB.BASEBOARD_FAB2(SCH_1):TP_USB2_P8_DN
BY55 TP_USB2_P9_DN USB2N_9 @BASEBOARD_FAB2_LIB.BASEBOARD_FAB2(SCH_1):TP_USB2_P9_DN
BV60 USB2_P01_DP USB2P_1 @BASEBOARD_FAB2_LIB.BASEBOARD_FAB2(SCH_1):USB2_P01_DP
BU65 TP_USB2_P10_DP USB2P_10 @BASEBOARD_FAB2_LIB.BASEBOARD_FAB2(SCH_1):TP_USB2_P10_DP
BW54 TP_USB2_P11_DP USB2P_11 @BASEBOARD_FAB2_LIB.BASEBOARD_FAB2(SCH_1):TP_USB2_P11_DP
BV66 TP_USB2_P12_DP USB2P_12 @BASEBOARD_FAB2_LIB.BASEBOARD_FAB2(SCH_1):TP_USB2_P12_DP
BV53 TP_USB2_P13_DP USB2P_13 @BASEBOARD_FAB2_LIB.BASEBOARD_FAB2(SCH_1):TP_USB2_P13_DP
BU67 TP_USB2_P14_DP USB2P_14 @BASEBOARD_FAB2_LIB.BASEBOARD_FAB2(SCH_1):TP_USB2_P14_DP
BW61 USB2_P02_DP_R USB2P_2 @BASEBOARD_FAB2_LIB.BASEBOARD_FAB2(SCH_1):USB2_P02_DP_R
BW59 TP_USB2_P03_DP USB2P_3 @BASEBOARD_FAB2_LIB.BASEBOARD_FAB2(SCH_1):TP_USB2_P03_DP
BV62 USB_PCH_BMC_P4_DP_R USB2P_4 @BASEBOARD_FAB2_LIB.BASEBOARD_FAB2(SCH_1):USB_PCH_BMC_P4_DP_R
BV58 USB2_PCH_BMC_P5_DP_R USB2P_5 @BASEBOARD_FAB2_LIB.BASEBOARD_FAB2(SCH_1):USB2_PCH_BMC_P5_DP_R
BW63 TP_USB2_P06_DP USB2P_6 @BASEBOARD_FAB2_LIB.BASEBOARD_FAB2(SCH_1):TP_USB2_P06_DP
BW57 TP_USB2_P07_DP USB2P_7 @BASEBOARD_FAB2_LIB.BASEBOARD_FAB2(SCH_1):TP_USB2_P07_DP
BV64 TP_USB2_P8_DP USB2P_8 @BASEBOARD_FAB2_LIB.BASEBOARD_FAB2(SCH_1):TP_USB2_P8_DP
BV55 TP_USB2_P9_DP USB2P_9 @BASEBOARD_FAB2_LIB.BASEBOARD_FAB2(SCH_1):TP_USB2_P9_DP
BN70 A_USB2_COMP USB2_COMP @BASEBOARD_FAB2_LIB.BASEBOARD_FAB2(SCH_1):A_USB2_COMP
BR67 A_USB2_VBUS USB2_VBUS @BASEBOARD_FAB2_LIB.BASEBOARD_FAB2(SCH_1):A_USB2_VBUS
BK71 USB3_P01_RXN USB3_1_RXN @BASEBOARD_FAB2_LIB.BASEBOARD_FAB2(SCH_1):USB3_P01_RXN
BK69 USB3_P01_RXP USB3_1_RXP @BASEBOARD_FAB2_LIB.BASEBOARD_FAB2(SCH_1):USB3_P01_RXP
BL52 USB3_P01_TXN USB3_1_TXN @BASEBOARD_FAB2_LIB.BASEBOARD_FAB2(SCH_1):USB3_P01_TXN
BK54 USB3_P01_TXP USB3_1_TXP @BASEBOARD_FAB2_LIB.BASEBOARD_FAB2(SCH_1):USB3_P01_TXP
BJ72 TP_USB3_P02_RXN USB3_2_RXN @BASEBOARD_FAB2_LIB.BASEBOARD_FAB2(SCH_1):TP_USB3_P02_RXN
BJ70 TP_USB3_P02_RXP USB3_2_RXP @BASEBOARD_FAB2_LIB.BASEBOARD_FAB2(SCH_1):TP_USB3_P02_RXP
BL56 TP_USB3_P02_TXN USB3_2_TXN @BASEBOARD_FAB2_LIB.BASEBOARD_FAB2(SCH_1):TP_USB3_P02_TXN
BJ56 TP_USB3_P02_TXP USB3_2_TXP @BASEBOARD_FAB2_LIB.BASEBOARD_FAB2(SCH_1):TP_USB3_P02_TXP
BH71 TP_USB3_P03_RXN USB3_3_RXN @BASEBOARD_FAB2_LIB.BASEBOARD_FAB2(SCH_1):TP_USB3_P03_RXN
BH69 TP_USB3_P03_RXP USB3_3_RXP @BASEBOARD_FAB2_LIB.BASEBOARD_FAB2(SCH_1):TP_USB3_P03_RXP
BM54 TP_USB3_P03_TXN USB3_3_TXN @BASEBOARD_FAB2_LIB.BASEBOARD_FAB2(SCH_1):TP_USB3_P03_TXN
BN56 TP_USB3_P03_TXP USB3_3_TXP @BASEBOARD_FAB2_LIB.BASEBOARD_FAB2(SCH_1):TP_USB3_P03_TXP
BF72 TP_USB3_P04_RXN USB3_4_RXN @BASEBOARD_FAB2_LIB.BASEBOARD_FAB2(SCH_1):TP_USB3_P04_RXN
BF70 TP_USB3_P04_RXP USB3_4_RXP @BASEBOARD_FAB2_LIB.BASEBOARD_FAB2(SCH_1):TP_USB3_P04_RXP
BH58 TP_USB3_P04_TXN USB3_4_TXN @BASEBOARD_FAB2_LIB.BASEBOARD_FAB2(SCH_1):TP_USB3_P04_TXN
BG56 TP_USB3_P04_TXP USB3_4_TXP @BASEBOARD_FAB2_LIB.BASEBOARD_FAB2(SCH_1):TP_USB3_P04_TXP
BE71 TP_USB3_P05_RXN USB3_5_RXN @BASEBOARD_FAB2_LIB.BASEBOARD_FAB2(SCH_1):TP_USB3_P05_RXN
BE69 TP_USB3_P05_RXP USB3_5_RXP @BASEBOARD_FAB2_LIB.BASEBOARD_FAB2(SCH_1):TP_USB3_P05_RXP
BK58 TP_USB3_P05_TXN USB3_5_TXN @BASEBOARD_FAB2_LIB.BASEBOARD_FAB2(SCH_1):TP_USB3_P05_TXN
BJ59 TP_USB3_P05_TXP USB3_5_TXP @BASEBOARD_FAB2_LIB.BASEBOARD_FAB2(SCH_1):TP_USB3_P05_TXP
BD72 TP_USB3_P06_RXN USB3_6_RXN @BASEBOARD_FAB2_LIB.BASEBOARD_FAB2(SCH_1):TP_USB3_P06_RXN
BD70 TP_USB3_P06_RXP USB3_6_RXP @BASEBOARD_FAB2_LIB.BASEBOARD_FAB2(SCH_1):TP_USB3_P06_RXP
BL59 TP_USB3_P06_TXN USB3_6_TXN @BASEBOARD_FAB2_LIB.BASEBOARD_FAB2(SCH_1):TP_USB3_P06_TXN
BM61 TP_USB3_P06_TXP USB3_6_TXP @BASEBOARD_FAB2_LIB.BASEBOARD_FAB2(SCH_1):TP_USB3_P06_TXP

RES_0402-113,1%,1/16W,CHIP,G21A  I90  R8B9
   1 A_USB2_COMP      A @BASEBOARD_FAB2_LIB.BASEBOARD_FAB2(SCH_1):A_USB2_COMP
   2    GND      B @BASEBOARD_FAB2_LIB.BASEBOARD_FAB2(SCH_1):GND

RES_0402-10.0K,1%,1/16W,CHIP,GA  I114  R8B32
   1 A_USB2_VBUS      A @BASEBOARD_FAB2_LIB.BASEBOARD_FAB2(SCH_1):A_USB2_VBUS
   2    GND      B @BASEBOARD_FAB2_LIB.BASEBOARD_FAB2(SCH_1):GND

RES_0402-0.0,5%,1/16W,CHIP,G21A  I118  R1W14
   1 USB2_PCH_BMC_P5_DP_R      A @BASEBOARD_FAB2_LIB.BASEBOARD_FAB2(SCH_1):USB2_PCH_BMC_P5_DP_R
   2 USB2_PCH_BMC_P5_DP      B @BASEBOARD_FAB2_LIB.BASEBOARD_FAB2(SCH_1):USB2_PCH_BMC_P5_DP

RES_0402-0.0,5%,1/16W,CHIP,G21A  I119  R1W15
   1 USB2_PCH_BMC_P5_DN_R      A @BASEBOARD_FAB2_LIB.BASEBOARD_FAB2(SCH_1):USB2_PCH_BMC_P5_DN_R
   2 USB2_PCH_BMC_P5_DN      B @BASEBOARD_FAB2_LIB.BASEBOARD_FAB2(SCH_1):USB2_PCH_BMC_P5_DN

RES_0402-0.0,5%,1/16W,CHIP,G21A  I120  R1W17
   1 USB_PCH_BMC_P4_DN_R      A @BASEBOARD_FAB2_LIB.BASEBOARD_FAB2(SCH_1):USB_PCH_BMC_P4_DN_R
   2 USB_PCH_BMC_P4_DN      B @BASEBOARD_FAB2_LIB.BASEBOARD_FAB2(SCH_1):USB_PCH_BMC_P4_DN

RES_0402-0.0,5%,1/16W,CHIP,G21A  I121  R1W16
   1 USB_PCH_BMC_P4_DP_R      A @BASEBOARD_FAB2_LIB.BASEBOARD_FAB2(SCH_1):USB_PCH_BMC_P4_DP_R
   2 USB_PCH_BMC_P4_DP      B @BASEBOARD_FAB2_LIB.BASEBOARD_FAB2(SCH_1):USB_PCH_BMC_P4_DP

RES_0402-0.0,5%,1/16W,CHIP,G21A  I122  R1W19
   1 USB2_P02_DN_R      A @BASEBOARD_FAB2_LIB.BASEBOARD_FAB2(SCH_1):USB2_P02_DN_R
   2 USB2_P02_DN      B @BASEBOARD_FAB2_LIB.BASEBOARD_FAB2(SCH_1):USB2_P02_DN

RES_0402-0.0,5%,1/16W,CHIP,G21A  I123  R1W18
   1 USB2_P02_DP_R      A @BASEBOARD_FAB2_LIB.BASEBOARD_FAB2(SCH_1):USB2_P02_DP_R
   2 USB2_P02_DP      B @BASEBOARD_FAB2_LIB.BASEBOARD_FAB2(SCH_1):USB2_P02_DP


DRAWING: @BASEBOARD_FAB2_LIB.BASEBOARD_FAB2(SCH_1):PAGE116 

RES_0402-100.0,1%,1/16W,CHIP,GA  I108  R3M11
   1 A_PCIE_RCOMP_P      A @BASEBOARD_FAB2_LIB.BASEBOARD_FAB2(SCH_1):A_PCIE_RCOMP_P
   2 A_PCIE_RCOMP_N      B @BASEBOARD_FAB2_LIB.BASEBOARD_FAB2(SCH_1):A_PCIE_RCOMP_N

RES_0402-100.0,1%,1/16W,CHIP,GA  I181  R3M12
   1 A_PCIEUP_RCOMP_P      A @BASEBOARD_FAB2_LIB.BASEBOARD_FAB2(SCH_1):A_PCIEUP_RCOMP_P
   2 A_PCIEUP_RCOMP_N      B @BASEBOARD_FAB2_LIB.BASEBOARD_FAB2(SCH_1):A_PCIEUP_RCOMP_N

LBG_CORE_QAT_EXT_D_BGA1-IC,H91A  I220  U7C1
 D66 A_EXTCLKN EXTCLKN @BASEBOARD_FAB2_LIB.BASEBOARD_FAB2(SCH_1):A_EXTCLKN
 E67 A_EXTCLKP EXTCLKP @BASEBOARD_FAB2_LIB.BASEBOARD_FAB2(SCH_1):A_EXTCLKP
AV63     NC PCIE10_SSATA4_RXN     NC
AU65     NC PCIE10_SSATA4_RXP     NC
AD70     NC PCIE10_SSATA4_TXN     NC
AD72     NC PCIE10_SSATA4_TXP     NC
AT66     NC PCIE11_SSATA5_GBE_RXN     NC
AV66     NC PCIE11_SSATA5_GBE_RXP     NC
AC69     NC PCIE11_SSATA5_GBE_TXN     NC
AC71     NC PCIE11_SSATA5_GBE_TXP     NC
AR61 SATA6G_PCH_PCIE_UP_SATA_RXN<0> PCIE12_UP0_SATA0_RXN @BASEBOARD_FAB2_LIB.BASEBOARD_FAB2(SCH_1):SATA6G_PCH_PCIE_UP_SATA_RXN(0)
AT63 SATA6G_PCH_PCIE_UP_SATA_RXP<0> PCIE12_UP0_SATA0_RXP @BASEBOARD_FAB2_LIB.BASEBOARD_FAB2(SCH_1):SATA6G_PCH_PCIE_UP_SATA_RXP(0)
 W69 SATA6G_PCH_PCIE_UP_SATA_TXN<0> PCIE12_UP0_SATA0_TXN @BASEBOARD_FAB2_LIB.BASEBOARD_FAB2(SCH_1):SATA6G_PCH_PCIE_UP_SATA_TXN(0)
 W71 SATA6G_PCH_PCIE_UP_SATA_TXP<0> PCIE12_UP0_SATA0_TXP @BASEBOARD_FAB2_LIB.BASEBOARD_FAB2(SCH_1):SATA6G_PCH_PCIE_UP_SATA_TXP(0)
AL66 SATA6G_PCH_PCIE_UP_SATA_RXN<1> PCIE13_UP1_SATA1_RXN @BASEBOARD_FAB2_LIB.BASEBOARD_FAB2(SCH_1):SATA6G_PCH_PCIE_UP_SATA_RXN(1)
AN65 SATA6G_PCH_PCIE_UP_SATA_RXP<1> PCIE13_UP1_SATA1_RXP @BASEBOARD_FAB2_LIB.BASEBOARD_FAB2(SCH_1):SATA6G_PCH_PCIE_UP_SATA_RXP(1)
 V70 SATA6G_PCH_PCIE_UP_SATA_TXN<1> PCIE13_UP1_SATA1_TXN @BASEBOARD_FAB2_LIB.BASEBOARD_FAB2(SCH_1):SATA6G_PCH_PCIE_UP_SATA_TXN(1)
 V72 SATA6G_PCH_PCIE_UP_SATA_TXP<1> PCIE13_UP1_SATA1_TXP @BASEBOARD_FAB2_LIB.BASEBOARD_FAB2(SCH_1):SATA6G_PCH_PCIE_UP_SATA_TXP(1)
AK65 SATA6G_PCH_PCIE_UP_SATA_RXN<2> PCIE14_UP2_SATA2_RXN @BASEBOARD_FAB2_LIB.BASEBOARD_FAB2(SCH_1):SATA6G_PCH_PCIE_UP_SATA_RXN(2)
AJ63 SATA6G_PCH_PCIE_UP_SATA_RXP<2> PCIE14_UP2_SATA2_RXP @BASEBOARD_FAB2_LIB.BASEBOARD_FAB2(SCH_1):SATA6G_PCH_PCIE_UP_SATA_RXP(2)
 T69 SATA6G_PCH_PCIE_UP_SATA_TXN<2> PCIE14_UP2_SATA2_TXN @BASEBOARD_FAB2_LIB.BASEBOARD_FAB2(SCH_1):SATA6G_PCH_PCIE_UP_SATA_TXN(2)
 T71 SATA6G_PCH_PCIE_UP_SATA_TXP<2> PCIE14_UP2_SATA2_TXP @BASEBOARD_FAB2_LIB.BASEBOARD_FAB2(SCH_1):SATA6G_PCH_PCIE_UP_SATA_TXP(2)
AP63 SATA6G_PCH_PCIE_UP_SATA_RXN<3> PCIE15_UP3_SATA3_RXN @BASEBOARD_FAB2_LIB.BASEBOARD_FAB2(SCH_1):SATA6G_PCH_PCIE_UP_SATA_RXN(3)
AL63 SATA6G_PCH_PCIE_UP_SATA_RXP<3> PCIE15_UP3_SATA3_RXP @BASEBOARD_FAB2_LIB.BASEBOARD_FAB2(SCH_1):SATA6G_PCH_PCIE_UP_SATA_RXP(3)
 R70 SATA6G_PCH_PCIE_UP_SATA_TXN<3> PCIE15_UP3_SATA3_TXN @BASEBOARD_FAB2_LIB.BASEBOARD_FAB2(SCH_1):SATA6G_PCH_PCIE_UP_SATA_TXN(3)
 R72 SATA6G_PCH_PCIE_UP_SATA_TXP<3> PCIE15_UP3_SATA3_TXP @BASEBOARD_FAB2_LIB.BASEBOARD_FAB2(SCH_1):SATA6G_PCH_PCIE_UP_SATA_TXP(3)
AF65 SATA6G_PCH_PCIE_UP_SATA_RXN<4> PCIE16_UP4_SATA4_RXN @BASEBOARD_FAB2_LIB.BASEBOARD_FAB2(SCH_1):SATA6G_PCH_PCIE_UP_SATA_RXN(4)
AH65 SATA6G_PCH_PCIE_UP_SATA_RXP<4> PCIE16_UP4_SATA4_RXP @BASEBOARD_FAB2_LIB.BASEBOARD_FAB2(SCH_1):SATA6G_PCH_PCIE_UP_SATA_RXP(4)
 P69 SATA6G_PCH_PCIE_UP_SATA_TXN<4> PCIE16_UP4_SATA4_TXN @BASEBOARD_FAB2_LIB.BASEBOARD_FAB2(SCH_1):SATA6G_PCH_PCIE_UP_SATA_TXN(4)
 P71 SATA6G_PCH_PCIE_UP_SATA_TXP<4> PCIE16_UP4_SATA4_TXP @BASEBOARD_FAB2_LIB.BASEBOARD_FAB2(SCH_1):SATA6G_PCH_PCIE_UP_SATA_TXP(4)
AH61 SATA6G_PCH_PCIE_UP_SATA_RXN<5> PCIE17_UP5_SATA5_RXN @BASEBOARD_FAB2_LIB.BASEBOARD_FAB2(SCH_1):SATA6G_PCH_PCIE_UP_SATA_RXN(5)
AG63 SATA6G_PCH_PCIE_UP_SATA_RXP<5> PCIE17_UP5_SATA5_RXP @BASEBOARD_FAB2_LIB.BASEBOARD_FAB2(SCH_1):SATA6G_PCH_PCIE_UP_SATA_RXP(5)
 N70 SATA6G_PCH_PCIE_UP_SATA_TXN<5> PCIE17_UP5_SATA5_TXN @BASEBOARD_FAB2_LIB.BASEBOARD_FAB2(SCH_1):SATA6G_PCH_PCIE_UP_SATA_TXN(5)
 N72 SATA6G_PCH_PCIE_UP_SATA_TXP<5> PCIE17_UP5_SATA5_TXP @BASEBOARD_FAB2_LIB.BASEBOARD_FAB2(SCH_1):SATA6G_PCH_PCIE_UP_SATA_TXP(5)
AP59 SATA6G_PCH_PCIE_UP_SATA_RXN<6> PCIE18_UP6_SATA6_RXN @BASEBOARD_FAB2_LIB.BASEBOARD_FAB2(SCH_1):SATA6G_PCH_PCIE_UP_SATA_RXN(6)
AN61 SATA6G_PCH_PCIE_UP_SATA_RXP<6> PCIE18_UP6_SATA6_RXP @BASEBOARD_FAB2_LIB.BASEBOARD_FAB2(SCH_1):SATA6G_PCH_PCIE_UP_SATA_RXP(6)
 M69 SATA6G_PCH_PCIE_UP_SATA_TXN<6> PCIE18_UP6_SATA6_TXN @BASEBOARD_FAB2_LIB.BASEBOARD_FAB2(SCH_1):SATA6G_PCH_PCIE_UP_SATA_TXN(6)
 M71 SATA6G_PCH_PCIE_UP_SATA_TXP<6> PCIE18_UP6_SATA6_TXP @BASEBOARD_FAB2_LIB.BASEBOARD_FAB2(SCH_1):SATA6G_PCH_PCIE_UP_SATA_TXP(6)
AA61 SATA6G_PCH_PCIE_UP_SATA_RXN<7> PCIE19_UP7_SATA7_RXN @BASEBOARD_FAB2_LIB.BASEBOARD_FAB2(SCH_1):SATA6G_PCH_PCIE_UP_SATA_RXN(7)
AD61 SATA6G_PCH_PCIE_UP_SATA_RXP<7> PCIE19_UP7_SATA7_RXP @BASEBOARD_FAB2_LIB.BASEBOARD_FAB2(SCH_1):SATA6G_PCH_PCIE_UP_SATA_RXP(7)
 L70 SATA6G_PCH_PCIE_UP_SATA_TXN<7> PCIE19_UP7_SATA7_TXN @BASEBOARD_FAB2_LIB.BASEBOARD_FAB2(SCH_1):SATA6G_PCH_PCIE_UP_SATA_TXN(7)
 L72 SATA6G_PCH_PCIE_UP_SATA_TXP<7> PCIE19_UP7_SATA7_TXP @BASEBOARD_FAB2_LIB.BASEBOARD_FAB2(SCH_1):SATA6G_PCH_PCIE_UP_SATA_TXP(7)
AN70 P2E_SSB_BMC_RX_C_DN PCIE4_GBE_RXN @BASEBOARD_FAB2_LIB.BASEBOARD_FAB2(SCH_1):P2E_SSB_BMC_RX_C_DN
AN72 P2E_SSB_BMC_RX_C_DP PCIE4_GBE_RXP @BASEBOARD_FAB2_LIB.BASEBOARD_FAB2(SCH_1):P2E_SSB_BMC_RX_C_DP
BG66 P2E_SSB_BMC_TX_DN PCIE4_GBE_TXN @BASEBOARD_FAB2_LIB.BASEBOARD_FAB2(SCH_1):P2E_SSB_BMC_TX_DN
BJ66 P2E_SSB_BMC_TX_DP PCIE4_GBE_TXP @BASEBOARD_FAB2_LIB.BASEBOARD_FAB2(SCH_1):P2E_SSB_BMC_TX_DP
AM69 PE_PCH_SPRV_RX_C_DN PCIE5_GBE_RXN @BASEBOARD_FAB2_LIB.BASEBOARD_FAB2(SCH_1):PE_PCH_SPRV_RX_C_DN
AM71 PE_PCH_SPRV_RX_C_DP PCIE5_GBE_RXP @BASEBOARD_FAB2_LIB.BASEBOARD_FAB2(SCH_1):PE_PCH_SPRV_RX_C_DP
BH65 PE_PCH_SPRV_TX_DN PCIE5_GBE_TXN @BASEBOARD_FAB2_LIB.BASEBOARD_FAB2(SCH_1):PE_PCH_SPRV_TX_DN
BJ63 PE_PCH_SPRV_TX_DP PCIE5_GBE_TXP @BASEBOARD_FAB2_LIB.BASEBOARD_FAB2(SCH_1):PE_PCH_SPRV_TX_DP
BB63 SATA6G_S0_RX_DN PCIE6_SSATA0_RXN @BASEBOARD_FAB2_LIB.BASEBOARD_FAB2(SCH_1):SATA6G_S0_RX_DN
BD61 SATA6G_S0_RX_DP PCIE6_SSATA0_RXP @BASEBOARD_FAB2_LIB.BASEBOARD_FAB2(SCH_1):SATA6G_S0_RX_DP
AJ70 SATA6G_S0_TX_DN PCIE6_SSATA0_TXN @BASEBOARD_FAB2_LIB.BASEBOARD_FAB2(SCH_1):SATA6G_S0_TX_DN
AJ72 SATA6G_S0_TX_DP PCIE6_SSATA0_TXP @BASEBOARD_FAB2_LIB.BASEBOARD_FAB2(SCH_1):SATA6G_S0_TX_DP
AY59 SATA6G_S1_RX_DN PCIE7_SSATA1_RXN @BASEBOARD_FAB2_LIB.BASEBOARD_FAB2(SCH_1):SATA6G_S1_RX_DN
BA61 SATA6G_S1_RX_DP PCIE7_SSATA1_RXP @BASEBOARD_FAB2_LIB.BASEBOARD_FAB2(SCH_1):SATA6G_S1_RX_DP
AH69 SATA6G_S1_TX_DN PCIE7_SSATA1_TXN @BASEBOARD_FAB2_LIB.BASEBOARD_FAB2(SCH_1):SATA6G_S1_TX_DN
AH71 SATA6G_S1_TX_DP PCIE7_SSATA1_TXP @BASEBOARD_FAB2_LIB.BASEBOARD_FAB2(SCH_1):SATA6G_S1_TX_DP
BA65     NC PCIE8_SSATA2_GBE_RXN     NC
BD65     NC PCIE8_SSATA2_GBE_RXP     NC
AF70     NC PCIE8_SSATA2_GBE_TXN     NC
AF72     NC PCIE8_SSATA2_GBE_TXP     NC
AW65     NC PCIE9_SSATA3_RXN     NC
AY66     NC PCIE9_SSATA3_RXP     NC
AE69     NC PCIE9_SSATA3_TXN     NC
AE71     NC PCIE9_SSATA3_TXP     NC
AF58 A_PCIEUP_RCOMP_N PCIEUP_RCOMPN @BASEBOARD_FAB2_LIB.BASEBOARD_FAB2(SCH_1):A_PCIEUP_RCOMP_N
AH58 A_PCIEUP_RCOMP_P PCIEUP_RCOMPP @BASEBOARD_FAB2_LIB.BASEBOARD_FAB2(SCH_1):A_PCIEUP_RCOMP_P
BD58 A_PCIE_RCOMP_N PCIE_RCOMPN @BASEBOARD_FAB2_LIB.BASEBOARD_FAB2(SCH_1):A_PCIE_RCOMP_N
BB56 A_PCIE_RCOMP_P PCIE_RCOMPP @BASEBOARD_FAB2_LIB.BASEBOARD_FAB2(SCH_1):A_PCIE_RCOMP_P
AA71 TP_PCH_RSVD52 RSVD<52> @BASEBOARD_FAB2_LIB.BASEBOARD_FAB2(SCH_1):TP_PCH_RSVD52
AA69 TP_PCH_RSVD51 RSVD<51> @BASEBOARD_FAB2_LIB.BASEBOARD_FAB2(SCH_1):TP_PCH_RSVD51
 H69 TP_PCH_RSVD50 RSVD<50> @BASEBOARD_FAB2_LIB.BASEBOARD_FAB2(SCH_1):TP_PCH_RSVD50
 G67 TP_PCH_RSVD49 RSVD<49> @BASEBOARD_FAB2_LIB.BASEBOARD_FAB2(SCH_1):TP_PCH_RSVD49
AP71 TP_PCH_RSVD48 RSVD<48> @BASEBOARD_FAB2_LIB.BASEBOARD_FAB2(SCH_1):TP_PCH_RSVD48
AP69 TP_PCH_RSVD47 RSVD<47> @BASEBOARD_FAB2_LIB.BASEBOARD_FAB2(SCH_1):TP_PCH_RSVD47
AV72 P3E_PCH_M2_RX_DN<3> USB3_10_PCIE3_GBE_RXN @BASEBOARD_FAB2_LIB.BASEBOARD_FAB2(SCH_1):P3E_PCH_M2_RX_DN(3)
AV70 P3E_PCH_M2_RX_DP<3> USB3_10_PCIE3_GBE_RXP @BASEBOARD_FAB2_LIB.BASEBOARD_FAB2(SCH_1):P3E_PCH_M2_RX_DP(3)
BH61 P3E_PCH_M2_TX_DN<3> USB3_10_PCIE3_GBE_TXN @BASEBOARD_FAB2_LIB.BASEBOARD_FAB2(SCH_1):P3E_PCH_M2_TX_DN(3)
BK61 P3E_PCH_M2_TX_DP<3> USB3_10_PCIE3_GBE_TXP @BASEBOARD_FAB2_LIB.BASEBOARD_FAB2(SCH_1):P3E_PCH_M2_TX_DP(3)
BA71 P3E_PCH_RX_0_DN USB3_7_PCIE0_RXN @BASEBOARD_FAB2_LIB.BASEBOARD_FAB2(SCH_1):P3E_PCH_RX_0_DN
BA69 P3E_PCH_RX_0_DP USB3_7_PCIE0_RXP @BASEBOARD_FAB2_LIB.BASEBOARD_FAB2(SCH_1):P3E_PCH_RX_0_DP
BR61 P3E_PCH_TX_0_DN USB3_7_PCIE0_TXN @BASEBOARD_FAB2_LIB.BASEBOARD_FAB2(SCH_1):P3E_PCH_TX_0_DN
BN63 P3E_PCH_TX_0_DP USB3_7_PCIE0_TXP @BASEBOARD_FAB2_LIB.BASEBOARD_FAB2(SCH_1):P3E_PCH_TX_0_DP
AY72 P3E_PCH_M2_RX_DN<1> USB3_8_PCIE1_RXN @BASEBOARD_FAB2_LIB.BASEBOARD_FAB2(SCH_1):P3E_PCH_M2_RX_DN(1)
AY70 P3E_PCH_M2_RX_DP<1> USB3_8_PCIE1_RXP @BASEBOARD_FAB2_LIB.BASEBOARD_FAB2(SCH_1):P3E_PCH_M2_RX_DP(1)
BM65 P3E_PCH_M2_TX_DN<1> USB3_8_PCIE1_TXN @BASEBOARD_FAB2_LIB.BASEBOARD_FAB2(SCH_1):P3E_PCH_M2_TX_DN(1)
BR65 P3E_PCH_M2_TX_DP<1> USB3_8_PCIE1_TXP @BASEBOARD_FAB2_LIB.BASEBOARD_FAB2(SCH_1):P3E_PCH_M2_TX_DP(1)
AW71 P3E_PCH_M2_RX_DN<2> USB3_9_PCIE2_RXN @BASEBOARD_FAB2_LIB.BASEBOARD_FAB2(SCH_1):P3E_PCH_M2_RX_DN(2)
AW69 P3E_PCH_M2_RX_DP<2> USB3_9_PCIE2_RXP @BASEBOARD_FAB2_LIB.BASEBOARD_FAB2(SCH_1):P3E_PCH_M2_RX_DP(2)
BK65 P3E_PCH_M2_TX_DN<2> USB3_9_PCIE2_TXN @BASEBOARD_FAB2_LIB.BASEBOARD_FAB2(SCH_1):P3E_PCH_M2_TX_DN(2)
BL66 P3E_PCH_M2_TX_DP<2> USB3_9_PCIE2_TXP @BASEBOARD_FAB2_LIB.BASEBOARD_FAB2(SCH_1):P3E_PCH_M2_TX_DP(2)

RES_0402-10.0K,1%,1/16W,EMPTY,A  I229  R7B8
   1 A_EXTCLKN      A @BASEBOARD_FAB2_LIB.BASEBOARD_FAB2(SCH_1):A_EXTCLKN
   2    GND      B @BASEBOARD_FAB2_LIB.BASEBOARD_FAB2(SCH_1):GND

RES_0402-10.0K,1%,1/16W,EMPTY,A  I230  R7B7
   1 A_EXTCLKP      A @BASEBOARD_FAB2_LIB.BASEBOARD_FAB2(SCH_1):A_EXTCLKP
   2    GND      B @BASEBOARD_FAB2_LIB.BASEBOARD_FAB2(SCH_1):GND

RES_0402-100.0K,1%,1/16W,CHIP,A  I234  R3M9
   1 P2E_SSB_BMC_RX_C_DN      A @BASEBOARD_FAB2_LIB.BASEBOARD_FAB2(SCH_1):P2E_SSB_BMC_RX_C_DN
   2    GND      B @BASEBOARD_FAB2_LIB.BASEBOARD_FAB2(SCH_1):GND

RES_0402-100.0K,1%,1/16W,CHIP,A  I235  R3M8
   1 P2E_SSB_BMC_RX_C_DP      A @BASEBOARD_FAB2_LIB.BASEBOARD_FAB2(SCH_1):P2E_SSB_BMC_RX_C_DP
   2    GND      B @BASEBOARD_FAB2_LIB.BASEBOARD_FAB2(SCH_1):GND

CAP_A_0402V-0.1UF,16V,10%,X7R,A  I238  C2M4
   1 P2E_SSB_BMC_TX_DP      A @BASEBOARD_FAB2_LIB.BASEBOARD_FAB2(SCH_1):P2E_SSB_BMC_TX_DP
   2 P2E_SSB_BMC_TX_C_DP      B @BASEBOARD_FAB2_LIB.BASEBOARD_FAB2(SCH_1):P2E_SSB_BMC_TX_C_DP

CAP_A_0402V-0.1UF,16V,10%,X7R,A  I239  C2M3
   1 P2E_SSB_BMC_TX_DN      A @BASEBOARD_FAB2_LIB.BASEBOARD_FAB2(SCH_1):P2E_SSB_BMC_TX_DN
   2 P2E_SSB_BMC_TX_C_DN      B @BASEBOARD_FAB2_LIB.BASEBOARD_FAB2(SCH_1):P2E_SSB_BMC_TX_C_DN


DRAWING: @BASEBOARD_FAB2_LIB.BASEBOARD_FAB2(SCH_1):PAGE117 

LBG_CORE_QAT_EXT_D_BGA1-IC,H91A  I9  U7C1
 C45 DMI_CPU0_PCH_TX_C_DN<3> DMI_RXN<3> @BASEBOARD_FAB2_LIB.BASEBOARD_FAB2(SCH_1):DMI_CPU0_PCH_TX_C_DN(3)
 D44 DMI_CPU0_PCH_TX_C_DN<2> DMI_RXN<2> @BASEBOARD_FAB2_LIB.BASEBOARD_FAB2(SCH_1):DMI_CPU0_PCH_TX_C_DN(2)
 C43 DMI_CPU0_PCH_TX_C_DN<1> DMI_RXN<1> @BASEBOARD_FAB2_LIB.BASEBOARD_FAB2(SCH_1):DMI_CPU0_PCH_TX_C_DN(1)
 D42 DMI_CPU0_PCH_TX_C_DN<0> DMI_RXN<0> @BASEBOARD_FAB2_LIB.BASEBOARD_FAB2(SCH_1):DMI_CPU0_PCH_TX_C_DN(0)
 A45 DMI_CPU0_PCH_TX_C_DP<3> DMI_RXP<3> @BASEBOARD_FAB2_LIB.BASEBOARD_FAB2(SCH_1):DMI_CPU0_PCH_TX_C_DP(3)
 B44 DMI_CPU0_PCH_TX_C_DP<2> DMI_RXP<2> @BASEBOARD_FAB2_LIB.BASEBOARD_FAB2(SCH_1):DMI_CPU0_PCH_TX_C_DP(2)
 A43 DMI_CPU0_PCH_TX_C_DP<1> DMI_RXP<1> @BASEBOARD_FAB2_LIB.BASEBOARD_FAB2(SCH_1):DMI_CPU0_PCH_TX_C_DP(1)
 B42 DMI_CPU0_PCH_TX_C_DP<0> DMI_RXP<0> @BASEBOARD_FAB2_LIB.BASEBOARD_FAB2(SCH_1):DMI_CPU0_PCH_TX_C_DP(0)
 P52 DMI_CPU0_PCH_RX_DN<3> DMI_TXN<3> @BASEBOARD_FAB2_LIB.BASEBOARD_FAB2(SCH_1):DMI_CPU0_PCH_RX_DN(3)
 K50 DMI_CPU0_PCH_RX_DN<2> DMI_TXN<2> @BASEBOARD_FAB2_LIB.BASEBOARD_FAB2(SCH_1):DMI_CPU0_PCH_RX_DN(2)
 J48 DMI_CPU0_PCH_RX_DN<1> DMI_TXN<1> @BASEBOARD_FAB2_LIB.BASEBOARD_FAB2(SCH_1):DMI_CPU0_PCH_RX_DN(1)
 H46 DMI_CPU0_PCH_RX_DN<0> DMI_TXN<0> @BASEBOARD_FAB2_LIB.BASEBOARD_FAB2(SCH_1):DMI_CPU0_PCH_RX_DN(0)
 N54 DMI_CPU0_PCH_RX_DP<3> DMI_TXP<3> @BASEBOARD_FAB2_LIB.BASEBOARD_FAB2(SCH_1):DMI_CPU0_PCH_RX_DP(3)
 M52 DMI_CPU0_PCH_RX_DP<2> DMI_TXP<2> @BASEBOARD_FAB2_LIB.BASEBOARD_FAB2(SCH_1):DMI_CPU0_PCH_RX_DP(2)
 H50 DMI_CPU0_PCH_RX_DP<1> DMI_TXP<1> @BASEBOARD_FAB2_LIB.BASEBOARD_FAB2(SCH_1):DMI_CPU0_PCH_RX_DP(1)
 K46 DMI_CPU0_PCH_RX_DP<0> DMI_TXP<0> @BASEBOARD_FAB2_LIB.BASEBOARD_FAB2(SCH_1):DMI_CPU0_PCH_RX_DP(0)
 C48 P3E_CPU0_PE1_PCH_TXN<0> PCIEUP_0_RXN @BASEBOARD_FAB2_LIB.BASEBOARD_FAB2(SCH_1):P3E_CPU0_PE1_PCH_TXN(0)
 A48 P3E_CPU0_PE1_PCH_TXP<0> PCIEUP_0_RXP @BASEBOARD_FAB2_LIB.BASEBOARD_FAB2(SCH_1):P3E_CPU0_PE1_PCH_TXP(0)
 J52 P3E_CPU0_PE1_PCH_RXN<0> PCIEUP_0_TXN @BASEBOARD_FAB2_LIB.BASEBOARD_FAB2(SCH_1):P3E_CPU0_PE1_PCH_RXN(0)
 G52 P3E_CPU0_PE1_PCH_RXP<0> PCIEUP_0_TXP @BASEBOARD_FAB2_LIB.BASEBOARD_FAB2(SCH_1):P3E_CPU0_PE1_PCH_RXP(0)
 C59 P3E_CPU0_PE1_PCH_C_TXP<10> PCIEUP_10_RXN @BASEBOARD_FAB2_LIB.BASEBOARD_FAB2(SCH_1):P3E_CPU0_PE1_PCH_C_TXP(10)
 A59 P3E_CPU0_PE1_PCH_C_TXN<10> PCIEUP_10_RXP @BASEBOARD_FAB2_LIB.BASEBOARD_FAB2(SCH_1):P3E_CPU0_PE1_PCH_C_TXN(10)
 N65 P3E_CPU0_PE1_PCH_R_RXN<10> PCIEUP_10_TXN @BASEBOARD_FAB2_LIB.BASEBOARD_FAB2(SCH_1):P3E_CPU0_PE1_PCH_R_RXN(10)
 P66 P3E_CPU0_PE1_PCH_R_RXP<10> PCIEUP_10_TXP @BASEBOARD_FAB2_LIB.BASEBOARD_FAB2(SCH_1):P3E_CPU0_PE1_PCH_R_RXP(10)
 D60 P3E_CPU0_PE1_PCH_C_TXN<11> PCIEUP_11_RXN @BASEBOARD_FAB2_LIB.BASEBOARD_FAB2(SCH_1):P3E_CPU0_PE1_PCH_C_TXN(11)
 B60 P3E_CPU0_PE1_PCH_C_TXP<11> PCIEUP_11_RXP @BASEBOARD_FAB2_LIB.BASEBOARD_FAB2(SCH_1):P3E_CPU0_PE1_PCH_C_TXP(11)
 T59 P3E_CPU0_PE1_PCH_R_RXN<11> PCIEUP_11_TXN @BASEBOARD_FAB2_LIB.BASEBOARD_FAB2(SCH_1):P3E_CPU0_PE1_PCH_R_RXN(11)
 V59 P3E_CPU0_PE1_PCH_R_RXP<11> PCIEUP_11_TXP @BASEBOARD_FAB2_LIB.BASEBOARD_FAB2(SCH_1):P3E_CPU0_PE1_PCH_R_RXP(11)
 C61 P3E_CPU0_PE1_PCH_C_TXP<12> PCIEUP_12_RXN @BASEBOARD_FAB2_LIB.BASEBOARD_FAB2(SCH_1):P3E_CPU0_PE1_PCH_C_TXP(12)
 A61 P3E_CPU0_PE1_PCH_C_TXN<12> PCIEUP_12_RXP @BASEBOARD_FAB2_LIB.BASEBOARD_FAB2(SCH_1):P3E_CPU0_PE1_PCH_C_TXN(12)
 R65 P3E_CPU0_PE1_PCH_R_RXN<12> PCIEUP_12_TXN @BASEBOARD_FAB2_LIB.BASEBOARD_FAB2(SCH_1):P3E_CPU0_PE1_PCH_R_RXN(12)
 U65 P3E_CPU0_PE1_PCH_R_RXP<12> PCIEUP_12_TXP @BASEBOARD_FAB2_LIB.BASEBOARD_FAB2(SCH_1):P3E_CPU0_PE1_PCH_R_RXP(12)
 D62 P3E_CPU0_PE1_PCH_C_TXP<13> PCIEUP_13_RXN @BASEBOARD_FAB2_LIB.BASEBOARD_FAB2(SCH_1):P3E_CPU0_PE1_PCH_C_TXP(13)
 B62 P3E_CPU0_PE1_PCH_C_TXN<13> PCIEUP_13_RXP @BASEBOARD_FAB2_LIB.BASEBOARD_FAB2(SCH_1):P3E_CPU0_PE1_PCH_C_TXN(13)
 T63 P3E_CPU0_PE1_PCH_R_RXN<13> PCIEUP_13_TXN @BASEBOARD_FAB2_LIB.BASEBOARD_FAB2(SCH_1):P3E_CPU0_PE1_PCH_R_RXN(13)
 U61 P3E_CPU0_PE1_PCH_R_RXP<13> PCIEUP_13_TXP @BASEBOARD_FAB2_LIB.BASEBOARD_FAB2(SCH_1):P3E_CPU0_PE1_PCH_R_RXP(13)
 C63 P3E_CPU0_PE1_PCH_C_TXP<14> PCIEUP_14_RXN @BASEBOARD_FAB2_LIB.BASEBOARD_FAB2(SCH_1):P3E_CPU0_PE1_PCH_C_TXP(14)
 A63 P3E_CPU0_PE1_PCH_C_TXN<14> PCIEUP_14_RXP @BASEBOARD_FAB2_LIB.BASEBOARD_FAB2(SCH_1):P3E_CPU0_PE1_PCH_C_TXN(14)
 W65 P3E_CPU0_PE1_PCH_R_RXN<14> PCIEUP_14_TXN @BASEBOARD_FAB2_LIB.BASEBOARD_FAB2(SCH_1):P3E_CPU0_PE1_PCH_R_RXN(14)
 V63 P3E_CPU0_PE1_PCH_R_RXP<14> PCIEUP_14_TXP @BASEBOARD_FAB2_LIB.BASEBOARD_FAB2(SCH_1):P3E_CPU0_PE1_PCH_R_RXP(14)
 D64 P3E_CPU0_PE1_PCH_C_TXP<15> PCIEUP_15_RXN @BASEBOARD_FAB2_LIB.BASEBOARD_FAB2(SCH_1):P3E_CPU0_PE1_PCH_C_TXP(15)
 B64 P3E_CPU0_PE1_PCH_C_TXN<15> PCIEUP_15_RXP @BASEBOARD_FAB2_LIB.BASEBOARD_FAB2(SCH_1):P3E_CPU0_PE1_PCH_C_TXN(15)
 Y66 P3E_CPU0_PE1_PCH_R_RXN<15> PCIEUP_15_TXN @BASEBOARD_FAB2_LIB.BASEBOARD_FAB2(SCH_1):P3E_CPU0_PE1_PCH_R_RXN(15)
AA65 P3E_CPU0_PE1_PCH_R_RXP<15> PCIEUP_15_TXP @BASEBOARD_FAB2_LIB.BASEBOARD_FAB2(SCH_1):P3E_CPU0_PE1_PCH_R_RXP(15)
 D49 P3E_CPU0_PE1_PCH_TXN<1> PCIEUP_1_RXN @BASEBOARD_FAB2_LIB.BASEBOARD_FAB2(SCH_1):P3E_CPU0_PE1_PCH_TXN(1)
 B49 P3E_CPU0_PE1_PCH_TXP<1> PCIEUP_1_RXP @BASEBOARD_FAB2_LIB.BASEBOARD_FAB2(SCH_1):P3E_CPU0_PE1_PCH_TXP(1)
 P56 P3E_CPU0_PE1_PCH_RXN<1> PCIEUP_1_TXN @BASEBOARD_FAB2_LIB.BASEBOARD_FAB2(SCH_1):P3E_CPU0_PE1_PCH_RXN(1)
 M56 P3E_CPU0_PE1_PCH_RXP<1> PCIEUP_1_TXP @BASEBOARD_FAB2_LIB.BASEBOARD_FAB2(SCH_1):P3E_CPU0_PE1_PCH_RXP(1)
 C50 P3E_CPU0_PE1_PCH_TXN<2> PCIEUP_2_RXN @BASEBOARD_FAB2_LIB.BASEBOARD_FAB2(SCH_1):P3E_CPU0_PE1_PCH_TXN(2)
 A50 P3E_CPU0_PE1_PCH_TXP<2> PCIEUP_2_RXP @BASEBOARD_FAB2_LIB.BASEBOARD_FAB2(SCH_1):P3E_CPU0_PE1_PCH_TXP(2)
 H54 P3E_CPU0_PE1_PCH_RXN<2> PCIEUP_2_TXN @BASEBOARD_FAB2_LIB.BASEBOARD_FAB2(SCH_1):P3E_CPU0_PE1_PCH_RXN(2)
 G56 P3E_CPU0_PE1_PCH_RXP<2> PCIEUP_2_TXP @BASEBOARD_FAB2_LIB.BASEBOARD_FAB2(SCH_1):P3E_CPU0_PE1_PCH_RXP(2)
 D51 P3E_CPU0_PE1_PCH_TXN<3> PCIEUP_3_RXN @BASEBOARD_FAB2_LIB.BASEBOARD_FAB2(SCH_1):P3E_CPU0_PE1_PCH_TXN(3)
 B51 P3E_CPU0_PE1_PCH_TXP<3> PCIEUP_3_RXP @BASEBOARD_FAB2_LIB.BASEBOARD_FAB2(SCH_1):P3E_CPU0_PE1_PCH_TXP(3)
 J56 P3E_CPU0_PE1_PCH_RXN<3> PCIEUP_3_TXN @BASEBOARD_FAB2_LIB.BASEBOARD_FAB2(SCH_1):P3E_CPU0_PE1_PCH_RXN(3)
 K58 P3E_CPU0_PE1_PCH_RXP<3> PCIEUP_3_TXP @BASEBOARD_FAB2_LIB.BASEBOARD_FAB2(SCH_1):P3E_CPU0_PE1_PCH_RXP(3)
 C52 P3E_CPU0_PE1_PCH_TXN<4> PCIEUP_4_RXN @BASEBOARD_FAB2_LIB.BASEBOARD_FAB2(SCH_1):P3E_CPU0_PE1_PCH_TXN(4)
 A52 P3E_CPU0_PE1_PCH_TXP<4> PCIEUP_4_RXP @BASEBOARD_FAB2_LIB.BASEBOARD_FAB2(SCH_1):P3E_CPU0_PE1_PCH_TXP(4)
 N58 P3E_CPU0_PE1_PCH_RXN<4> PCIEUP_4_TXN @BASEBOARD_FAB2_LIB.BASEBOARD_FAB2(SCH_1):P3E_CPU0_PE1_PCH_RXN(4)
 M59 P3E_CPU0_PE1_PCH_RXP<4> PCIEUP_4_TXP @BASEBOARD_FAB2_LIB.BASEBOARD_FAB2(SCH_1):P3E_CPU0_PE1_PCH_RXP(4)
 D53 P3E_CPU0_PE1_PCH_TXN<5> PCIEUP_5_RXN @BASEBOARD_FAB2_LIB.BASEBOARD_FAB2(SCH_1):P3E_CPU0_PE1_PCH_TXN(5)
 B53 P3E_CPU0_PE1_PCH_TXP<5> PCIEUP_5_RXP @BASEBOARD_FAB2_LIB.BASEBOARD_FAB2(SCH_1):P3E_CPU0_PE1_PCH_TXP(5)
 N61 P3E_CPU0_PE1_PCH_RXN<5> PCIEUP_5_TXN @BASEBOARD_FAB2_LIB.BASEBOARD_FAB2(SCH_1):P3E_CPU0_PE1_PCH_RXN(5)
 K61 P3E_CPU0_PE1_PCH_RXP<5> PCIEUP_5_TXP @BASEBOARD_FAB2_LIB.BASEBOARD_FAB2(SCH_1):P3E_CPU0_PE1_PCH_RXP(5)
 C54 P3E_CPU0_PE1_PCH_TXN<6> PCIEUP_6_RXN @BASEBOARD_FAB2_LIB.BASEBOARD_FAB2(SCH_1):P3E_CPU0_PE1_PCH_TXN(6)
 A54 P3E_CPU0_PE1_PCH_TXP<6> PCIEUP_6_RXP @BASEBOARD_FAB2_LIB.BASEBOARD_FAB2(SCH_1):P3E_CPU0_PE1_PCH_TXP(6)
 H61 P3E_CPU0_PE1_PCH_RXN<6> PCIEUP_6_TXN @BASEBOARD_FAB2_LIB.BASEBOARD_FAB2(SCH_1):P3E_CPU0_PE1_PCH_RXN(6)
 J63 P3E_CPU0_PE1_PCH_RXP<6> PCIEUP_6_TXP @BASEBOARD_FAB2_LIB.BASEBOARD_FAB2(SCH_1):P3E_CPU0_PE1_PCH_RXP(6)
 D55 P3E_CPU0_PE1_PCH_TXN<7> PCIEUP_7_RXN @BASEBOARD_FAB2_LIB.BASEBOARD_FAB2(SCH_1):P3E_CPU0_PE1_PCH_TXN(7)
 B55 P3E_CPU0_PE1_PCH_TXP<7> PCIEUP_7_RXP @BASEBOARD_FAB2_LIB.BASEBOARD_FAB2(SCH_1):P3E_CPU0_PE1_PCH_TXP(7)
 P59 P3E_CPU0_PE1_PCH_RXN<7> PCIEUP_7_TXN @BASEBOARD_FAB2_LIB.BASEBOARD_FAB2(SCH_1):P3E_CPU0_PE1_PCH_RXN(7)
 R61 P3E_CPU0_PE1_PCH_RXP<7> PCIEUP_7_TXP @BASEBOARD_FAB2_LIB.BASEBOARD_FAB2(SCH_1):P3E_CPU0_PE1_PCH_RXP(7)
 C57 P3E_CPU0_PE1_PCH_C_TXP<8> PCIEUP_8_RXN @BASEBOARD_FAB2_LIB.BASEBOARD_FAB2(SCH_1):P3E_CPU0_PE1_PCH_C_TXP(8)
 A57 P3E_CPU0_PE1_PCH_C_TXN<8> PCIEUP_8_RXP @BASEBOARD_FAB2_LIB.BASEBOARD_FAB2(SCH_1):P3E_CPU0_PE1_PCH_C_TXN(8)
 K65 P3E_CPU0_PE1_PCH_R_RXN<8> PCIEUP_8_TXN @BASEBOARD_FAB2_LIB.BASEBOARD_FAB2(SCH_1):P3E_CPU0_PE1_PCH_R_RXN(8)
 M63 P3E_CPU0_PE1_PCH_R_RXP<8> PCIEUP_8_TXP @BASEBOARD_FAB2_LIB.BASEBOARD_FAB2(SCH_1):P3E_CPU0_PE1_PCH_R_RXP(8)
 D58 P3E_CPU0_PE1_PCH_C_TXP<9> PCIEUP_9_RXN @BASEBOARD_FAB2_LIB.BASEBOARD_FAB2(SCH_1):P3E_CPU0_PE1_PCH_C_TXP(9)
 B58 P3E_CPU0_PE1_PCH_C_TXN<9> PCIEUP_9_RXP @BASEBOARD_FAB2_LIB.BASEBOARD_FAB2(SCH_1):P3E_CPU0_PE1_PCH_C_TXN(9)
 J66 P3E_CPU0_PE1_PCH_R_RXN<9> PCIEUP_9_TXN @BASEBOARD_FAB2_LIB.BASEBOARD_FAB2(SCH_1):P3E_CPU0_PE1_PCH_R_RXN(9)
 M66 P3E_CPU0_PE1_PCH_R_RXP<9> PCIEUP_9_TXP @BASEBOARD_FAB2_LIB.BASEBOARD_FAB2(SCH_1):P3E_CPU0_PE1_PCH_R_RXP(9)


DRAWING: @BASEBOARD_FAB2_LIB.BASEBOARD_FAB2(SCH_1):PAGE118 

RES_0402-10.0,1%,1/16W,CHIP,G2A  I66  R3N9
   1 H_PM_SYNC1_GTL_R      A @BASEBOARD_FAB2_LIB.BASEBOARD_FAB2(SCH_1):H_PM_SYNC1_GTL_R
   2 H_PM_SYNC_GTL      B @BASEBOARD_FAB2_LIB.BASEBOARD_FAB2(SCH_1):H_PM_SYNC_GTL

RES_0402-49.9,1%,1/16W,EMPTY,GA  I67  R3N14
   1 H_PM_SYNC_GTL      A @BASEBOARD_FAB2_LIB.BASEBOARD_FAB2(SCH_1):H_PM_SYNC_GTL
   2    GND      B @BASEBOARD_FAB2_LIB.BASEBOARD_FAB2(SCH_1):GND

RES_0402-4.75K,1%,1/16W,CHIP,GA  I71  R3N13
   1 P3V3_STBY      A @BASEBOARD_FAB2_LIB.BASEBOARD_FAB2(SCH_1):P3V3_STBY
   2 IRQ_LVC3_WAKE_N      B @BASEBOARD_FAB2_LIB.BASEBOARD_FAB2(SCH_1):IRQ_LVC3_WAKE_N

LBG_CORE_QAT_EXT_D_BGA1-IC,H91A  I73  U7C1
AT56 XDP_TRST_N CPU_TRST_N @BASEBOARD_FAB2_LIB.BASEBOARD_FAB2(SCH_1):XDP_TRST_N
 K13 PWRGD_DSW_PWROK DSW_PWROK @BASEBOARD_FAB2_LIB.BASEBOARD_FAB2(SCH_1):PWRGD_DSW_PWROK
 G15 XDP_PCH_PWR_DEBUG_N   GPD0 @BASEBOARD_FAB2_LIB.BASEBOARD_FAB2(SCH_1):XDP_PCH_PWR_DEBUG_N
 B14 FM_CPU0_RC_ERROR_R_N GPD10_SLP_S5_N @BASEBOARD_FAB2_LIB.BASEBOARD_FAB2(SCH_1):FM_CPU0_RC_ERROR_R_N
 A13 FM_GBE_LOM_DISABLE_N GPD11_GBEPHY @BASEBOARD_FAB2_LIB.BASEBOARD_FAB2(SCH_1):FM_GBE_LOM_DISABLE_N
 H13 FM_CPU1_SKTOCC_LVT3_N GPD1_ACPRESENT @BASEBOARD_FAB2_LIB.BASEBOARD_FAB2(SCH_1):FM_CPU1_SKTOCC_LVT3_N
 M11 RST_BMC_SRST_R_N GPD2_GBE_WAKE_N @BASEBOARD_FAB2_LIB.BASEBOARD_FAB2(SCH_1):RST_BMC_SRST_R_N
 C15 FM_PCH_PWRBTN_N GPD3_PWRBTN_N @BASEBOARD_FAB2_LIB.BASEBOARD_FAB2(SCH_1):FM_PCH_PWRBTN_N
 D14 FM_SLPS3_R_N GPD4_SLP_S3_N @BASEBOARD_FAB2_LIB.BASEBOARD_FAB2(SCH_1):FM_SLPS3_R_N
 B16 FM_SLPS4_N GPD5_SLP_S4_N @BASEBOARD_FAB2_LIB.BASEBOARD_FAB2(SCH_1):FM_SLPS4_N
 G11 FM_CPU0_SKTOCC_LVT3_N GPD6_SLP_A_N @BASEBOARD_FAB2_LIB.BASEBOARD_FAB2(SCH_1):FM_CPU0_SKTOCC_LVT3_N
  H9 FM_BATTERY_SENSE_EN_R_N   GPD7 @BASEBOARD_FAB2_LIB.BASEBOARD_FAB2(SCH_1):FM_BATTERY_SENSE_EN_R_N
 C13 TP_PCH_GDP8_SUSCLK GPD8_SUSCLK @BASEBOARD_FAB2_LIB.BASEBOARD_FAB2(SCH_1):TP_PCH_GDP8_SUSCLK
 A15 FM_BMC_CPLD_MP_RST_N   GPD9 @BASEBOARD_FAB2_LIB.BASEBOARD_FAB2(SCH_1):FM_BMC_CPLD_MP_RST_N
AR54 XDP_ITP_PMODE ITP_PMODE @BASEBOARD_FAB2_LIB.BASEBOARD_FAB2(SCH_1):XDP_ITP_PMODE
AF54 XDP_PCH_CPU_TCK0  JTAGX @BASEBOARD_FAB2_LIB.BASEBOARD_FAB2(SCH_1):XDP_PCH_CPU_TCK0
AL56 XDP_PCH_TCK1 JTAG_TCK @BASEBOARD_FAB2_LIB.BASEBOARD_FAB2(SCH_1):XDP_PCH_TCK1
AN54 XDP_TDI JTAG_TDI @BASEBOARD_FAB2_LIB.BASEBOARD_FAB2(SCH_1):XDP_TDI
AP56 XDP_TDO JTAG_TDO @BASEBOARD_FAB2_LIB.BASEBOARD_FAB2(SCH_1):XDP_TDO
AH54 XDP_TMS JTAG_TMS @BASEBOARD_FAB2_LIB.BASEBOARD_FAB2(SCH_1):XDP_TMS
BB29 A_KR0_RBIAS LAN_RBIAS_0 @BASEBOARD_FAB2_LIB.BASEBOARD_FAB2(SCH_1):A_KR0_RBIAS
BD42 A_KR1_RBIAS LAN_RBIAS_1 @BASEBOARD_FAB2_LIB.BASEBOARD_FAB2(SCH_1):A_KR1_RBIAS
BH31 KR_P0_OCP_RX_C_DN LAN_RX_P0N @BASEBOARD_FAB2_LIB.BASEBOARD_FAB2(SCH_1):KR_P0_OCP_RX_C_DN
BF31 KR_P0_OCP_RX_C_DP LAN_RX_P0P @BASEBOARD_FAB2_LIB.BASEBOARD_FAB2(SCH_1):KR_P0_OCP_RX_C_DP
BG29 KR_P1_OCP_RX_C_DN LAN_RX_P1N @BASEBOARD_FAB2_LIB.BASEBOARD_FAB2(SCH_1):KR_P1_OCP_RX_C_DN
BJ29 KR_P1_OCP_RX_C_DP LAN_RX_P1P @BASEBOARD_FAB2_LIB.BASEBOARD_FAB2(SCH_1):KR_P1_OCP_RX_C_DP
BJ37     NC LAN_RX_P2N     NC
BG37     NC LAN_RX_P2P     NC
BF35     NC LAN_RX_P3N     NC
BH35     NC LAN_RX_P3P     NC
BM27 KR_P0_OCP_TX_DN LAN_TX_P0N @BASEBOARD_FAB2_LIB.BASEBOARD_FAB2(SCH_1):KR_P0_OCP_TX_DN
BR27 KR_P0_OCP_TX_DP LAN_TX_P0P @BASEBOARD_FAB2_LIB.BASEBOARD_FAB2(SCH_1):KR_P0_OCP_TX_DP
BM24 KR_P1_OCP_TX_DN LAN_TX_P1N @BASEBOARD_FAB2_LIB.BASEBOARD_FAB2(SCH_1):KR_P1_OCP_TX_DN
BR24 KR_P1_OCP_TX_DP LAN_TX_P1P @BASEBOARD_FAB2_LIB.BASEBOARD_FAB2(SCH_1):KR_P1_OCP_TX_DP
BM35     NC LAN_TX_P2N     NC
BR35     NC LAN_TX_P2P     NC
BR31     NC LAN_TX_P3N     NC
BM31     NC LAN_TX_P3P     NC
BV16 XTAL_KR_25M_IN LAN_XTAL_IN @BASEBOARD_FAB2_LIB.BASEBOARD_FAB2(SCH_1):XTAL_KR_25M_IN
BY16 XTAL_KR_25M_OUT LAN_XTAL_OUT @BASEBOARD_FAB2_LIB.BASEBOARD_FAB2(SCH_1):XTAL_KR_25M_OUT
 R17 PWRGD_PCH_PWROK PCH_PWROK @BASEBOARD_FAB2_LIB.BASEBOARD_FAB2(SCH_1):PWRGD_PCH_PWROK
  U9 PECI_PCH   PECI @BASEBOARD_FAB2_LIB.BASEBOARD_FAB2(SCH_1):PECI_PCH
 U17 TP_PLTRST_CPU_N PLTRST_CPU_N @BASEBOARD_FAB2_LIB.BASEBOARD_FAB2(SCH_1):TP_PLTRST_CPU_N
 U13 H_PM_SYNC1_GTL_R PM_SYNC @BASEBOARD_FAB2_LIB.BASEBOARD_FAB2(SCH_1):H_PM_SYNC1_GTL_R
  V7 TP_PM_SYNC_GTL PM_SYNC2 @BASEBOARD_FAB2_LIB.BASEBOARD_FAB2(SCH_1):TP_PM_SYNC_GTL
AD54 XDP_PRDY_N PRDY_N @BASEBOARD_FAB2_LIB.BASEBOARD_FAB2(SCH_1):XDP_PRDY_N
 U54 XDP_PREQ_N PREQ_N @BASEBOARD_FAB2_LIB.BASEBOARD_FAB2(SCH_1):XDP_PREQ_N
  R9 PWRGD_CPUPWRGD_GTL PROC_PWRGD @BASEBOARD_FAB2_LIB.BASEBOARD_FAB2(SCH_1):PWRGD_CPUPWRGD_GTL
 P15 RST_RSMRST_N RSMRST_N @BASEBOARD_FAB2_LIB.BASEBOARD_FAB2(SCH_1):RST_RSMRST_N
 R24 TP_PCH_RSVD54 RSVD<54> @BASEBOARD_FAB2_LIB.BASEBOARD_FAB2(SCH_1):TP_PCH_RSVD54
 P26 TP_PCH_RSVD53 RSVD<53> @BASEBOARD_FAB2_LIB.BASEBOARD_FAB2(SCH_1):TP_PCH_RSVD53
 P22 TP_PCH_RSVD45 RSVD<45> @BASEBOARD_FAB2_LIB.BASEBOARD_FAB2(SCH_1):TP_PCH_RSVD45
BN33 TP_10GBE_KR1_MON_DP RSVD<44> @BASEBOARD_FAB2_LIB.BASEBOARD_FAB2(SCH_1):TP_10GBE_KR1_MON_DP
BL33 TP_10GBE_KR1_MON_DN RSVD<43> @BASEBOARD_FAB2_LIB.BASEBOARD_FAB2(SCH_1):TP_10GBE_KR1_MON_DN
BG40 TP_PCH_RSVD42 RSVD<42> @BASEBOARD_FAB2_LIB.BASEBOARD_FAB2(SCH_1):TP_PCH_RSVD42
BJ40 TP_PCH_RSVD41 RSVD<41> @BASEBOARD_FAB2_LIB.BASEBOARD_FAB2(SCH_1):TP_PCH_RSVD41
BN26 TP_10GBE_KR0_MON_DP RSVD<40> @BASEBOARD_FAB2_LIB.BASEBOARD_FAB2(SCH_1):TP_10GBE_KR0_MON_DP
BL26 TP_10GBE_KR0_MON_DN RSVD<39> @BASEBOARD_FAB2_LIB.BASEBOARD_FAB2(SCH_1):TP_10GBE_KR0_MON_DN
BL29 TP_PCH_RSVD38 RSVD<38> @BASEBOARD_FAB2_LIB.BASEBOARD_FAB2(SCH_1):TP_PCH_RSVD38
BN29 TP_PCH_RSVD37 RSVD<37> @BASEBOARD_FAB2_LIB.BASEBOARD_FAB2(SCH_1):TP_PCH_RSVD37
AK54 TP_PCH_RSVD36 RSVD<36> @BASEBOARD_FAB2_LIB.BASEBOARD_FAB2(SCH_1):TP_PCH_RSVD36
 W54 TP_PCH_RSVD35 RSVD<35> @BASEBOARD_FAB2_LIB.BASEBOARD_FAB2(SCH_1):TP_PCH_RSVD35
 Y56 TP_PCH_RSVD34 RSVD<34> @BASEBOARD_FAB2_LIB.BASEBOARD_FAB2(SCH_1):TP_PCH_RSVD34
 V56 TP_PCH_RSVD33 RSVD<33> @BASEBOARD_FAB2_LIB.BASEBOARD_FAB2(SCH_1):TP_PCH_RSVD33
AA54 TP_PCH_RSVD32 RSVD<32> @BASEBOARD_FAB2_LIB.BASEBOARD_FAB2(SCH_1):TP_PCH_RSVD32
 M15 TP_SLP_LAN_N SLP_GBE_N @BASEBOARD_FAB2_LIB.BASEBOARD_FAB2(SCH_1):TP_SLP_LAN_N
  P7 FM_SLP_SUS_N SLP_SUS_N @BASEBOARD_FAB2_LIB.BASEBOARD_FAB2(SCH_1):FM_SLP_SUS_N
BY19 PWRGD_SYS_PWROK SYS_PWROK @BASEBOARD_FAB2_LIB.BASEBOARD_FAB2(SCH_1):PWRGD_SYS_PWROK
BV19 RST_BMC_SYSRST_BTN_OUT_B_N SYS_RESET_N @BASEBOARD_FAB2_LIB.BASEBOARD_FAB2(SCH_1):RST_BMC_SYSRST_BTN_OUT_B_N
 V15 FM_PCH_LVC1_THERMTRIP_N THRMTRIP_N @BASEBOARD_FAB2_LIB.BASEBOARD_FAB2(SCH_1):FM_PCH_LVC1_THERMTRIP_N
  M7 TP_CPU_PCH_TRIGGER_IN TRIGGER_IN @BASEBOARD_FAB2_LIB.BASEBOARD_FAB2(SCH_1):TP_CPU_PCH_TRIGGER_IN
 R13 TP_CPU_PCH_TRIGGER_OUT TRIGGER_OUT @BASEBOARD_FAB2_LIB.BASEBOARD_FAB2(SCH_1):TP_CPU_PCH_TRIGGER_OUT
  K9 IRQ_LVC3_WAKE_N WAKE_N @BASEBOARD_FAB2_LIB.BASEBOARD_FAB2(SCH_1):IRQ_LVC3_WAKE_N

CRYSTAL_2013-25.000MHZ,IC,H196A  I76  Y8C1
   1 XTAL_KR_25M_IN      A @BASEBOARD_FAB2_LIB.BASEBOARD_FAB2(SCH_1):XTAL_KR_25M_IN
   3 XTAL_KR_25M_OUT      B @BASEBOARD_FAB2_LIB.BASEBOARD_FAB2(SCH_1):XTAL_KR_25M_OUT

RES_0402-1.0K,0.1%,1/16W,CHIP,A  I96  R2N4
   1 P1V05_PCH_STBY_KR_PLL      A @BASEBOARD_FAB2_LIB.BASEBOARD_FAB2(SCH_1):P1V05_PCH_STBY_KR_PLL
   2 A_KR0_RBIAS      B @BASEBOARD_FAB2_LIB.BASEBOARD_FAB2(SCH_1):A_KR0_RBIAS

RES_0402-1.0K,0.1%,1/16W,CHIP,A  I99  R2M6
   1 A_KR1_RBIAS      A @BASEBOARD_FAB2_LIB.BASEBOARD_FAB2(SCH_1):A_KR1_RBIAS
   2 P1V05_PCH_STBY_KR_PLL      B @BASEBOARD_FAB2_LIB.BASEBOARD_FAB2(SCH_1):P1V05_PCH_STBY_KR_PLL

RES_0402-0.0,5%,1/16W,CHIP,G21A  I120  R8C24
   1 FM_GBE_LOM_DISABLE_N      A @BASEBOARD_FAB2_LIB.BASEBOARD_FAB2(SCH_1):FM_GBE_LOM_DISABLE_N
   2 FM_1GB_LOM_DISABLE_N      B @BASEBOARD_FAB2_LIB.BASEBOARD_FAB2(SCH_1):FM_1GB_LOM_DISABLE_N

RES_0402-0.0,5%,1/16W,EMPTY,G2A  I125  R8C23
   1 FM_GBE_LOM_DISABLE_N      A @BASEBOARD_FAB2_LIB.BASEBOARD_FAB2(SCH_1):FM_GBE_LOM_DISABLE_N
   2 FM_10GBE_LOM_DISABLE_N      B @BASEBOARD_FAB2_LIB.BASEBOARD_FAB2(SCH_1):FM_10GBE_LOM_DISABLE_N

RES_0402-10.0K,1%,1/16W,CHIP,GA  I128  R2N6
   1 P3V3_STBY      A @BASEBOARD_FAB2_LIB.BASEBOARD_FAB2(SCH_1):P3V3_STBY
   2 FM_GBE_LOM_DISABLE_N      B @BASEBOARD_FAB2_LIB.BASEBOARD_FAB2(SCH_1):FM_GBE_LOM_DISABLE_N

RES_0402-0.0,5%,1/16W,CHIP,G21A  I131  R7D23
   1 RST_BMC_SRST_N      A @BASEBOARD_FAB2_LIB.BASEBOARD_FAB2(SCH_1):RST_BMC_SRST_N
   2 RST_BMC_SRST_R_N      B @BASEBOARD_FAB2_LIB.BASEBOARD_FAB2(SCH_1):RST_BMC_SRST_R_N

CAP_A_0402V-0.1UF,16V,10%,X7R,A  I136  C7D1
   1 P3V3_STBY      A @BASEBOARD_FAB2_LIB.BASEBOARD_FAB2(SCH_1):P3V3_STBY
   2    GND      B @BASEBOARD_FAB2_LIB.BASEBOARD_FAB2(SCH_1):GND

74CBTLV1G125_SMLF-IC,C88177-00A  I142  U7D1
   4 XDP_CPU_PWR_DEBUG_N      B @BASEBOARD_FAB2_LIB.BASEBOARD_FAB2(SCH_1):XDP_CPU_PWR_DEBUG_N
   1 PWRGD_PVCCIO_CPU0   OE_N @BASEBOARD_FAB2_LIB.BASEBOARD_FAB2(SCH_1):PWRGD_PVCCIO_CPU0
   2 XDP_PCH_PWR_DEBUG_N      A @BASEBOARD_FAB2_LIB.BASEBOARD_FAB2(SCH_1):XDP_PCH_PWR_DEBUG_N

RES_0402-10.0K,1%,1/16W,CHIP,GA  I144  R7C23
   1 P3V3_STBY      A @BASEBOARD_FAB2_LIB.BASEBOARD_FAB2(SCH_1):P3V3_STBY
   2 XDP_PCH_PWR_DEBUG_N      B @BASEBOARD_FAB2_LIB.BASEBOARD_FAB2(SCH_1):XDP_PCH_PWR_DEBUG_N

RES_0402-0.0,5%,1/16W,CHIP,G21A  I167  R7W1
   1 FM_SLPS3_N      A @BASEBOARD_FAB2_LIB.BASEBOARD_FAB2(SCH_1):FM_SLPS3_N
   2 FM_SLPS3_R_N      B @BASEBOARD_FAB2_LIB.BASEBOARD_FAB2(SCH_1):FM_SLPS3_R_N

RES_0402-0.0,5%,1/16W,EMPTY,G2A  I168  R1W30
   1 RST_BMC_SYSRST_BTN_OUT_B_N      A @BASEBOARD_FAB2_LIB.BASEBOARD_FAB2(SCH_1):RST_BMC_SYSRST_BTN_OUT_B_N
   2 RST_SYSTEM_BTN_BUF_N      B @BASEBOARD_FAB2_LIB.BASEBOARD_FAB2(SCH_1):RST_SYSTEM_BTN_BUF_N

RES_0402-0.0,5%,1/16W,CHIP,G21A  I176  R7W6
   1 FM_BATTERY_SENSE_EN_N      A @BASEBOARD_FAB2_LIB.BASEBOARD_FAB2(SCH_1):FM_BATTERY_SENSE_EN_N
   2 FM_BATTERY_SENSE_EN_R_N      B @BASEBOARD_FAB2_LIB.BASEBOARD_FAB2(SCH_1):FM_BATTERY_SENSE_EN_R_N

RES_0402-0.0,5%,1/16W,CHIP,G21A  I177  R7W9
   1 FM_CPU0_RC_ERROR_N      A @BASEBOARD_FAB2_LIB.BASEBOARD_FAB2(SCH_1):FM_CPU0_RC_ERROR_N
   2 FM_CPU0_RC_ERROR_R_N      B @BASEBOARD_FAB2_LIB.BASEBOARD_FAB2(SCH_1):FM_CPU0_RC_ERROR_R_N

CAP_0402LF-33.0PF,50V,5%,COG,AA  I178  C8C1
   1 XTAL_KR_25M_IN      A @BASEBOARD_FAB2_LIB.BASEBOARD_FAB2(SCH_1):XTAL_KR_25M_IN
   2    GND      B @BASEBOARD_FAB2_LIB.BASEBOARD_FAB2(SCH_1):GND

CAP_0402LF-33.0PF,50V,5%,COG,AA  I179  C8C2
   1 XTAL_KR_25M_OUT      A @BASEBOARD_FAB2_LIB.BASEBOARD_FAB2(SCH_1):XTAL_KR_25M_OUT
   2    GND      B @BASEBOARD_FAB2_LIB.BASEBOARD_FAB2(SCH_1):GND

RES_0402-4.75K,1%,1/16W,CHIP,GA  I180  R7W19
   1 P3V3_STBY      A @BASEBOARD_FAB2_LIB.BASEBOARD_FAB2(SCH_1):P3V3_STBY
   2 FM_BATTERY_SENSE_EN_R_N      B @BASEBOARD_FAB2_LIB.BASEBOARD_FAB2(SCH_1):FM_BATTERY_SENSE_EN_R_N

RES_0402-4.75K,1%,1/16W,CHIP,GA  I183  R7W21
   1 P3V3_STBY      A @BASEBOARD_FAB2_LIB.BASEBOARD_FAB2(SCH_1):P3V3_STBY
   2 RST_BMC_SRST_R_N      B @BASEBOARD_FAB2_LIB.BASEBOARD_FAB2(SCH_1):RST_BMC_SRST_R_N


DRAWING: @BASEBOARD_FAB2_LIB.BASEBOARD_FAB2(SCH_1):PAGE119 

LBG_CORE_QAT_EXT_D_BGA1-IC,H91A  I115  U7C1
  N3 PU_FM_RCIN_N GPP_A0_RCIN_N_ESPI_ALERT1_N @BASEBOARD_FAB2_LIB.BASEBOARD_FAB2(SCH_1):PU_FM_RCIN_N
 AA4     NC GPP_A10_CLKOUT_LPC1     NC
 AC2 PU_LPC_PME_N GPP_A11_PME_N @BASEBOARD_FAB2_LIB.BASEBOARD_FAB2(SCH_1):PU_LPC_PME_N
  R1 PU_IRQ_PCH_SCI_WHEA_N GPP_A12_BMBUSY_N_SXEXITHLDOFF_N @BASEBOARD_FAB2_LIB.BASEBOARD_FAB2(SCH_1):PU_IRQ_PCH_SCI_WHEA_N
  T4 FM_MB_SLOT_ID0 GPP_A13_SUSWARN_N_SUSPWRDNACK @BASEBOARD_FAB2_LIB.BASEBOARD_FAB2(SCH_1):FM_MB_SLOT_ID0
 AB3 FM_MB_SLOT_ID1 GPP_A14_ESPI_RESET_N @BASEBOARD_FAB2_LIB.BASEBOARD_FAB2(SCH_1):FM_MB_SLOT_ID1
 AC4 FM_MB_SLOT_ID2 GPP_A15_SUSACK_N @BASEBOARD_FAB2_LIB.BASEBOARD_FAB2(SCH_1):FM_MB_SLOT_ID2
  T2 FM_UART_PRES_N GPP_A16_CLKOUT_LPC2 @BASEBOARD_FAB2_LIB.BASEBOARD_FAB2(SCH_1):FM_UART_PRES_N
 AD1 FM_CPU_BMC_INIT GPP_A17 @BASEBOARD_FAB2_LIB.BASEBOARD_FAB2(SCH_1):FM_CPU_BMC_INIT
 AD3 RST_PCH_SYSRST_BTN_OUT_N GPP_A18 @BASEBOARD_FAB2_LIB.BASEBOARD_FAB2(SCH_1):RST_PCH_SYSRST_BTN_OUT_N
  V3 FM_ME_RECOVER_N GPP_A19 @BASEBOARD_FAB2_LIB.BASEBOARD_FAB2(SCH_1):FM_ME_RECOVER_N
  Y3 LPC_LAD0_IO0 GPP_A1_LAD0_ESPI_IO0 @BASEBOARD_FAB2_LIB.BASEBOARD_FAB2(SCH_1):LPC_LAD0_IO0
  W4     NC GPP_A20     NC
 AE2 FM_OCP_MEZZA_PRES_R GPP_A21 @BASEBOARD_FAB2_LIB.BASEBOARD_FAB2(SCH_1):FM_OCP_MEZZA_PRES_R
 AE4 FM_TPM_PRES_N GPP_A22 @BASEBOARD_FAB2_LIB.BASEBOARD_FAB2(SCH_1):FM_TPM_PRES_N
  V1 FM_BMC_READY_R_N GPP_A23 @BASEBOARD_FAB2_LIB.BASEBOARD_FAB2(SCH_1):FM_BMC_READY_R_N
  N1 LPC_LAD1_IO1 GPP_A2_LAD1_ESPI_IO1 @BASEBOARD_FAB2_LIB.BASEBOARD_FAB2(SCH_1):LPC_LAD1_IO1
  W2 LPC_LAD2_IO2 GPP_A3_LAD2_ESPI_IO2 @BASEBOARD_FAB2_LIB.BASEBOARD_FAB2(SCH_1):LPC_LAD2_IO2
  Y1 LPC_LAD3_IO3 GPP_A4_LAD3_ESPI_IO3 @BASEBOARD_FAB2_LIB.BASEBOARD_FAB2(SCH_1):LPC_LAD3_IO3
  P4 LPC_LFRAME_N_CS0_N GPP_A5_LFRAME_N_ESPI_CS0_N @BASEBOARD_FAB2_LIB.BASEBOARD_FAB2(SCH_1):LPC_LFRAME_N_CS0_N
  P2 IRQ_LPC_SERIRQ_N GPP_A6_SERIRQ_ESPI_CS1_N @BASEBOARD_FAB2_LIB.BASEBOARD_FAB2(SCH_1):IRQ_LPC_SERIRQ_N
 AA2 IRQ_PIRQA_SPI_TPM_N GPP_A7_PIRQA_N_ESPI_ALERT0_N @BASEBOARD_FAB2_LIB.BASEBOARD_FAB2(SCH_1):IRQ_PIRQA_SPI_TPM_N
 AB1 PU_LPC_CLKRUN_N GPP_A8_CLKRUN_N @BASEBOARD_FAB2_LIB.BASEBOARD_FAB2(SCH_1):PU_LPC_CLKRUN_N
  R3 CLK_24M_BMC_LPC_R GPP_A9_CLKOUT_LPC0_ESPI_CLK @BASEBOARD_FAB2_LIB.BASEBOARD_FAB2(SCH_1):CLK_24M_BMC_LPC_R
 BL7 VID_PCH_CORE_PVNN_AUX_VID_0 GPP_B0_CORE_VID0 @BASEBOARD_FAB2_LIB.BASEBOARD_FAB2(SCH_1):VID_PCH_CORE_PVNN_AUX_VID_0
BL11 RST_SYSTEM_BTN_N GPP_B10_SRCCLKREQ5_N @BASEBOARD_FAB2_LIB.BASEBOARD_FAB2(SCH_1):RST_SYSTEM_BTN_N
 BK9 FM_PMBUS_ALERT_BUF_EN_R2_N GPP_B11 @BASEBOARD_FAB2_LIB.BASEBOARD_FAB2(SCH_1):FM_PMBUS_ALERT_BUF_EN_R2_N
BL18 FM_GLOBAL_RST_WARN_N GPP_B12_GLB_RST_WARN_N @BASEBOARD_FAB2_LIB.BASEBOARD_FAB2(SCH_1):FM_GLOBAL_RST_WARN_N
BN18 RST_PLTRST_N GPP_B13_PLTRST_N @BASEBOARD_FAB2_LIB.BASEBOARD_FAB2(SCH_1):RST_PLTRST_N
BH13 FM_BIOS_TOP_SWAP_SPKR GPP_B14_SPKR @BASEBOARD_FAB2_LIB.BASEBOARD_FAB2(SCH_1):FM_BIOS_TOP_SWAP_SPKR
BK13 FM_UART_ALERT_N GPP_B15 @BASEBOARD_FAB2_LIB.BASEBOARD_FAB2(SCH_1):FM_UART_ALERT_N
BG22 IRQ_PCH_NIC_ALERT_N GPP_B16 @BASEBOARD_FAB2_LIB.BASEBOARD_FAB2(SCH_1):IRQ_PCH_NIC_ALERT_N
BG15 FM_PCH_PWRBTN_OUT_N GPP_B17 @BASEBOARD_FAB2_LIB.BASEBOARD_FAB2(SCH_1):FM_PCH_PWRBTN_OUT_N
BL15 FM_UV_ADR_TRIGGER_EN GPP_B18 @BASEBOARD_FAB2_LIB.BASEBOARD_FAB2(SCH_1):FM_UV_ADR_TRIGGER_EN
BK20 FM_BIOS_PREFRB2_GOOD GPP_B19 @BASEBOARD_FAB2_LIB.BASEBOARD_FAB2(SCH_1):FM_BIOS_PREFRB2_GOOD
 BH9 VID_PCH_CORE_PVNN_AUX_VID_1 GPP_B1_CORE_VID1 @BASEBOARD_FAB2_LIB.BASEBOARD_FAB2(SCH_1):VID_PCH_CORE_PVNN_AUX_VID_1
BN15 PU_IRQ_VRALERT_N GPP_B2 @BASEBOARD_FAB2_LIB.BASEBOARD_FAB2(SCH_1):PU_IRQ_VRALERT_N
BJ22 FM_BIOS_POST_CMPLT_N GPP_B20 @BASEBOARD_FAB2_LIB.BASEBOARD_FAB2(SCH_1):FM_BIOS_POST_CMPLT_N
BH17 FM_FAST_PROCHOT_EN_N GPP_B21 @BASEBOARD_FAB2_LIB.BASEBOARD_FAB2(SCH_1):FM_FAST_PROCHOT_EN_N
BR17 FM_USB_P0_EN_BOOT_BIOS_STRAP_N GPP_B22 @BASEBOARD_FAB2_LIB.BASEBOARD_FAB2(SCH_1):FM_USB_P0_EN_BOOT_BIOS_STRAP_N
BM20 FM_PCH_BMC_THERMTRIP_EXI_STRAP_ GPP_B23_MEIE_SML1ALRT_N_PHOT_N @BASEBOARD_FAB2_LIB.BASEBOARD_FAB2(SCH_1):FM_PCH_BMC_THERMTRIP_EXI_STRAP_N
 BR9 FM_QAT_EN_N GPP_B3_CPU_GP2 @BASEBOARD_FAB2_LIB.BASEBOARD_FAB2(SCH_1):FM_QAT_EN_N
 BN7 IRQ_PVDDQ_ABC_VRHOT_LVT3_N GPP_B4_CPU_GP3 @BASEBOARD_FAB2_LIB.BASEBOARD_FAB2(SCH_1):IRQ_PVDDQ_ABC_VRHOT_LVT3_N
BK17 IRQ_PVDDQ_DEF_VRHOT_LVT3_N GPP_B5_SRCCLKREQ0_N @BASEBOARD_FAB2_LIB.BASEBOARD_FAB2(SCH_1):IRQ_PVDDQ_DEF_VRHOT_LVT3_N
BG18 IRQ_PVDDQ_GHJ_VRHOT_LVT3_N GPP_B6_SRCCLKREQ1_N @BASEBOARD_FAB2_LIB.BASEBOARD_FAB2(SCH_1):IRQ_PVDDQ_GHJ_VRHOT_LVT3_N
BR13 IRQ_PVDDQ_KLM_VRHOT_LVT3_N GPP_B7_SRCCLKREQ2_N @BASEBOARD_FAB2_LIB.BASEBOARD_FAB2(SCH_1):IRQ_PVDDQ_KLM_VRHOT_LVT3_N
BN11 FP_NMI_BTN_N GPP_B8_SRCCLKREQ3_N @BASEBOARD_FAB2_LIB.BASEBOARD_FAB2(SCH_1):FP_NMI_BTN_N
BH20 FM_PWR_BTN_N GPP_B9_SRCCLKREQ4_N @BASEBOARD_FAB2_LIB.BASEBOARD_FAB2(SCH_1):FM_PWR_BTN_N
BW28 SMB_HOST_STBY_LVC3_SCL_R1 GPP_C0_SMBCLK @BASEBOARD_FAB2_LIB.BASEBOARD_FAB2(SCH_1):SMB_HOST_STBY_LVC3_SCL_R1
BV31 FM_PCH_SATA_RAID_KEY GPP_C10 @BASEBOARD_FAB2_LIB.BASEBOARD_FAB2(SCH_1):FM_PCH_SATA_RAID_KEY
BV33 FM_BOARD_REV_ID2 GPP_C11 @BASEBOARD_FAB2_LIB.BASEBOARD_FAB2(SCH_1):FM_BOARD_REV_ID2
CA30 FM_BOARD_REV_ID0 GPP_C12 @BASEBOARD_FAB2_LIB.BASEBOARD_FAB2(SCH_1):FM_BOARD_REV_ID0
BV38 FM_BOARD_REV_ID1 GPP_C13 @BASEBOARD_FAB2_LIB.BASEBOARD_FAB2(SCH_1):FM_BOARD_REV_ID1
BY38 IRQ_BMC_PCH_SCI_LPC_N GPP_C14 @BASEBOARD_FAB2_LIB.BASEBOARD_FAB2(SCH_1):IRQ_BMC_PCH_SCI_LPC_N
CA32 FM_SLT_CFG0 GPP_C15 @BASEBOARD_FAB2_LIB.BASEBOARD_FAB2(SCH_1):FM_SLT_CFG0
BW37 FM_SLT_CFG1 GPP_C16 @BASEBOARD_FAB2_LIB.BASEBOARD_FAB2(SCH_1):FM_SLT_CFG1
BY31 FM_SLT_CFG2_R GPP_C17 @BASEBOARD_FAB2_LIB.BASEBOARD_FAB2(SCH_1):FM_SLT_CFG2_R
BY35 FM_PMBUS_ALERT_BUF_EN_R_N GPP_C18 @BASEBOARD_FAB2_LIB.BASEBOARD_FAB2(SCH_1):FM_PMBUS_ALERT_BUF_EN_R_N
BW39 FM_BB_BMC_MP_GPIO GPP_C19 @BASEBOARD_FAB2_LIB.BASEBOARD_FAB2(SCH_1):FM_BB_BMC_MP_GPIO
BV27 SMB_HOST_STBY_LVC3_SDA_R1 GPP_C1_SMBDATA @BASEBOARD_FAB2_LIB.BASEBOARD_FAB2(SCH_1):SMB_HOST_STBY_LVC3_SDA_R1
CA39 FM_THROTTLE_R2_N GPP_C20 @BASEBOARD_FAB2_LIB.BASEBOARD_FAB2(SCH_1):FM_THROTTLE_R2_N
BY33 FM_BIOS_POST_CMPLT_N GPP_C21 @BASEBOARD_FAB2_LIB.BASEBOARD_FAB2(SCH_1):FM_BIOS_POST_CMPLT_N
CA34 IRQ_BMC_PCH_SMI_LPC_N GPP_C22 @BASEBOARD_FAB2_LIB.BASEBOARD_FAB2(SCH_1):IRQ_BMC_PCH_SMI_LPC_N
CA37 FM_CPU_CATERR_DLY_LVT3_R_N GPP_C23 @BASEBOARD_FAB2_LIB.BASEBOARD_FAB2(SCH_1):FM_CPU_CATERR_DLY_LVT3_R_N
BY27 PU_PCH_TLS_ENABLE_STRAP GPP_C2_SMBALERT_N @BASEBOARD_FAB2_LIB.BASEBOARD_FAB2(SCH_1):PU_PCH_TLS_ENABLE_STRAP
BV29 SMB_SMLINK0_STBY_LVC3_SCL_R1 GPP_C3_SML0CLK_IE @BASEBOARD_FAB2_LIB.BASEBOARD_FAB2(SCH_1):SMB_SMLINK0_STBY_LVC3_SCL_R1
BW30 SMB_SMLINK0_STBY_LVC3_SDA_R1 GPP_C4_SML0DATA_IE @BASEBOARD_FAB2_LIB.BASEBOARD_FAB2(SCH_1):SMB_SMLINK0_STBY_LVC3_SDA_R1
BW34 IRQ_SML0_ALERT_N GPP_C5_SML0ALERT_IE_N @BASEBOARD_FAB2_LIB.BASEBOARD_FAB2(SCH_1):IRQ_SML0_ALERT_N
CA28 SMB_PMBUS_BMC_STBY_LVC3_SCL_R1 GPP_C6_SML1CLK_IE @BASEBOARD_FAB2_LIB.BASEBOARD_FAB2(SCH_1):SMB_PMBUS_BMC_STBY_LVC3_SCL_R1
BV35 SMB_PMBUS_BMC_STBY_LVC3_SDA_R1 GPP_C7_SML1DATA_IE @BASEBOARD_FAB2_LIB.BASEBOARD_FAB2(SCH_1):SMB_PMBUS_BMC_STBY_LVC3_SDA_R1
BW32 FM_PASSWORD_CLEAR_N GPP_C8 @BASEBOARD_FAB2_LIB.BASEBOARD_FAB2(SCH_1):FM_PASSWORD_CLEAR_N
BY29 FM_CPU1_RC_EN GPP_C9 @BASEBOARD_FAB2_LIB.BASEBOARD_FAB2(SCH_1):FM_CPU1_RC_EN
BR42 IRQ_BMC_PCH_NMI_STBY_R_N GPP_D0 @BASEBOARD_FAB2_LIB.BASEBOARD_FAB2(SCH_1):IRQ_BMC_PCH_NMI_STBY_R_N
BK46 FM_PWR_LED_N GPP_D1 @BASEBOARD_FAB2_LIB.BASEBOARD_FAB2(SCH_1):FM_PWR_LED_N
BV47 H_CPU0_FAST_WAKE_LVT3_N GPP_D10_SSATA_DEVSLP4 @BASEBOARD_FAB2_LIB.BASEBOARD_FAB2(SCH_1):H_CPU0_FAST_WAKE_LVT3_N
BY47 IRQ_LOM_ALERT_N GPP_D11_SSATA_DEVSLP5 @BASEBOARD_FAB2_LIB.BASEBOARD_FAB2(SCH_1):IRQ_LOM_ALERT_N
BN40 FM_TPM_PRES_RST_N GPP_D12_SSATA_SDATAOUT1 @BASEBOARD_FAB2_LIB.BASEBOARD_FAB2(SCH_1):FM_TPM_PRES_RST_N
BY44 SMB_SLOTX24_PCH_STBY_LVC3_SCL GPP_D13_SML0BCLK_IE @BASEBOARD_FAB2_LIB.BASEBOARD_FAB2(SCH_1):SMB_SLOTX24_PCH_STBY_LVC3_SCL
BL44 SMB_SLOTX24_PCH_STBY_LVC3_SDA GPP_D14_SML0BDATA_IE @BASEBOARD_FAB2_LIB.BASEBOARD_FAB2(SCH_1):SMB_SLOTX24_PCH_STBY_LVC3_SDA
BW43 SGPIO_PCH_SSATA_DOUT0 GPP_D15_SSATA_SDATAOUT0 @BASEBOARD_FAB2_LIB.BASEBOARD_FAB2(SCH_1):SGPIO_PCH_SSATA_DOUT0
BV42 IRQ_OOB_MGMT_RISER_ALERT_N GPP_D16_SML0BALERT_IE_N @BASEBOARD_FAB2_LIB.BASEBOARD_FAB2(SCH_1):IRQ_OOB_MGMT_RISER_ALERT_N
BW48 FM_XRC_PRESENT_N GPP_D17 @BASEBOARD_FAB2_LIB.BASEBOARD_FAB2(SCH_1):FM_XRC_PRESENT_N
CA41 FM_XRC_READY_N GPP_D18 @BASEBOARD_FAB2_LIB.BASEBOARD_FAB2(SCH_1):FM_XRC_READY_N
CA43 FM_ADR_MODE_SEL_R GPP_D19 @BASEBOARD_FAB2_LIB.BASEBOARD_FAB2(SCH_1):FM_ADR_MODE_SEL_R
BJ44 IRQ_HSC_FAULT_N GPP_D2 @BASEBOARD_FAB2_LIB.BASEBOARD_FAB2(SCH_1):IRQ_HSC_FAULT_N
CA48 FM_BMC_HEARTBEAT_N GPP_D20 @BASEBOARD_FAB2_LIB.BASEBOARD_FAB2(SCH_1):FM_BMC_HEARTBEAT_N
BV44     NC GPP_D21_IE_UART_RX     NC
BR46     NC GPP_D22_IE_UART_TX     NC
BN44 FM_CPU0_THERMTRIP_LATCH_LVT3_N GPP_D23 @BASEBOARD_FAB2_LIB.BASEBOARD_FAB2(SCH_1):FM_CPU0_THERMTRIP_LATCH_LVT3_N
BW45 IRQ_MEZZ_LAN_ALERT_N GPP_D3 @BASEBOARD_FAB2_LIB.BASEBOARD_FAB2(SCH_1):IRQ_MEZZ_LAN_ALERT_N
BM42 FM_PCH_PLD_DATA_R GPP_D4 @BASEBOARD_FAB2_LIB.BASEBOARD_FAB2(SCH_1):FM_PCH_PLD_DATA_R
BM38 FM_BMC_ENABLE_N GPP_D5 @BASEBOARD_FAB2_LIB.BASEBOARD_FAB2(SCH_1):FM_BMC_ENABLE_N
BW41 FM_CPLD_BMC_PWRDN_N GPP_D6 @BASEBOARD_FAB2_LIB.BASEBOARD_FAB2(SCH_1):FM_CPLD_BMC_PWRDN_N
CA45 FM_BMC_CPLD_GPO GPP_D7 @BASEBOARD_FAB2_LIB.BASEBOARD_FAB2(SCH_1):FM_BMC_CPLD_GPO
BR38 FM_BMC_FAULT_LED_N GPP_D8 @BASEBOARD_FAB2_LIB.BASEBOARD_FAB2(SCH_1):FM_BMC_FAULT_LED_N
BY42 IRQ_FORCE_NM_THROTTLE_N GPP_D9_SSATA_DEVSLP3 @BASEBOARD_FAB2_LIB.BASEBOARD_FAB2(SCH_1):IRQ_FORCE_NM_THROTTLE_N

RES_0402-33.2,1%,1/16W,CHIP,G2A  I172  R2M3
   1 FM_PCH_PLD_DATA_R      A @BASEBOARD_FAB2_LIB.BASEBOARD_FAB2(SCH_1):FM_PCH_PLD_DATA_R
   2 FM_PCH_PLD_DATA      B @BASEBOARD_FAB2_LIB.BASEBOARD_FAB2(SCH_1):FM_PCH_PLD_DATA

RES_0402-33.2,1%,1/16W,CHIP,G2A  I173  R2N1
   1 FM_CPU_CATERR_DLY_LVT3_R_N      A @BASEBOARD_FAB2_LIB.BASEBOARD_FAB2(SCH_1):FM_CPU_CATERR_DLY_LVT3_R_N
   2 FM_CPU_CATERR_DLY_LVT3_N      B @BASEBOARD_FAB2_LIB.BASEBOARD_FAB2(SCH_1):FM_CPU_CATERR_DLY_LVT3_N

RES_0402-33.2,1%,1/16W,CHIP,G2A  I174  R2M7
   1 FM_ADR_MODE_SEL_R      A @BASEBOARD_FAB2_LIB.BASEBOARD_FAB2(SCH_1):FM_ADR_MODE_SEL_R
   2 FM_ADR_MODE_SEL      B @BASEBOARD_FAB2_LIB.BASEBOARD_FAB2(SCH_1):FM_ADR_MODE_SEL

FET_N_DUAL_SMLF-NTJD4001N,FET,A  I175  Q9A2
   2 FM_PWR_LED_N GATE<0> @BASEBOARD_FAB2_LIB.BASEBOARD_FAB2(SCH_1):FM_PWR_LED_N
   1    GND SOURCE<0> @BASEBOARD_FAB2_LIB.BASEBOARD_FAB2(SCH_1):GND
   6 FM_PWR_LED DRAIN<0> @BASEBOARD_FAB2_LIB.BASEBOARD_FAB2(SCH_1):FM_PWR_LED

RES_0402-221,1.0%,1/16W,CHIP,GA  I178  R9A20
   1 FM_PWR_LED_A      A @BASEBOARD_FAB2_LIB.BASEBOARD_FAB2(SCH_1):FM_PWR_LED_A
   2 P3V3_STBY      B @BASEBOARD_FAB2_LIB.BASEBOARD_FAB2(SCH_1):P3V3_STBY

LED_A1LF-GREEN,IC,C97278-010  I179  DS9A5
   2 FM_PWR_LED_K      C @BASEBOARD_FAB2_LIB.BASEBOARD_FAB2(SCH_1):FM_PWR_LED_K
   1 FM_PWR_LED_A      A @BASEBOARD_FAB2_LIB.BASEBOARD_FAB2(SCH_1):FM_PWR_LED_A

FET_N_DUAL_SMLF-NTJD4001N,FET,A  I180  Q9A2
   5 FM_PWR_LED GATE<0> @BASEBOARD_FAB2_LIB.BASEBOARD_FAB2(SCH_1):FM_PWR_LED
   4    GND SOURCE<0> @BASEBOARD_FAB2_LIB.BASEBOARD_FAB2(SCH_1):GND
   3 FM_PWR_LED_K DRAIN<0> @BASEBOARD_FAB2_LIB.BASEBOARD_FAB2(SCH_1):FM_PWR_LED_K

RES_0402-4.75K,1%,1/16W,CHIP,GA  I183  R9A18
   1 P3V3_STBY      A @BASEBOARD_FAB2_LIB.BASEBOARD_FAB2(SCH_1):P3V3_STBY
   2 FM_PWR_LED      B @BASEBOARD_FAB2_LIB.BASEBOARD_FAB2(SCH_1):FM_PWR_LED

RES_0402-4.75K,1%,1/16W,CHIP,GA  I186  R9A21
   1 P3V3_STBY      A @BASEBOARD_FAB2_LIB.BASEBOARD_FAB2(SCH_1):P3V3_STBY
   2 FM_PWR_LED_N      B @BASEBOARD_FAB2_LIB.BASEBOARD_FAB2(SCH_1):FM_PWR_LED_N

RES_0402-33.2,1%,1/16W,CHIP,G2A  I189  R7C26
   1 CLK_24M_BMC_LPC      A @BASEBOARD_FAB2_LIB.BASEBOARD_FAB2(SCH_1):CLK_24M_BMC_LPC
   2 CLK_24M_BMC_LPC_R      B @BASEBOARD_FAB2_LIB.BASEBOARD_FAB2(SCH_1):CLK_24M_BMC_LPC_R

RES_0402-4.75K,1%,1/16W,CHIP,GA  I213  R2U48
   1 P3V3_STBY      A @BASEBOARD_FAB2_LIB.BASEBOARD_FAB2(SCH_1):P3V3_STBY
   2 FM_SLT_CFG2_R      B @BASEBOARD_FAB2_LIB.BASEBOARD_FAB2(SCH_1):FM_SLT_CFG2_R

RES_0402-0.0,5%,1/16W,CHIP,G21A  I223  R2W3
   1 FM_PMBUS_ALERT_BUF_EN_R_N      A @BASEBOARD_FAB2_LIB.BASEBOARD_FAB2(SCH_1):FM_PMBUS_ALERT_BUF_EN_R_N
   2 FM_PMBUS_ALERT_BUF_EN_N      B @BASEBOARD_FAB2_LIB.BASEBOARD_FAB2(SCH_1):FM_PMBUS_ALERT_BUF_EN_N

RES_0402-0.0,5%,1/16W,CHIP,G21A  I224  R2W4
   1 FM_PMBUS_ALERT_BUF_EN_N      A @BASEBOARD_FAB2_LIB.BASEBOARD_FAB2(SCH_1):FM_PMBUS_ALERT_BUF_EN_N
   2 FM_PMBUS_ALERT_BUF_EN_R2_N      B @BASEBOARD_FAB2_LIB.BASEBOARD_FAB2(SCH_1):FM_PMBUS_ALERT_BUF_EN_R2_N

RES_0402-0.0,5%,1/16W,CHIP,G21A  I226  R7W13
   1 FM_BMC_READY_N      A @BASEBOARD_FAB2_LIB.BASEBOARD_FAB2(SCH_1):FM_BMC_READY_N
   2 FM_BMC_READY_R_N      B @BASEBOARD_FAB2_LIB.BASEBOARD_FAB2(SCH_1):FM_BMC_READY_R_N

RES_0402-0.0,5%,1/16W,CHIP,G21A  I227  R7W15
   1 FM_OCP_MEZZA_PRES      A @BASEBOARD_FAB2_LIB.BASEBOARD_FAB2(SCH_1):FM_OCP_MEZZA_PRES
   2 FM_OCP_MEZZA_PRES_R      B @BASEBOARD_FAB2_LIB.BASEBOARD_FAB2(SCH_1):FM_OCP_MEZZA_PRES_R

RES_0402-0.0,5%,1/16W,CHIP,G21A  I228  R2U50
   1 FM_SLT_CFG2_R      A @BASEBOARD_FAB2_LIB.BASEBOARD_FAB2(SCH_1):FM_SLT_CFG2_R
   2 FM_PWRBRK_SLOT_N      B @BASEBOARD_FAB2_LIB.BASEBOARD_FAB2(SCH_1):FM_PWRBRK_SLOT_N

RES_0402-0.0,5%,1/16W,CHIP,G21A  I229  R7W17
   1 FM_THROTTLE_R2_N      A @BASEBOARD_FAB2_LIB.BASEBOARD_FAB2(SCH_1):FM_THROTTLE_R2_N
   2 FM_THROTTLE_N      B @BASEBOARD_FAB2_LIB.BASEBOARD_FAB2(SCH_1):FM_THROTTLE_N

RES_0402-4.75K,1%,1/16W,CHIP,GA  I230  R7W22
   1 P3V3_STBY      A @BASEBOARD_FAB2_LIB.BASEBOARD_FAB2(SCH_1):P3V3_STBY
   2 FM_BMC_ENABLE_N      B @BASEBOARD_FAB2_LIB.BASEBOARD_FAB2(SCH_1):FM_BMC_ENABLE_N


DRAWING: @BASEBOARD_FAB2_LIB.BASEBOARD_FAB2(SCH_1):PAGE120 

LBG_CORE_QAT_EXT_D_BGA1-IC,H91A  I147  U7C1
BY25 A_RCOMP_3P3 GPIO_RCOMP_3P3 @BASEBOARD_FAB2_LIB.BASEBOARD_FAB2(SCH_1):A_RCOMP_3P3
BH50 FM_CPU0_RC_ERROR_R1_N GPP_E0_SATAXPCIE0_SATAGP0 @BASEBOARD_FAB2_LIB.BASEBOARD_FAB2(SCH_1):FM_CPU0_RC_ERROR_R1_N
BN48 IRQ_BMC_PCH_SCI_LPC_N GPP_E10_USB2_OC1_N @BASEBOARD_FAB2_LIB.BASEBOARD_FAB2(SCH_1):IRQ_BMC_PCH_SCI_LPC_N
AW54 IRQ_BMC_PCH_SMI_LPC_N GPP_E11_USB2_OC2_N @BASEBOARD_FAB2_LIB.BASEBOARD_FAB2(SCH_1):IRQ_BMC_PCH_SMI_LPC_N
AU58 IRQ_UV_DETECT_N GPP_E12_USB2_OC3_N @BASEBOARD_FAB2_LIB.BASEBOARD_FAB2(SCH_1):IRQ_UV_DETECT_N
AY52 FM_CPU1_RC_ERROR_R1_N GPP_E1_SATAXPCIE1_SATAGP1 @BASEBOARD_FAB2_LIB.BASEBOARD_FAB2(SCH_1):FM_CPU1_RC_ERROR_R1_N
BG52 FM_POST_CARD_PRES_BMC_R1_N GPP_E2_SATAXPCIE2_SATAGP2 @BASEBOARD_FAB2_LIB.BASEBOARD_FAB2(SCH_1):FM_POST_CARD_PRES_BMC_R1_N
BE52 FM_CPLD_ADR_TRIGGER_R_N GPP_E3_CPU_GP0 @BASEBOARD_FAB2_LIB.BASEBOARD_FAB2(SCH_1):FM_CPLD_ADR_TRIGGER_R_N
AV52 FM_CPU_ERR2_LVT3_N GPP_E4_SATA_DEVSLP0 @BASEBOARD_FAB2_LIB.BASEBOARD_FAB2(SCH_1):FM_CPU_ERR2_LVT3_N
AT52 FM_CPU_MSMI_LVT3_N GPP_E5_SATA_DEVSLP1 @BASEBOARD_FAB2_LIB.BASEBOARD_FAB2(SCH_1):FM_CPU_MSMI_LVT3_N
BB52 IRQ_BMC_PCH_NMI_STBY_N GPP_E6_SATA_DEVSLP2 @BASEBOARD_FAB2_LIB.BASEBOARD_FAB2(SCH_1):IRQ_BMC_PCH_NMI_STBY_N
BJ48 FM_ADR_SMI_GPIO_N GPP_E7_CPU_GP1 @BASEBOARD_FAB2_LIB.BASEBOARD_FAB2(SCH_1):FM_ADR_SMI_GPIO_N
AV56 LED_PCH_SATA_HDD_N GPP_E8_SATA_LED_N @BASEBOARD_FAB2_LIB.BASEBOARD_FAB2(SCH_1):LED_PCH_SATA_HDD_N
BL48 FM_OC0_USB_N GPP_E9_USB2_OC0_N @BASEBOARD_FAB2_LIB.BASEBOARD_FAB2(SCH_1):FM_OC0_USB_N
 AG7 IRQ_OC_DETECT_N GPP_F0_SATAXPCIE3_SATAGP3 @BASEBOARD_FAB2_LIB.BASEBOARD_FAB2(SCH_1):IRQ_OC_DETECT_N
 AL7 SGPIO_PCH_SATA_CLOCK GPP_F10_SATA_SCLOCK @BASEBOARD_FAB2_LIB.BASEBOARD_FAB2(SCH_1):SGPIO_PCH_SATA_CLOCK
 AR9 SGPIO_PCH_SATA_LOAD GPP_F11_SATA_SLOAD @BASEBOARD_FAB2_LIB.BASEBOARD_FAB2(SCH_1):SGPIO_PCH_SATA_LOAD
 AP7 IRQ_SML1_PMBUS_ALERT_R1_N GPP_F12_SATA_SDATAOUT1 @BASEBOARD_FAB2_LIB.BASEBOARD_FAB2(SCH_1):IRQ_SML1_PMBUS_ALERT_R1_N
AP11 SGPIO_PCH_SATA_DOUT0 GPP_F13_SATA_SDATAOUT0 @BASEBOARD_FAB2_LIB.BASEBOARD_FAB2(SCH_1):SGPIO_PCH_SATA_DOUT0
AL11 LED_PCH_SSATA_HDD_N GPP_F14_SSATA_LED_N @BASEBOARD_FAB2_LIB.BASEBOARD_FAB2(SCH_1):LED_PCH_SSATA_HDD_N
AR13 FM_FORCE_ADR_N GPP_F15_USB2_OC4_N @BASEBOARD_FAB2_LIB.BASEBOARD_FAB2(SCH_1):FM_FORCE_ADR_N
AU13 FM_IE_DISABLE_N GPP_F16_USB2_OC5_N @BASEBOARD_FAB2_LIB.BASEBOARD_FAB2(SCH_1):FM_IE_DISABLE_N
AP15 FM_BIOS_TOP_SWAP GPP_F17_USB2_OC6_N @BASEBOARD_FAB2_LIB.BASEBOARD_FAB2(SCH_1):FM_BIOS_TOP_SWAP
AL15 FM_MEM_THERM_EVENT_PCH_N GPP_F18_USB2_OC7_N @BASEBOARD_FAB2_LIB.BASEBOARD_FAB2(SCH_1):FM_MEM_THERM_EVENT_PCH_N
 AU9 SMB_LAN_STBY_LVC3_SCL_R2 GPP_F19_LAN_SMBCLK @BASEBOARD_FAB2_LIB.BASEBOARD_FAB2(SCH_1):SMB_LAN_STBY_LVC3_SCL_R2
 AK9 FM_HSC_TIMER_EXP_N GPP_F1_SATAXPCIE4_SATAGP4 @BASEBOARD_FAB2_LIB.BASEBOARD_FAB2(SCH_1):FM_HSC_TIMER_EXP_N
AU20 SMB_LAN_STBY_LVC3_SDA_R2 GPP_F20_LAN_SMBDATA @BASEBOARD_FAB2_LIB.BASEBOARD_FAB2(SCH_1):SMB_LAN_STBY_LVC3_SDA_R2
AR17 IRQ_PCH_NIC_ALERT_N GPP_F21_LAN_SMBALRT_N @BASEBOARD_FAB2_LIB.BASEBOARD_FAB2(SCH_1):IRQ_PCH_NIC_ALERT_N
AP18 SGPIO_PCH_SSATA_CLOCK GPP_F22_SSATA_SCLOCK @BASEBOARD_FAB2_LIB.BASEBOARD_FAB2(SCH_1):SGPIO_PCH_SSATA_CLOCK
AU17 SGPIO_PCH_SSATA_LOAD GPP_F23_SSATA_SLOAD @BASEBOARD_FAB2_LIB.BASEBOARD_FAB2(SCH_1):SGPIO_PCH_SSATA_LOAD
AK20 FM_MP_PS_FAIL_N GPP_F2_SATAXPCIE5_SATAGP5 @BASEBOARD_FAB2_LIB.BASEBOARD_FAB2(SCH_1):FM_MP_PS_FAIL_N
AK13 FM_MP_PS_REDUNDANT_LOST_N GPP_F3_SATAXPCIE6_SATAGP6 @BASEBOARD_FAB2_LIB.BASEBOARD_FAB2(SCH_1):FM_MP_PS_REDUNDANT_LOST_N
AH13 FM_BMC_READY_R1_N GPP_F4_SATAXPCIE7_SATAGP7 @BASEBOARD_FAB2_LIB.BASEBOARD_FAB2(SCH_1):FM_BMC_READY_R1_N
AH17 FM_BIOS_USB_RECOVERY GPP_F5_SATA_DEVSLP3 @BASEBOARD_FAB2_LIB.BASEBOARD_FAB2(SCH_1):FM_BIOS_USB_RECOVERY
AL18 JTAG_PCH_PLD_TCK GPP_F6_SATA_DEVSLP4 @BASEBOARD_FAB2_LIB.BASEBOARD_FAB2(SCH_1):JTAG_PCH_PLD_TCK
AK17 JTAG_PCH_PLD_TDI GPP_F7_SATA_DEVSLP5 @BASEBOARD_FAB2_LIB.BASEBOARD_FAB2(SCH_1):JTAG_PCH_PLD_TDI
 AH9 JTAG_PCH_PLD_TMS GPP_F8_SATA_DEVSLP6 @BASEBOARD_FAB2_LIB.BASEBOARD_FAB2(SCH_1):JTAG_PCH_PLD_TMS
AR20 JTAG_PCH_PLD_TDO GPP_F9_SATA_DEVSLP7 @BASEBOARD_FAB2_LIB.BASEBOARD_FAB2(SCH_1):JTAG_PCH_PLD_TDO
AY11     NC GPP_G0_FANTACH0_FANTACH0IE     NC
BE11     NC GPP_G10_FANPWM2_FANPWM2IE     NC
BA20     NC GPP_G11_FANPWM3_FANPMW3IE     NC
BD13 FM_BOARD_SKU_ID0 GPP_G12 @BASEBOARD_FAB2_LIB.BASEBOARD_FAB2(SCH_1):FM_BOARD_SKU_ID0
AY18 FM_BOARD_SKU_ID1 GPP_G13 @BASEBOARD_FAB2_LIB.BASEBOARD_FAB2(SCH_1):FM_BOARD_SKU_ID1
 AV7 FM_BOARD_SKU_ID2 GPP_G14 @BASEBOARD_FAB2_LIB.BASEBOARD_FAB2(SCH_1):FM_BOARD_SKU_ID2
BE18 FM_BOARD_SKU_ID3 GPP_G15 @BASEBOARD_FAB2_LIB.BASEBOARD_FAB2(SCH_1):FM_BOARD_SKU_ID3
BD17 FM_BOARD_SKU_ID4 GPP_G16 @BASEBOARD_FAB2_LIB.BASEBOARD_FAB2(SCH_1):FM_BOARD_SKU_ID4
 BD9 FM_ADR_COMPLETE_R1 GPP_G17_ADR_COMPLETE @BASEBOARD_FAB2_LIB.BASEBOARD_FAB2(SCH_1):FM_ADR_COMPLETE_R1
 BE7 FM_NMI_EVENT_N GPP_G18_NMI_N @BASEBOARD_FAB2_LIB.BASEBOARD_FAB2(SCH_1):FM_NMI_EVENT_N
BE15 FM_BIOS_SMI_ACTIVE_N GPP_G19_SMI_N @BASEBOARD_FAB2_LIB.BASEBOARD_FAB2(SCH_1):FM_BIOS_SMI_ACTIVE_N
AV15     NC GPP_G1_FANTACH1_FANTACH1IE     NC
BA17 IRQ_FORCE_NM_THROTTLE_N GPP_G20_SSATA_DEVSLP0 @BASEBOARD_FAB2_LIB.BASEBOARD_FAB2(SCH_1):IRQ_FORCE_NM_THROTTLE_N
 BG7 FM_SOL_UART_CH_SEL GPP_G21_SSATA_DEVSLP1 @BASEBOARD_FAB2_LIB.BASEBOARD_FAB2(SCH_1):FM_SOL_UART_CH_SEL
BD20 FM_CPU0_RC_EN GPP_G22_SSATA_DEVSLP2 @BASEBOARD_FAB2_LIB.BASEBOARD_FAB2(SCH_1):FM_CPU0_RC_EN
BA13 FM_UARTSW_MSB_N GPP_G23_SSATAXPCIE0_SSATAGP0 @BASEBOARD_FAB2_LIB.BASEBOARD_FAB2(SCH_1):FM_UARTSW_MSB_N
BE22     NC GPP_G2_FANTACH2_FANTACH2IE     NC
 AY7     NC GPP_G3_FANTACH3_FANTACH3IE     NC
 BA9     NC GPP_G4_FANTACH4_FANTACH4IE     NC
AW20     NC GPP_G5_FANTACH5_FANTACH5IE     NC
AV18 FM_CPU1_THERMTRIP_LATCH_LVT3_N GPP_G6_FANTACH6_FANTACH6IE @BASEBOARD_FAB2_LIB.BASEBOARD_FAB2(SCH_1):FM_CPU1_THERMTRIP_LATCH_LVT3_N
AY15     NC GPP_G7_FANTACH7_FANTACH7IE     NC
BG11     NC GPP_G8_FANPWM0_FANPWM0IE     NC
AV11     NC GPP_G9_FANPWM1_FAMPWM1IE     NC
 AT4 FM_UARTSW_LSB_N GPP_H0_SRCCLKREQ6_N @BASEBOARD_FAB2_LIB.BASEBOARD_FAB2(SCH_1):FM_UARTSW_LSB_N
 BA4 SMB_VR_STBY_LVC3_SCL_R1 GPP_H10_SML2CLK_IE @BASEBOARD_FAB2_LIB.BASEBOARD_FAB2(SCH_1):SMB_VR_STBY_LVC3_SCL_R1
 BD1 SMB_VR_STBY_LVC3_SDA_R1 GPP_H11_SML2DATA_IE @BASEBOARD_FAB2_LIB.BASEBOARD_FAB2(SCH_1):SMB_VR_STBY_LVC3_SDA_R1
 BB1 FM_FLASH_ATTACH_CFG_STRAP GPP_H12_SML2ALERT_N_IE_N @BASEBOARD_FAB2_LIB.BASEBOARD_FAB2(SCH_1):FM_FLASH_ATTACH_CFG_STRAP
 AY1     NC GPP_H13_SML3CLK_IE     NC
 BC2     NC GPP_H14_SML3DATA_IE     NC
 BB3 PU_ADR_TIMER_HOLD_OFF_N GPP_H15_SML3ALERT_N_IE_N @BASEBOARD_FAB2_LIB.BASEBOARD_FAB2(SCH_1):PU_ADR_TIMER_HOLD_OFF_N
 BF1 SMB_LAN_STBY_LVC3_SCL_R1 GPP_H16_SML4CLK_IE @BASEBOARD_FAB2_LIB.BASEBOARD_FAB2(SCH_1):SMB_LAN_STBY_LVC3_SCL_R1
 BE4 SMB_LAN_STBY_LVC3_SDA_R1 GPP_H17_SML4DATA_IE @BASEBOARD_FAB2_LIB.BASEBOARD_FAB2(SCH_1):SMB_LAN_STBY_LVC3_SDA_R1
 BC4 FM_OC_DETECT_EN_N GPP_H18_SML4ALERT_N_IE_N @BASEBOARD_FAB2_LIB.BASEBOARD_FAB2(SCH_1):FM_OC_DETECT_EN_N
 BD3 FP_PWR_ID_LED_N GPP_H19_SSATAXPCIE1_SSATAGP1 @BASEBOARD_FAB2_LIB.BASEBOARD_FAB2(SCH_1):FP_PWR_ID_LED_N
 AW4 FM_BACKUP_BIOS_SEL_N GPP_H1_SRCCLKREQ7_N @BASEBOARD_FAB2_LIB.BASEBOARD_FAB2(SCH_1):FM_BACKUP_BIOS_SEL_N
 BF3 FM_BMC_NMI_N GPP_H20_SSATAXPCIE2_SSATAGP2 @BASEBOARD_FAB2_LIB.BASEBOARD_FAB2(SCH_1):FM_BMC_NMI_N
 BA2 FM_BIOS_SMI_ACTIVE_N GPP_H21_SSATAXPCIE3_SSATAGP3 @BASEBOARD_FAB2_LIB.BASEBOARD_FAB2(SCH_1):FM_BIOS_SMI_ACTIVE_N
 BH2 FM_PCH_BMC_THERMTRIP_N GPP_H22_SSATAXPCIE4_SSATAGP4 @BASEBOARD_FAB2_LIB.BASEBOARD_FAB2(SCH_1):FM_PCH_BMC_THERMTRIP_N
 BH4 FM_SSATA_PCIE_M2_SEL GPP_H23_SSATAXPCIE5_SSATAGP5 @BASEBOARD_FAB2_LIB.BASEBOARD_FAB2(SCH_1):FM_SSATA_PCIE_M2_SEL
 AV3     NC GPP_H2_SRCCLKREQ8_N     NC
 AR1     NC GPP_H3_SRCCLKREQ9_N     NC
 AT2     NC GPP_H4_SRCCLKREQ10_N     NC
 AY3     NC GPP_H5_SRCCLKREQ11_N     NC
 AW2     NC GPP_H6_SRCCLKREQ12_N     NC
 AV1     NC GPP_H7_SRCCLKREQ13_N     NC
 AR3     NC GPP_H8_SRCCLKREQ14_N     NC
 BE2     NC GPP_H9_SRCCLKREQ15_N     NC
CA20 JTAG_PCH_GBE_TDO GPP_I0_LAN_TDO @BASEBOARD_FAB2_LIB.BASEBOARD_FAB2(SCH_1):JTAG_PCH_GBE_TDO
BV25 FM_BIOS_MRC_DEBUG_MSG_DIS_N GPP_I10 @BASEBOARD_FAB2_LIB.BASEBOARD_FAB2(SCH_1):FM_BIOS_MRC_DEBUG_MSG_DIS_N
BV21 JTAG_PCH_GBE_CLK GPP_I1_LAN_TCK @BASEBOARD_FAB2_LIB.BASEBOARD_FAB2(SCH_1):JTAG_PCH_GBE_CLK
CA22 JTAG_PCH_GBE_TMS GPP_I2_LAN_TMS @BASEBOARD_FAB2_LIB.BASEBOARD_FAB2(SCH_1):JTAG_PCH_GBE_TMS
BY23 JTAG_PCH_GBE_TDI GPP_I3_LAN_TDI @BASEBOARD_FAB2_LIB.BASEBOARD_FAB2(SCH_1):JTAG_PCH_GBE_TDI
BW20 IRQ_DIMM_SAVE_LVT3_R_N GPP_I4_DO_RESET_IN_N @BASEBOARD_FAB2_LIB.BASEBOARD_FAB2(SCH_1):IRQ_DIMM_SAVE_LVT3_R_N
BW24 IRQ_BOARD_BMC_ALERT_N GPP_I5_DO_RESET_OUT_N @BASEBOARD_FAB2_LIB.BASEBOARD_FAB2(SCH_1):IRQ_BOARD_BMC_ALERT_N
BV23 FM_CPU1_RC_ERROR_R_N GPP_I6_RESET_DONE @BASEBOARD_FAB2_LIB.BASEBOARD_FAB2(SCH_1):FM_CPU1_RC_ERROR_R_N
CA24 JTAG_PCH_GBE_TRST_N GPP_I7_LAN_TRST_N @BASEBOARD_FAB2_LIB.BASEBOARD_FAB2(SCH_1):JTAG_PCH_GBE_TRST_N
BW22 PU_10GBE_LOM_PCI_DISABLE_N GPP_I8_PCI_DIS_N @BASEBOARD_FAB2_LIB.BASEBOARD_FAB2(SCH_1):PU_10GBE_LOM_PCI_DISABLE_N
BY21 FM_10GBE_LOM_DISABLE_N GPP_I9_LAN_DIS_N @BASEBOARD_FAB2_LIB.BASEBOARD_FAB2(SCH_1):FM_10GBE_LOM_DISABLE_N
 BL1 LED_GBE_P0_0 GPP_J0_LAN_LED_P0_0 @BASEBOARD_FAB2_LIB.BASEBOARD_FAB2(SCH_1):LED_GBE_P0_0
 BW5 SMB_PCH_MEZZ_LOM1_SCL GPP_J10_LAN_I2C_SCL_MDC_P1 @BASEBOARD_FAB2_LIB.BASEBOARD_FAB2(SCH_1):SMB_PCH_MEZZ_LOM1_SCL
 BV8 SMB_PCH_MEZZ_LOM1_SDA GPP_J11_LAN_I2C_SDA_MDIO_P1 @BASEBOARD_FAB2_LIB.BASEBOARD_FAB2(SCH_1):SMB_PCH_MEZZ_LOM1_SDA
 BT5 SMB_PCH_MEZZ_LOM2_SCL GPP_J12_LAN_I2C_SCL_MDC_P2 @BASEBOARD_FAB2_LIB.BASEBOARD_FAB2(SCH_1):SMB_PCH_MEZZ_LOM2_SCL
BW11 SMB_PCH_MEZZ_LOM2_SDA GPP_J13_LAN_I2C_SDA_MDIO_P2 @BASEBOARD_FAB2_LIB.BASEBOARD_FAB2(SCH_1):SMB_PCH_MEZZ_LOM2_SDA
 BW6 SMB_PCH_MEZZ_LOM3_SCL GPP_J14_LAN_I2C_SCL_MDC_P3 @BASEBOARD_FAB2_LIB.BASEBOARD_FAB2(SCH_1):SMB_PCH_MEZZ_LOM3_SCL
 BW9 SMB_PCH_MEZZ_LOM3_SDA GPP_J15_LAN_I2C_SDA_MDIO_P3 @BASEBOARD_FAB2_LIB.BASEBOARD_FAB2(SCH_1):SMB_PCH_MEZZ_LOM3_SDA
BV10 FM_GBE0_LVC3_MOD_ABS GPP_J16_LAN_SDP_P0_0 @BASEBOARD_FAB2_LIB.BASEBOARD_FAB2(SCH_1):FM_GBE0_LVC3_MOD_ABS
CA11 TP_PCH_GPP_J17 GPP_J17_LAN_SDP_P0_1 @BASEBOARD_FAB2_LIB.BASEBOARD_FAB2(SCH_1):TP_PCH_GPP_J17
BY10 FM_GBE1_LVC3_MOD_ABS GPP_J18_LAN_SDP_P1_0 @BASEBOARD_FAB2_LIB.BASEBOARD_FAB2(SCH_1):FM_GBE1_LVC3_MOD_ABS
BY14 TP_PCH_GPP_J19 GPP_J19_LAN_SDP_P1_1 @BASEBOARD_FAB2_LIB.BASEBOARD_FAB2(SCH_1):TP_PCH_GPP_J19
 BK4 LED_GBE_P0_1 GPP_J1_LAN_LED_P0_1 @BASEBOARD_FAB2_LIB.BASEBOARD_FAB2(SCH_1):LED_GBE_P0_1
BW13 FM_GBE2_LVC3_MOD_ABS GPP_J20_LAN_SDP_P2_0 @BASEBOARD_FAB2_LIB.BASEBOARD_FAB2(SCH_1):FM_GBE2_LVC3_MOD_ABS
BV12 TP_PCH_GPP_J21 GPP_J21_LAN_SDP_P2_1 @BASEBOARD_FAB2_LIB.BASEBOARD_FAB2(SCH_1):TP_PCH_GPP_J21
BY12 FM_GBE3_LVC3_MOD_ABS GPP_J22_LAN_SDP_P3_0 @BASEBOARD_FAB2_LIB.BASEBOARD_FAB2(SCH_1):FM_GBE3_LVC3_MOD_ABS
BV14 TP_PCH_GPP_J23 GPP_J23_LAN_SDP_P3_1 @BASEBOARD_FAB2_LIB.BASEBOARD_FAB2(SCH_1):TP_PCH_GPP_J23
 BP4 LED_GBE_P1_0 GPP_J2_LAN_LED_P1_0 @BASEBOARD_FAB2_LIB.BASEBOARD_FAB2(SCH_1):LED_GBE_P1_0
 BK2 LED_GBE_P1_1 GPP_J3_LAN_LED_P1_1 @BASEBOARD_FAB2_LIB.BASEBOARD_FAB2(SCH_1):LED_GBE_P1_1
 BL3 LED_GBE_P2_0 GPP_J4_LAN_LED_P2_0 @BASEBOARD_FAB2_LIB.BASEBOARD_FAB2(SCH_1):LED_GBE_P2_0
 BU6 LED_GBE_P2_1 GPP_J5_LAN_LED_P2_1 @BASEBOARD_FAB2_LIB.BASEBOARD_FAB2(SCH_1):LED_GBE_P2_1
CA13 LED_GBE_P3_0 GPP_J6_LAN_LED_P3_0 @BASEBOARD_FAB2_LIB.BASEBOARD_FAB2(SCH_1):LED_GBE_P3_0
 BM2 LED_GBE_P3_1 GPP_J7_LAN_LED_P3_1 @BASEBOARD_FAB2_LIB.BASEBOARD_FAB2(SCH_1):LED_GBE_P3_1
 BM4 SMB_PCH_MEZZ_LOM0_SCL GPP_J8_LAN_I2C_SCL_MDC_P0 @BASEBOARD_FAB2_LIB.BASEBOARD_FAB2(SCH_1):SMB_PCH_MEZZ_LOM0_SCL
 BN3 SMB_PCH_MEZZ_LOM0_SDA GPP_J9_LAN_I2C_SDA_MDIO_P0 @BASEBOARD_FAB2_LIB.BASEBOARD_FAB2(SCH_1):SMB_PCH_MEZZ_LOM0_SDA

RES_0402-33.2,1%,1/16W,CHIP,G2A  I218  R2M1
   1 FM_CPLD_ADR_TRIGGER_N      A @BASEBOARD_FAB2_LIB.BASEBOARD_FAB2(SCH_1):FM_CPLD_ADR_TRIGGER_N
   2 FM_CPLD_ADR_TRIGGER_R_N      B @BASEBOARD_FAB2_LIB.BASEBOARD_FAB2(SCH_1):FM_CPLD_ADR_TRIGGER_R_N

RES_0402-33.2,1%,1/16W,CHIP,G2A  I219  R2N26
   1 FM_ADR_COMPLETE      A @BASEBOARD_FAB2_LIB.BASEBOARD_FAB2(SCH_1):FM_ADR_COMPLETE
   2 FM_ADR_COMPLETE_R1      B @BASEBOARD_FAB2_LIB.BASEBOARD_FAB2(SCH_1):FM_ADR_COMPLETE_R1

RES_0402-0.0,5%,1/16W,CHIP,G21A  I269  R7W8
   1 FM_POST_CARD_PRES_BMC_N      A @BASEBOARD_FAB2_LIB.BASEBOARD_FAB2(SCH_1):FM_POST_CARD_PRES_BMC_N
   2 FM_POST_CARD_PRES_BMC_R1_N      B @BASEBOARD_FAB2_LIB.BASEBOARD_FAB2(SCH_1):FM_POST_CARD_PRES_BMC_R1_N

RES_0402-0.0,5%,1/16W,CHIP,G21A  I270  R7W10
   1 FM_CPU0_RC_ERROR_N      A @BASEBOARD_FAB2_LIB.BASEBOARD_FAB2(SCH_1):FM_CPU0_RC_ERROR_N
   2 FM_CPU0_RC_ERROR_R1_N      B @BASEBOARD_FAB2_LIB.BASEBOARD_FAB2(SCH_1):FM_CPU0_RC_ERROR_R1_N

RES_0402-0.0,5%,1/16W,CHIP,G21A  I271  R7W12
   1 FM_CPU1_RC_ERROR_N      A @BASEBOARD_FAB2_LIB.BASEBOARD_FAB2(SCH_1):FM_CPU1_RC_ERROR_N
   2 FM_CPU1_RC_ERROR_R1_N      B @BASEBOARD_FAB2_LIB.BASEBOARD_FAB2(SCH_1):FM_CPU1_RC_ERROR_R1_N

RES_0402-0.0,5%,1/16W,CHIP,G21A  I273  R7W11
   1 FM_CPU1_RC_ERROR_R_N      A @BASEBOARD_FAB2_LIB.BASEBOARD_FAB2(SCH_1):FM_CPU1_RC_ERROR_R_N
   2 FM_CPU1_RC_ERROR_N      B @BASEBOARD_FAB2_LIB.BASEBOARD_FAB2(SCH_1):FM_CPU1_RC_ERROR_N

RES_0402-0.0,5%,1/16W,CHIP,G21A  I274  R7W14
   1 FM_BMC_READY_N      A @BASEBOARD_FAB2_LIB.BASEBOARD_FAB2(SCH_1):FM_BMC_READY_N
   2 FM_BMC_READY_R1_N      B @BASEBOARD_FAB2_LIB.BASEBOARD_FAB2(SCH_1):FM_BMC_READY_R1_N

RES_0402-100.0,1%,1/16W,CHIP,GA  I275  R8C21
   1 A_RCOMP_3P3      A @BASEBOARD_FAB2_LIB.BASEBOARD_FAB2(SCH_1):A_RCOMP_3P3
   2    GND      B @BASEBOARD_FAB2_LIB.BASEBOARD_FAB2(SCH_1):GND

RES_0402-0.0,5%,1/16W,CHIP,G21A  I276  R7W16
   1 IRQ_DIMM_SAVE_LVT3_R_N      A @BASEBOARD_FAB2_LIB.BASEBOARD_FAB2(SCH_1):IRQ_DIMM_SAVE_LVT3_R_N
   2 IRQ_DIMM_SAVE_LVT3_N      B @BASEBOARD_FAB2_LIB.BASEBOARD_FAB2(SCH_1):IRQ_DIMM_SAVE_LVT3_N

RES_0402-0.0,5%,1/16W,CHIP,G21A  I277  R7W18
   1 IRQ_SML1_PMBUS_ALERT_N      A @BASEBOARD_FAB2_LIB.BASEBOARD_FAB2(SCH_1):IRQ_SML1_PMBUS_ALERT_N
   2 IRQ_SML1_PMBUS_ALERT_R1_N      B @BASEBOARD_FAB2_LIB.BASEBOARD_FAB2(SCH_1):IRQ_SML1_PMBUS_ALERT_R1_N

RES_0402-4.75K,1%,1/16W,CHIP,GA  I278  R7W20
   1 P3V3_STBY      A @BASEBOARD_FAB2_LIB.BASEBOARD_FAB2(SCH_1):P3V3_STBY
   2 FM_POST_CARD_PRES_BMC_R1_N      B @BASEBOARD_FAB2_LIB.BASEBOARD_FAB2(SCH_1):FM_POST_CARD_PRES_BMC_R1_N


DRAWING: @BASEBOARD_FAB2_LIB.BASEBOARD_FAB2(SCH_1):PAGE121 

RES_0402-0.0,5%,1/16W,CHIP,G21A  I31  R7C15
   1 SPI_PCH_MOSI_R      A @BASEBOARD_FAB2_LIB.BASEBOARD_FAB2(SCH_1):SPI_PCH_MOSI_R
   2 SPI_PCH_MOSI      B @BASEBOARD_FAB2_LIB.BASEBOARD_FAB2(SCH_1):SPI_PCH_MOSI

RES_0402-33.2,1%,1/16W,CHIP,G2A  I33  R7C16
   1 SPI_PCH_CS0_R_N      A @BASEBOARD_FAB2_LIB.BASEBOARD_FAB2(SCH_1):SPI_PCH_CS0_R_N
   2 SPI_PCH_CS0_N      B @BASEBOARD_FAB2_LIB.BASEBOARD_FAB2(SCH_1):SPI_PCH_CS0_N

LBG_CORE_QAT_EXT_D_BGA1-IC,H91A  I34  U7C1
 C70 FM_PCH_PRSNT_N CGC_DUT_DETECT_N @BASEBOARD_FAB2_LIB.BASEBOARD_FAB2(SCH_1):FM_PCH_PRSNT_N
 AM4 A_1P8_3P3_RCOMP GPIO_RCOMP_1P8_3P3 @BASEBOARD_FAB2_LIB.BASEBOARD_FAB2(SCH_1):A_1P8_3P3_RCOMP
 AJ1 CLK_50M_CKMNG_PCH_10GBE GPP_K0_LAN_NCSI_CLK_IN @BASEBOARD_FAB2_LIB.BASEBOARD_FAB2(SCH_1):CLK_50M_CKMNG_PCH_10GBE
 AH4 RST_PCIE_PCH_PERST_N GPP_K10_PE_RST_N @BASEBOARD_FAB2_LIB.BASEBOARD_FAB2(SCH_1):RST_PCIE_PCH_PERST_N
 AM2 RMII_BMC_PCH_SPRNGVLLE_TXD0 GPP_K1_LAN_NCSI_TXD0 @BASEBOARD_FAB2_LIB.BASEBOARD_FAB2(SCH_1):RMII_BMC_PCH_SPRNGVLLE_TXD0
 AK2 RMII_BMC_PCH_SPRNGVLLE_TXD1 GPP_K2_LAN_NCSI_TXD1 @BASEBOARD_FAB2_LIB.BASEBOARD_FAB2(SCH_1):RMII_BMC_PCH_SPRNGVLLE_TXD1
 AL3 RMII_BMC_PCH_SPRNGVLLE_TXEN GPP_K3_LAN_NCSI_TX_EN @BASEBOARD_FAB2_LIB.BASEBOARD_FAB2(SCH_1):RMII_BMC_PCH_SPRNGVLLE_TXEN
 AN3 RMII_BMC_PCH_SPRNGVLLE_CRSDV_R1 GPP_K4_LAN_NCSI_CRS_DV @BASEBOARD_FAB2_LIB.BASEBOARD_FAB2(SCH_1):RMII_BMC_PCH_SPRNGVLLE_CRSDV_R1
 AL1 RMII_SPRNGVLLE_BMC_PCH_RXD0_R1 GPP_K5_LAN_NCSI_RXD0 @BASEBOARD_FAB2_LIB.BASEBOARD_FAB2(SCH_1):RMII_SPRNGVLLE_BMC_PCH_RXD0_R1
 AN1 RMII_SPRNGVLLE_BMC_PCH_RXD1_R1 GPP_K6_LAN_NCSI_RXD1 @BASEBOARD_FAB2_LIB.BASEBOARD_FAB2(SCH_1):RMII_SPRNGVLLE_BMC_PCH_RXD1_R1
 AH2 RMII_BMC_PCH_SPRNGVLLE_RXER_R GPP_K7 @BASEBOARD_FAB2_LIB.BASEBOARD_FAB2(SCH_1):RMII_BMC_PCH_SPRNGVLLE_RXER_R
 AJ3 RMII_PCH_SPRNGVLLE_ARB_IN GPP_K8_LAN_NCSI_ARB_IN @BASEBOARD_FAB2_LIB.BASEBOARD_FAB2(SCH_1):RMII_PCH_SPRNGVLLE_ARB_IN
 AK4 RMII_PCH_SPRNGVLLE_ARB_OUT_R GPP_K9_LAN_NCSI_ARB_OUT @BASEBOARD_FAB2_LIB.BASEBOARD_FAB2(SCH_1):RMII_PCH_SPRNGVLLE_ARB_OUT_R
AF20 TP_PCH_GPP_L10 GPP_L10_TESTCH0_CLK @BASEBOARD_FAB2_LIB.BASEBOARD_FAB2(SCH_1):TP_PCH_GPP_L10
AD20 TP_PCH_GPP_L11 GPP_L11_TESTCH1_D0 @BASEBOARD_FAB2_LIB.BASEBOARD_FAB2(SCH_1):TP_PCH_GPP_L11
 Y15 H_CPU0_MEMABC_MEMHOT_PCH_N GPP_L12_TESTCH1_D1 @BASEBOARD_FAB2_LIB.BASEBOARD_FAB2(SCH_1):H_CPU0_MEMABC_MEMHOT_PCH_N
AD13 H_CPU0_MEMDEF_MEMHOT_PCH_N GPP_L13_TESTCH1_D2 @BASEBOARD_FAB2_LIB.BASEBOARD_FAB2(SCH_1):H_CPU0_MEMDEF_MEMHOT_PCH_N
AA13 H_CPU1_MEMGHJ_MEMHOT_PCH_N GPP_L14_TESTCH1_D3 @BASEBOARD_FAB2_LIB.BASEBOARD_FAB2(SCH_1):H_CPU1_MEMGHJ_MEMHOT_PCH_N
 Y11 H_CPU1_MEMKLM_MEMHOT_PCH_N GPP_L15_TESTCH1_D4 @BASEBOARD_FAB2_LIB.BASEBOARD_FAB2(SCH_1):H_CPU1_MEMKLM_MEMHOT_PCH_N
  Y7 FM_CPU0_PROCHOT_PCH_N GPP_L16_TESTCH1_D5 @BASEBOARD_FAB2_LIB.BASEBOARD_FAB2(SCH_1):FM_CPU0_PROCHOT_PCH_N
 AA9 FM_CPU1_PROCHOT_PCH_N GPP_L17_TESTCH1_D6 @BASEBOARD_FAB2_LIB.BASEBOARD_FAB2(SCH_1):FM_CPU1_PROCHOT_PCH_N
 AE7 FM_CPU_ERR0_PCH_N GPP_L18_TESTCH1_D7 @BASEBOARD_FAB2_LIB.BASEBOARD_FAB2(SCH_1):FM_CPU_ERR0_PCH_N
AG11 FM_CPU_ERR1_PCH_N GPP_L19_TESTCH1_CLK @BASEBOARD_FAB2_LIB.BASEBOARD_FAB2(SCH_1):FM_CPU_ERR1_PCH_N
AE18 FM_PRSNT_2_1_N GPP_L2_TESTCH0_D0 @BASEBOARD_FAB2_LIB.BASEBOARD_FAB2(SCH_1):FM_PRSNT_2_1_N
AE15 FM_PRSNT_2_2_N GPP_L3_TESTCH0_D1 @BASEBOARD_FAB2_LIB.BASEBOARD_FAB2(SCH_1):FM_PRSNT_2_2_N
AE11 FM_PRSNT_2_3_N GPP_L4_TESTCH0_D2 @BASEBOARD_FAB2_LIB.BASEBOARD_FAB2(SCH_1):FM_PRSNT_2_3_N
 Y18 FM_PRSNT_2_4_N GPP_L5_TESTCH0_D3 @BASEBOARD_FAB2_LIB.BASEBOARD_FAB2(SCH_1):FM_PRSNT_2_4_N
AA20 FM_PRSNT_2_5_N GPP_L6_TESTCH0_D4 @BASEBOARD_FAB2_LIB.BASEBOARD_FAB2(SCH_1):FM_PRSNT_2_5_N
AA17 FM_PRSNT_2_6_N GPP_L7_TESTCH0_D5 @BASEBOARD_FAB2_LIB.BASEBOARD_FAB2(SCH_1):FM_PRSNT_2_6_N
 AD9 FM_OCP_MEZZB_PRES_1V05_PCH_N GPP_L8_TESTCH0_D6 @BASEBOARD_FAB2_LIB.BASEBOARD_FAB2(SCH_1):FM_OCP_MEZZB_PRES_1V05_PCH_N
AD17 FM_OCP_MEZZC_PRES_1V05_PCH_N GPP_L9_TESTCH0_D7 @BASEBOARD_FAB2_LIB.BASEBOARD_FAB2(SCH_1):FM_OCP_MEZZC_PRES_1V05_PCH_N
 P18 TP_PCH_HDA_BCLK HDA_BCLK @BASEBOARD_FAB2_LIB.BASEBOARD_FAB2(SCH_1):TP_PCH_HDA_BCLK
 M18 TP_PCH_HSA_RST_N HDA_RST_N @BASEBOARD_FAB2_LIB.BASEBOARD_FAB2(SCH_1):TP_PCH_HSA_RST_N
 K20 TP_PCH_HDA_SDI_0 HDA_SDI_0 @BASEBOARD_FAB2_LIB.BASEBOARD_FAB2(SCH_1):TP_PCH_HDA_SDI_0
 V18 TP_PCH_HDA_SDI_1 HDA_SDI_1 @BASEBOARD_FAB2_LIB.BASEBOARD_FAB2(SCH_1):TP_PCH_HDA_SDI_1
 U24 FM_FLASH_DESC_OVERRIDE HDA_SDO @BASEBOARD_FAB2_LIB.BASEBOARD_FAB2(SCH_1):FM_FLASH_DESC_OVERRIDE
 H20 TP_PCH_HDA_SYNC HDA_SYNC @BASEBOARD_FAB2_LIB.BASEBOARD_FAB2(SCH_1):TP_PCH_HDA_SYNC
AG18 FM_INTRUDER_HDR_PCH_N INTRUDER_N @BASEBOARD_FAB2_LIB.BASEBOARD_FAB2(SCH_1):FM_INTRUDER_HDR_PCH_N
 V22 TP_PCH_DISPA_SDO RSVD<68> @BASEBOARD_FAB2_LIB.BASEBOARD_FAB2(SCH_1):TP_PCH_DISPA_SDO
 R20 TP_PCH_DISPA_SDI RSVD<67> @BASEBOARD_FAB2_LIB.BASEBOARD_FAB2(SCH_1):TP_PCH_DISPA_SDI
 U20 TP_PCH_DISPA_BCLK RSVD<66> @BASEBOARD_FAB2_LIB.BASEBOARD_FAB2(SCH_1):TP_PCH_DISPA_BCLK
 BW3 TP_PCH_RSVD46 RSVD<46> @BASEBOARD_FAB2_LIB.BASEBOARD_FAB2(SCH_1):TP_PCH_RSVD46
BG26 TP_PCH_RSVD27 RSVD<27> @BASEBOARD_FAB2_LIB.BASEBOARD_FAB2(SCH_1):TP_PCH_RSVD27
BH24 TP_PCH_RSVD26 RSVD<26> @BASEBOARD_FAB2_LIB.BASEBOARD_FAB2(SCH_1):TP_PCH_RSVD26
 P48 TP_PCH_RSVD25 RSVD<25> @BASEBOARD_FAB2_LIB.BASEBOARD_FAB2(SCH_1):TP_PCH_RSVD25
 P44 TP_PCH_RSVD24 RSVD<24> @BASEBOARD_FAB2_LIB.BASEBOARD_FAB2(SCH_1):TP_PCH_RSVD24
 P40 TP_PCH_RSVD23 RSVD<23> @BASEBOARD_FAB2_LIB.BASEBOARD_FAB2(SCH_1):TP_PCH_RSVD23
AT71 TP_PCH_RSVD22 RSVD<22> @BASEBOARD_FAB2_LIB.BASEBOARD_FAB2(SCH_1):TP_PCH_RSVD22
 A11 TP_PCH_RSVD21 RSVD<21> @BASEBOARD_FAB2_LIB.BASEBOARD_FAB2(SCH_1):TP_PCH_RSVD21
 D10 TP_PCH_RSVD20 RSVD<20> @BASEBOARD_FAB2_LIB.BASEBOARD_FAB2(SCH_1):TP_PCH_RSVD20
  C9 TP_PCH_RSVD19 RSVD<19> @BASEBOARD_FAB2_LIB.BASEBOARD_FAB2(SCH_1):TP_PCH_RSVD19
 C11 TP_PCH_RSVD18 RSVD<18> @BASEBOARD_FAB2_LIB.BASEBOARD_FAB2(SCH_1):TP_PCH_RSVD18
 B10 TP_PCH_RSVD17 RSVD<17> @BASEBOARD_FAB2_LIB.BASEBOARD_FAB2(SCH_1):TP_PCH_RSVD17
  C5 TP_PCH_RSVD16 RSVD<16> @BASEBOARD_FAB2_LIB.BASEBOARD_FAB2(SCH_1):TP_PCH_RSVD16
  C6 TP_PCH_RSVD15 RSVD<15> @BASEBOARD_FAB2_LIB.BASEBOARD_FAB2(SCH_1):TP_PCH_RSVD15
 E18 TP_PCH_RSVD14 RSVD<14> @BASEBOARD_FAB2_LIB.BASEBOARD_FAB2(SCH_1):TP_PCH_RSVD14
 C67 TP_PCH_RSVD13 RSVD<13> @BASEBOARD_FAB2_LIB.BASEBOARD_FAB2(SCH_1):TP_PCH_RSVD13
 C68 TP_PCH_RSVD12 RSVD<12> @BASEBOARD_FAB2_LIB.BASEBOARD_FAB2(SCH_1):TP_PCH_RSVD12
 C18 FM_SINT_PRSNT_N RSVD<11> @BASEBOARD_FAB2_LIB.BASEBOARD_FAB2(SCH_1):FM_SINT_PRSNT_N
  D8 FM_WBG_PRSNT_N RSVD<10> @BASEBOARD_FAB2_LIB.BASEBOARD_FAB2(SCH_1):FM_WBG_PRSNT_N
 F66 TP_PCH_RSVD9 RSVD<9> @BASEBOARD_FAB2_LIB.BASEBOARD_FAB2(SCH_1):TP_PCH_RSVD9
 F69 TP_PCH_RSVD8 RSVD<8> @BASEBOARD_FAB2_LIB.BASEBOARD_FAB2(SCH_1):TP_PCH_RSVD8
  F8 TP_PCH_RSVD7 RSVD<7> @BASEBOARD_FAB2_LIB.BASEBOARD_FAB2(SCH_1):TP_PCH_RSVD7
AT69 TP_PCH_RSVD6 RSVD<6> @BASEBOARD_FAB2_LIB.BASEBOARD_FAB2(SCH_1):TP_PCH_RSVD6
AG15 TP_PCH_RSVD5 RSVD<5> @BASEBOARD_FAB2_LIB.BASEBOARD_FAB2(SCH_1):TP_PCH_RSVD5
 P37 TP_PCH_RSVD4 RSVD<4> @BASEBOARD_FAB2_LIB.BASEBOARD_FAB2(SCH_1):TP_PCH_RSVD4
 V11 TP_PCH_RSVD3 RSVD<3> @BASEBOARD_FAB2_LIB.BASEBOARD_FAB2(SCH_1):TP_PCH_RSVD3
AA58 TP_PCH_RSVD2 RSVD<2> @BASEBOARD_FAB2_LIB.BASEBOARD_FAB2(SCH_1):TP_PCH_RSVD2
AC56 TP_PCH_RSVD1 RSVD<1> @BASEBOARD_FAB2_LIB.BASEBOARD_FAB2(SCH_1):TP_PCH_RSVD1
AF61 TP_PCH_RSVD0 RSVD<0> @BASEBOARD_FAB2_LIB.BASEBOARD_FAB2(SCH_1):TP_PCH_RSVD0
 P11 RST_RTCRST_N RTCRST_N @BASEBOARD_FAB2_LIB.BASEBOARD_FAB2(SCH_1):RST_RTCRST_N
  K2 SPI_PCH_CLK SPI0_CLK @BASEBOARD_FAB2_LIB.BASEBOARD_FAB2(SCH_1):SPI_PCH_CLK
  J3 SPI_PCH_CS0_R_N SPI0_FLASH_CS0_N @BASEBOARD_FAB2_LIB.BASEBOARD_FAB2(SCH_1):SPI_PCH_CS0_R_N
  G7 TP_SPI_PCH_CS1_R1_N SPI0_FLASH_CS1_N @BASEBOARD_FAB2_LIB.BASEBOARD_FAB2(SCH_1):TP_SPI_PCH_CS1_R1_N
  F5 SPI_PCH_IO2 SPI0_IO2 @BASEBOARD_FAB2_LIB.BASEBOARD_FAB2(SCH_1):SPI_PCH_IO2
  L1 SPI_PCH_IO3 SPI0_IO3 @BASEBOARD_FAB2_LIB.BASEBOARD_FAB2(SCH_1):SPI_PCH_IO3
  L3 SPI_PCH_MISO SPI0_MISO_IO1 @BASEBOARD_FAB2_LIB.BASEBOARD_FAB2(SCH_1):SPI_PCH_MISO
  H4 SPI_PCH_MOSI_R SPI0_MOSI_IO0 @BASEBOARD_FAB2_LIB.BASEBOARD_FAB2(SCH_1):SPI_PCH_MOSI_R
  K4 SPI_PCH_TPM_CS_N SPI0_TPM_CS_N @BASEBOARD_FAB2_LIB.BASEBOARD_FAB2(SCH_1):SPI_PCH_TPM_CS_N
 G18 RST_SRTCRST_N SRTCRST_N @BASEBOARD_FAB2_LIB.BASEBOARD_FAB2(SCH_1):RST_SRTCRST_N

RES_0402-100.0,1%,1/16W,CHIP,GA  I35  R8C26
   1 A_1P8_3P3_RCOMP      A @BASEBOARD_FAB2_LIB.BASEBOARD_FAB2(SCH_1):A_1P8_3P3_RCOMP
   2    GND      B @BASEBOARD_FAB2_LIB.BASEBOARD_FAB2(SCH_1):GND

RES_0402-10.0K,1%,1/16W,CHIP,GA  I37  R3N10
   1 P3V3_STBY      A @BASEBOARD_FAB2_LIB.BASEBOARD_FAB2(SCH_1):P3V3_STBY
   2 FM_INTRUDER_HDR_PCH_N      B @BASEBOARD_FAB2_LIB.BASEBOARD_FAB2(SCH_1):FM_INTRUDER_HDR_PCH_N

RES_0402-10.0K,1%,1/16W,CHIP,GA  I73  R7C20
   1 CLK_50M_CKMNG_PCH_10GBE      A @BASEBOARD_FAB2_LIB.BASEBOARD_FAB2(SCH_1):CLK_50M_CKMNG_PCH_10GBE
   2    GND      B @BASEBOARD_FAB2_LIB.BASEBOARD_FAB2(SCH_1):GND

RES_0402-0.0,5%,1/16W,CHIP,G21A  I89  R3P3
   1 RMII_SPRNGVLLE_BMC_PCH_RXD0      A @BASEBOARD_FAB2_LIB.BASEBOARD_FAB2(SCH_1):RMII_SPRNGVLLE_BMC_PCH_RXD0
   2 RMII_SPRNGVLLE_BMC_PCH_RXD0_R1      B @BASEBOARD_FAB2_LIB.BASEBOARD_FAB2(SCH_1):RMII_SPRNGVLLE_BMC_PCH_RXD0_R1

RES_0402-0.0,5%,1/16W,CHIP,G21A  I90  R3P2
   1 RMII_BMC_PCH_SPRNGVLLE_CRSDV      A @BASEBOARD_FAB2_LIB.BASEBOARD_FAB2(SCH_1):RMII_BMC_PCH_SPRNGVLLE_CRSDV
   2 RMII_BMC_PCH_SPRNGVLLE_CRSDV_R1      B @BASEBOARD_FAB2_LIB.BASEBOARD_FAB2(SCH_1):RMII_BMC_PCH_SPRNGVLLE_CRSDV_R1

RES_0402-0.0,5%,1/16W,CHIP,G21A  I91  R2P1
   1 RMII_SPRNGVLLE_BMC_PCH_RXD1      A @BASEBOARD_FAB2_LIB.BASEBOARD_FAB2(SCH_1):RMII_SPRNGVLLE_BMC_PCH_RXD1
   2 RMII_SPRNGVLLE_BMC_PCH_RXD1_R1      B @BASEBOARD_FAB2_LIB.BASEBOARD_FAB2(SCH_1):RMII_SPRNGVLLE_BMC_PCH_RXD1_R1

RES_0402-33.2,1%,1/16W,CHIP,G2A  I98  R7C14
   1 RMII_BMC_PCH_SPRNGVLLE_RXER      A @BASEBOARD_FAB2_LIB.BASEBOARD_FAB2(SCH_1):RMII_BMC_PCH_SPRNGVLLE_RXER
   2 RMII_BMC_PCH_SPRNGVLLE_RXER_R      B @BASEBOARD_FAB2_LIB.BASEBOARD_FAB2(SCH_1):RMII_BMC_PCH_SPRNGVLLE_RXER_R

RES_0402-33.2,1%,1/16W,CHIP,G2A  I101  R8D11
   1 RMII_PCH_SPRNGVLLE_ARB_OUT      A @BASEBOARD_FAB2_LIB.BASEBOARD_FAB2(SCH_1):RMII_PCH_SPRNGVLLE_ARB_OUT
   2 RMII_PCH_SPRNGVLLE_ARB_OUT_R      B @BASEBOARD_FAB2_LIB.BASEBOARD_FAB2(SCH_1):RMII_PCH_SPRNGVLLE_ARB_OUT_R


DRAWING: @BASEBOARD_FAB2_LIB.BASEBOARD_FAB2(SCH_1):PAGE122 

LBG_CORE_QAT_EXT_D_BGA1-IC,H91A  I63  U7C1
AT27 TP_PCH_RSVD59 RSVD<59> @BASEBOARD_FAB2_LIB.BASEBOARD_FAB2(SCH_1):TP_PCH_RSVD59
AP27 TP_PCH_RSVD58 RSVD<58> @BASEBOARD_FAB2_LIB.BASEBOARD_FAB2(SCH_1):TP_PCH_RSVD58
 P29 TP_PCH_RSVD31 RSVD<31> @BASEBOARD_FAB2_LIB.BASEBOARD_FAB2(SCH_1):TP_PCH_RSVD31
 R31 TP_PCH_RSVD30 RSVD<30> @BASEBOARD_FAB2_LIB.BASEBOARD_FAB2(SCH_1):TP_PCH_RSVD30
 P33 TP_PCH_RSVD29 RSVD<29> @BASEBOARD_FAB2_LIB.BASEBOARD_FAB2(SCH_1):TP_PCH_RSVD29
 R35 TP_PCH_RSVD28 RSVD<28> @BASEBOARD_FAB2_LIB.BASEBOARD_FAB2(SCH_1):TP_PCH_RSVD28
AE46 P1V05_PCH_STBY_ISCLK_PLL VCCA_CLKFILT_1P05<4> @BASEBOARD_FAB2_LIB.BASEBOARD_FAB2(SCH_1):P1V05_PCH_STBY_ISCLK_PLL
AJ48 P1V05_PCH_STBY_ISCLK_PLL VCCA_CLKFILT_1P05<3> @BASEBOARD_FAB2_LIB.BASEBOARD_FAB2(SCH_1):P1V05_PCH_STBY_ISCLK_PLL
AJ46 P1V05_PCH_STBY_ISCLK_PLL VCCA_CLKFILT_1P05<2> @BASEBOARD_FAB2_LIB.BASEBOARD_FAB2(SCH_1):P1V05_PCH_STBY_ISCLK_PLL
AG45 P1V05_PCH_STBY_ISCLK_PLL VCCA_CLKFILT_1P05<1> @BASEBOARD_FAB2_LIB.BASEBOARD_FAB2(SCH_1):P1V05_PCH_STBY_ISCLK_PLL
 W50 P1V05_PCH_STBY_ISCLK_PLL VCCA_CLKFILT_1P05<0> @BASEBOARD_FAB2_LIB.BASEBOARD_FAB2(SCH_1):P1V05_PCH_STBY_ISCLK_PLL
 U50 P1V05_PCH_STBY VCCA_CLKUNF_1P05<1> @BASEBOARD_FAB2_LIB.BASEBOARD_FAB2(SCH_1):P1V05_PCH_STBY
AH50 P1V05_PCH_STBY VCCA_CLKUNF_1P05<0> @BASEBOARD_FAB2_LIB.BASEBOARD_FAB2(SCH_1):P1V05_PCH_STBY
AD50 P1V05_PCH_STBY_VCCA_XTAL VCCA_CLKXTAL_1P05 @BASEBOARD_FAB2_LIB.BASEBOARD_FAB2(SCH_1):P1V05_PCH_STBY_VCCA_XTAL
AG48 P1V05_PCH_STBY_VCCA_PLL0 VCCA_PLL0_1P05 @BASEBOARD_FAB2_LIB.BASEBOARD_FAB2(SCH_1):P1V05_PCH_STBY_VCCA_PLL0
AE45 P1V05_PCH_STBY_VCCA_PLL1 VCCA_PLL1_1P05 @BASEBOARD_FAB2_LIB.BASEBOARD_FAB2(SCH_1):P1V05_PCH_STBY_VCCA_PLL1
AK43 P1V05_PCH_STBY VCCMPHY_1P05<12> @BASEBOARD_FAB2_LIB.BASEBOARD_FAB2(SCH_1):P1V05_PCH_STBY
AK45 P1V05_PCH_STBY VCCMPHY_1P05<11> @BASEBOARD_FAB2_LIB.BASEBOARD_FAB2(SCH_1):P1V05_PCH_STBY
AM43 P1V05_PCH_STBY VCCMPHY_1P05<10> @BASEBOARD_FAB2_LIB.BASEBOARD_FAB2(SCH_1):P1V05_PCH_STBY
AM45 P1V05_PCH_STBY VCCMPHY_1P05<9> @BASEBOARD_FAB2_LIB.BASEBOARD_FAB2(SCH_1):P1V05_PCH_STBY
AP43 P1V05_PCH_STBY VCCMPHY_1P05<8> @BASEBOARD_FAB2_LIB.BASEBOARD_FAB2(SCH_1):P1V05_PCH_STBY
AP45 P1V05_PCH_STBY VCCMPHY_1P05<7> @BASEBOARD_FAB2_LIB.BASEBOARD_FAB2(SCH_1):P1V05_PCH_STBY
AT43 P1V05_PCH_STBY VCCMPHY_1P05<6> @BASEBOARD_FAB2_LIB.BASEBOARD_FAB2(SCH_1):P1V05_PCH_STBY
AT45 P1V05_PCH_STBY VCCMPHY_1P05<5> @BASEBOARD_FAB2_LIB.BASEBOARD_FAB2(SCH_1):P1V05_PCH_STBY
AU43 P1V05_PCH_STBY VCCMPHY_1P05<4> @BASEBOARD_FAB2_LIB.BASEBOARD_FAB2(SCH_1):P1V05_PCH_STBY
AU45 P1V05_PCH_STBY VCCMPHY_1P05<3> @BASEBOARD_FAB2_LIB.BASEBOARD_FAB2(SCH_1):P1V05_PCH_STBY
AJ43 P1V05_PCH_STBY VCCMPHY_1P05<2> @BASEBOARD_FAB2_LIB.BASEBOARD_FAB2(SCH_1):P1V05_PCH_STBY
AW43 P1V05_PCH_STBY VCCMPHY_1P05<1> @BASEBOARD_FAB2_LIB.BASEBOARD_FAB2(SCH_1):P1V05_PCH_STBY
AW45 P1V05_PCH_STBY VCCMPHY_1P05<0> @BASEBOARD_FAB2_LIB.BASEBOARD_FAB2(SCH_1):P1V05_PCH_STBY
BA39 P1V05_PCH_STBY_KR_PLL VCCP10GBEPLL_1P05<3> @BASEBOARD_FAB2_LIB.BASEBOARD_FAB2(SCH_1):P1V05_PCH_STBY_KR_PLL
BA41 P1V05_PCH_STBY_KR_PLL VCCP10GBEPLL_1P05<2> @BASEBOARD_FAB2_LIB.BASEBOARD_FAB2(SCH_1):P1V05_PCH_STBY_KR_PLL
BB40 P1V05_PCH_STBY_KR_PLL VCCP10GBEPLL_1P05<1> @BASEBOARD_FAB2_LIB.BASEBOARD_FAB2(SCH_1):P1V05_PCH_STBY_KR_PLL
BD38 P1V05_PCH_STBY_KR_PLL VCCP10GBEPLL_1P05<0> @BASEBOARD_FAB2_LIB.BASEBOARD_FAB2(SCH_1):P1V05_PCH_STBY_KR_PLL
BA27 P1V8_PCH_STBY VCCP10GBE_HV_1P8<1> @BASEBOARD_FAB2_LIB.BASEBOARD_FAB2(SCH_1):P1V8_PCH_STBY
BA29 P1V8_PCH_STBY VCCP10GBE_HV_1P8<0> @BASEBOARD_FAB2_LIB.BASEBOARD_FAB2(SCH_1):P1V8_PCH_STBY
BA30 P1V05_PCH_STBY VCCP10GBE_LV_1P05<6> @BASEBOARD_FAB2_LIB.BASEBOARD_FAB2(SCH_1):P1V05_PCH_STBY
BA32 P1V05_PCH_STBY VCCP10GBE_LV_1P05<5> @BASEBOARD_FAB2_LIB.BASEBOARD_FAB2(SCH_1):P1V05_PCH_STBY
BA34 P1V05_PCH_STBY VCCP10GBE_LV_1P05<4> @BASEBOARD_FAB2_LIB.BASEBOARD_FAB2(SCH_1):P1V05_PCH_STBY
BA36 P1V05_PCH_STBY VCCP10GBE_LV_1P05<3> @BASEBOARD_FAB2_LIB.BASEBOARD_FAB2(SCH_1):P1V05_PCH_STBY
BA37 P1V05_PCH_STBY VCCP10GBE_LV_1P05<2> @BASEBOARD_FAB2_LIB.BASEBOARD_FAB2(SCH_1):P1V05_PCH_STBY
BB33 P1V05_PCH_STBY VCCP10GBE_LV_1P05<1> @BASEBOARD_FAB2_LIB.BASEBOARD_FAB2(SCH_1):P1V05_PCH_STBY
BB37 P1V05_PCH_STBY VCCP10GBE_LV_1P05<0> @BASEBOARD_FAB2_LIB.BASEBOARD_FAB2(SCH_1):P1V05_PCH_STBY
AH24 P3V3_STBY VCCPDSW_3P3 @BASEBOARD_FAB2_LIB.BASEBOARD_FAB2(SCH_1):P3V3_STBY
AW24 P3V3_STBY VCCPGPPA @BASEBOARD_FAB2_LIB.BASEBOARD_FAB2(SCH_1):P3V3_STBY
BE26 P3V3_STBY VCCPGPPB @BASEBOARD_FAB2_LIB.BASEBOARD_FAB2(SCH_1):P3V3_STBY
BE40 P3V3_STBY VCCPGPPC @BASEBOARD_FAB2_LIB.BASEBOARD_FAB2(SCH_1):P3V3_STBY
BA43 P3V3_STBY VCCPGPPD @BASEBOARD_FAB2_LIB.BASEBOARD_FAB2(SCH_1):P3V3_STBY
BE44 P3V3_STBY VCCPGPPE @BASEBOARD_FAB2_LIB.BASEBOARD_FAB2(SCH_1):P3V3_STBY
AU27 P3V3_STBY VCCPGPPF @BASEBOARD_FAB2_LIB.BASEBOARD_FAB2(SCH_1):P3V3_STBY
BA26 P3V3_STBY VCCPGPPG @BASEBOARD_FAB2_LIB.BASEBOARD_FAB2(SCH_1):P3V3_STBY
BA24 P3V3_STBY VCCPGPPH @BASEBOARD_FAB2_LIB.BASEBOARD_FAB2(SCH_1):P3V3_STBY
BB26 P3V3_STBY VCCPGPPJ @BASEBOARD_FAB2_LIB.BASEBOARD_FAB2(SCH_1):P3V3_STBY
AU24 P3V3_STBY VCCPGPPK @BASEBOARD_FAB2_LIB.BASEBOARD_FAB2(SCH_1):P3V3_STBY
AK24 P1V8_PCH_STBY VCCPGPP_1P8<6> @BASEBOARD_FAB2_LIB.BASEBOARD_FAB2(SCH_1):P1V8_PCH_STBY
AW27 P1V8_PCH_STBY VCCPGPP_1P8<5> @BASEBOARD_FAB2_LIB.BASEBOARD_FAB2(SCH_1):P1V8_PCH_STBY
AP29 P1V8_PCH_STBY VCCPGPP_1P8<4> @BASEBOARD_FAB2_LIB.BASEBOARD_FAB2(SCH_1):P1V8_PCH_STBY
AM29 P1V8_PCH_STBY VCCPGPP_1P8<3> @BASEBOARD_FAB2_LIB.BASEBOARD_FAB2(SCH_1):P1V8_PCH_STBY
AT29 P1V8_PCH_STBY VCCPGPP_1P8<2> @BASEBOARD_FAB2_LIB.BASEBOARD_FAB2(SCH_1):P1V8_PCH_STBY
AW29 P1V8_PCH_STBY VCCPGPP_1P8<1> @BASEBOARD_FAB2_LIB.BASEBOARD_FAB2(SCH_1):P1V8_PCH_STBY
AU29 P1V8_PCH_STBY VCCPGPP_1P8<0> @BASEBOARD_FAB2_LIB.BASEBOARD_FAB2(SCH_1):P1V8_PCH_STBY
AG27 P1V8_PCH_STBY VCCPHDA_1P8 @BASEBOARD_FAB2_LIB.BASEBOARD_FAB2(SCH_1):P1V8_PCH_STBY
 Y26 P1V05_PCH_STBY VCCPRIM_1P05<19> @BASEBOARD_FAB2_LIB.BASEBOARD_FAB2(SCH_1):P1V05_PCH_STBY
AA24 P1V05_PCH_STBY VCCPRIM_1P05<18> @BASEBOARD_FAB2_LIB.BASEBOARD_FAB2(SCH_1):P1V05_PCH_STBY
AK27 P1V05_PCH_STBY VCCPRIM_1P05<17> @BASEBOARD_FAB2_LIB.BASEBOARD_FAB2(SCH_1):P1V05_PCH_STBY
 R42 P1V05_PCH_STBY VCCPRIM_1P05<16> @BASEBOARD_FAB2_LIB.BASEBOARD_FAB2(SCH_1):P1V05_PCH_STBY
 R46 P1V05_PCH_STBY VCCPRIM_1P05<15> @BASEBOARD_FAB2_LIB.BASEBOARD_FAB2(SCH_1):P1V05_PCH_STBY
 T44 P1V05_PCH_STBY VCCPRIM_1P05<14> @BASEBOARD_FAB2_LIB.BASEBOARD_FAB2(SCH_1):P1V05_PCH_STBY
 U46 P1V05_PCH_STBY VCCPRIM_1P05<13> @BASEBOARD_FAB2_LIB.BASEBOARD_FAB2(SCH_1):P1V05_PCH_STBY
 V44 P1V05_PCH_STBY VCCPRIM_1P05<12> @BASEBOARD_FAB2_LIB.BASEBOARD_FAB2(SCH_1):P1V05_PCH_STBY
 Y45 P1V05_PCH_STBY VCCPRIM_1P05<11> @BASEBOARD_FAB2_LIB.BASEBOARD_FAB2(SCH_1):P1V05_PCH_STBY
 Y46 P1V05_PCH_STBY VCCPRIM_1P05<10> @BASEBOARD_FAB2_LIB.BASEBOARD_FAB2(SCH_1):P1V05_PCH_STBY
AA45 P1V05_PCH_STBY VCCPRIM_1P05<9> @BASEBOARD_FAB2_LIB.BASEBOARD_FAB2(SCH_1):P1V05_PCH_STBY
AA46 P1V05_PCH_STBY VCCPRIM_1P05<8> @BASEBOARD_FAB2_LIB.BASEBOARD_FAB2(SCH_1):P1V05_PCH_STBY
AC26 P1V05_PCH_STBY VCCPRIM_1P05<7> @BASEBOARD_FAB2_LIB.BASEBOARD_FAB2(SCH_1):P1V05_PCH_STBY
AJ29 P1V05_PCH_STBY VCCPRIM_1P05<6> @BASEBOARD_FAB2_LIB.BASEBOARD_FAB2(SCH_1):P1V05_PCH_STBY
AM27 P1V05_PCH_STBY VCCPRIM_1P05<5> @BASEBOARD_FAB2_LIB.BASEBOARD_FAB2(SCH_1):P1V05_PCH_STBY
AT39 P1V05_PCH_STBY VCCPRIM_1P05<4> @BASEBOARD_FAB2_LIB.BASEBOARD_FAB2(SCH_1):P1V05_PCH_STBY
AU37 P1V05_PCH_STBY VCCPRIM_1P05<3> @BASEBOARD_FAB2_LIB.BASEBOARD_FAB2(SCH_1):P1V05_PCH_STBY
AU39 P1V05_PCH_STBY VCCPRIM_1P05<2> @BASEBOARD_FAB2_LIB.BASEBOARD_FAB2(SCH_1):P1V05_PCH_STBY
BE48 P1V05_PCH_STBY VCCPRIM_1P05<1> @BASEBOARD_FAB2_LIB.BASEBOARD_FAB2(SCH_1):P1V05_PCH_STBY
BF46 P1V05_PCH_STBY VCCPRIM_1P05<0> @BASEBOARD_FAB2_LIB.BASEBOARD_FAB2(SCH_1):P1V05_PCH_STBY
AJ27 P3V3_RTC_STBY VCCPRTC @BASEBOARD_FAB2_LIB.BASEBOARD_FAB2(SCH_1):P3V3_RTC_STBY
AG29 P3V3_STBY VCCPRTCPRIM_3P3 @BASEBOARD_FAB2_LIB.BASEBOARD_FAB2(SCH_1):P3V3_STBY
AR24 P3V3_STBY VCCPSPI @BASEBOARD_FAB2_LIB.BASEBOARD_FAB2(SCH_1):P3V3_STBY
AK29 P1V8_PCH_STBY VCCPSPI_1P8 @BASEBOARD_FAB2_LIB.BASEBOARD_FAB2(SCH_1):P1V8_PCH_STBY
BA48 P3V3_STBY VCCPUSBDSW_3P3 @BASEBOARD_FAB2_LIB.BASEBOARD_FAB2(SCH_1):P3V3_STBY
AE26 P1V8_PCH_STBY VCCP_1P8<1> @BASEBOARD_FAB2_LIB.BASEBOARD_FAB2(SCH_1):P1V8_PCH_STBY
BD46 P1V8_PCH_STBY VCCP_1P8<0> @BASEBOARD_FAB2_LIB.BASEBOARD_FAB2(SCH_1):P1V8_PCH_STBY
AN24 P3V3_STBY VCCP_3P3<5> @BASEBOARD_FAB2_LIB.BASEBOARD_FAB2(SCH_1):P3V3_STBY
AD24 P3V3_STBY VCCP_3P3<2> @BASEBOARD_FAB2_LIB.BASEBOARD_FAB2(SCH_1):P3V3_STBY
BA45 P3V3_STBY VCCP_3P3<1> @BASEBOARD_FAB2_LIB.BASEBOARD_FAB2(SCH_1):P3V3_STBY
BA46 P3V3_STBY VCCP_3P3<0> @BASEBOARD_FAB2_LIB.BASEBOARD_FAB2(SCH_1):P3V3_STBY
AT48 P1V05_PCH_STBY VCCP_HSIOPLLUNF_1P05 @BASEBOARD_FAB2_LIB.BASEBOARD_FAB2(SCH_1):P1V05_PCH_STBY
AP48 P1V05_PCH_STBY_WM26_PLL VCCP_HSIOPLL_1P05<3> @BASEBOARD_FAB2_LIB.BASEBOARD_FAB2(SCH_1):P1V05_PCH_STBY_WM26_PLL
AU48 P1V05_PCH_STBY_WM26_PLL VCCP_HSIOPLL_1P05<2> @BASEBOARD_FAB2_LIB.BASEBOARD_FAB2(SCH_1):P1V05_PCH_STBY_WM26_PLL
AW48 P1V05_PCH_STBY_WM26_PLL VCCP_HSIOPLL_1P05<0> @BASEBOARD_FAB2_LIB.BASEBOARD_FAB2(SCH_1):P1V05_PCH_STBY_WM26_PLL
AM48 P1V05_PCH_STBY VCCP_UPPLLUNF_1P05 @BASEBOARD_FAB2_LIB.BASEBOARD_FAB2(SCH_1):P1V05_PCH_STBY
AK50 P1V05_PCH_STBY_WM20_PLL VCCP_UPPLL_1P05<2> @BASEBOARD_FAB2_LIB.BASEBOARD_FAB2(SCH_1):P1V05_PCH_STBY_WM20_PLL
AN50 P1V05_PCH_STBY_WM20_PLL VCCP_UPPLL_1P05<0> @BASEBOARD_FAB2_LIB.BASEBOARD_FAB2(SCH_1):P1V05_PCH_STBY_WM20_PLL
AG22 A_PVCCRTC_EXT_CAP VCCRTCEXT @BASEBOARD_FAB2_LIB.BASEBOARD_FAB2(SCH_1):A_PVCCRTC_EXT_CAP


DRAWING: @BASEBOARD_FAB2_LIB.BASEBOARD_FAB2(SCH_1):PAGE123 

LBG_CORE_QAT_EXT_D_BGA1-IC,H91A  I13  U7C1
BP69    GND VSS<494> @BASEBOARD_FAB2_LIB.BASEBOARD_FAB2(SCH_1):GND
BT69    GND VSS<493> @BASEBOARD_FAB2_LIB.BASEBOARD_FAB2(SCH_1):GND
BU70    GND VSS<492> @BASEBOARD_FAB2_LIB.BASEBOARD_FAB2(SCH_1):GND
BR70    GND VSS<491> @BASEBOARD_FAB2_LIB.BASEBOARD_FAB2(SCH_1):GND
 F70    GND VSS<490> @BASEBOARD_FAB2_LIB.BASEBOARD_FAB2(SCH_1):GND
 E70    GND VSS<489> @BASEBOARD_FAB2_LIB.BASEBOARD_FAB2(SCH_1):GND
 BU3    GND VSS<488> @BASEBOARD_FAB2_LIB.BASEBOARD_FAB2(SCH_1):GND
 BR3    GND VSS<487> @BASEBOARD_FAB2_LIB.BASEBOARD_FAB2(SCH_1):GND
  F3    GND VSS<486> @BASEBOARD_FAB2_LIB.BASEBOARD_FAB2(SCH_1):GND
  E3    GND VSS<485> @BASEBOARD_FAB2_LIB.BASEBOARD_FAB2(SCH_1):GND
  A5    GND VSS<484> @BASEBOARD_FAB2_LIB.BASEBOARD_FAB2(SCH_1):GND
  A7    GND VSS<483> @BASEBOARD_FAB2_LIB.BASEBOARD_FAB2(SCH_1):GND
  A9    GND VSS<482> @BASEBOARD_FAB2_LIB.BASEBOARD_FAB2(SCH_1):GND
 A65    GND VSS<481> @BASEBOARD_FAB2_LIB.BASEBOARD_FAB2(SCH_1):GND
 A66    GND VSS<480> @BASEBOARD_FAB2_LIB.BASEBOARD_FAB2(SCH_1):GND
 A68    GND VSS<479> @BASEBOARD_FAB2_LIB.BASEBOARD_FAB2(SCH_1):GND
  J1    GND VSS<478> @BASEBOARD_FAB2_LIB.BASEBOARD_FAB2(SCH_1):GND
 J72    GND VSS<477> @BASEBOARD_FAB2_LIB.BASEBOARD_FAB2(SCH_1):GND
 BN1    GND VSS<476> @BASEBOARD_FAB2_LIB.BASEBOARD_FAB2(SCH_1):GND
BN72    GND VSS<475> @BASEBOARD_FAB2_LIB.BASEBOARD_FAB2(SCH_1):GND
CA68    GND VSS<474> @BASEBOARD_FAB2_LIB.BASEBOARD_FAB2(SCH_1):GND
CA66    GND VSS<473> @BASEBOARD_FAB2_LIB.BASEBOARD_FAB2(SCH_1):GND
CA65    GND VSS<472> @BASEBOARD_FAB2_LIB.BASEBOARD_FAB2(SCH_1):GND
 CA9    GND VSS<471> @BASEBOARD_FAB2_LIB.BASEBOARD_FAB2(SCH_1):GND
 CA7    GND VSS<470> @BASEBOARD_FAB2_LIB.BASEBOARD_FAB2(SCH_1):GND
 CA5    GND VSS<469> @BASEBOARD_FAB2_LIB.BASEBOARD_FAB2(SCH_1):GND
 A70    GND VSS<468> @BASEBOARD_FAB2_LIB.BASEBOARD_FAB2(SCH_1):GND
 CA3    GND VSS<467> @BASEBOARD_FAB2_LIB.BASEBOARD_FAB2(SCH_1):GND
 BW1    GND VSS<466> @BASEBOARD_FAB2_LIB.BASEBOARD_FAB2(SCH_1):GND
 BU1    GND VSS<465> @BASEBOARD_FAB2_LIB.BASEBOARD_FAB2(SCH_1):GND
 BR1    GND VSS<464> @BASEBOARD_FAB2_LIB.BASEBOARD_FAB2(SCH_1):GND
  C3    GND VSS<463> @BASEBOARD_FAB2_LIB.BASEBOARD_FAB2(SCH_1):GND
 C72    GND VSS<462> @BASEBOARD_FAB2_LIB.BASEBOARD_FAB2(SCH_1):GND
  E1    GND VSS<461> @BASEBOARD_FAB2_LIB.BASEBOARD_FAB2(SCH_1):GND
 E72    GND VSS<460> @BASEBOARD_FAB2_LIB.BASEBOARD_FAB2(SCH_1):GND
  G1    GND VSS<459> @BASEBOARD_FAB2_LIB.BASEBOARD_FAB2(SCH_1):GND
 G72    GND VSS<458> @BASEBOARD_FAB2_LIB.BASEBOARD_FAB2(SCH_1):GND
BR72    GND VSS<457> @BASEBOARD_FAB2_LIB.BASEBOARD_FAB2(SCH_1):GND
BU72    GND VSS<456> @BASEBOARD_FAB2_LIB.BASEBOARD_FAB2(SCH_1):GND
BW70    GND VSS<455> @BASEBOARD_FAB2_LIB.BASEBOARD_FAB2(SCH_1):GND
BW72    GND VSS<454> @BASEBOARD_FAB2_LIB.BASEBOARD_FAB2(SCH_1):GND
CA70    GND VSS<453> @BASEBOARD_FAB2_LIB.BASEBOARD_FAB2(SCH_1):GND
BB48    GND VSS<452> @BASEBOARD_FAB2_LIB.BASEBOARD_FAB2(SCH_1):GND
AT37    GND VSS<451> @BASEBOARD_FAB2_LIB.BASEBOARD_FAB2(SCH_1):GND
 Y72    GND VSS<450> @BASEBOARD_FAB2_LIB.BASEBOARD_FAB2(SCH_1):GND
 Y70    GND VSS<449> @BASEBOARD_FAB2_LIB.BASEBOARD_FAB2(SCH_1):GND
 A18    GND VSS<448> @BASEBOARD_FAB2_LIB.BASEBOARD_FAB2(SCH_1):GND
 A22    GND VSS<447> @BASEBOARD_FAB2_LIB.BASEBOARD_FAB2(SCH_1):GND
 A30    GND VSS<446> @BASEBOARD_FAB2_LIB.BASEBOARD_FAB2(SCH_1):GND
 A34    GND VSS<445> @BASEBOARD_FAB2_LIB.BASEBOARD_FAB2(SCH_1):GND
 A37    GND VSS<444> @BASEBOARD_FAB2_LIB.BASEBOARD_FAB2(SCH_1):GND
 A41    GND VSS<443> @BASEBOARD_FAB2_LIB.BASEBOARD_FAB2(SCH_1):GND
 B12    GND VSS<442> @BASEBOARD_FAB2_LIB.BASEBOARD_FAB2(SCH_1):GND
 B19    GND VSS<441> @BASEBOARD_FAB2_LIB.BASEBOARD_FAB2(SCH_1):GND
 B25    GND VSS<440> @BASEBOARD_FAB2_LIB.BASEBOARD_FAB2(SCH_1):GND
 B27    GND VSS<439> @BASEBOARD_FAB2_LIB.BASEBOARD_FAB2(SCH_1):GND
 B47    GND VSS<438> @BASEBOARD_FAB2_LIB.BASEBOARD_FAB2(SCH_1):GND
 C22    GND VSS<437> @BASEBOARD_FAB2_LIB.BASEBOARD_FAB2(SCH_1):GND
 C30    GND VSS<436> @BASEBOARD_FAB2_LIB.BASEBOARD_FAB2(SCH_1):GND
 C34    GND VSS<435> @BASEBOARD_FAB2_LIB.BASEBOARD_FAB2(SCH_1):GND
 C37    GND VSS<434> @BASEBOARD_FAB2_LIB.BASEBOARD_FAB2(SCH_1):GND
 C41    GND VSS<433> @BASEBOARD_FAB2_LIB.BASEBOARD_FAB2(SCH_1):GND
 C65    GND VSS<432> @BASEBOARD_FAB2_LIB.BASEBOARD_FAB2(SCH_1):GND
 D12    GND VSS<431> @BASEBOARD_FAB2_LIB.BASEBOARD_FAB2(SCH_1):GND
 D16    GND VSS<430> @BASEBOARD_FAB2_LIB.BASEBOARD_FAB2(SCH_1):GND
 D19    GND VSS<429> @BASEBOARD_FAB2_LIB.BASEBOARD_FAB2(SCH_1):GND
 D25    GND VSS<428> @BASEBOARD_FAB2_LIB.BASEBOARD_FAB2(SCH_1):GND
 D27    GND VSS<427> @BASEBOARD_FAB2_LIB.BASEBOARD_FAB2(SCH_1):GND
 E59    GND VSS<426> @BASEBOARD_FAB2_LIB.BASEBOARD_FAB2(SCH_1):GND
 E65    GND VSS<425> @BASEBOARD_FAB2_LIB.BASEBOARD_FAB2(SCH_1):GND
 D47    GND VSS<424> @BASEBOARD_FAB2_LIB.BASEBOARD_FAB2(SCH_1):GND
 E11    GND VSS<423> @BASEBOARD_FAB2_LIB.BASEBOARD_FAB2(SCH_1):GND
 E13    GND VSS<422> @BASEBOARD_FAB2_LIB.BASEBOARD_FAB2(SCH_1):GND
 E15    GND VSS<421> @BASEBOARD_FAB2_LIB.BASEBOARD_FAB2(SCH_1):GND
 E20    GND VSS<420> @BASEBOARD_FAB2_LIB.BASEBOARD_FAB2(SCH_1):GND
 E22    GND VSS<419> @BASEBOARD_FAB2_LIB.BASEBOARD_FAB2(SCH_1):GND
 E24    GND VSS<418> @BASEBOARD_FAB2_LIB.BASEBOARD_FAB2(SCH_1):GND
 E26    GND VSS<417> @BASEBOARD_FAB2_LIB.BASEBOARD_FAB2(SCH_1):GND
 E28    GND VSS<416> @BASEBOARD_FAB2_LIB.BASEBOARD_FAB2(SCH_1):GND
 E30    GND VSS<415> @BASEBOARD_FAB2_LIB.BASEBOARD_FAB2(SCH_1):GND
 E32    GND VSS<414> @BASEBOARD_FAB2_LIB.BASEBOARD_FAB2(SCH_1):GND
 E34    GND VSS<413> @BASEBOARD_FAB2_LIB.BASEBOARD_FAB2(SCH_1):GND
 E37    GND VSS<412> @BASEBOARD_FAB2_LIB.BASEBOARD_FAB2(SCH_1):GND
 E39    GND VSS<411> @BASEBOARD_FAB2_LIB.BASEBOARD_FAB2(SCH_1):GND
 E41    GND VSS<410> @BASEBOARD_FAB2_LIB.BASEBOARD_FAB2(SCH_1):GND
 E43    GND VSS<409> @BASEBOARD_FAB2_LIB.BASEBOARD_FAB2(SCH_1):GND
 E45    GND VSS<408> @BASEBOARD_FAB2_LIB.BASEBOARD_FAB2(SCH_1):GND
 E48    GND VSS<407> @BASEBOARD_FAB2_LIB.BASEBOARD_FAB2(SCH_1):GND
 E50    GND VSS<406> @BASEBOARD_FAB2_LIB.BASEBOARD_FAB2(SCH_1):GND
 E52    GND VSS<405> @BASEBOARD_FAB2_LIB.BASEBOARD_FAB2(SCH_1):GND
 E54    GND VSS<404> @BASEBOARD_FAB2_LIB.BASEBOARD_FAB2(SCH_1):GND
 E57    GND VSS<403> @BASEBOARD_FAB2_LIB.BASEBOARD_FAB2(SCH_1):GND
  E6    GND VSS<402> @BASEBOARD_FAB2_LIB.BASEBOARD_FAB2(SCH_1):GND
 E61    GND VSS<401> @BASEBOARD_FAB2_LIB.BASEBOARD_FAB2(SCH_1):GND
 E63    GND VSS<400> @BASEBOARD_FAB2_LIB.BASEBOARD_FAB2(SCH_1):GND
 G59    GND VSS<399> @BASEBOARD_FAB2_LIB.BASEBOARD_FAB2(SCH_1):GND
  E9    GND VSS<398> @BASEBOARD_FAB2_LIB.BASEBOARD_FAB2(SCH_1):GND
 G22    GND VSS<397> @BASEBOARD_FAB2_LIB.BASEBOARD_FAB2(SCH_1):GND
 G29    GND VSS<396> @BASEBOARD_FAB2_LIB.BASEBOARD_FAB2(SCH_1):GND
 G37    GND VSS<395> @BASEBOARD_FAB2_LIB.BASEBOARD_FAB2(SCH_1):GND
 G48    GND VSS<394> @BASEBOARD_FAB2_LIB.BASEBOARD_FAB2(SCH_1):GND
  G6    GND VSS<393> @BASEBOARD_FAB2_LIB.BASEBOARD_FAB2(SCH_1):GND
 G63    GND VSS<392> @BASEBOARD_FAB2_LIB.BASEBOARD_FAB2(SCH_1):GND
 G66    GND VSS<391> @BASEBOARD_FAB2_LIB.BASEBOARD_FAB2(SCH_1):GND
 H58    GND VSS<390> @BASEBOARD_FAB2_LIB.BASEBOARD_FAB2(SCH_1):GND
 J29    GND VSS<389> @BASEBOARD_FAB2_LIB.BASEBOARD_FAB2(SCH_1):GND
  J5    GND VSS<388> @BASEBOARD_FAB2_LIB.BASEBOARD_FAB2(SCH_1):GND
  J7    GND VSS<387> @BASEBOARD_FAB2_LIB.BASEBOARD_FAB2(SCH_1):GND
 H65    GND VSS<386> @BASEBOARD_FAB2_LIB.BASEBOARD_FAB2(SCH_1):GND
 J11    GND VSS<385> @BASEBOARD_FAB2_LIB.BASEBOARD_FAB2(SCH_1):GND
 J15    GND VSS<384> @BASEBOARD_FAB2_LIB.BASEBOARD_FAB2(SCH_1):GND
 J22    GND VSS<383> @BASEBOARD_FAB2_LIB.BASEBOARD_FAB2(SCH_1):GND
 J37    GND VSS<382> @BASEBOARD_FAB2_LIB.BASEBOARD_FAB2(SCH_1):GND
 J44    GND VSS<381> @BASEBOARD_FAB2_LIB.BASEBOARD_FAB2(SCH_1):GND
 J59    GND VSS<380> @BASEBOARD_FAB2_LIB.BASEBOARD_FAB2(SCH_1):GND
 J68    GND VSS<379> @BASEBOARD_FAB2_LIB.BASEBOARD_FAB2(SCH_1):GND
 J70    GND VSS<378> @BASEBOARD_FAB2_LIB.BASEBOARD_FAB2(SCH_1):GND
 K54    GND VSS<377> @BASEBOARD_FAB2_LIB.BASEBOARD_FAB2(SCH_1):GND
 K69    GND VSS<376> @BASEBOARD_FAB2_LIB.BASEBOARD_FAB2(SCH_1):GND
 K71    GND VSS<375> @BASEBOARD_FAB2_LIB.BASEBOARD_FAB2(SCH_1):GND
  L5    GND VSS<374> @BASEBOARD_FAB2_LIB.BASEBOARD_FAB2(SCH_1):GND
 L68    GND VSS<373> @BASEBOARD_FAB2_LIB.BASEBOARD_FAB2(SCH_1):GND
  M2    GND VSS<372> @BASEBOARD_FAB2_LIB.BASEBOARD_FAB2(SCH_1):GND
 M22    GND VSS<371> @BASEBOARD_FAB2_LIB.BASEBOARD_FAB2(SCH_1):GND
 M26    GND VSS<370> @BASEBOARD_FAB2_LIB.BASEBOARD_FAB2(SCH_1):GND
 M29    GND VSS<369> @BASEBOARD_FAB2_LIB.BASEBOARD_FAB2(SCH_1):GND
 M33    GND VSS<368> @BASEBOARD_FAB2_LIB.BASEBOARD_FAB2(SCH_1):GND
 M37    GND VSS<367> @BASEBOARD_FAB2_LIB.BASEBOARD_FAB2(SCH_1):GND
  M4    GND VSS<366> @BASEBOARD_FAB2_LIB.BASEBOARD_FAB2(SCH_1):GND
 M40    GND VSS<365> @BASEBOARD_FAB2_LIB.BASEBOARD_FAB2(SCH_1):GND
 N42    GND VSS<364> @BASEBOARD_FAB2_LIB.BASEBOARD_FAB2(SCH_1):GND
 N50    GND VSS<363> @BASEBOARD_FAB2_LIB.BASEBOARD_FAB2(SCH_1):GND
 M44    GND VSS<362> @BASEBOARD_FAB2_LIB.BASEBOARD_FAB2(SCH_1):GND
 M48    GND VSS<361> @BASEBOARD_FAB2_LIB.BASEBOARD_FAB2(SCH_1):GND
 N13    GND VSS<360> @BASEBOARD_FAB2_LIB.BASEBOARD_FAB2(SCH_1):GND
 N17    GND VSS<359> @BASEBOARD_FAB2_LIB.BASEBOARD_FAB2(SCH_1):GND
 N20    GND VSS<358> @BASEBOARD_FAB2_LIB.BASEBOARD_FAB2(SCH_1):GND
 N24    GND VSS<357> @BASEBOARD_FAB2_LIB.BASEBOARD_FAB2(SCH_1):GND
 N27    GND VSS<356> @BASEBOARD_FAB2_LIB.BASEBOARD_FAB2(SCH_1):GND
 N31    GND VSS<355> @BASEBOARD_FAB2_LIB.BASEBOARD_FAB2(SCH_1):GND

LBG_CORE_QAT_EXT_D_BGA1-IC,H91A  I21  U7C1
AE27 P1V05_PCH_STBY VCCMPHY_1P05<13> @BASEBOARD_FAB2_LIB.BASEBOARD_FAB2(SCH_1):P1V05_PCH_STBY
AK32 PVNN_PCH_STBY VCCPRIM_AVID<62> @BASEBOARD_FAB2_LIB.BASEBOARD_FAB2(SCH_1):PVNN_PCH_STBY
 U31 PVNN_PCH_STBY VCCPRIM_AVID<61> @BASEBOARD_FAB2_LIB.BASEBOARD_FAB2(SCH_1):PVNN_PCH_STBY
 U35 PVNN_PCH_STBY VCCPRIM_AVID<60> @BASEBOARD_FAB2_LIB.BASEBOARD_FAB2(SCH_1):PVNN_PCH_STBY
 U38 PVNN_PCH_STBY VCCPRIM_AVID<59> @BASEBOARD_FAB2_LIB.BASEBOARD_FAB2(SCH_1):PVNN_PCH_STBY
 V29 PVNN_PCH_STBY VCCPRIM_AVID<58> @BASEBOARD_FAB2_LIB.BASEBOARD_FAB2(SCH_1):PVNN_PCH_STBY
 V33 PVNN_PCH_STBY VCCPRIM_AVID<57> @BASEBOARD_FAB2_LIB.BASEBOARD_FAB2(SCH_1):PVNN_PCH_STBY
 V40 PVNN_PCH_STBY VCCPRIM_AVID<56> @BASEBOARD_FAB2_LIB.BASEBOARD_FAB2(SCH_1):PVNN_PCH_STBY
 Y29 PVNN_PCH_STBY VCCPRIM_AVID<55> @BASEBOARD_FAB2_LIB.BASEBOARD_FAB2(SCH_1):PVNN_PCH_STBY
 Y30 PVNN_PCH_STBY VCCPRIM_AVID<54> @BASEBOARD_FAB2_LIB.BASEBOARD_FAB2(SCH_1):PVNN_PCH_STBY
 Y32 PVNN_PCH_STBY VCCPRIM_AVID<53> @BASEBOARD_FAB2_LIB.BASEBOARD_FAB2(SCH_1):PVNN_PCH_STBY
 Y34 PVNN_PCH_STBY VCCPRIM_AVID<52> @BASEBOARD_FAB2_LIB.BASEBOARD_FAB2(SCH_1):PVNN_PCH_STBY
 Y36 PVNN_PCH_STBY VCCPRIM_AVID<51> @BASEBOARD_FAB2_LIB.BASEBOARD_FAB2(SCH_1):PVNN_PCH_STBY
 Y37 PVNN_PCH_STBY VCCPRIM_AVID<50> @BASEBOARD_FAB2_LIB.BASEBOARD_FAB2(SCH_1):PVNN_PCH_STBY
 Y39 PVNN_PCH_STBY VCCPRIM_AVID<49> @BASEBOARD_FAB2_LIB.BASEBOARD_FAB2(SCH_1):PVNN_PCH_STBY
 Y41 PVNN_PCH_STBY VCCPRIM_AVID<48> @BASEBOARD_FAB2_LIB.BASEBOARD_FAB2(SCH_1):PVNN_PCH_STBY
AA29 PVNN_PCH_STBY VCCPRIM_AVID<47> @BASEBOARD_FAB2_LIB.BASEBOARD_FAB2(SCH_1):PVNN_PCH_STBY
AA30 PVNN_PCH_STBY VCCPRIM_AVID<46> @BASEBOARD_FAB2_LIB.BASEBOARD_FAB2(SCH_1):PVNN_PCH_STBY
AA32 PVNN_PCH_STBY VCCPRIM_AVID<45> @BASEBOARD_FAB2_LIB.BASEBOARD_FAB2(SCH_1):PVNN_PCH_STBY
AA34 PVNN_PCH_STBY VCCPRIM_AVID<44> @BASEBOARD_FAB2_LIB.BASEBOARD_FAB2(SCH_1):PVNN_PCH_STBY
AA36 PVNN_PCH_STBY VCCPRIM_AVID<43> @BASEBOARD_FAB2_LIB.BASEBOARD_FAB2(SCH_1):PVNN_PCH_STBY
AA37 PVNN_PCH_STBY VCCPRIM_AVID<42> @BASEBOARD_FAB2_LIB.BASEBOARD_FAB2(SCH_1):PVNN_PCH_STBY
AA39 PVNN_PCH_STBY VCCPRIM_AVID<41> @BASEBOARD_FAB2_LIB.BASEBOARD_FAB2(SCH_1):PVNN_PCH_STBY
AA41 PVNN_PCH_STBY VCCPRIM_AVID<40> @BASEBOARD_FAB2_LIB.BASEBOARD_FAB2(SCH_1):PVNN_PCH_STBY
AC29 PVNN_PCH_STBY VCCPRIM_AVID<39> @BASEBOARD_FAB2_LIB.BASEBOARD_FAB2(SCH_1):PVNN_PCH_STBY
AC30 PVNN_PCH_STBY VCCPRIM_AVID<38> @BASEBOARD_FAB2_LIB.BASEBOARD_FAB2(SCH_1):PVNN_PCH_STBY
AC32 PVNN_PCH_STBY VCCPRIM_AVID<37> @BASEBOARD_FAB2_LIB.BASEBOARD_FAB2(SCH_1):PVNN_PCH_STBY
AC34 PVNN_PCH_STBY VCCPRIM_AVID<36> @BASEBOARD_FAB2_LIB.BASEBOARD_FAB2(SCH_1):PVNN_PCH_STBY
AC36 PVNN_PCH_STBY VCCPRIM_AVID<35> @BASEBOARD_FAB2_LIB.BASEBOARD_FAB2(SCH_1):PVNN_PCH_STBY
AC37 PVNN_PCH_STBY VCCPRIM_AVID<34> @BASEBOARD_FAB2_LIB.BASEBOARD_FAB2(SCH_1):PVNN_PCH_STBY
AC39 PVNN_PCH_STBY VCCPRIM_AVID<33> @BASEBOARD_FAB2_LIB.BASEBOARD_FAB2(SCH_1):PVNN_PCH_STBY
AC41 PVNN_PCH_STBY VCCPRIM_AVID<32> @BASEBOARD_FAB2_LIB.BASEBOARD_FAB2(SCH_1):PVNN_PCH_STBY
 U27 PVNN_PCH_STBY VCCPRIM_AVID<31> @BASEBOARD_FAB2_LIB.BASEBOARD_FAB2(SCH_1):PVNN_PCH_STBY
AE30 PVNN_PCH_STBY VCCPRIM_AVID<30> @BASEBOARD_FAB2_LIB.BASEBOARD_FAB2(SCH_1):PVNN_PCH_STBY
AE32 PVNN_PCH_STBY VCCPRIM_AVID<29> @BASEBOARD_FAB2_LIB.BASEBOARD_FAB2(SCH_1):PVNN_PCH_STBY
AE34 PVNN_PCH_STBY VCCPRIM_AVID<28> @BASEBOARD_FAB2_LIB.BASEBOARD_FAB2(SCH_1):PVNN_PCH_STBY
AE36 PVNN_PCH_STBY VCCPRIM_AVID<27> @BASEBOARD_FAB2_LIB.BASEBOARD_FAB2(SCH_1):PVNN_PCH_STBY
AE37 PVNN_PCH_STBY VCCPRIM_AVID<26> @BASEBOARD_FAB2_LIB.BASEBOARD_FAB2(SCH_1):PVNN_PCH_STBY
AE39 PVNN_PCH_STBY VCCPRIM_AVID<25> @BASEBOARD_FAB2_LIB.BASEBOARD_FAB2(SCH_1):PVNN_PCH_STBY
AE41 PVNN_PCH_STBY VCCPRIM_AVID<24> @BASEBOARD_FAB2_LIB.BASEBOARD_FAB2(SCH_1):PVNN_PCH_STBY
AG32 PVNN_PCH_STBY VCCPRIM_AVID<23> @BASEBOARD_FAB2_LIB.BASEBOARD_FAB2(SCH_1):PVNN_PCH_STBY
AG34 PVNN_PCH_STBY VCCPRIM_AVID<22> @BASEBOARD_FAB2_LIB.BASEBOARD_FAB2(SCH_1):PVNN_PCH_STBY
AG36 PVNN_PCH_STBY VCCPRIM_AVID<21> @BASEBOARD_FAB2_LIB.BASEBOARD_FAB2(SCH_1):PVNN_PCH_STBY
AG37 PVNN_PCH_STBY VCCPRIM_AVID<20> @BASEBOARD_FAB2_LIB.BASEBOARD_FAB2(SCH_1):PVNN_PCH_STBY
AG39 PVNN_PCH_STBY VCCPRIM_AVID<19> @BASEBOARD_FAB2_LIB.BASEBOARD_FAB2(SCH_1):PVNN_PCH_STBY
AK34 PVNN_PCH_STBY VCCPRIM_AVID<18> @BASEBOARD_FAB2_LIB.BASEBOARD_FAB2(SCH_1):PVNN_PCH_STBY
AK37 PVNN_PCH_STBY VCCPRIM_AVID<17> @BASEBOARD_FAB2_LIB.BASEBOARD_FAB2(SCH_1):PVNN_PCH_STBY
AK39 PVNN_PCH_STBY VCCPRIM_AVID<16> @BASEBOARD_FAB2_LIB.BASEBOARD_FAB2(SCH_1):PVNN_PCH_STBY
AM32 PVNN_PCH_STBY VCCPRIM_AVID<15> @BASEBOARD_FAB2_LIB.BASEBOARD_FAB2(SCH_1):PVNN_PCH_STBY
AM34 PVNN_PCH_STBY VCCPRIM_AVID<14> @BASEBOARD_FAB2_LIB.BASEBOARD_FAB2(SCH_1):PVNN_PCH_STBY
AM36 PVNN_PCH_STBY VCCPRIM_AVID<13> @BASEBOARD_FAB2_LIB.BASEBOARD_FAB2(SCH_1):PVNN_PCH_STBY
AM37 PVNN_PCH_STBY VCCPRIM_AVID<12> @BASEBOARD_FAB2_LIB.BASEBOARD_FAB2(SCH_1):PVNN_PCH_STBY
AM39 PVNN_PCH_STBY VCCPRIM_AVID<11> @BASEBOARD_FAB2_LIB.BASEBOARD_FAB2(SCH_1):PVNN_PCH_STBY
AP32 PVNN_PCH_STBY VCCPRIM_AVID<10> @BASEBOARD_FAB2_LIB.BASEBOARD_FAB2(SCH_1):PVNN_PCH_STBY
AP34 PVNN_PCH_STBY VCCPRIM_AVID<9> @BASEBOARD_FAB2_LIB.BASEBOARD_FAB2(SCH_1):PVNN_PCH_STBY
AP36 PVNN_PCH_STBY VCCPRIM_AVID<8> @BASEBOARD_FAB2_LIB.BASEBOARD_FAB2(SCH_1):PVNN_PCH_STBY
AP37 PVNN_PCH_STBY VCCPRIM_AVID<7> @BASEBOARD_FAB2_LIB.BASEBOARD_FAB2(SCH_1):PVNN_PCH_STBY
AP39 PVNN_PCH_STBY VCCPRIM_AVID<6> @BASEBOARD_FAB2_LIB.BASEBOARD_FAB2(SCH_1):PVNN_PCH_STBY
AT32 PVNN_PCH_STBY VCCPRIM_AVID<5> @BASEBOARD_FAB2_LIB.BASEBOARD_FAB2(SCH_1):PVNN_PCH_STBY
AT34 PVNN_PCH_STBY VCCPRIM_AVID<4> @BASEBOARD_FAB2_LIB.BASEBOARD_FAB2(SCH_1):PVNN_PCH_STBY
AT36 PVNN_PCH_STBY VCCPRIM_AVID<3> @BASEBOARD_FAB2_LIB.BASEBOARD_FAB2(SCH_1):PVNN_PCH_STBY
AU32 PVNN_PCH_STBY VCCPRIM_AVID<2> @BASEBOARD_FAB2_LIB.BASEBOARD_FAB2(SCH_1):PVNN_PCH_STBY
AU34 PVNN_PCH_STBY VCCPRIM_AVID<1> @BASEBOARD_FAB2_LIB.BASEBOARD_FAB2(SCH_1):PVNN_PCH_STBY
AU36 PVNN_PCH_STBY VCCPRIM_AVID<0> @BASEBOARD_FAB2_LIB.BASEBOARD_FAB2(SCH_1):PVNN_PCH_STBY
 V37 VSENSE_PVNN_PCH_STBY_QAT VCCPRIM_AVID_QAT_SENSE @BASEBOARD_FAB2_LIB.BASEBOARD_FAB2(SCH_1):VSENSE_PVNN_PCH_STBY_QAT
AK36 VSENSE_PVNN_PCH_STBY_FPK VCCPRIM_AVID_SENSE @BASEBOARD_FAB2_LIB.BASEBOARD_FAB2(SCH_1):VSENSE_PVNN_PCH_STBY_FPK


DRAWING: @BASEBOARD_FAB2_LIB.BASEBOARD_FAB2(SCH_1):PAGE124 

LBG_CORE_QAT_EXT_D_BGA1-IC,H91A  I15  U7C1
BK24    GND VSS<74> @BASEBOARD_FAB2_LIB.BASEBOARD_FAB2(SCH_1):GND
BK27    GND VSS<73> @BASEBOARD_FAB2_LIB.BASEBOARD_FAB2(SCH_1):GND
BK31    GND VSS<72> @BASEBOARD_FAB2_LIB.BASEBOARD_FAB2(SCH_1):GND
BK35    GND VSS<71> @BASEBOARD_FAB2_LIB.BASEBOARD_FAB2(SCH_1):GND
BK38    GND VSS<70> @BASEBOARD_FAB2_LIB.BASEBOARD_FAB2(SCH_1):GND
BK42    GND VSS<69> @BASEBOARD_FAB2_LIB.BASEBOARD_FAB2(SCH_1):GND
BK50    GND VSS<68> @BASEBOARD_FAB2_LIB.BASEBOARD_FAB2(SCH_1):GND
BL22    GND VSS<67> @BASEBOARD_FAB2_LIB.BASEBOARD_FAB2(SCH_1):GND
BL40    GND VSS<66> @BASEBOARD_FAB2_LIB.BASEBOARD_FAB2(SCH_1):GND
BL68    GND VSS<65> @BASEBOARD_FAB2_LIB.BASEBOARD_FAB2(SCH_1):GND
BL37    GND VSS<64> @BASEBOARD_FAB2_LIB.BASEBOARD_FAB2(SCH_1):GND
 BL5    GND VSS<63> @BASEBOARD_FAB2_LIB.BASEBOARD_FAB2(SCH_1):GND
BL63    GND VSS<62> @BASEBOARD_FAB2_LIB.BASEBOARD_FAB2(SCH_1):GND
BL70    GND VSS<61> @BASEBOARD_FAB2_LIB.BASEBOARD_FAB2(SCH_1):GND
BL72    GND VSS<60> @BASEBOARD_FAB2_LIB.BASEBOARD_FAB2(SCH_1):GND
BM13    GND VSS<59> @BASEBOARD_FAB2_LIB.BASEBOARD_FAB2(SCH_1):GND
BM17    GND VSS<58> @BASEBOARD_FAB2_LIB.BASEBOARD_FAB2(SCH_1):GND
BN37    GND VSS<57> @BASEBOARD_FAB2_LIB.BASEBOARD_FAB2(SCH_1):GND
BM46    GND VSS<56> @BASEBOARD_FAB2_LIB.BASEBOARD_FAB2(SCH_1):GND
BM50    GND VSS<55> @BASEBOARD_FAB2_LIB.BASEBOARD_FAB2(SCH_1):GND
BM58    GND VSS<54> @BASEBOARD_FAB2_LIB.BASEBOARD_FAB2(SCH_1):GND
BM69    GND VSS<53> @BASEBOARD_FAB2_LIB.BASEBOARD_FAB2(SCH_1):GND
BM71    GND VSS<52> @BASEBOARD_FAB2_LIB.BASEBOARD_FAB2(SCH_1):GND
 BM9    GND VSS<51> @BASEBOARD_FAB2_LIB.BASEBOARD_FAB2(SCH_1):GND
BN22    GND VSS<50> @BASEBOARD_FAB2_LIB.BASEBOARD_FAB2(SCH_1):GND
BN59    GND VSS<49> @BASEBOARD_FAB2_LIB.BASEBOARD_FAB2(SCH_1):GND
 BN5    GND VSS<48> @BASEBOARD_FAB2_LIB.BASEBOARD_FAB2(SCH_1):GND
BN52    GND VSS<47> @BASEBOARD_FAB2_LIB.BASEBOARD_FAB2(SCH_1):GND
BN66    GND VSS<46> @BASEBOARD_FAB2_LIB.BASEBOARD_FAB2(SCH_1):GND
BR20    GND VSS<45> @BASEBOARD_FAB2_LIB.BASEBOARD_FAB2(SCH_1):GND
BR50    GND VSS<44> @BASEBOARD_FAB2_LIB.BASEBOARD_FAB2(SCH_1):GND
 BT8    GND VSS<43> @BASEBOARD_FAB2_LIB.BASEBOARD_FAB2(SCH_1):GND
BR54    GND VSS<42> @BASEBOARD_FAB2_LIB.BASEBOARD_FAB2(SCH_1):GND
BR58    GND VSS<41> @BASEBOARD_FAB2_LIB.BASEBOARD_FAB2(SCH_1):GND
 BR6    GND VSS<40> @BASEBOARD_FAB2_LIB.BASEBOARD_FAB2(SCH_1):GND
BT66    GND VSS<39> @BASEBOARD_FAB2_LIB.BASEBOARD_FAB2(SCH_1):GND
BU13    GND VSS<38> @BASEBOARD_FAB2_LIB.BASEBOARD_FAB2(SCH_1):GND
BU11    GND VSS<37> @BASEBOARD_FAB2_LIB.BASEBOARD_FAB2(SCH_1):GND
BV49    GND VSS<36> @BASEBOARD_FAB2_LIB.BASEBOARD_FAB2(SCH_1):GND
BU15    GND VSS<35> @BASEBOARD_FAB2_LIB.BASEBOARD_FAB2(SCH_1):GND
BU18    GND VSS<34> @BASEBOARD_FAB2_LIB.BASEBOARD_FAB2(SCH_1):GND
BU20    GND VSS<33> @BASEBOARD_FAB2_LIB.BASEBOARD_FAB2(SCH_1):GND
BU22    GND VSS<32> @BASEBOARD_FAB2_LIB.BASEBOARD_FAB2(SCH_1):GND
BU24    GND VSS<31> @BASEBOARD_FAB2_LIB.BASEBOARD_FAB2(SCH_1):GND
BU26    GND VSS<30> @BASEBOARD_FAB2_LIB.BASEBOARD_FAB2(SCH_1):GND
BU28    GND VSS<29> @BASEBOARD_FAB2_LIB.BASEBOARD_FAB2(SCH_1):GND
BU30    GND VSS<28> @BASEBOARD_FAB2_LIB.BASEBOARD_FAB2(SCH_1):GND
BU32    GND VSS<27> @BASEBOARD_FAB2_LIB.BASEBOARD_FAB2(SCH_1):GND
BU34    GND VSS<26> @BASEBOARD_FAB2_LIB.BASEBOARD_FAB2(SCH_1):GND
BU37    GND VSS<25> @BASEBOARD_FAB2_LIB.BASEBOARD_FAB2(SCH_1):GND
BU39    GND VSS<24> @BASEBOARD_FAB2_LIB.BASEBOARD_FAB2(SCH_1):GND
BU41    GND VSS<23> @BASEBOARD_FAB2_LIB.BASEBOARD_FAB2(SCH_1):GND
BU43    GND VSS<22> @BASEBOARD_FAB2_LIB.BASEBOARD_FAB2(SCH_1):GND
BU45    GND VSS<21> @BASEBOARD_FAB2_LIB.BASEBOARD_FAB2(SCH_1):GND
BU48    GND VSS<20> @BASEBOARD_FAB2_LIB.BASEBOARD_FAB2(SCH_1):GND
BU50    GND VSS<19> @BASEBOARD_FAB2_LIB.BASEBOARD_FAB2(SCH_1):GND
BU52    GND VSS<18> @BASEBOARD_FAB2_LIB.BASEBOARD_FAB2(SCH_1):GND
BU54    GND VSS<17> @BASEBOARD_FAB2_LIB.BASEBOARD_FAB2(SCH_1):GND
BU57    GND VSS<16> @BASEBOARD_FAB2_LIB.BASEBOARD_FAB2(SCH_1):GND
BU59    GND VSS<15> @BASEBOARD_FAB2_LIB.BASEBOARD_FAB2(SCH_1):GND
BU61    GND VSS<14> @BASEBOARD_FAB2_LIB.BASEBOARD_FAB2(SCH_1):GND
BU63    GND VSS<13> @BASEBOARD_FAB2_LIB.BASEBOARD_FAB2(SCH_1):GND
 BU9    GND VSS<12> @BASEBOARD_FAB2_LIB.BASEBOARD_FAB2(SCH_1):GND
BV40    GND VSS<11> @BASEBOARD_FAB2_LIB.BASEBOARD_FAB2(SCH_1):GND
BW15    GND VSS<10> @BASEBOARD_FAB2_LIB.BASEBOARD_FAB2(SCH_1):GND
BW18    GND VSS<9> @BASEBOARD_FAB2_LIB.BASEBOARD_FAB2(SCH_1):GND
BW26    GND VSS<8> @BASEBOARD_FAB2_LIB.BASEBOARD_FAB2(SCH_1):GND
BW52    GND VSS<7> @BASEBOARD_FAB2_LIB.BASEBOARD_FAB2(SCH_1):GND
BY40    GND VSS<6> @BASEBOARD_FAB2_LIB.BASEBOARD_FAB2(SCH_1):GND
BY49    GND VSS<5> @BASEBOARD_FAB2_LIB.BASEBOARD_FAB2(SCH_1):GND
CA15    GND VSS<4> @BASEBOARD_FAB2_LIB.BASEBOARD_FAB2(SCH_1):GND
CA18    GND VSS<3> @BASEBOARD_FAB2_LIB.BASEBOARD_FAB2(SCH_1):GND
CA26    GND VSS<2> @BASEBOARD_FAB2_LIB.BASEBOARD_FAB2(SCH_1):GND
CA50    GND VSS<1> @BASEBOARD_FAB2_LIB.BASEBOARD_FAB2(SCH_1):GND
CA52    GND VSS<0> @BASEBOARD_FAB2_LIB.BASEBOARD_FAB2(SCH_1):GND

LBG_CORE_QAT_EXT_D_BGA1-IC,H91A  I16  U7C1
AL68    GND VSS<214> @BASEBOARD_FAB2_LIB.BASEBOARD_FAB2(SCH_1):GND
AL70    GND VSS<213> @BASEBOARD_FAB2_LIB.BASEBOARD_FAB2(SCH_1):GND
AL72    GND VSS<212> @BASEBOARD_FAB2_LIB.BASEBOARD_FAB2(SCH_1):GND
AM26    GND VSS<211> @BASEBOARD_FAB2_LIB.BASEBOARD_FAB2(SCH_1):GND
AM30    GND VSS<210> @BASEBOARD_FAB2_LIB.BASEBOARD_FAB2(SCH_1):GND
AM41    GND VSS<209> @BASEBOARD_FAB2_LIB.BASEBOARD_FAB2(SCH_1):GND
AM46    GND VSS<208> @BASEBOARD_FAB2_LIB.BASEBOARD_FAB2(SCH_1):GND
AN13    GND VSS<207> @BASEBOARD_FAB2_LIB.BASEBOARD_FAB2(SCH_1):GND
AN17    GND VSS<206> @BASEBOARD_FAB2_LIB.BASEBOARD_FAB2(SCH_1):GND
AN68    GND VSS<205> @BASEBOARD_FAB2_LIB.BASEBOARD_FAB2(SCH_1):GND
AP22    GND VSS<204> @BASEBOARD_FAB2_LIB.BASEBOARD_FAB2(SCH_1):GND
AN20    GND VSS<203> @BASEBOARD_FAB2_LIB.BASEBOARD_FAB2(SCH_1):GND
 AN5    GND VSS<202> @BASEBOARD_FAB2_LIB.BASEBOARD_FAB2(SCH_1):GND
AN58    GND VSS<201> @BASEBOARD_FAB2_LIB.BASEBOARD_FAB2(SCH_1):GND
 AN9    GND VSS<200> @BASEBOARD_FAB2_LIB.BASEBOARD_FAB2(SCH_1):GND
 AP2    GND VSS<199> @BASEBOARD_FAB2_LIB.BASEBOARD_FAB2(SCH_1):GND
AP26    GND VSS<198> @BASEBOARD_FAB2_LIB.BASEBOARD_FAB2(SCH_1):GND
AP30    GND VSS<197> @BASEBOARD_FAB2_LIB.BASEBOARD_FAB2(SCH_1):GND
 AP4    GND VSS<196> @BASEBOARD_FAB2_LIB.BASEBOARD_FAB2(SCH_1):GND
AP41    GND VSS<195> @BASEBOARD_FAB2_LIB.BASEBOARD_FAB2(SCH_1):GND
AP46    GND VSS<194> @BASEBOARD_FAB2_LIB.BASEBOARD_FAB2(SCH_1):GND
AP52    GND VSS<193> @BASEBOARD_FAB2_LIB.BASEBOARD_FAB2(SCH_1):GND
AP66    GND VSS<192> @BASEBOARD_FAB2_LIB.BASEBOARD_FAB2(SCH_1):GND
 AR5    GND VSS<191> @BASEBOARD_FAB2_LIB.BASEBOARD_FAB2(SCH_1):GND
AR50    GND VSS<190> @BASEBOARD_FAB2_LIB.BASEBOARD_FAB2(SCH_1):GND
AR58    GND VSS<189> @BASEBOARD_FAB2_LIB.BASEBOARD_FAB2(SCH_1):GND
AR65    GND VSS<188> @BASEBOARD_FAB2_LIB.BASEBOARD_FAB2(SCH_1):GND
AR68    GND VSS<187> @BASEBOARD_FAB2_LIB.BASEBOARD_FAB2(SCH_1):GND
AR70    GND VSS<186> @BASEBOARD_FAB2_LIB.BASEBOARD_FAB2(SCH_1):GND
AR72    GND VSS<185> @BASEBOARD_FAB2_LIB.BASEBOARD_FAB2(SCH_1):GND
 AT7    GND VSS<184> @BASEBOARD_FAB2_LIB.BASEBOARD_FAB2(SCH_1):GND
AT11    GND VSS<183> @BASEBOARD_FAB2_LIB.BASEBOARD_FAB2(SCH_1):GND
AT15    GND VSS<182> @BASEBOARD_FAB2_LIB.BASEBOARD_FAB2(SCH_1):GND
AT18    GND VSS<181> @BASEBOARD_FAB2_LIB.BASEBOARD_FAB2(SCH_1):GND
AT22    GND VSS<180> @BASEBOARD_FAB2_LIB.BASEBOARD_FAB2(SCH_1):GND
AT26    GND VSS<179> @BASEBOARD_FAB2_LIB.BASEBOARD_FAB2(SCH_1):GND
AT30    GND VSS<178> @BASEBOARD_FAB2_LIB.BASEBOARD_FAB2(SCH_1):GND
AT41    GND VSS<177> @BASEBOARD_FAB2_LIB.BASEBOARD_FAB2(SCH_1):GND
AT46    GND VSS<176> @BASEBOARD_FAB2_LIB.BASEBOARD_FAB2(SCH_1):GND
AT59    GND VSS<175> @BASEBOARD_FAB2_LIB.BASEBOARD_FAB2(SCH_1):GND
AU26    GND VSS<174> @BASEBOARD_FAB2_LIB.BASEBOARD_FAB2(SCH_1):GND
AU30    GND VSS<173> @BASEBOARD_FAB2_LIB.BASEBOARD_FAB2(SCH_1):GND
AE22    GND VSS<172> @BASEBOARD_FAB2_LIB.BASEBOARD_FAB2(SCH_1):GND
AU41    GND VSS<171> @BASEBOARD_FAB2_LIB.BASEBOARD_FAB2(SCH_1):GND
AU46    GND VSS<170> @BASEBOARD_FAB2_LIB.BASEBOARD_FAB2(SCH_1):GND
AU50    GND VSS<169> @BASEBOARD_FAB2_LIB.BASEBOARD_FAB2(SCH_1):GND
AU54    GND VSS<168> @BASEBOARD_FAB2_LIB.BASEBOARD_FAB2(SCH_1):GND
AU61    GND VSS<167> @BASEBOARD_FAB2_LIB.BASEBOARD_FAB2(SCH_1):GND
 AV5    GND VSS<166> @BASEBOARD_FAB2_LIB.BASEBOARD_FAB2(SCH_1):GND
AV22    GND VSS<165> @BASEBOARD_FAB2_LIB.BASEBOARD_FAB2(SCH_1):GND
AV59    GND VSS<164> @BASEBOARD_FAB2_LIB.BASEBOARD_FAB2(SCH_1):GND
AV68    GND VSS<163> @BASEBOARD_FAB2_LIB.BASEBOARD_FAB2(SCH_1):GND
 AW9    GND VSS<162> @BASEBOARD_FAB2_LIB.BASEBOARD_FAB2(SCH_1):GND
AW13    GND VSS<161> @BASEBOARD_FAB2_LIB.BASEBOARD_FAB2(SCH_1):GND
AW17    GND VSS<160> @BASEBOARD_FAB2_LIB.BASEBOARD_FAB2(SCH_1):GND
AW26    GND VSS<159> @BASEBOARD_FAB2_LIB.BASEBOARD_FAB2(SCH_1):GND
AW30    GND VSS<158> @BASEBOARD_FAB2_LIB.BASEBOARD_FAB2(SCH_1):GND
AW32    GND VSS<157> @BASEBOARD_FAB2_LIB.BASEBOARD_FAB2(SCH_1):GND
AW34    GND VSS<156> @BASEBOARD_FAB2_LIB.BASEBOARD_FAB2(SCH_1):GND
AW36    GND VSS<155> @BASEBOARD_FAB2_LIB.BASEBOARD_FAB2(SCH_1):GND
AW37    GND VSS<154> @BASEBOARD_FAB2_LIB.BASEBOARD_FAB2(SCH_1):GND
AW39    GND VSS<153> @BASEBOARD_FAB2_LIB.BASEBOARD_FAB2(SCH_1):GND
AW41    GND VSS<152> @BASEBOARD_FAB2_LIB.BASEBOARD_FAB2(SCH_1):GND
AW46    GND VSS<151> @BASEBOARD_FAB2_LIB.BASEBOARD_FAB2(SCH_1):GND
AW50    GND VSS<150> @BASEBOARD_FAB2_LIB.BASEBOARD_FAB2(SCH_1):GND
AW58    GND VSS<149> @BASEBOARD_FAB2_LIB.BASEBOARD_FAB2(SCH_1):GND
AW61    GND VSS<148> @BASEBOARD_FAB2_LIB.BASEBOARD_FAB2(SCH_1):GND
 AY5    GND VSS<147> @BASEBOARD_FAB2_LIB.BASEBOARD_FAB2(SCH_1):GND
AY22    GND VSS<146> @BASEBOARD_FAB2_LIB.BASEBOARD_FAB2(SCH_1):GND
AY56    GND VSS<145> @BASEBOARD_FAB2_LIB.BASEBOARD_FAB2(SCH_1):GND
AY63    GND VSS<144> @BASEBOARD_FAB2_LIB.BASEBOARD_FAB2(SCH_1):GND
AY68    GND VSS<143> @BASEBOARD_FAB2_LIB.BASEBOARD_FAB2(SCH_1):GND
BA50    GND VSS<142> @BASEBOARD_FAB2_LIB.BASEBOARD_FAB2(SCH_1):GND
BA54    GND VSS<141> @BASEBOARD_FAB2_LIB.BASEBOARD_FAB2(SCH_1):GND
BA58    GND VSS<140> @BASEBOARD_FAB2_LIB.BASEBOARD_FAB2(SCH_1):GND
 BB5    GND VSS<139> @BASEBOARD_FAB2_LIB.BASEBOARD_FAB2(SCH_1):GND
 BB7    GND VSS<138> @BASEBOARD_FAB2_LIB.BASEBOARD_FAB2(SCH_1):GND
BB11    GND VSS<137> @BASEBOARD_FAB2_LIB.BASEBOARD_FAB2(SCH_1):GND
BB15    GND VSS<136> @BASEBOARD_FAB2_LIB.BASEBOARD_FAB2(SCH_1):GND
BB18    GND VSS<135> @BASEBOARD_FAB2_LIB.BASEBOARD_FAB2(SCH_1):GND
BB22    GND VSS<134> @BASEBOARD_FAB2_LIB.BASEBOARD_FAB2(SCH_1):GND
BB44    GND VSS<133> @BASEBOARD_FAB2_LIB.BASEBOARD_FAB2(SCH_1):GND
BB59    GND VSS<132> @BASEBOARD_FAB2_LIB.BASEBOARD_FAB2(SCH_1):GND
BB66    GND VSS<131> @BASEBOARD_FAB2_LIB.BASEBOARD_FAB2(SCH_1):GND
BB68    GND VSS<130> @BASEBOARD_FAB2_LIB.BASEBOARD_FAB2(SCH_1):GND
BB70    GND VSS<129> @BASEBOARD_FAB2_LIB.BASEBOARD_FAB2(SCH_1):GND
BB72    GND VSS<128> @BASEBOARD_FAB2_LIB.BASEBOARD_FAB2(SCH_1):GND
BC69    GND VSS<127> @BASEBOARD_FAB2_LIB.BASEBOARD_FAB2(SCH_1):GND
BC71    GND VSS<126> @BASEBOARD_FAB2_LIB.BASEBOARD_FAB2(SCH_1):GND
BD24    GND VSS<125> @BASEBOARD_FAB2_LIB.BASEBOARD_FAB2(SCH_1):GND
BD27    GND VSS<124> @BASEBOARD_FAB2_LIB.BASEBOARD_FAB2(SCH_1):GND
BD31    GND VSS<123> @BASEBOARD_FAB2_LIB.BASEBOARD_FAB2(SCH_1):GND
BD35    GND VSS<122> @BASEBOARD_FAB2_LIB.BASEBOARD_FAB2(SCH_1):GND
 BD5    GND VSS<121> @BASEBOARD_FAB2_LIB.BASEBOARD_FAB2(SCH_1):GND
BD50    GND VSS<120> @BASEBOARD_FAB2_LIB.BASEBOARD_FAB2(SCH_1):GND
BD54    GND VSS<119> @BASEBOARD_FAB2_LIB.BASEBOARD_FAB2(SCH_1):GND
BD68    GND VSS<118> @BASEBOARD_FAB2_LIB.BASEBOARD_FAB2(SCH_1):GND
BE29    GND VSS<117> @BASEBOARD_FAB2_LIB.BASEBOARD_FAB2(SCH_1):GND
BE33    GND VSS<116> @BASEBOARD_FAB2_LIB.BASEBOARD_FAB2(SCH_1):GND
BE37    GND VSS<115> @BASEBOARD_FAB2_LIB.BASEBOARD_FAB2(SCH_1):GND
BE56    GND VSS<114> @BASEBOARD_FAB2_LIB.BASEBOARD_FAB2(SCH_1):GND
BE59    GND VSS<113> @BASEBOARD_FAB2_LIB.BASEBOARD_FAB2(SCH_1):GND
BE63    GND VSS<112> @BASEBOARD_FAB2_LIB.BASEBOARD_FAB2(SCH_1):GND
BE66    GND VSS<111> @BASEBOARD_FAB2_LIB.BASEBOARD_FAB2(SCH_1):GND
BF13    GND VSS<110> @BASEBOARD_FAB2_LIB.BASEBOARD_FAB2(SCH_1):GND
BF17    GND VSS<109> @BASEBOARD_FAB2_LIB.BASEBOARD_FAB2(SCH_1):GND
BF54    GND VSS<108> @BASEBOARD_FAB2_LIB.BASEBOARD_FAB2(SCH_1):GND
BG44    GND VSS<107> @BASEBOARD_FAB2_LIB.BASEBOARD_FAB2(SCH_1):GND
BF20    GND VSS<106> @BASEBOARD_FAB2_LIB.BASEBOARD_FAB2(SCH_1):GND
BF24    GND VSS<105> @BASEBOARD_FAB2_LIB.BASEBOARD_FAB2(SCH_1):GND
BF27    GND VSS<104> @BASEBOARD_FAB2_LIB.BASEBOARD_FAB2(SCH_1):GND
BF38    GND VSS<103> @BASEBOARD_FAB2_LIB.BASEBOARD_FAB2(SCH_1):GND
BF42    GND VSS<102> @BASEBOARD_FAB2_LIB.BASEBOARD_FAB2(SCH_1):GND
 BF5    GND VSS<101> @BASEBOARD_FAB2_LIB.BASEBOARD_FAB2(SCH_1):GND
BF50    GND VSS<100> @BASEBOARD_FAB2_LIB.BASEBOARD_FAB2(SCH_1):GND
BF58    GND VSS<99> @BASEBOARD_FAB2_LIB.BASEBOARD_FAB2(SCH_1):GND
BF61    GND VSS<98> @BASEBOARD_FAB2_LIB.BASEBOARD_FAB2(SCH_1):GND
BF65    GND VSS<97> @BASEBOARD_FAB2_LIB.BASEBOARD_FAB2(SCH_1):GND
BF68    GND VSS<96> @BASEBOARD_FAB2_LIB.BASEBOARD_FAB2(SCH_1):GND
 BF9    GND VSS<95> @BASEBOARD_FAB2_LIB.BASEBOARD_FAB2(SCH_1):GND
BG33    GND VSS<94> @BASEBOARD_FAB2_LIB.BASEBOARD_FAB2(SCH_1):GND
BG48    GND VSS<93> @BASEBOARD_FAB2_LIB.BASEBOARD_FAB2(SCH_1):GND
BG59    GND VSS<92> @BASEBOARD_FAB2_LIB.BASEBOARD_FAB2(SCH_1):GND
BG63    GND VSS<91> @BASEBOARD_FAB2_LIB.BASEBOARD_FAB2(SCH_1):GND
BH27    GND VSS<90> @BASEBOARD_FAB2_LIB.BASEBOARD_FAB2(SCH_1):GND
BH38    GND VSS<89> @BASEBOARD_FAB2_LIB.BASEBOARD_FAB2(SCH_1):GND
BH42    GND VSS<88> @BASEBOARD_FAB2_LIB.BASEBOARD_FAB2(SCH_1):GND
BH46    GND VSS<87> @BASEBOARD_FAB2_LIB.BASEBOARD_FAB2(SCH_1):GND
BH54    GND VSS<86> @BASEBOARD_FAB2_LIB.BASEBOARD_FAB2(SCH_1):GND
 BJ1    GND VSS<85> @BASEBOARD_FAB2_LIB.BASEBOARD_FAB2(SCH_1):GND
BJ11    GND VSS<84> @BASEBOARD_FAB2_LIB.BASEBOARD_FAB2(SCH_1):GND
 BJ5    GND VSS<83> @BASEBOARD_FAB2_LIB.BASEBOARD_FAB2(SCH_1):GND
 BJ7    GND VSS<82> @BASEBOARD_FAB2_LIB.BASEBOARD_FAB2(SCH_1):GND
BJ15    GND VSS<81> @BASEBOARD_FAB2_LIB.BASEBOARD_FAB2(SCH_1):GND
BJ18    GND VSS<80> @BASEBOARD_FAB2_LIB.BASEBOARD_FAB2(SCH_1):GND
BJ26    GND VSS<79> @BASEBOARD_FAB2_LIB.BASEBOARD_FAB2(SCH_1):GND
 BJ3    GND VSS<78> @BASEBOARD_FAB2_LIB.BASEBOARD_FAB2(SCH_1):GND
BJ33    GND VSS<77> @BASEBOARD_FAB2_LIB.BASEBOARD_FAB2(SCH_1):GND
BJ52    GND VSS<76> @BASEBOARD_FAB2_LIB.BASEBOARD_FAB2(SCH_1):GND
BJ68    GND VSS<75> @BASEBOARD_FAB2_LIB.BASEBOARD_FAB2(SCH_1):GND

LBG_CORE_QAT_EXT_D_BGA1-IC,H91A  I17  U7C1
 N35    GND VSS<354> @BASEBOARD_FAB2_LIB.BASEBOARD_FAB2(SCH_1):GND
 N38    GND VSS<353> @BASEBOARD_FAB2_LIB.BASEBOARD_FAB2(SCH_1):GND
 N46    GND VSS<352> @BASEBOARD_FAB2_LIB.BASEBOARD_FAB2(SCH_1):GND
  N5    GND VSS<351> @BASEBOARD_FAB2_LIB.BASEBOARD_FAB2(SCH_1):GND
 R38    GND VSS<350> @BASEBOARD_FAB2_LIB.BASEBOARD_FAB2(SCH_1):GND
 N68    GND VSS<349> @BASEBOARD_FAB2_LIB.BASEBOARD_FAB2(SCH_1):GND
  N9    GND VSS<348> @BASEBOARD_FAB2_LIB.BASEBOARD_FAB2(SCH_1):GND
AE43    GND VSS<347> @BASEBOARD_FAB2_LIB.BASEBOARD_FAB2(SCH_1):GND
 P63    GND VSS<346> @BASEBOARD_FAB2_LIB.BASEBOARD_FAB2(SCH_1):GND
 R27    GND VSS<345> @BASEBOARD_FAB2_LIB.BASEBOARD_FAB2(SCH_1):GND
 U42    GND VSS<344> @BASEBOARD_FAB2_LIB.BASEBOARD_FAB2(SCH_1):GND
  R5    GND VSS<343> @BASEBOARD_FAB2_LIB.BASEBOARD_FAB2(SCH_1):GND
 R50    GND VSS<342> @BASEBOARD_FAB2_LIB.BASEBOARD_FAB2(SCH_1):GND
 R54    GND VSS<341> @BASEBOARD_FAB2_LIB.BASEBOARD_FAB2(SCH_1):GND
 T56    GND VSS<340> @BASEBOARD_FAB2_LIB.BASEBOARD_FAB2(SCH_1):GND
 R58    GND VSS<339> @BASEBOARD_FAB2_LIB.BASEBOARD_FAB2(SCH_1):GND
 R68    GND VSS<338> @BASEBOARD_FAB2_LIB.BASEBOARD_FAB2(SCH_1):GND
 T11    GND VSS<337> @BASEBOARD_FAB2_LIB.BASEBOARD_FAB2(SCH_1):GND
 T15    GND VSS<336> @BASEBOARD_FAB2_LIB.BASEBOARD_FAB2(SCH_1):GND
 T18    GND VSS<335> @BASEBOARD_FAB2_LIB.BASEBOARD_FAB2(SCH_1):GND
 T22    GND VSS<334> @BASEBOARD_FAB2_LIB.BASEBOARD_FAB2(SCH_1):GND
 T26    GND VSS<333> @BASEBOARD_FAB2_LIB.BASEBOARD_FAB2(SCH_1):GND
 T29    GND VSS<332> @BASEBOARD_FAB2_LIB.BASEBOARD_FAB2(SCH_1):GND
 T33    GND VSS<331> @BASEBOARD_FAB2_LIB.BASEBOARD_FAB2(SCH_1):GND
 T37    GND VSS<330> @BASEBOARD_FAB2_LIB.BASEBOARD_FAB2(SCH_1):GND
 T40    GND VSS<329> @BASEBOARD_FAB2_LIB.BASEBOARD_FAB2(SCH_1):GND
AJ45    GND VSS<328> @BASEBOARD_FAB2_LIB.BASEBOARD_FAB2(SCH_1):GND
 T48    GND VSS<327> @BASEBOARD_FAB2_LIB.BASEBOARD_FAB2(SCH_1):GND
 T52    GND VSS<326> @BASEBOARD_FAB2_LIB.BASEBOARD_FAB2(SCH_1):GND
 T66    GND VSS<325> @BASEBOARD_FAB2_LIB.BASEBOARD_FAB2(SCH_1):GND
  T7    GND VSS<324> @BASEBOARD_FAB2_LIB.BASEBOARD_FAB2(SCH_1):GND
AF50    GND VSS<323> @BASEBOARD_FAB2_LIB.BASEBOARD_FAB2(SCH_1):GND
AG46    GND VSS<322> @BASEBOARD_FAB2_LIB.BASEBOARD_FAB2(SCH_1):GND
 U58    GND VSS<321> @BASEBOARD_FAB2_LIB.BASEBOARD_FAB2(SCH_1):GND
 V26    GND VSS<320> @BASEBOARD_FAB2_LIB.BASEBOARD_FAB2(SCH_1):GND
 V48    GND VSS<319> @BASEBOARD_FAB2_LIB.BASEBOARD_FAB2(SCH_1):GND
  V5    GND VSS<318> @BASEBOARD_FAB2_LIB.BASEBOARD_FAB2(SCH_1):GND
 V52    GND VSS<317> @BASEBOARD_FAB2_LIB.BASEBOARD_FAB2(SCH_1):GND
 W58    GND VSS<316> @BASEBOARD_FAB2_LIB.BASEBOARD_FAB2(SCH_1):GND
 V66    GND VSS<315> @BASEBOARD_FAB2_LIB.BASEBOARD_FAB2(SCH_1):GND
 V68    GND VSS<314> @BASEBOARD_FAB2_LIB.BASEBOARD_FAB2(SCH_1):GND
 W13    GND VSS<313> @BASEBOARD_FAB2_LIB.BASEBOARD_FAB2(SCH_1):GND
 W17    GND VSS<312> @BASEBOARD_FAB2_LIB.BASEBOARD_FAB2(SCH_1):GND
 W20    GND VSS<311> @BASEBOARD_FAB2_LIB.BASEBOARD_FAB2(SCH_1):GND
 W24    GND VSS<310> @BASEBOARD_FAB2_LIB.BASEBOARD_FAB2(SCH_1):GND
AA50    GND VSS<309> @BASEBOARD_FAB2_LIB.BASEBOARD_FAB2(SCH_1):GND
 Y43    GND VSS<308> @BASEBOARD_FAB2_LIB.BASEBOARD_FAB2(SCH_1):GND
 W61    GND VSS<307> @BASEBOARD_FAB2_LIB.BASEBOARD_FAB2(SCH_1):GND
  W9    GND VSS<306> @BASEBOARD_FAB2_LIB.BASEBOARD_FAB2(SCH_1):GND
 Y22    GND VSS<305> @BASEBOARD_FAB2_LIB.BASEBOARD_FAB2(SCH_1):GND
 Y27    GND VSS<304> @BASEBOARD_FAB2_LIB.BASEBOARD_FAB2(SCH_1):GND
 Y48    GND VSS<303> @BASEBOARD_FAB2_LIB.BASEBOARD_FAB2(SCH_1):GND
  Y5    GND VSS<302> @BASEBOARD_FAB2_LIB.BASEBOARD_FAB2(SCH_1):GND
 Y52    GND VSS<301> @BASEBOARD_FAB2_LIB.BASEBOARD_FAB2(SCH_1):GND
 Y59    GND VSS<300> @BASEBOARD_FAB2_LIB.BASEBOARD_FAB2(SCH_1):GND
 Y63    GND VSS<299> @BASEBOARD_FAB2_LIB.BASEBOARD_FAB2(SCH_1):GND
 Y68    GND VSS<298> @BASEBOARD_FAB2_LIB.BASEBOARD_FAB2(SCH_1):GND
AA26    GND VSS<297> @BASEBOARD_FAB2_LIB.BASEBOARD_FAB2(SCH_1):GND
AA27    GND VSS<296> @BASEBOARD_FAB2_LIB.BASEBOARD_FAB2(SCH_1):GND
AA43    GND VSS<295> @BASEBOARD_FAB2_LIB.BASEBOARD_FAB2(SCH_1):GND
AA48    GND VSS<294> @BASEBOARD_FAB2_LIB.BASEBOARD_FAB2(SCH_1):GND
 AB5    GND VSS<293> @BASEBOARD_FAB2_LIB.BASEBOARD_FAB2(SCH_1):GND
AB68    GND VSS<292> @BASEBOARD_FAB2_LIB.BASEBOARD_FAB2(SCH_1):GND
AB70    GND VSS<291> @BASEBOARD_FAB2_LIB.BASEBOARD_FAB2(SCH_1):GND
AB72    GND VSS<290> @BASEBOARD_FAB2_LIB.BASEBOARD_FAB2(SCH_1):GND
AC11    GND VSS<289> @BASEBOARD_FAB2_LIB.BASEBOARD_FAB2(SCH_1):GND
AC15    GND VSS<288> @BASEBOARD_FAB2_LIB.BASEBOARD_FAB2(SCH_1):GND
AC18    GND VSS<287> @BASEBOARD_FAB2_LIB.BASEBOARD_FAB2(SCH_1):GND
AC22    GND VSS<286> @BASEBOARD_FAB2_LIB.BASEBOARD_FAB2(SCH_1):GND
AC45    GND VSS<285> @BASEBOARD_FAB2_LIB.BASEBOARD_FAB2(SCH_1):GND
AD58    GND VSS<284> @BASEBOARD_FAB2_LIB.BASEBOARD_FAB2(SCH_1):GND
AC27    GND VSS<283> @BASEBOARD_FAB2_LIB.BASEBOARD_FAB2(SCH_1):GND
AC43    GND VSS<282> @BASEBOARD_FAB2_LIB.BASEBOARD_FAB2(SCH_1):GND
AC46    GND VSS<281> @BASEBOARD_FAB2_LIB.BASEBOARD_FAB2(SCH_1):GND
AC48    GND VSS<280> @BASEBOARD_FAB2_LIB.BASEBOARD_FAB2(SCH_1):GND
AC52    GND VSS<279> @BASEBOARD_FAB2_LIB.BASEBOARD_FAB2(SCH_1):GND
AC59    GND VSS<278> @BASEBOARD_FAB2_LIB.BASEBOARD_FAB2(SCH_1):GND
AC63    GND VSS<277> @BASEBOARD_FAB2_LIB.BASEBOARD_FAB2(SCH_1):GND
AC66    GND VSS<276> @BASEBOARD_FAB2_LIB.BASEBOARD_FAB2(SCH_1):GND
 AC7    GND VSS<275> @BASEBOARD_FAB2_LIB.BASEBOARD_FAB2(SCH_1):GND
 AD5    GND VSS<274> @BASEBOARD_FAB2_LIB.BASEBOARD_FAB2(SCH_1):GND
AD65    GND VSS<273> @BASEBOARD_FAB2_LIB.BASEBOARD_FAB2(SCH_1):GND
AD68    GND VSS<272> @BASEBOARD_FAB2_LIB.BASEBOARD_FAB2(SCH_1):GND
AE29    GND VSS<271> @BASEBOARD_FAB2_LIB.BASEBOARD_FAB2(SCH_1):GND
 J18    GND VSS<270> @BASEBOARD_FAB2_LIB.BASEBOARD_FAB2(SCH_1):GND
AE48    GND VSS<269> @BASEBOARD_FAB2_LIB.BASEBOARD_FAB2(SCH_1):GND
AE52    GND VSS<268> @BASEBOARD_FAB2_LIB.BASEBOARD_FAB2(SCH_1):GND
AE56    GND VSS<267> @BASEBOARD_FAB2_LIB.BASEBOARD_FAB2(SCH_1):GND
AE59    GND VSS<266> @BASEBOARD_FAB2_LIB.BASEBOARD_FAB2(SCH_1):GND
AE63    GND VSS<265> @BASEBOARD_FAB2_LIB.BASEBOARD_FAB2(SCH_1):GND
AE66    GND VSS<264> @BASEBOARD_FAB2_LIB.BASEBOARD_FAB2(SCH_1):GND
 AF1    GND VSS<263> @BASEBOARD_FAB2_LIB.BASEBOARD_FAB2(SCH_1):GND
AF13    GND VSS<262> @BASEBOARD_FAB2_LIB.BASEBOARD_FAB2(SCH_1):GND
 AF5    GND VSS<261> @BASEBOARD_FAB2_LIB.BASEBOARD_FAB2(SCH_1):GND
 AF9    GND VSS<260> @BASEBOARD_FAB2_LIB.BASEBOARD_FAB2(SCH_1):GND
AF17    GND VSS<259> @BASEBOARD_FAB2_LIB.BASEBOARD_FAB2(SCH_1):GND
AF24    GND VSS<258> @BASEBOARD_FAB2_LIB.BASEBOARD_FAB2(SCH_1):GND
 AF3    GND VSS<257> @BASEBOARD_FAB2_LIB.BASEBOARD_FAB2(SCH_1):GND
AF68    GND VSS<256> @BASEBOARD_FAB2_LIB.BASEBOARD_FAB2(SCH_1):GND
AG26    GND VSS<255> @BASEBOARD_FAB2_LIB.BASEBOARD_FAB2(SCH_1):GND
AG30    GND VSS<254> @BASEBOARD_FAB2_LIB.BASEBOARD_FAB2(SCH_1):GND
AG41    GND VSS<253> @BASEBOARD_FAB2_LIB.BASEBOARD_FAB2(SCH_1):GND
AG43    GND VSS<252> @BASEBOARD_FAB2_LIB.BASEBOARD_FAB2(SCH_1):GND
AG52    GND VSS<251> @BASEBOARD_FAB2_LIB.BASEBOARD_FAB2(SCH_1):GND
AG56    GND VSS<250> @BASEBOARD_FAB2_LIB.BASEBOARD_FAB2(SCH_1):GND
AG59    GND VSS<249> @BASEBOARD_FAB2_LIB.BASEBOARD_FAB2(SCH_1):GND
AG66    GND VSS<248> @BASEBOARD_FAB2_LIB.BASEBOARD_FAB2(SCH_1):GND
AH20    GND VSS<247> @BASEBOARD_FAB2_LIB.BASEBOARD_FAB2(SCH_1):GND
AJ11    GND VSS<246> @BASEBOARD_FAB2_LIB.BASEBOARD_FAB2(SCH_1):GND
AJ32    GND VSS<245> @BASEBOARD_FAB2_LIB.BASEBOARD_FAB2(SCH_1):GND
AJ56    GND VSS<244> @BASEBOARD_FAB2_LIB.BASEBOARD_FAB2(SCH_1):GND
AK30    GND VSS<243> @BASEBOARD_FAB2_LIB.BASEBOARD_FAB2(SCH_1):GND
AJ15    GND VSS<242> @BASEBOARD_FAB2_LIB.BASEBOARD_FAB2(SCH_1):GND
AJ18    GND VSS<241> @BASEBOARD_FAB2_LIB.BASEBOARD_FAB2(SCH_1):GND
AJ22    GND VSS<240> @BASEBOARD_FAB2_LIB.BASEBOARD_FAB2(SCH_1):GND
AJ26    GND VSS<239> @BASEBOARD_FAB2_LIB.BASEBOARD_FAB2(SCH_1):GND
AJ30    GND VSS<238> @BASEBOARD_FAB2_LIB.BASEBOARD_FAB2(SCH_1):GND
AJ34    GND VSS<237> @BASEBOARD_FAB2_LIB.BASEBOARD_FAB2(SCH_1):GND
AJ36    GND VSS<236> @BASEBOARD_FAB2_LIB.BASEBOARD_FAB2(SCH_1):GND
AJ37    GND VSS<235> @BASEBOARD_FAB2_LIB.BASEBOARD_FAB2(SCH_1):GND
AJ39    GND VSS<234> @BASEBOARD_FAB2_LIB.BASEBOARD_FAB2(SCH_1):GND
AJ41    GND VSS<233> @BASEBOARD_FAB2_LIB.BASEBOARD_FAB2(SCH_1):GND
 AJ5    GND VSS<232> @BASEBOARD_FAB2_LIB.BASEBOARD_FAB2(SCH_1):GND
AJ52    GND VSS<231> @BASEBOARD_FAB2_LIB.BASEBOARD_FAB2(SCH_1):GND
AJ59    GND VSS<230> @BASEBOARD_FAB2_LIB.BASEBOARD_FAB2(SCH_1):GND
AJ66    GND VSS<229> @BASEBOARD_FAB2_LIB.BASEBOARD_FAB2(SCH_1):GND
AJ68    GND VSS<228> @BASEBOARD_FAB2_LIB.BASEBOARD_FAB2(SCH_1):GND
 AJ7    GND VSS<227> @BASEBOARD_FAB2_LIB.BASEBOARD_FAB2(SCH_1):GND
AK26    GND VSS<226> @BASEBOARD_FAB2_LIB.BASEBOARD_FAB2(SCH_1):GND
AK41    GND VSS<225> @BASEBOARD_FAB2_LIB.BASEBOARD_FAB2(SCH_1):GND
AK46    GND VSS<224> @BASEBOARD_FAB2_LIB.BASEBOARD_FAB2(SCH_1):GND
AK48    GND VSS<223> @BASEBOARD_FAB2_LIB.BASEBOARD_FAB2(SCH_1):GND
AK58    GND VSS<222> @BASEBOARD_FAB2_LIB.BASEBOARD_FAB2(SCH_1):GND
AK61    GND VSS<221> @BASEBOARD_FAB2_LIB.BASEBOARD_FAB2(SCH_1):GND
AK69    GND VSS<220> @BASEBOARD_FAB2_LIB.BASEBOARD_FAB2(SCH_1):GND
AK71    GND VSS<219> @BASEBOARD_FAB2_LIB.BASEBOARD_FAB2(SCH_1):GND
AL22    GND VSS<218> @BASEBOARD_FAB2_LIB.BASEBOARD_FAB2(SCH_1):GND
 AL5    GND VSS<217> @BASEBOARD_FAB2_LIB.BASEBOARD_FAB2(SCH_1):GND
AL52    GND VSS<216> @BASEBOARD_FAB2_LIB.BASEBOARD_FAB2(SCH_1):GND
AL59    GND VSS<215> @BASEBOARD_FAB2_LIB.BASEBOARD_FAB2(SCH_1):GND


DRAWING: @BASEBOARD_FAB2_LIB.BASEBOARD_FAB2(SCH_1):PAGE125 

RES_0402-1.00K,1%,1/16W,EMPTY,A  I11  R2R11
   1 SPI_PCH_IO2      A @BASEBOARD_FAB2_LIB.BASEBOARD_FAB2(SCH_1):SPI_PCH_IO2
   2    GND      B @BASEBOARD_FAB2_LIB.BASEBOARD_FAB2(SCH_1):GND

RES_0402-1.00K,1%,1/16W,EMPTY,A  I21  R8E6
   1 P3V3_STBY      A @BASEBOARD_FAB2_LIB.BASEBOARD_FAB2(SCH_1):P3V3_STBY
   2 SPI_PCH_MOSI      B @BASEBOARD_FAB2_LIB.BASEBOARD_FAB2(SCH_1):SPI_PCH_MOSI

RES_0402-1.00K,1%,1/16W,EMPTY,A  I24  R8E4
   1 SPI_PCH_MOSI      A @BASEBOARD_FAB2_LIB.BASEBOARD_FAB2(SCH_1):SPI_PCH_MOSI
   2    GND      B @BASEBOARD_FAB2_LIB.BASEBOARD_FAB2(SCH_1):GND

RES_0402-1.00K,1%,1/16W,CHIP,GA  I40  R8C18
   1 P3V3_STBY      A @BASEBOARD_FAB2_LIB.BASEBOARD_FAB2(SCH_1):P3V3_STBY
   2 PU_PCH_TLS_ENABLE_STRAP      B @BASEBOARD_FAB2_LIB.BASEBOARD_FAB2(SCH_1):PU_PCH_TLS_ENABLE_STRAP

RES_0402-1.00K,1%,1/16W,EMPTY,A  I41  R8C17
   1 PU_PCH_TLS_ENABLE_STRAP      A @BASEBOARD_FAB2_LIB.BASEBOARD_FAB2(SCH_1):PU_PCH_TLS_ENABLE_STRAP
   2    GND      B @BASEBOARD_FAB2_LIB.BASEBOARD_FAB2(SCH_1):GND

RES_0402-1.00K,1%,1/16W,EMPTY,A  I50  R8D5
   1 PU_ADR_TIMER_HOLD_OFF_N      A @BASEBOARD_FAB2_LIB.BASEBOARD_FAB2(SCH_1):PU_ADR_TIMER_HOLD_OFF_N
   2    GND      B @BASEBOARD_FAB2_LIB.BASEBOARD_FAB2(SCH_1):GND

RES_0402-8.2K,1%,1/16W,EMPTY,GA  I60  R7D13
   1 P3V3_STBY      A @BASEBOARD_FAB2_LIB.BASEBOARD_FAB2(SCH_1):P3V3_STBY
   2 RMII_BMC_PCH_SPRNGVLLE_RXER      B @BASEBOARD_FAB2_LIB.BASEBOARD_FAB2(SCH_1):RMII_BMC_PCH_SPRNGVLLE_RXER

RES_0402-4.75K,1%,1/16W,EMPTY,A  I72  R3N2
   1 P3V3_STBY      A @BASEBOARD_FAB2_LIB.BASEBOARD_FAB2(SCH_1):P3V3_STBY
   2 FM_FLASH_DESC_OVERRIDE      B @BASEBOARD_FAB2_LIB.BASEBOARD_FAB2(SCH_1):FM_FLASH_DESC_OVERRIDE

RES_0402-1.00K,1%,1/16W,EMPTY,A  I78  R3N17
   1 P3V3_STBY      A @BASEBOARD_FAB2_LIB.BASEBOARD_FAB2(SCH_1):P3V3_STBY
   2 SPI_PCH_IO3      B @BASEBOARD_FAB2_LIB.BASEBOARD_FAB2(SCH_1):SPI_PCH_IO3

RES_0402-1.00K,1%,1/16W,EMPTY,A  I83  R2N14
   1 P3V3_STBY      A @BASEBOARD_FAB2_LIB.BASEBOARD_FAB2(SCH_1):P3V3_STBY
   2 FM_USB_P0_EN_BOOT_BIOS_STRAP_N      B @BASEBOARD_FAB2_LIB.BASEBOARD_FAB2(SCH_1):FM_USB_P0_EN_BOOT_BIOS_STRAP_N

RES_0402-10.0K,1%,1/16W,CHIP,GA  I85  R8D16
   1 P3V3_STBY      A @BASEBOARD_FAB2_LIB.BASEBOARD_FAB2(SCH_1):P3V3_STBY
   2 RMII_PCH_SPRNGVLLE_ARB_OUT      B @BASEBOARD_FAB2_LIB.BASEBOARD_FAB2(SCH_1):RMII_PCH_SPRNGVLLE_ARB_OUT

RES_0402-1.00K,1%,1/16W,EMPTY,A  I86  R7D1
   1 RMII_PCH_SPRNGVLLE_ARB_OUT      A @BASEBOARD_FAB2_LIB.BASEBOARD_FAB2(SCH_1):RMII_PCH_SPRNGVLLE_ARB_OUT
   2    GND      B @BASEBOARD_FAB2_LIB.BASEBOARD_FAB2(SCH_1):GND

RES_0402-10.0K,1%,1/16W,EMPTY,A  I87  R8D13
   1 P3V3_STBY      A @BASEBOARD_FAB2_LIB.BASEBOARD_FAB2(SCH_1):P3V3_STBY
   2 PU_ADR_TIMER_HOLD_OFF_N      B @BASEBOARD_FAB2_LIB.BASEBOARD_FAB2(SCH_1):PU_ADR_TIMER_HOLD_OFF_N

RES_0402-4.75K,1%,1/16W,EMPTY,A  I88  R2U30
   1 P3V3_STBY      A @BASEBOARD_FAB2_LIB.BASEBOARD_FAB2(SCH_1):P3V3_STBY
   2 FM_UV_ADR_TRIGGER_EN      B @BASEBOARD_FAB2_LIB.BASEBOARD_FAB2(SCH_1):FM_UV_ADR_TRIGGER_EN

RES_0402-1.00K,1%,1/16W,EMPTY,A  I89  R2T1
   1 SPI_PCH_IO3      A @BASEBOARD_FAB2_LIB.BASEBOARD_FAB2(SCH_1):SPI_PCH_IO3
   2    GND      B @BASEBOARD_FAB2_LIB.BASEBOARD_FAB2(SCH_1):GND


DRAWING: @BASEBOARD_FAB2_LIB.BASEBOARD_FAB2(SCH_1):PAGE126 

RES_0402-1.00K,1%,1/16W,EMPTY,A  I6  R7D19
   1 FM_OC_DETECT_EN_N      A @BASEBOARD_FAB2_LIB.BASEBOARD_FAB2(SCH_1):FM_OC_DETECT_EN_N
   2    GND      B @BASEBOARD_FAB2_LIB.BASEBOARD_FAB2(SCH_1):GND

RES_0402-4.75K,1%,1/16W,CHIP,GA  I12  R1D35
   1 P3V3_STBY      A @BASEBOARD_FAB2_LIB.BASEBOARD_FAB2(SCH_1):P3V3_STBY
   2 FM_OC_DETECT_EN_N      B @BASEBOARD_FAB2_LIB.BASEBOARD_FAB2(SCH_1):FM_OC_DETECT_EN_N

FET_N_SOT23LF-2N7002,FET,C7925A  I13  Q8E2
   1 RST_RSMRST_DLY   GATE @BASEBOARD_FAB2_LIB.BASEBOARD_FAB2(SCH_1):RST_RSMRST_DLY
   2    GND    SRC @BASEBOARD_FAB2_LIB.BASEBOARD_FAB2(SCH_1):GND
   3 IRQ_SML0_ALERT_N    DRN @BASEBOARD_FAB2_LIB.BASEBOARD_FAB2(SCH_1):IRQ_SML0_ALERT_N

RES_0402-4.75K,1%,1/16W,CHIP,GA  I20  R8C9
   1 P3V3_STBY      A @BASEBOARD_FAB2_LIB.BASEBOARD_FAB2(SCH_1):P3V3_STBY
   2 IRQ_SML0_ALERT_N      B @BASEBOARD_FAB2_LIB.BASEBOARD_FAB2(SCH_1):IRQ_SML0_ALERT_N

RES_0402-4.75K,1%,1/16W,EMPTY,A  I22  R3P62
   1 P3V3_STBY      A @BASEBOARD_FAB2_LIB.BASEBOARD_FAB2(SCH_1):P3V3_STBY
   2 FM_FLASH_ATTACH_CFG_STRAP      B @BASEBOARD_FAB2_LIB.BASEBOARD_FAB2(SCH_1):FM_FLASH_ATTACH_CFG_STRAP

RES_0402-1.00K,1%,1/16W,EMPTY,A  I23  R3P64
   1 FM_FLASH_ATTACH_CFG_STRAP      A @BASEBOARD_FAB2_LIB.BASEBOARD_FAB2(SCH_1):FM_FLASH_ATTACH_CFG_STRAP
   2    GND      B @BASEBOARD_FAB2_LIB.BASEBOARD_FAB2(SCH_1):GND

RES_0402-4.75K,1%,1/16W,EMPTY,A  I27  R2N10
   1 P3V3_STBY      A @BASEBOARD_FAB2_LIB.BASEBOARD_FAB2(SCH_1):P3V3_STBY
   2 FM_PCH_BMC_THERMTRIP_EXI_STRAP_      B @BASEBOARD_FAB2_LIB.BASEBOARD_FAB2(SCH_1):FM_PCH_BMC_THERMTRIP_EXI_STRAP_N


DRAWING: @BASEBOARD_FAB2_LIB.BASEBOARD_FAB2(SCH_1):PAGE127 

FERRITE_SM-120,FB,693286-027  I8  FB3M1
   1 P1V05_PCH_STBY      A @BASEBOARD_FAB2_LIB.BASEBOARD_FAB2(SCH_1):P1V05_PCH_STBY
   2 P1V05_PCH_STBY_VCCA_PLL1      B @BASEBOARD_FAB2_LIB.BASEBOARD_FAB2(SCH_1):P1V05_PCH_STBY_VCCA_PLL1

CAP_A_0402V-1.0UF,6.3V,10%,X6SA  I9  C3M21
   1 P1V05_PCH_STBY      A @BASEBOARD_FAB2_LIB.BASEBOARD_FAB2(SCH_1):P1V05_PCH_STBY
   2    GND      B @BASEBOARD_FAB2_LIB.BASEBOARD_FAB2(SCH_1):GND

FERRITE_SM-120,FB,693286-027  I17  FB3M2
   1 P1V05_PCH_STBY      A @BASEBOARD_FAB2_LIB.BASEBOARD_FAB2(SCH_1):P1V05_PCH_STBY
   2 P1V05_PCH_STBY_VCCA_PLL0      B @BASEBOARD_FAB2_LIB.BASEBOARD_FAB2(SCH_1):P1V05_PCH_STBY_VCCA_PLL0

CAP_A_0402V-1.0UF,6.3V,10%,X6SA  I18  C3M22
   1 P1V05_PCH_STBY      A @BASEBOARD_FAB2_LIB.BASEBOARD_FAB2(SCH_1):P1V05_PCH_STBY
   2    GND      B @BASEBOARD_FAB2_LIB.BASEBOARD_FAB2(SCH_1):GND

FERRITE_SM-120,FB,693286-027  I26  FB3M3
   1 P1V05_PCH_STBY      A @BASEBOARD_FAB2_LIB.BASEBOARD_FAB2(SCH_1):P1V05_PCH_STBY
   2 P1V05_PCH_STBY_VCCA_XTAL      B @BASEBOARD_FAB2_LIB.BASEBOARD_FAB2(SCH_1):P1V05_PCH_STBY_VCCA_XTAL

CAP_A_0402V-1.0UF,6.3V,10%,X6SA  I27  C3M30
   1 P1V05_PCH_STBY      A @BASEBOARD_FAB2_LIB.BASEBOARD_FAB2(SCH_1):P1V05_PCH_STBY
   2    GND      B @BASEBOARD_FAB2_LIB.BASEBOARD_FAB2(SCH_1):GND

CAP_0603LF-10UF,4V,20%,X6S,E15A  I43  C2M5
   1 P1V05_PCH_STBY_WM20_PLL      A @BASEBOARD_FAB2_LIB.BASEBOARD_FAB2(SCH_1):P1V05_PCH_STBY_WM20_PLL
   2    GND      B @BASEBOARD_FAB2_LIB.BASEBOARD_FAB2(SCH_1):GND

CAP_A_0402V-1.0UF,6.3V,10%,X6SA  I44  C2M7
   1 P1V05_PCH_STBY_WM20_PLL      A @BASEBOARD_FAB2_LIB.BASEBOARD_FAB2(SCH_1):P1V05_PCH_STBY_WM20_PLL
   2    GND      B @BASEBOARD_FAB2_LIB.BASEBOARD_FAB2(SCH_1):GND

FERRITE_SM-120,FB,693286-027  I46  FB2M1
   1 P1V05_PCH_STBY      A @BASEBOARD_FAB2_LIB.BASEBOARD_FAB2(SCH_1):P1V05_PCH_STBY
   2 P1V05_PCH_STBY_WM20_PLL      B @BASEBOARD_FAB2_LIB.BASEBOARD_FAB2(SCH_1):P1V05_PCH_STBY_WM20_PLL

CAP_0603LF-10UF,4V,20%,X6S,E15A  I49  C2M10
   1 P1V05_PCH_STBY_WM26_PLL      A @BASEBOARD_FAB2_LIB.BASEBOARD_FAB2(SCH_1):P1V05_PCH_STBY_WM26_PLL
   2    GND      B @BASEBOARD_FAB2_LIB.BASEBOARD_FAB2(SCH_1):GND

CAP_A_0402V-1.0UF,6.3V,10%,X6SA  I50  C2M9
   1 P1V05_PCH_STBY_WM26_PLL      A @BASEBOARD_FAB2_LIB.BASEBOARD_FAB2(SCH_1):P1V05_PCH_STBY_WM26_PLL
   2    GND      B @BASEBOARD_FAB2_LIB.BASEBOARD_FAB2(SCH_1):GND

FERRITE_SM-120,FB,693286-027  I56  FB3M4
   1 P1V05_PCH_STBY      A @BASEBOARD_FAB2_LIB.BASEBOARD_FAB2(SCH_1):P1V05_PCH_STBY
   2 P1V05_PCH_STBY_ISCLK_PLL      B @BASEBOARD_FAB2_LIB.BASEBOARD_FAB2(SCH_1):P1V05_PCH_STBY_ISCLK_PLL

CAP_A_0402V-1.0UF,6.3V,10%,X6SA  I57  C3M31
   1 P1V05_PCH_STBY      A @BASEBOARD_FAB2_LIB.BASEBOARD_FAB2(SCH_1):P1V05_PCH_STBY
   2    GND      B @BASEBOARD_FAB2_LIB.BASEBOARD_FAB2(SCH_1):GND

CAP_0603LF-10UF,4V,20%,X6S,E15A  I64  C2N6
   1 P1V05_PCH_STBY_KR_PLL      A @BASEBOARD_FAB2_LIB.BASEBOARD_FAB2(SCH_1):P1V05_PCH_STBY_KR_PLL
   2    GND      B @BASEBOARD_FAB2_LIB.BASEBOARD_FAB2(SCH_1):GND

CAP_A_0402V-1.0UF,6.3V,10%,X6SA  I65  C2N5
   1 P1V05_PCH_STBY_KR_PLL      A @BASEBOARD_FAB2_LIB.BASEBOARD_FAB2(SCH_1):P1V05_PCH_STBY_KR_PLL
   2    GND      B @BASEBOARD_FAB2_LIB.BASEBOARD_FAB2(SCH_1):GND

FERRITE_SM-120,FB,693286-027  I69  FB2M2
   1 P1V05_PCH_STBY      A @BASEBOARD_FAB2_LIB.BASEBOARD_FAB2(SCH_1):P1V05_PCH_STBY
   2 P1V05_PCH_STBY_WM26_PLL      B @BASEBOARD_FAB2_LIB.BASEBOARD_FAB2(SCH_1):P1V05_PCH_STBY_WM26_PLL

INDUCTOR_SMT-0.022UH,IND,72189A  I71  L2M1
   1 P1V05_PCH_STBY    INA @BASEBOARD_FAB2_LIB.BASEBOARD_FAB2(SCH_1):P1V05_PCH_STBY
   2 P1V05_PCH_STBY_KR_PLL    INB @BASEBOARD_FAB2_LIB.BASEBOARD_FAB2(SCH_1):P1V05_PCH_STBY_KR_PLL

CAP_A_0402V-1.0UF,6.3V,10%,X6SA  I74  C2M8
   1 P1V05_PCH_STBY      A @BASEBOARD_FAB2_LIB.BASEBOARD_FAB2(SCH_1):P1V05_PCH_STBY
   2    GND      B @BASEBOARD_FAB2_LIB.BASEBOARD_FAB2(SCH_1):GND

CAP_A_0402V-1.0UF,6.3V,10%,X6SA  I76  C2M6
   1 P1V05_PCH_STBY      A @BASEBOARD_FAB2_LIB.BASEBOARD_FAB2(SCH_1):P1V05_PCH_STBY
   2    GND      B @BASEBOARD_FAB2_LIB.BASEBOARD_FAB2(SCH_1):GND

CAP_A_0402V-1.0UF,6.3V,10%,X6SA  I78  C2M25
   1 P1V05_PCH_STBY      A @BASEBOARD_FAB2_LIB.BASEBOARD_FAB2(SCH_1):P1V05_PCH_STBY
   2    GND      B @BASEBOARD_FAB2_LIB.BASEBOARD_FAB2(SCH_1):GND

CAP_A_0402V-1.0UF,6.3V,10%,X6SA  I80  C3M29
   1 P1V05_PCH_STBY_ISCLK_PLL      A @BASEBOARD_FAB2_LIB.BASEBOARD_FAB2(SCH_1):P1V05_PCH_STBY_ISCLK_PLL
   2    GND      B @BASEBOARD_FAB2_LIB.BASEBOARD_FAB2(SCH_1):GND

CAP_0603LF-10UF,4V,20%,X6S,E15A  I81  C3M24
   1 P1V05_PCH_STBY_ISCLK_PLL      A @BASEBOARD_FAB2_LIB.BASEBOARD_FAB2(SCH_1):P1V05_PCH_STBY_ISCLK_PLL
   2    GND      B @BASEBOARD_FAB2_LIB.BASEBOARD_FAB2(SCH_1):GND

CAP_0603LF-10UF,4V,20%,X6S,E15A  I82  C3M23
   1 P1V05_PCH_STBY_VCCA_XTAL      A @BASEBOARD_FAB2_LIB.BASEBOARD_FAB2(SCH_1):P1V05_PCH_STBY_VCCA_XTAL
   2    GND      B @BASEBOARD_FAB2_LIB.BASEBOARD_FAB2(SCH_1):GND

CAP_A_0402V-1.0UF,6.3V,10%,X6SA  I83  C3M27
   1 P1V05_PCH_STBY_VCCA_XTAL      A @BASEBOARD_FAB2_LIB.BASEBOARD_FAB2(SCH_1):P1V05_PCH_STBY_VCCA_XTAL
   2    GND      B @BASEBOARD_FAB2_LIB.BASEBOARD_FAB2(SCH_1):GND

CAP_A_0402V-1.0UF,6.3V,10%,X6SA  I84  C3M20
   1 P1V05_PCH_STBY_VCCA_PLL0      A @BASEBOARD_FAB2_LIB.BASEBOARD_FAB2(SCH_1):P1V05_PCH_STBY_VCCA_PLL0
   2    GND      B @BASEBOARD_FAB2_LIB.BASEBOARD_FAB2(SCH_1):GND

CAP_0603LF-10UF,4V,20%,X6S,E15A  I85  C3M18
   1 P1V05_PCH_STBY_VCCA_PLL0      A @BASEBOARD_FAB2_LIB.BASEBOARD_FAB2(SCH_1):P1V05_PCH_STBY_VCCA_PLL0
   2    GND      B @BASEBOARD_FAB2_LIB.BASEBOARD_FAB2(SCH_1):GND

CAP_0603LF-10UF,4V,20%,X6S,E15A  I86  C3M17
   1 P1V05_PCH_STBY_VCCA_PLL1      A @BASEBOARD_FAB2_LIB.BASEBOARD_FAB2(SCH_1):P1V05_PCH_STBY_VCCA_PLL1
   2    GND      B @BASEBOARD_FAB2_LIB.BASEBOARD_FAB2(SCH_1):GND

CAP_A_0402V-1.0UF,6.3V,10%,X6SA  I87  C3M19
   1 P1V05_PCH_STBY_VCCA_PLL1      A @BASEBOARD_FAB2_LIB.BASEBOARD_FAB2(SCH_1):P1V05_PCH_STBY_VCCA_PLL1
   2    GND      B @BASEBOARD_FAB2_LIB.BASEBOARD_FAB2(SCH_1):GND


DRAWING: @BASEBOARD_FAB2_LIB.BASEBOARD_FAB2(SCH_1):PAGE129 

CAP_0402-0.22UF,16V,10%,X7R,A3A  I35  C7B25
   1 DMI_CPU0_PCH_TX_DP<3>      A @BASEBOARD_FAB2_LIB.BASEBOARD_FAB2(SCH_1):DMI_CPU0_PCH_TX_DP(3)
   2 DMI_CPU0_PCH_TX_C_DP<3>      B @BASEBOARD_FAB2_LIB.BASEBOARD_FAB2(SCH_1):DMI_CPU0_PCH_TX_C_DP(3)

CAP_0402-0.22UF,16V,10%,X7R,A3A  I69  C7B27
   1 DMI_CPU0_PCH_TX_DP<2>      A @BASEBOARD_FAB2_LIB.BASEBOARD_FAB2(SCH_1):DMI_CPU0_PCH_TX_DP(2)
   2 DMI_CPU0_PCH_TX_C_DP<2>      B @BASEBOARD_FAB2_LIB.BASEBOARD_FAB2(SCH_1):DMI_CPU0_PCH_TX_C_DP(2)

CAP_0402-0.22UF,16V,10%,X7R,A3A  I70  C7B28
   1 DMI_CPU0_PCH_TX_DP<1>      A @BASEBOARD_FAB2_LIB.BASEBOARD_FAB2(SCH_1):DMI_CPU0_PCH_TX_DP(1)
   2 DMI_CPU0_PCH_TX_C_DP<1>      B @BASEBOARD_FAB2_LIB.BASEBOARD_FAB2(SCH_1):DMI_CPU0_PCH_TX_C_DP(1)

CAP_0402-0.22UF,16V,10%,X7R,A3A  I71  C7C2
   1 DMI_CPU0_PCH_TX_DP<0>      A @BASEBOARD_FAB2_LIB.BASEBOARD_FAB2(SCH_1):DMI_CPU0_PCH_TX_DP(0)
   2 DMI_CPU0_PCH_TX_C_DP<0>      B @BASEBOARD_FAB2_LIB.BASEBOARD_FAB2(SCH_1):DMI_CPU0_PCH_TX_C_DP(0)

CAP_0402-0.22UF,16V,10%,X7R,A3A  I72  C3M40
   1 DMI_CPU0_PCH_RX_DP<0>      A @BASEBOARD_FAB2_LIB.BASEBOARD_FAB2(SCH_1):DMI_CPU0_PCH_RX_DP(0)
   2 DMI_CPU0_PCH_RX_C_DP<0>      B @BASEBOARD_FAB2_LIB.BASEBOARD_FAB2(SCH_1):DMI_CPU0_PCH_RX_C_DP(0)

CAP_0402-0.22UF,16V,10%,X7R,A3A  I73  C3M37
   1 DMI_CPU0_PCH_RX_DP<1>      A @BASEBOARD_FAB2_LIB.BASEBOARD_FAB2(SCH_1):DMI_CPU0_PCH_RX_DP(1)
   2 DMI_CPU0_PCH_RX_C_DP<1>      B @BASEBOARD_FAB2_LIB.BASEBOARD_FAB2(SCH_1):DMI_CPU0_PCH_RX_C_DP(1)

CAP_0402-0.22UF,16V,10%,X7R,A3A  I74  C3N9
   1 DMI_CPU0_PCH_RX_DP<2>      A @BASEBOARD_FAB2_LIB.BASEBOARD_FAB2(SCH_1):DMI_CPU0_PCH_RX_DP(2)
   2 DMI_CPU0_PCH_RX_C_DP<2>      B @BASEBOARD_FAB2_LIB.BASEBOARD_FAB2(SCH_1):DMI_CPU0_PCH_RX_C_DP(2)

CAP_0402-0.22UF,16V,10%,X7R,A3A  I75  C3N8
   1 DMI_CPU0_PCH_RX_DP<3>      A @BASEBOARD_FAB2_LIB.BASEBOARD_FAB2(SCH_1):DMI_CPU0_PCH_RX_DP(3)
   2 DMI_CPU0_PCH_RX_C_DP<3>      B @BASEBOARD_FAB2_LIB.BASEBOARD_FAB2(SCH_1):DMI_CPU0_PCH_RX_C_DP(3)

CAP_0402-0.22UF,16V,10%,X7R,A3A  I76  C7C3
   1 DMI_CPU0_PCH_TX_DN<0>      A @BASEBOARD_FAB2_LIB.BASEBOARD_FAB2(SCH_1):DMI_CPU0_PCH_TX_DN(0)
   2 DMI_CPU0_PCH_TX_C_DN<0>      B @BASEBOARD_FAB2_LIB.BASEBOARD_FAB2(SCH_1):DMI_CPU0_PCH_TX_C_DN(0)

CAP_0402-0.22UF,16V,10%,X7R,A3A  I77  C7C1
   1 DMI_CPU0_PCH_TX_DN<1>      A @BASEBOARD_FAB2_LIB.BASEBOARD_FAB2(SCH_1):DMI_CPU0_PCH_TX_DN(1)
   2 DMI_CPU0_PCH_TX_C_DN<1>      B @BASEBOARD_FAB2_LIB.BASEBOARD_FAB2(SCH_1):DMI_CPU0_PCH_TX_C_DN(1)

CAP_0402-0.22UF,16V,10%,X7R,A3A  I78  C7B29
   1 DMI_CPU0_PCH_TX_DN<2>      A @BASEBOARD_FAB2_LIB.BASEBOARD_FAB2(SCH_1):DMI_CPU0_PCH_TX_DN(2)
   2 DMI_CPU0_PCH_TX_C_DN<2>      B @BASEBOARD_FAB2_LIB.BASEBOARD_FAB2(SCH_1):DMI_CPU0_PCH_TX_C_DN(2)

CAP_0402-0.22UF,16V,10%,X7R,A3A  I79  C7B26
   1 DMI_CPU0_PCH_TX_DN<3>      A @BASEBOARD_FAB2_LIB.BASEBOARD_FAB2(SCH_1):DMI_CPU0_PCH_TX_DN(3)
   2 DMI_CPU0_PCH_TX_C_DN<3>      B @BASEBOARD_FAB2_LIB.BASEBOARD_FAB2(SCH_1):DMI_CPU0_PCH_TX_C_DN(3)

CAP_0402-0.22UF,16V,10%,X7R,A3A  I80  C3M44
   1 DMI_CPU0_PCH_RX_DN<0>      A @BASEBOARD_FAB2_LIB.BASEBOARD_FAB2(SCH_1):DMI_CPU0_PCH_RX_DN(0)
   2 DMI_CPU0_PCH_RX_C_DN<0>      B @BASEBOARD_FAB2_LIB.BASEBOARD_FAB2(SCH_1):DMI_CPU0_PCH_RX_C_DN(0)

CAP_0402-0.22UF,16V,10%,X7R,A3A  I81  C3M41
   1 DMI_CPU0_PCH_RX_DN<1>      A @BASEBOARD_FAB2_LIB.BASEBOARD_FAB2(SCH_1):DMI_CPU0_PCH_RX_DN(1)
   2 DMI_CPU0_PCH_RX_C_DN<1>      B @BASEBOARD_FAB2_LIB.BASEBOARD_FAB2(SCH_1):DMI_CPU0_PCH_RX_C_DN(1)

CAP_0402-0.22UF,16V,10%,X7R,A3A  I82  C3M45
   1 DMI_CPU0_PCH_RX_DN<2>      A @BASEBOARD_FAB2_LIB.BASEBOARD_FAB2(SCH_1):DMI_CPU0_PCH_RX_DN(2)
   2 DMI_CPU0_PCH_RX_C_DN<2>      B @BASEBOARD_FAB2_LIB.BASEBOARD_FAB2(SCH_1):DMI_CPU0_PCH_RX_C_DN(2)

CAP_0402-0.22UF,16V,10%,X7R,A3A  I83  C3N13
   1 DMI_CPU0_PCH_RX_DN<3>      A @BASEBOARD_FAB2_LIB.BASEBOARD_FAB2(SCH_1):DMI_CPU0_PCH_RX_DN(3)
   2 DMI_CPU0_PCH_RX_C_DN<3>      B @BASEBOARD_FAB2_LIB.BASEBOARD_FAB2(SCH_1):DMI_CPU0_PCH_RX_C_DN(3)


DRAWING: @BASEBOARD_FAB2_LIB.BASEBOARD_FAB2(SCH_1):PAGE130 

CAP_0603-10UF,6.3V,20%,X6S,E15A  I2  C7D2
   1 P3V3_STBY      A @BASEBOARD_FAB2_LIB.BASEBOARD_FAB2(SCH_1):P3V3_STBY
   2    GND      B @BASEBOARD_FAB2_LIB.BASEBOARD_FAB2(SCH_1):GND

CAP_A_0402V-1.0UF,6.3V,10%,X6SA  I4  C2N26
   1 P3V3_STBY      A @BASEBOARD_FAB2_LIB.BASEBOARD_FAB2(SCH_1):P3V3_STBY
   2    GND      B @BASEBOARD_FAB2_LIB.BASEBOARD_FAB2(SCH_1):GND

CAP_A_0402V-1.0UF,6.3V,10%,X6SA  I7  C2N19
   1 P3V3_STBY      A @BASEBOARD_FAB2_LIB.BASEBOARD_FAB2(SCH_1):P3V3_STBY
   2    GND      B @BASEBOARD_FAB2_LIB.BASEBOARD_FAB2(SCH_1):GND

CAP_0603-10UF,6.3V,20%,X6S,E15A  I8  C2N24
   1 P3V3_STBY      A @BASEBOARD_FAB2_LIB.BASEBOARD_FAB2(SCH_1):P3V3_STBY
   2    GND      B @BASEBOARD_FAB2_LIB.BASEBOARD_FAB2(SCH_1):GND

CAP_0603-10UF,6.3V,20%,X6S,E15A  I9  C2N22
   1 P3V3_STBY      A @BASEBOARD_FAB2_LIB.BASEBOARD_FAB2(SCH_1):P3V3_STBY
   2    GND      B @BASEBOARD_FAB2_LIB.BASEBOARD_FAB2(SCH_1):GND

CAP_A_0402V-1.0UF,6.3V,10%,X6SA  I12  C2N20
   1 P3V3_STBY      A @BASEBOARD_FAB2_LIB.BASEBOARD_FAB2(SCH_1):P3V3_STBY
   2    GND      B @BASEBOARD_FAB2_LIB.BASEBOARD_FAB2(SCH_1):GND

CAP_0603-10UF,6.3V,20%,X6S,E15A  I15  C2N21
   1 P3V3_STBY      A @BASEBOARD_FAB2_LIB.BASEBOARD_FAB2(SCH_1):P3V3_STBY
   2    GND      B @BASEBOARD_FAB2_LIB.BASEBOARD_FAB2(SCH_1):GND

CAP_A_0402V-0.1UF,16V,10%,X7R,A  I16  C3N29
   1 A_PVCCRTC_EXT_CAP      A @BASEBOARD_FAB2_LIB.BASEBOARD_FAB2(SCH_1):A_PVCCRTC_EXT_CAP
   2    GND      B @BASEBOARD_FAB2_LIB.BASEBOARD_FAB2(SCH_1):GND

CAP_0603-10UF,6.3V,20%,X6S,E15A  I19  C8C3
   1 P3V3_STBY      A @BASEBOARD_FAB2_LIB.BASEBOARD_FAB2(SCH_1):P3V3_STBY
   2    GND      B @BASEBOARD_FAB2_LIB.BASEBOARD_FAB2(SCH_1):GND

CAP_0603-10UF,6.3V,20%,X6S,E15A  I20  C8C4
   1 P3V3_STBY      A @BASEBOARD_FAB2_LIB.BASEBOARD_FAB2(SCH_1):P3V3_STBY
   2    GND      B @BASEBOARD_FAB2_LIB.BASEBOARD_FAB2(SCH_1):GND

CAP_0603-10UF,6.3V,20%,X6S,E15A  I21  C8C5
   1 P3V3_STBY      A @BASEBOARD_FAB2_LIB.BASEBOARD_FAB2(SCH_1):P3V3_STBY
   2    GND      B @BASEBOARD_FAB2_LIB.BASEBOARD_FAB2(SCH_1):GND

CAP_0603-10UF,6.3V,20%,X6S,E15A  I22  C8C6
   1 P3V3_STBY      A @BASEBOARD_FAB2_LIB.BASEBOARD_FAB2(SCH_1):P3V3_STBY
   2    GND      B @BASEBOARD_FAB2_LIB.BASEBOARD_FAB2(SCH_1):GND

CAP_0603-10UF,6.3V,20%,X6S,E15A  I24  C2N23
   1 P3V3_STBY      A @BASEBOARD_FAB2_LIB.BASEBOARD_FAB2(SCH_1):P3V3_STBY
   2    GND      B @BASEBOARD_FAB2_LIB.BASEBOARD_FAB2(SCH_1):GND

CAP_0603-10UF,6.3V,20%,X6S,E15A  I25  C2N14
   1 P3V3_STBY      A @BASEBOARD_FAB2_LIB.BASEBOARD_FAB2(SCH_1):P3V3_STBY
   2    GND      B @BASEBOARD_FAB2_LIB.BASEBOARD_FAB2(SCH_1):GND

CAP_0603-10UF,6.3V,20%,X6S,E15A  I28  C2N17
   1 P3V3_STBY      A @BASEBOARD_FAB2_LIB.BASEBOARD_FAB2(SCH_1):P3V3_STBY
   2    GND      B @BASEBOARD_FAB2_LIB.BASEBOARD_FAB2(SCH_1):GND

CAP_A_0402V-1.0UF,6.3V,10%,X6SA  I29  C2N18
   1 P3V3_STBY      A @BASEBOARD_FAB2_LIB.BASEBOARD_FAB2(SCH_1):P3V3_STBY
   2    GND      B @BASEBOARD_FAB2_LIB.BASEBOARD_FAB2(SCH_1):GND

CAP_A_0603V-22.0UF,4V,20%,X6S,A  I30  C8B2
   1 P1V8_PCH_STBY      A @BASEBOARD_FAB2_LIB.BASEBOARD_FAB2(SCH_1):P1V8_PCH_STBY
   2    GND      B @BASEBOARD_FAB2_LIB.BASEBOARD_FAB2(SCH_1):GND

CAP_A_0603V-22.0UF,4V,20%,X6S,A  I32  C8B3
   1 P1V8_PCH_STBY      A @BASEBOARD_FAB2_LIB.BASEBOARD_FAB2(SCH_1):P1V8_PCH_STBY
   2    GND      B @BASEBOARD_FAB2_LIB.BASEBOARD_FAB2(SCH_1):GND

CAP_A_0402V-1.0UF,6.3V,10%,X6SA  I34  C2N25
   1 P3V3_STBY      A @BASEBOARD_FAB2_LIB.BASEBOARD_FAB2(SCH_1):P3V3_STBY
   2    GND      B @BASEBOARD_FAB2_LIB.BASEBOARD_FAB2(SCH_1):GND

CAP_A_0402V-1.0UF,6.3V,10%,X6SA  I37  C2M16
   1 P3V3_STBY      A @BASEBOARD_FAB2_LIB.BASEBOARD_FAB2(SCH_1):P3V3_STBY
   2    GND      B @BASEBOARD_FAB2_LIB.BASEBOARD_FAB2(SCH_1):GND

CAP_A_0603V-22.0UF,4V,20%,X6S,A  I38  C7D3
   1 P1V8_PCH_STBY      A @BASEBOARD_FAB2_LIB.BASEBOARD_FAB2(SCH_1):P1V8_PCH_STBY
   2    GND      B @BASEBOARD_FAB2_LIB.BASEBOARD_FAB2(SCH_1):GND

CAP_A_0603V-22.0UF,4V,20%,X6S,A  I39  C8B4
   1 P1V8_PCH_STBY      A @BASEBOARD_FAB2_LIB.BASEBOARD_FAB2(SCH_1):P1V8_PCH_STBY
   2    GND      B @BASEBOARD_FAB2_LIB.BASEBOARD_FAB2(SCH_1):GND

CAP_A_0603V-22.0UF,4V,20%,X6S,A  I41  C8B1
   1 P1V8_PCH_STBY      A @BASEBOARD_FAB2_LIB.BASEBOARD_FAB2(SCH_1):P1V8_PCH_STBY
   2    GND      B @BASEBOARD_FAB2_LIB.BASEBOARD_FAB2(SCH_1):GND

CAP_A_0402V-1.0UF,6.3V,10%,X6SA  I42  C3N23
   1 P3V3_STBY      A @BASEBOARD_FAB2_LIB.BASEBOARD_FAB2(SCH_1):P3V3_STBY
   2    GND      B @BASEBOARD_FAB2_LIB.BASEBOARD_FAB2(SCH_1):GND

CAP_A_0603V-22.0UF,4V,20%,X6S,A  I43  C2M1
   1 P1V8_PCH_STBY      A @BASEBOARD_FAB2_LIB.BASEBOARD_FAB2(SCH_1):P1V8_PCH_STBY
   2    GND      B @BASEBOARD_FAB2_LIB.BASEBOARD_FAB2(SCH_1):GND

CAP_A_0603V-22.0UF,4V,20%,X6S,A  I45  C2M2
   1 P1V8_PCH_STBY      A @BASEBOARD_FAB2_LIB.BASEBOARD_FAB2(SCH_1):P1V8_PCH_STBY
   2    GND      B @BASEBOARD_FAB2_LIB.BASEBOARD_FAB2(SCH_1):GND

CAP_A_0402V-1.0UF,6.3V,10%,X6SA  I47  C2N15
   1 P1V8_PCH_STBY      A @BASEBOARD_FAB2_LIB.BASEBOARD_FAB2(SCH_1):P1V8_PCH_STBY
   2    GND      B @BASEBOARD_FAB2_LIB.BASEBOARD_FAB2(SCH_1):GND

CAP_A_0402V-1.0UF,6.3V,10%,X6SA  I49  C3N21
   1 P1V8_PCH_STBY      A @BASEBOARD_FAB2_LIB.BASEBOARD_FAB2(SCH_1):P1V8_PCH_STBY
   2    GND      B @BASEBOARD_FAB2_LIB.BASEBOARD_FAB2(SCH_1):GND

CAP_A_0402V-1.0UF,6.3V,10%,X6SA  I50  C3N25
   1 P1V8_PCH_STBY      A @BASEBOARD_FAB2_LIB.BASEBOARD_FAB2(SCH_1):P1V8_PCH_STBY
   2    GND      B @BASEBOARD_FAB2_LIB.BASEBOARD_FAB2(SCH_1):GND

CAP_A_0402V-1.0UF,6.3V,10%,X6SA  I52  C2N16
   1 P1V8_PCH_STBY      A @BASEBOARD_FAB2_LIB.BASEBOARD_FAB2(SCH_1):P1V8_PCH_STBY
   2    GND      B @BASEBOARD_FAB2_LIB.BASEBOARD_FAB2(SCH_1):GND

CAP_A_0402V-1.0UF,6.3V,10%,X6SA  I53  C3N22
   1 P1V8_PCH_STBY      A @BASEBOARD_FAB2_LIB.BASEBOARD_FAB2(SCH_1):P1V8_PCH_STBY
   2    GND      B @BASEBOARD_FAB2_LIB.BASEBOARD_FAB2(SCH_1):GND


DRAWING: @BASEBOARD_FAB2_LIB.BASEBOARD_FAB2(SCH_1):PAGE131 

CAP_A_0603V-22.0UF,4V,20%,X6S,A  I1  C7B15
   1 P1V05_PCH_STBY      A @BASEBOARD_FAB2_LIB.BASEBOARD_FAB2(SCH_1):P1V05_PCH_STBY
   2    GND      B @BASEBOARD_FAB2_LIB.BASEBOARD_FAB2(SCH_1):GND

CAP_A_0603V-22.0UF,4V,20%,X6S,A  I2  C7B19
   1 P1V05_PCH_STBY      A @BASEBOARD_FAB2_LIB.BASEBOARD_FAB2(SCH_1):P1V05_PCH_STBY
   2    GND      B @BASEBOARD_FAB2_LIB.BASEBOARD_FAB2(SCH_1):GND

CAP_A_0603V-22.0UF,4V,20%,X6S,A  I3  C7B16
   1 P1V05_PCH_STBY      A @BASEBOARD_FAB2_LIB.BASEBOARD_FAB2(SCH_1):P1V05_PCH_STBY
   2    GND      B @BASEBOARD_FAB2_LIB.BASEBOARD_FAB2(SCH_1):GND

CAP_A_0603V-22.0UF,4V,20%,X6S,A  I4  C7B21
   1 P1V05_PCH_STBY      A @BASEBOARD_FAB2_LIB.BASEBOARD_FAB2(SCH_1):P1V05_PCH_STBY
   2    GND      B @BASEBOARD_FAB2_LIB.BASEBOARD_FAB2(SCH_1):GND

CAP_A_0603V-22.0UF,4V,20%,X6S,A  I6  C7B20
   1 P1V05_PCH_STBY      A @BASEBOARD_FAB2_LIB.BASEBOARD_FAB2(SCH_1):P1V05_PCH_STBY
   2    GND      B @BASEBOARD_FAB2_LIB.BASEBOARD_FAB2(SCH_1):GND

CAP_A_0603V-22.0UF,4V,20%,X6S,A  I7  C7B23
   1 P1V05_PCH_STBY      A @BASEBOARD_FAB2_LIB.BASEBOARD_FAB2(SCH_1):P1V05_PCH_STBY
   2    GND      B @BASEBOARD_FAB2_LIB.BASEBOARD_FAB2(SCH_1):GND

CAP_A_0603V-22.0UF,4V,20%,X6S,A  I8  C8B10
   1 P1V05_PCH_STBY      A @BASEBOARD_FAB2_LIB.BASEBOARD_FAB2(SCH_1):P1V05_PCH_STBY
   2    GND      B @BASEBOARD_FAB2_LIB.BASEBOARD_FAB2(SCH_1):GND

CAP_A_0603V-22.0UF,4V,20%,X6S,A  I10  C7B22
   1 P1V05_PCH_STBY      A @BASEBOARD_FAB2_LIB.BASEBOARD_FAB2(SCH_1):P1V05_PCH_STBY
   2    GND      B @BASEBOARD_FAB2_LIB.BASEBOARD_FAB2(SCH_1):GND

CAP_A_0603V-22.0UF,4V,20%,X6S,A  I11  C7B24
   1 P1V05_PCH_STBY      A @BASEBOARD_FAB2_LIB.BASEBOARD_FAB2(SCH_1):P1V05_PCH_STBY
   2    GND      B @BASEBOARD_FAB2_LIB.BASEBOARD_FAB2(SCH_1):GND

CAP_A_0603V-22.0UF,4V,20%,X6S,A  I12  C7B18
   1 P1V05_PCH_STBY      A @BASEBOARD_FAB2_LIB.BASEBOARD_FAB2(SCH_1):P1V05_PCH_STBY
   2    GND      B @BASEBOARD_FAB2_LIB.BASEBOARD_FAB2(SCH_1):GND

CAP_A_0603V-22.0UF,4V,20%,X6S,A  I14  C8B9
   1 P1V05_PCH_STBY      A @BASEBOARD_FAB2_LIB.BASEBOARD_FAB2(SCH_1):P1V05_PCH_STBY
   2    GND      B @BASEBOARD_FAB2_LIB.BASEBOARD_FAB2(SCH_1):GND

CAP_A_0603V-22.0UF,4V,20%,X6S,A  I15  C8B11
   1 P1V05_PCH_STBY      A @BASEBOARD_FAB2_LIB.BASEBOARD_FAB2(SCH_1):P1V05_PCH_STBY
   2    GND      B @BASEBOARD_FAB2_LIB.BASEBOARD_FAB2(SCH_1):GND

CAP_A_0603V-22.0UF,4V,20%,X6S,A  I16  C8B14
   1 P1V05_PCH_STBY      A @BASEBOARD_FAB2_LIB.BASEBOARD_FAB2(SCH_1):P1V05_PCH_STBY
   2    GND      B @BASEBOARD_FAB2_LIB.BASEBOARD_FAB2(SCH_1):GND

CAP_A_0603V-22.0UF,4V,20%,X6S,A  I18  C7B17
   1 P1V05_PCH_STBY      A @BASEBOARD_FAB2_LIB.BASEBOARD_FAB2(SCH_1):P1V05_PCH_STBY
   2    GND      B @BASEBOARD_FAB2_LIB.BASEBOARD_FAB2(SCH_1):GND

CAP_A_0603V-22.0UF,4V,20%,X6S,A  I20  C8B13
   1 P1V05_PCH_STBY      A @BASEBOARD_FAB2_LIB.BASEBOARD_FAB2(SCH_1):P1V05_PCH_STBY
   2    GND      B @BASEBOARD_FAB2_LIB.BASEBOARD_FAB2(SCH_1):GND

CAP_0805-47UF,4V,20%,X6S,C9533A  I22  C8B16
   1 P1V05_PCH_STBY      A @BASEBOARD_FAB2_LIB.BASEBOARD_FAB2(SCH_1):P1V05_PCH_STBY
   2    GND      B @BASEBOARD_FAB2_LIB.BASEBOARD_FAB2(SCH_1):GND

CAP_0805-47UF,4V,20%,X6S,C9533A  I24  C8B15
   1 P1V05_PCH_STBY      A @BASEBOARD_FAB2_LIB.BASEBOARD_FAB2(SCH_1):P1V05_PCH_STBY
   2    GND      B @BASEBOARD_FAB2_LIB.BASEBOARD_FAB2(SCH_1):GND

CAP_A_0402V-1.0UF,6.3V,10%,X6SA  I27  C2M22
   1 P1V05_PCH_STBY      A @BASEBOARD_FAB2_LIB.BASEBOARD_FAB2(SCH_1):P1V05_PCH_STBY
   2    GND      B @BASEBOARD_FAB2_LIB.BASEBOARD_FAB2(SCH_1):GND

CAP_A_0402V-1.0UF,6.3V,10%,X6SA  I28  C2M21
   1 P1V05_PCH_STBY      A @BASEBOARD_FAB2_LIB.BASEBOARD_FAB2(SCH_1):P1V05_PCH_STBY
   2    GND      B @BASEBOARD_FAB2_LIB.BASEBOARD_FAB2(SCH_1):GND

CAP_A_0402V-1.0UF,6.3V,10%,X6SA  I29  C2M18
   1 P1V05_PCH_STBY      A @BASEBOARD_FAB2_LIB.BASEBOARD_FAB2(SCH_1):P1V05_PCH_STBY
   2    GND      B @BASEBOARD_FAB2_LIB.BASEBOARD_FAB2(SCH_1):GND

CAP_A_0402V-1.0UF,6.3V,10%,X6SA  I31  C2M19
   1 P1V05_PCH_STBY      A @BASEBOARD_FAB2_LIB.BASEBOARD_FAB2(SCH_1):P1V05_PCH_STBY
   2    GND      B @BASEBOARD_FAB2_LIB.BASEBOARD_FAB2(SCH_1):GND

CAP_A_0402V-1.0UF,6.3V,10%,X6SA  I32  C3M38
   1 P1V05_PCH_STBY      A @BASEBOARD_FAB2_LIB.BASEBOARD_FAB2(SCH_1):P1V05_PCH_STBY
   2    GND      B @BASEBOARD_FAB2_LIB.BASEBOARD_FAB2(SCH_1):GND

CAP_0805-47UF,4V,20%,X6S,C9533A  I34  C2M17
   1 P1V05_PCH_STBY      A @BASEBOARD_FAB2_LIB.BASEBOARD_FAB2(SCH_1):P1V05_PCH_STBY
   2    GND      B @BASEBOARD_FAB2_LIB.BASEBOARD_FAB2(SCH_1):GND

CAP_0805-47UF,4V,20%,X6S,C9533A  I35  C2M11
   1 P1V05_PCH_STBY      A @BASEBOARD_FAB2_LIB.BASEBOARD_FAB2(SCH_1):P1V05_PCH_STBY
   2    GND      B @BASEBOARD_FAB2_LIB.BASEBOARD_FAB2(SCH_1):GND

CAP_0805-47UF,4V,20%,X6S,C9533A  I37  C8A13
   1 P1V05_PCH_STBY      A @BASEBOARD_FAB2_LIB.BASEBOARD_FAB2(SCH_1):P1V05_PCH_STBY
   2    GND      B @BASEBOARD_FAB2_LIB.BASEBOARD_FAB2(SCH_1):GND

CAP_A_0402V-1.0UF,6.3V,10%,X6SA  I39  C2M20
   1 P1V05_PCH_STBY      A @BASEBOARD_FAB2_LIB.BASEBOARD_FAB2(SCH_1):P1V05_PCH_STBY
   2    GND      B @BASEBOARD_FAB2_LIB.BASEBOARD_FAB2(SCH_1):GND

CAP_A_0402V-1.0UF,6.3V,10%,X6SA  I40  C2N13
   1 P1V05_PCH_STBY      A @BASEBOARD_FAB2_LIB.BASEBOARD_FAB2(SCH_1):P1V05_PCH_STBY
   2    GND      B @BASEBOARD_FAB2_LIB.BASEBOARD_FAB2(SCH_1):GND

CAP_A_0402V-1.0UF,6.3V,10%,X6SA  I41  C2N2
   1 P1V05_PCH_STBY      A @BASEBOARD_FAB2_LIB.BASEBOARD_FAB2(SCH_1):P1V05_PCH_STBY
   2    GND      B @BASEBOARD_FAB2_LIB.BASEBOARD_FAB2(SCH_1):GND

CAP_A_0402V-1.0UF,6.3V,10%,X6SA  I42  C3M43
   1 P1V05_PCH_STBY      A @BASEBOARD_FAB2_LIB.BASEBOARD_FAB2(SCH_1):P1V05_PCH_STBY
   2    GND      B @BASEBOARD_FAB2_LIB.BASEBOARD_FAB2(SCH_1):GND

CAP_A_0402V-1.0UF,6.3V,10%,X6SA  I43  C2N7
   1 P1V05_PCH_STBY      A @BASEBOARD_FAB2_LIB.BASEBOARD_FAB2(SCH_1):P1V05_PCH_STBY
   2    GND      B @BASEBOARD_FAB2_LIB.BASEBOARD_FAB2(SCH_1):GND

CAP_A_0402V-1.0UF,6.3V,10%,X6SA  I44  C3M39
   1 P1V05_PCH_STBY      A @BASEBOARD_FAB2_LIB.BASEBOARD_FAB2(SCH_1):P1V05_PCH_STBY
   2    GND      B @BASEBOARD_FAB2_LIB.BASEBOARD_FAB2(SCH_1):GND

CAP_A_0402V-1.0UF,6.3V,10%,X6SA  I45  C3M42
   1 P1V05_PCH_STBY      A @BASEBOARD_FAB2_LIB.BASEBOARD_FAB2(SCH_1):P1V05_PCH_STBY
   2    GND      B @BASEBOARD_FAB2_LIB.BASEBOARD_FAB2(SCH_1):GND

CAP_A_0402V-1.0UF,6.3V,10%,X6SA  I47  C2N8
   1 P1V05_PCH_STBY      A @BASEBOARD_FAB2_LIB.BASEBOARD_FAB2(SCH_1):P1V05_PCH_STBY
   2    GND      B @BASEBOARD_FAB2_LIB.BASEBOARD_FAB2(SCH_1):GND

CAP_A_0603V-22.0UF,4V,20%,X6S,A  I48  C2M13
   1 P1V05_PCH_STBY      A @BASEBOARD_FAB2_LIB.BASEBOARD_FAB2(SCH_1):P1V05_PCH_STBY
   2    GND      B @BASEBOARD_FAB2_LIB.BASEBOARD_FAB2(SCH_1):GND

CAP_A_0603V-22.0UF,4V,20%,X6S,A  I50  C2N10
   1 P1V05_PCH_STBY      A @BASEBOARD_FAB2_LIB.BASEBOARD_FAB2(SCH_1):P1V05_PCH_STBY
   2    GND      B @BASEBOARD_FAB2_LIB.BASEBOARD_FAB2(SCH_1):GND

CAP_A_0603V-22.0UF,4V,20%,X6S,A  I52  C2M12
   1 P1V05_PCH_STBY      A @BASEBOARD_FAB2_LIB.BASEBOARD_FAB2(SCH_1):P1V05_PCH_STBY
   2    GND      B @BASEBOARD_FAB2_LIB.BASEBOARD_FAB2(SCH_1):GND


DRAWING: @BASEBOARD_FAB2_LIB.BASEBOARD_FAB2(SCH_1):PAGE132 

CAP_A_0603V-22.0UF,4V,20%,X6S,A  I1  C3L25
   1 PVNN_PCH_STBY      A @BASEBOARD_FAB2_LIB.BASEBOARD_FAB2(SCH_1):PVNN_PCH_STBY
   2    GND      B @BASEBOARD_FAB2_LIB.BASEBOARD_FAB2(SCH_1):GND

CAP_A_0603V-22.0UF,4V,20%,X6S,A  I2  C3M7
   1 PVNN_PCH_STBY      A @BASEBOARD_FAB2_LIB.BASEBOARD_FAB2(SCH_1):PVNN_PCH_STBY
   2    GND      B @BASEBOARD_FAB2_LIB.BASEBOARD_FAB2(SCH_1):GND

CAP_A_0603V-22.0UF,4V,20%,X6S,A  I3  C3L26
   1 PVNN_PCH_STBY      A @BASEBOARD_FAB2_LIB.BASEBOARD_FAB2(SCH_1):PVNN_PCH_STBY
   2    GND      B @BASEBOARD_FAB2_LIB.BASEBOARD_FAB2(SCH_1):GND

CAP_A_0603V-22.0UF,4V,20%,X6S,A  I4  C3L27
   1 PVNN_PCH_STBY      A @BASEBOARD_FAB2_LIB.BASEBOARD_FAB2(SCH_1):PVNN_PCH_STBY
   2    GND      B @BASEBOARD_FAB2_LIB.BASEBOARD_FAB2(SCH_1):GND

CAP_A_0603V-22.0UF,4V,20%,X6S,A  I6  C3M6
   1 PVNN_PCH_STBY      A @BASEBOARD_FAB2_LIB.BASEBOARD_FAB2(SCH_1):PVNN_PCH_STBY
   2    GND      B @BASEBOARD_FAB2_LIB.BASEBOARD_FAB2(SCH_1):GND

CAP_A_0603V-22.0UF,4V,20%,X6S,A  I7  C7C9
   1 PVNN_PCH_STBY      A @BASEBOARD_FAB2_LIB.BASEBOARD_FAB2(SCH_1):PVNN_PCH_STBY
   2    GND      B @BASEBOARD_FAB2_LIB.BASEBOARD_FAB2(SCH_1):GND

CAP_A_0603V-22.0UF,4V,20%,X6S,A  I8  C3N27
   1 PVNN_PCH_STBY      A @BASEBOARD_FAB2_LIB.BASEBOARD_FAB2(SCH_1):PVNN_PCH_STBY
   2    GND      B @BASEBOARD_FAB2_LIB.BASEBOARD_FAB2(SCH_1):GND

CAP_A_0603V-22.0UF,4V,20%,X6S,A  I9  C3N30
   1 PVNN_PCH_STBY      A @BASEBOARD_FAB2_LIB.BASEBOARD_FAB2(SCH_1):PVNN_PCH_STBY
   2    GND      B @BASEBOARD_FAB2_LIB.BASEBOARD_FAB2(SCH_1):GND

CAP_A_0603V-22.0UF,4V,20%,X6S,A  I11  C7A36
   1 PVNN_PCH_STBY      A @BASEBOARD_FAB2_LIB.BASEBOARD_FAB2(SCH_1):PVNN_PCH_STBY
   2    GND      B @BASEBOARD_FAB2_LIB.BASEBOARD_FAB2(SCH_1):GND

CAP_A_0603V-22.0UF,4V,20%,X6S,A  I12  C3N12
   1 PVNN_PCH_STBY      A @BASEBOARD_FAB2_LIB.BASEBOARD_FAB2(SCH_1):PVNN_PCH_STBY
   2    GND      B @BASEBOARD_FAB2_LIB.BASEBOARD_FAB2(SCH_1):GND

CAP_A_0603V-22.0UF,4V,20%,X6S,A  I13  C3N10
   1 PVNN_PCH_STBY      A @BASEBOARD_FAB2_LIB.BASEBOARD_FAB2(SCH_1):PVNN_PCH_STBY
   2    GND      B @BASEBOARD_FAB2_LIB.BASEBOARD_FAB2(SCH_1):GND

CAP_A_0603V-22.0UF,4V,20%,X6S,A  I16  C3N24
   1 PVNN_PCH_STBY      A @BASEBOARD_FAB2_LIB.BASEBOARD_FAB2(SCH_1):PVNN_PCH_STBY
   2    GND      B @BASEBOARD_FAB2_LIB.BASEBOARD_FAB2(SCH_1):GND

CAP_A_0603V-22.0UF,4V,20%,X6S,A  I17  C3N28
   1 PVNN_PCH_STBY      A @BASEBOARD_FAB2_LIB.BASEBOARD_FAB2(SCH_1):PVNN_PCH_STBY
   2    GND      B @BASEBOARD_FAB2_LIB.BASEBOARD_FAB2(SCH_1):GND

CAP_A_0603V-22.0UF,4V,20%,X6S,A  I19  C3N11
   1 PVNN_PCH_STBY      A @BASEBOARD_FAB2_LIB.BASEBOARD_FAB2(SCH_1):PVNN_PCH_STBY
   2    GND      B @BASEBOARD_FAB2_LIB.BASEBOARD_FAB2(SCH_1):GND

CAP_A_0603V-22.0UF,4V,20%,X6S,A  I20  C3N31
   1 PVNN_PCH_STBY      A @BASEBOARD_FAB2_LIB.BASEBOARD_FAB2(SCH_1):PVNN_PCH_STBY
   2    GND      B @BASEBOARD_FAB2_LIB.BASEBOARD_FAB2(SCH_1):GND

CAP_0805-47UF,4V,20%,X6S,C9533A  I23  C7A33
   1 PVNN_PCH_STBY      A @BASEBOARD_FAB2_LIB.BASEBOARD_FAB2(SCH_1):PVNN_PCH_STBY
   2    GND      B @BASEBOARD_FAB2_LIB.BASEBOARD_FAB2(SCH_1):GND

CAP_0805-47UF,4V,20%,X6S,C9533A  I24  C7B4
   1 PVNN_PCH_STBY      A @BASEBOARD_FAB2_LIB.BASEBOARD_FAB2(SCH_1):PVNN_PCH_STBY
   2    GND      B @BASEBOARD_FAB2_LIB.BASEBOARD_FAB2(SCH_1):GND

CAP_A_0402V-1.0UF,6.3V,10%,X6SA  I26  C2N9
   1 PVNN_PCH_STBY      A @BASEBOARD_FAB2_LIB.BASEBOARD_FAB2(SCH_1):PVNN_PCH_STBY
   2    GND      B @BASEBOARD_FAB2_LIB.BASEBOARD_FAB2(SCH_1):GND

CAP_A_0402V-1.0UF,6.3V,10%,X6SA  I27  C2N3
   1 PVNN_PCH_STBY      A @BASEBOARD_FAB2_LIB.BASEBOARD_FAB2(SCH_1):PVNN_PCH_STBY
   2    GND      B @BASEBOARD_FAB2_LIB.BASEBOARD_FAB2(SCH_1):GND

CAP_A_0402V-1.0UF,6.3V,10%,X6SA  I28  C2N4
   1 PVNN_PCH_STBY      A @BASEBOARD_FAB2_LIB.BASEBOARD_FAB2(SCH_1):PVNN_PCH_STBY
   2    GND      B @BASEBOARD_FAB2_LIB.BASEBOARD_FAB2(SCH_1):GND

CAP_A_0402V-1.0UF,6.3V,10%,X6SA  I29  C2N12
   1 PVNN_PCH_STBY      A @BASEBOARD_FAB2_LIB.BASEBOARD_FAB2(SCH_1):PVNN_PCH_STBY
   2    GND      B @BASEBOARD_FAB2_LIB.BASEBOARD_FAB2(SCH_1):GND

CAP_A_0402V-1.0UF,6.3V,10%,X6SA  I30  C2N11
   1 PVNN_PCH_STBY      A @BASEBOARD_FAB2_LIB.BASEBOARD_FAB2(SCH_1):PVNN_PCH_STBY
   2    GND      B @BASEBOARD_FAB2_LIB.BASEBOARD_FAB2(SCH_1):GND

CAP_A_0402V-1.0UF,6.3V,10%,X6SA  I31  C3N19
   1 PVNN_PCH_STBY      A @BASEBOARD_FAB2_LIB.BASEBOARD_FAB2(SCH_1):PVNN_PCH_STBY
   2    GND      B @BASEBOARD_FAB2_LIB.BASEBOARD_FAB2(SCH_1):GND

CAP_A_0402V-1.0UF,6.3V,10%,X6SA  I32  C3N3
   1 PVNN_PCH_STBY      A @BASEBOARD_FAB2_LIB.BASEBOARD_FAB2(SCH_1):PVNN_PCH_STBY
   2    GND      B @BASEBOARD_FAB2_LIB.BASEBOARD_FAB2(SCH_1):GND

CAP_A_0402V-1.0UF,6.3V,10%,X6SA  I34  C3N1
   1 PVNN_PCH_STBY      A @BASEBOARD_FAB2_LIB.BASEBOARD_FAB2(SCH_1):PVNN_PCH_STBY
   2    GND      B @BASEBOARD_FAB2_LIB.BASEBOARD_FAB2(SCH_1):GND

CAP_A_0402V-1.0UF,6.3V,10%,X6SA  I35  C3N7
   1 PVNN_PCH_STBY      A @BASEBOARD_FAB2_LIB.BASEBOARD_FAB2(SCH_1):PVNN_PCH_STBY
   2    GND      B @BASEBOARD_FAB2_LIB.BASEBOARD_FAB2(SCH_1):GND

CAP_A_0402V-1.0UF,6.3V,10%,X6SA  I36  C3N16
   1 PVNN_PCH_STBY      A @BASEBOARD_FAB2_LIB.BASEBOARD_FAB2(SCH_1):PVNN_PCH_STBY
   2    GND      B @BASEBOARD_FAB2_LIB.BASEBOARD_FAB2(SCH_1):GND

CAP_0805-47UF,4V,20%,X6S,C9533A  I38  C7A32
   1 PVNN_PCH_STBY      A @BASEBOARD_FAB2_LIB.BASEBOARD_FAB2(SCH_1):PVNN_PCH_STBY
   2    GND      B @BASEBOARD_FAB2_LIB.BASEBOARD_FAB2(SCH_1):GND

CAP_0805-47UF,4V,20%,X6S,C9533A  I40  C7A31
   1 PVNN_PCH_STBY      A @BASEBOARD_FAB2_LIB.BASEBOARD_FAB2(SCH_1):PVNN_PCH_STBY
   2    GND      B @BASEBOARD_FAB2_LIB.BASEBOARD_FAB2(SCH_1):GND

CAP_A_0402V-1.0UF,6.3V,10%,X6SA  I42  C3N18
   1 PVNN_PCH_STBY      A @BASEBOARD_FAB2_LIB.BASEBOARD_FAB2(SCH_1):PVNN_PCH_STBY
   2    GND      B @BASEBOARD_FAB2_LIB.BASEBOARD_FAB2(SCH_1):GND

CAP_A_0402V-1.0UF,6.3V,10%,X6SA  I43  C3N2
   1 PVNN_PCH_STBY      A @BASEBOARD_FAB2_LIB.BASEBOARD_FAB2(SCH_1):PVNN_PCH_STBY
   2    GND      B @BASEBOARD_FAB2_LIB.BASEBOARD_FAB2(SCH_1):GND

CAP_A_0402V-1.0UF,6.3V,10%,X6SA  I44  C3N6
   1 PVNN_PCH_STBY      A @BASEBOARD_FAB2_LIB.BASEBOARD_FAB2(SCH_1):PVNN_PCH_STBY
   2    GND      B @BASEBOARD_FAB2_LIB.BASEBOARD_FAB2(SCH_1):GND

CAP_A_0402V-1.0UF,6.3V,10%,X6SA  I45  C3N17
   1 PVNN_PCH_STBY      A @BASEBOARD_FAB2_LIB.BASEBOARD_FAB2(SCH_1):PVNN_PCH_STBY
   2    GND      B @BASEBOARD_FAB2_LIB.BASEBOARD_FAB2(SCH_1):GND

CAP_A_0402V-1.0UF,6.3V,10%,X6SA  I46  C3N4
   1 PVNN_PCH_STBY      A @BASEBOARD_FAB2_LIB.BASEBOARD_FAB2(SCH_1):PVNN_PCH_STBY
   2    GND      B @BASEBOARD_FAB2_LIB.BASEBOARD_FAB2(SCH_1):GND

CAP_A_0402V-1.0UF,6.3V,10%,X6SA  I48  C3N5
   1 PVNN_PCH_STBY      A @BASEBOARD_FAB2_LIB.BASEBOARD_FAB2(SCH_1):PVNN_PCH_STBY
   2    GND      B @BASEBOARD_FAB2_LIB.BASEBOARD_FAB2(SCH_1):GND

CAP_A_0402V-1.0UF,6.3V,10%,X6SA  I49  C3N15
   1 PVNN_PCH_STBY      A @BASEBOARD_FAB2_LIB.BASEBOARD_FAB2(SCH_1):PVNN_PCH_STBY
   2    GND      B @BASEBOARD_FAB2_LIB.BASEBOARD_FAB2(SCH_1):GND

CAP_A_0402V-1.0UF,6.3V,10%,X6SA  I51  C3N20
   1 PVNN_PCH_STBY      A @BASEBOARD_FAB2_LIB.BASEBOARD_FAB2(SCH_1):PVNN_PCH_STBY
   2    GND      B @BASEBOARD_FAB2_LIB.BASEBOARD_FAB2(SCH_1):GND

CAP_A_0603V-22.0UF,4V,20%,X6S,A  I52  C3L23
   1 PVNN_PCH_STBY      A @BASEBOARD_FAB2_LIB.BASEBOARD_FAB2(SCH_1):PVNN_PCH_STBY
   2    GND      B @BASEBOARD_FAB2_LIB.BASEBOARD_FAB2(SCH_1):GND

CAP_A_0603V-22.0UF,4V,20%,X6S,A  I54  C3L22
   1 PVNN_PCH_STBY      A @BASEBOARD_FAB2_LIB.BASEBOARD_FAB2(SCH_1):PVNN_PCH_STBY
   2    GND      B @BASEBOARD_FAB2_LIB.BASEBOARD_FAB2(SCH_1):GND

CAP_A_0603V-22.0UF,4V,20%,X6S,A  I56  C3L24
   1 PVNN_PCH_STBY      A @BASEBOARD_FAB2_LIB.BASEBOARD_FAB2(SCH_1):PVNN_PCH_STBY
   2    GND      B @BASEBOARD_FAB2_LIB.BASEBOARD_FAB2(SCH_1):GND


DRAWING: @BASEBOARD_FAB2_LIB.BASEBOARD_FAB2(SCH_1):PAGE133 

RES_0402-2.0K,1%,1/16W,CHIP,G2A  I120  R3N3
   1    GND      A @BASEBOARD_FAB2_LIB.BASEBOARD_FAB2(SCH_1):GND
   2 PWRGD_PCH_PWROK      B @BASEBOARD_FAB2_LIB.BASEBOARD_FAB2(SCH_1):PWRGD_PCH_PWROK

RES_0402-10.0K,1%,1/16W,EMPTY,A  I122  R2N12
   1    GND      A @BASEBOARD_FAB2_LIB.BASEBOARD_FAB2(SCH_1):GND
   2 PWRGD_SYS_PWROK      B @BASEBOARD_FAB2_LIB.BASEBOARD_FAB2(SCH_1):PWRGD_SYS_PWROK

RES_0402-10.0K,1%,1/16W,CHIP,GA  I200  R7D8
   1 P3V3_STBY      A @BASEBOARD_FAB2_LIB.BASEBOARD_FAB2(SCH_1):P3V3_STBY
   2 PU_LPC_CLKRUN_N      B @BASEBOARD_FAB2_LIB.BASEBOARD_FAB2(SCH_1):PU_LPC_CLKRUN_N

RES_0402-10.0K,1%,1/16W,CHIP,GA  I202  R7D10
   1 P3V3_STBY      A @BASEBOARD_FAB2_LIB.BASEBOARD_FAB2(SCH_1):P3V3_STBY
   2 PU_LPC_PME_N      B @BASEBOARD_FAB2_LIB.BASEBOARD_FAB2(SCH_1):PU_LPC_PME_N

RES_0402-10.0K,1%,1/16W,CHIP,GA  I237  R7D12
   1 P3V3_STBY      A @BASEBOARD_FAB2_LIB.BASEBOARD_FAB2(SCH_1):P3V3_STBY
   2 FM_OCP_MEZZA_PRES      B @BASEBOARD_FAB2_LIB.BASEBOARD_FAB2(SCH_1):FM_OCP_MEZZA_PRES

RES_0402-4.75K,1%,1/16W,CHIP,GA  I243  R7D3
   1 P3V3_STBY      A @BASEBOARD_FAB2_LIB.BASEBOARD_FAB2(SCH_1):P3V3_STBY
   2 IRQ_LPC_SERIRQ_N      B @BASEBOARD_FAB2_LIB.BASEBOARD_FAB2(SCH_1):IRQ_LPC_SERIRQ_N

RES_0402-10.0K,1%,1/16W,CHIP,GA  I245  R7D4
   1 P3V3_STBY      A @BASEBOARD_FAB2_LIB.BASEBOARD_FAB2(SCH_1):P3V3_STBY
   2 PU_IRQ_PCH_SCI_WHEA_N      B @BASEBOARD_FAB2_LIB.BASEBOARD_FAB2(SCH_1):PU_IRQ_PCH_SCI_WHEA_N

RES_0402-10.0K,1%,1/16W,CHIP,GA  I247  R2N16
   1 P3V3_STBY      A @BASEBOARD_FAB2_LIB.BASEBOARD_FAB2(SCH_1):P3V3_STBY
   2 PU_IRQ_VRALERT_N      B @BASEBOARD_FAB2_LIB.BASEBOARD_FAB2(SCH_1):PU_IRQ_VRALERT_N

RES_0402-1.00K,1%,1/16W,CHIP,GA  I258  R2R5
   1 P3V3_STBY      A @BASEBOARD_FAB2_LIB.BASEBOARD_FAB2(SCH_1):P3V3_STBY
   2 FM_PCH_PLD_DATA      B @BASEBOARD_FAB2_LIB.BASEBOARD_FAB2(SCH_1):FM_PCH_PLD_DATA

RES_0402-10.0K,1%,1/16W,CHIP,GA  I267  R2N9
   1 P3V3_STBY      A @BASEBOARD_FAB2_LIB.BASEBOARD_FAB2(SCH_1):P3V3_STBY
   2 PU_10GBE_LOM_PCI_DISABLE_N      B @BASEBOARD_FAB2_LIB.BASEBOARD_FAB2(SCH_1):PU_10GBE_LOM_PCI_DISABLE_N

RES_0402-1.00K,1%,1/16W,CHIP,GA  I280  R8B23
   1 P3V3_STBY      A @BASEBOARD_FAB2_LIB.BASEBOARD_FAB2(SCH_1):P3V3_STBY
   2 FM_XRC_PRESENT_N      B @BASEBOARD_FAB2_LIB.BASEBOARD_FAB2(SCH_1):FM_XRC_PRESENT_N

RES_0402-1.00K,1%,1/16W,CHIP,GA  I282  R8B30
   1 P3V3_STBY      A @BASEBOARD_FAB2_LIB.BASEBOARD_FAB2(SCH_1):P3V3_STBY
   2 FM_XRC_READY_N      B @BASEBOARD_FAB2_LIB.BASEBOARD_FAB2(SCH_1):FM_XRC_READY_N

RES_0402-1.00K,1%,1/16W,CHIP,GA  I284  R2M4
   1 P3V3_STBY      A @BASEBOARD_FAB2_LIB.BASEBOARD_FAB2(SCH_1):P3V3_STBY
   2 IRQ_HSC_FAULT_N      B @BASEBOARD_FAB2_LIB.BASEBOARD_FAB2(SCH_1):IRQ_HSC_FAULT_N

RES_0402-1.00K,1%,1/16W,CHIP,GA  I286  R8C4
   1 P3V3_STBY      A @BASEBOARD_FAB2_LIB.BASEBOARD_FAB2(SCH_1):P3V3_STBY
   2 IRQ_BMC_PCH_SMI_LPC_N      B @BASEBOARD_FAB2_LIB.BASEBOARD_FAB2(SCH_1):IRQ_BMC_PCH_SMI_LPC_N

RES_0402-10.0K,1%,1/16W,CHIP,GA  I295  R7B6
   1 P3V3_STBY      A @BASEBOARD_FAB2_LIB.BASEBOARD_FAB2(SCH_1):P3V3_STBY
   2 FM_PCH_PRSNT_N      B @BASEBOARD_FAB2_LIB.BASEBOARD_FAB2(SCH_1):FM_PCH_PRSNT_N

RES_0402-10.0K,1%,1/16W,CHIP,GA  I296  R7C8
   1 P3V3_STBY      A @BASEBOARD_FAB2_LIB.BASEBOARD_FAB2(SCH_1):P3V3_STBY
   2 FM_WBG_PRSNT_N      B @BASEBOARD_FAB2_LIB.BASEBOARD_FAB2(SCH_1):FM_WBG_PRSNT_N

RES_0402-10.0K,1%,1/16W,CHIP,GA  I297  R7C5
   1 P3V3_STBY      A @BASEBOARD_FAB2_LIB.BASEBOARD_FAB2(SCH_1):P3V3_STBY
   2 FM_SINT_PRSNT_N      B @BASEBOARD_FAB2_LIB.BASEBOARD_FAB2(SCH_1):FM_SINT_PRSNT_N

RES_0402-4.75K,1%,1/16W,CHIP,GA  I301  R8D14
   1 P3V3_STBY      A @BASEBOARD_FAB2_LIB.BASEBOARD_FAB2(SCH_1):P3V3_STBY
   2 FP_PWR_ID_LED_N      B @BASEBOARD_FAB2_LIB.BASEBOARD_FAB2(SCH_1):FP_PWR_ID_LED_N

RES_0402-4.75K,1%,1/16W,CHIP,GA  I303  R8C6
   1 P3V3_STBY      A @BASEBOARD_FAB2_LIB.BASEBOARD_FAB2(SCH_1):P3V3_STBY
   2 FM_BIOS_POST_CMPLT_N      B @BASEBOARD_FAB2_LIB.BASEBOARD_FAB2(SCH_1):FM_BIOS_POST_CMPLT_N

RES_0402-4.75K,1%,1/16W,CHIP,GA  I304  R8C2
   1 P3V3_STBY      A @BASEBOARD_FAB2_LIB.BASEBOARD_FAB2(SCH_1):P3V3_STBY
   2 IRQ_BMC_PCH_SCI_LPC_N      B @BASEBOARD_FAB2_LIB.BASEBOARD_FAB2(SCH_1):IRQ_BMC_PCH_SCI_LPC_N

RES_0402-4.75K,1%,1/16W,CHIP,GA  I306  R7D6
   1 P3V3_STBY      A @BASEBOARD_FAB2_LIB.BASEBOARD_FAB2(SCH_1):P3V3_STBY
   2 FM_BMC_READY_N      B @BASEBOARD_FAB2_LIB.BASEBOARD_FAB2(SCH_1):FM_BMC_READY_N

RES_0402-4.75K,1%,1/16W,CHIP,GA  I307  R8B31
   1 P3V3_STBY      A @BASEBOARD_FAB2_LIB.BASEBOARD_FAB2(SCH_1):P3V3_STBY
   2 FM_THROTTLE_N      B @BASEBOARD_FAB2_LIB.BASEBOARD_FAB2(SCH_1):FM_THROTTLE_N

RES_0402-4.75K,1%,1/16W,CHIP,GA  I309  R2N7
   1 P3V3_STBY      A @BASEBOARD_FAB2_LIB.BASEBOARD_FAB2(SCH_1):P3V3_STBY
   2 IRQ_BOARD_BMC_ALERT_N      B @BASEBOARD_FAB2_LIB.BASEBOARD_FAB2(SCH_1):IRQ_BOARD_BMC_ALERT_N

RES_0402-1.00K,1%,1/16W,CHIP,GA  I322  R3P8
   1 P1V05_PCH_STBY      A @BASEBOARD_FAB2_LIB.BASEBOARD_FAB2(SCH_1):P1V05_PCH_STBY
   2 FM_PRSNT_2_6_N      B @BASEBOARD_FAB2_LIB.BASEBOARD_FAB2(SCH_1):FM_PRSNT_2_6_N

RES_0402-4.75K,1%,1/16W,CHIP,GA  I326  R8C1
   1 P3V3_STBY      A @BASEBOARD_FAB2_LIB.BASEBOARD_FAB2(SCH_1):P3V3_STBY
   2 FM_SLT_CFG1      B @BASEBOARD_FAB2_LIB.BASEBOARD_FAB2(SCH_1):FM_SLT_CFG1

RES_0402-4.75K,1%,1/16W,CHIP,GA  I327  R8C7
   1 P3V3_STBY      A @BASEBOARD_FAB2_LIB.BASEBOARD_FAB2(SCH_1):P3V3_STBY
   2 FM_SLT_CFG0      B @BASEBOARD_FAB2_LIB.BASEBOARD_FAB2(SCH_1):FM_SLT_CFG0

RES_0402-1.00K,1%,1/16W,CHIP,GA  I331  R7D7
   1 P3V3_STBY      A @BASEBOARD_FAB2_LIB.BASEBOARD_FAB2(SCH_1):P3V3_STBY
   2 IRQ_PIRQA_SPI_TPM_N      B @BASEBOARD_FAB2_LIB.BASEBOARD_FAB2(SCH_1):IRQ_PIRQA_SPI_TPM_N

RES_0402-1.00K,1%,1/16W,CHIP,GA  I332  R7D2
   1 P3V3_STBY      A @BASEBOARD_FAB2_LIB.BASEBOARD_FAB2(SCH_1):P3V3_STBY
   2 PU_FM_RCIN_N      B @BASEBOARD_FAB2_LIB.BASEBOARD_FAB2(SCH_1):PU_FM_RCIN_N

RES_0402-4.75K,1%,1/16W,CHIP,GA  I333  R8C25
   1 P3V3_STBY      A @BASEBOARD_FAB2_LIB.BASEBOARD_FAB2(SCH_1):P3V3_STBY
   2 IRQ_PCH_NIC_ALERT_N      B @BASEBOARD_FAB2_LIB.BASEBOARD_FAB2(SCH_1):IRQ_PCH_NIC_ALERT_N

RES_0402-4.75K,1%,1/16W,CHIP,GA  I341  R2N32
   1 P3V3_STBY      A @BASEBOARD_FAB2_LIB.BASEBOARD_FAB2(SCH_1):P3V3_STBY
   2 FM_BIOS_SMI_ACTIVE_N      B @BASEBOARD_FAB2_LIB.BASEBOARD_FAB2(SCH_1):FM_BIOS_SMI_ACTIVE_N

RES_0402-1.5K,1%,1/16W,CHIP,G2A  I349  R2M8
   1 P3V3_STBY      A @BASEBOARD_FAB2_LIB.BASEBOARD_FAB2(SCH_1):P3V3_STBY
   2 FM_CPU0_RC_ERROR_N      B @BASEBOARD_FAB2_LIB.BASEBOARD_FAB2(SCH_1):FM_CPU0_RC_ERROR_N

RES_0402-1.5K,1%,1/16W,CHIP,G2A  I352  R2N29
   1 P3V3_STBY      A @BASEBOARD_FAB2_LIB.BASEBOARD_FAB2(SCH_1):P3V3_STBY
   2 FM_CPU1_RC_ERROR_N      B @BASEBOARD_FAB2_LIB.BASEBOARD_FAB2(SCH_1):FM_CPU1_RC_ERROR_N

RES_0402-4.75K,1%,1/16W,CHIP,GA  I356  R7D44
   1 P1V05_PCH_STBY      A @BASEBOARD_FAB2_LIB.BASEBOARD_FAB2(SCH_1):P1V05_PCH_STBY
   2 FM_OCP_MEZZB_PRES_1V05_PCH_N      B @BASEBOARD_FAB2_LIB.BASEBOARD_FAB2(SCH_1):FM_OCP_MEZZB_PRES_1V05_PCH_N

RES_0402-10.0K,1%,1/16W,CHIP,GA  I360  R2P22
   1 P3V3_STBY      A @BASEBOARD_FAB2_LIB.BASEBOARD_FAB2(SCH_1):P3V3_STBY
   2 FM_CPU1_RC_EN      B @BASEBOARD_FAB2_LIB.BASEBOARD_FAB2(SCH_1):FM_CPU1_RC_EN

RES_0402-10.0K,1%,1/16W,CHIP,GA  I362  R8D44
   1 P3V3_STBY      A @BASEBOARD_FAB2_LIB.BASEBOARD_FAB2(SCH_1):P3V3_STBY
   2 FM_CPU0_RC_EN      B @BASEBOARD_FAB2_LIB.BASEBOARD_FAB2(SCH_1):FM_CPU0_RC_EN

RES_0402-4.75K,1%,1/16W,CHIP,GA  I365  R3P53
   1 P1V05_PCH_STBY      A @BASEBOARD_FAB2_LIB.BASEBOARD_FAB2(SCH_1):P1V05_PCH_STBY
   2 FM_OCP_MEZZC_PRES_1V05_PCH_N      B @BASEBOARD_FAB2_LIB.BASEBOARD_FAB2(SCH_1):FM_OCP_MEZZC_PRES_1V05_PCH_N

RES_0402-1.00K,1%,1/16W,EMPTY,A  I366  R3P5
   1 P1V05_PCH_STBY      A @BASEBOARD_FAB2_LIB.BASEBOARD_FAB2(SCH_1):P1V05_PCH_STBY
   2 FM_PRSNT_2_2_N      B @BASEBOARD_FAB2_LIB.BASEBOARD_FAB2(SCH_1):FM_PRSNT_2_2_N

RES_0402-1.00K,1%,1/16W,EMPTY,A  I367  R3P6
   1 P1V05_PCH_STBY      A @BASEBOARD_FAB2_LIB.BASEBOARD_FAB2(SCH_1):P1V05_PCH_STBY
   2 FM_PRSNT_2_3_N      B @BASEBOARD_FAB2_LIB.BASEBOARD_FAB2(SCH_1):FM_PRSNT_2_3_N

RES_0402-1.00K,1%,1/16W,EMPTY,A  I368  R3N15
   1 P1V05_PCH_STBY      A @BASEBOARD_FAB2_LIB.BASEBOARD_FAB2(SCH_1):P1V05_PCH_STBY
   2 FM_PRSNT_2_4_N      B @BASEBOARD_FAB2_LIB.BASEBOARD_FAB2(SCH_1):FM_PRSNT_2_4_N

RES_0402-1.00K,1%,1/16W,EMPTY,A  I369  R3N16
   1 P1V05_PCH_STBY      A @BASEBOARD_FAB2_LIB.BASEBOARD_FAB2(SCH_1):P1V05_PCH_STBY
   2 FM_PRSNT_2_5_N      B @BASEBOARD_FAB2_LIB.BASEBOARD_FAB2(SCH_1):FM_PRSNT_2_5_N

RES_0402-1.00K,1%,1/16W,EMPTY,A  I370  R3P7
   1 P1V05_PCH_STBY      A @BASEBOARD_FAB2_LIB.BASEBOARD_FAB2(SCH_1):P1V05_PCH_STBY
   2 FM_PRSNT_2_1_N      B @BASEBOARD_FAB2_LIB.BASEBOARD_FAB2(SCH_1):FM_PRSNT_2_1_N

RES_0402-4.75K,1%,1/16W,CHIP,GA  I371  R8E3
   1 P3V3_STBY      A @BASEBOARD_FAB2_LIB.BASEBOARD_FAB2(SCH_1):P3V3_STBY
   2 FM_TPM_PRES_N      B @BASEBOARD_FAB2_LIB.BASEBOARD_FAB2(SCH_1):FM_TPM_PRES_N


DRAWING: @BASEBOARD_FAB2_LIB.BASEBOARD_FAB2(SCH_1):PAGE134 

RES_0402-4.75K,1%,1/16W,CHIP,GA  I3  R2P17
   1 P3V3_STBY      A @BASEBOARD_FAB2_LIB.BASEBOARD_FAB2(SCH_1):P3V3_STBY
   2 FM_PCH_BMC_THERMTRIP_N      B @BASEBOARD_FAB2_LIB.BASEBOARD_FAB2(SCH_1):FM_PCH_BMC_THERMTRIP_N

RES_0402-10.0K,1%,1/16W,CHIP,GA  I9  R7C21
   1 P1V05_PCH_STBY      A @BASEBOARD_FAB2_LIB.BASEBOARD_FAB2(SCH_1):P1V05_PCH_STBY
   2 FM_PCH_LVC1_THERMTRIP_N      B @BASEBOARD_FAB2_LIB.BASEBOARD_FAB2(SCH_1):FM_PCH_LVC1_THERMTRIP_N

RES_0402-1.00K,1%,1/16W,CHIP,GA  I11  R7D18
   1 FM_THERMTRIP_DLY      A @BASEBOARD_FAB2_LIB.BASEBOARD_FAB2(SCH_1):FM_THERMTRIP_DLY
   2 FM_THERMTRIP_DLY_R      B @BASEBOARD_FAB2_LIB.BASEBOARD_FAB2(SCH_1):FM_THERMTRIP_DLY_R

FET_N_SOT23LF-2N7002,FET,C7925A  I14  Q7D1
   1 FM_THERMTRIP_DLY_R   GATE @BASEBOARD_FAB2_LIB.BASEBOARD_FAB2(SCH_1):FM_THERMTRIP_DLY_R
   2    GND    SRC @BASEBOARD_FAB2_LIB.BASEBOARD_FAB2(SCH_1):GND
   3 FM_PCH_LVC1_THERMTRIP_N    DRN @BASEBOARD_FAB2_LIB.BASEBOARD_FAB2(SCH_1):FM_PCH_LVC1_THERMTRIP_N

FET_N_SOT23LF-2N7002,FET,C7925A  I15  Q8D2
   1 RST_PLTRST_BUF_N   GATE @BASEBOARD_FAB2_LIB.BASEBOARD_FAB2(SCH_1):RST_PLTRST_BUF_N
   2 FM_PCH_BMC_THERMTRIP_EXI_STRAP_    SRC @BASEBOARD_FAB2_LIB.BASEBOARD_FAB2(SCH_1):FM_PCH_BMC_THERMTRIP_EXI_STRAP_N
   3 FM_PCH_BMC_THERMTRIP_N    DRN @BASEBOARD_FAB2_LIB.BASEBOARD_FAB2(SCH_1):FM_PCH_BMC_THERMTRIP_N


DRAWING: @BASEBOARD_FAB2_LIB.BASEBOARD_FAB2(SCH_1):PAGE135 

RES_0402-10.0K,1%,1/16W,CHIP,GA  I107  R2P19
   1 P3V3_STBY      A @BASEBOARD_FAB2_LIB.BASEBOARD_FAB2(SCH_1):P3V3_STBY
   2 FM_DIS_ADR_DLY      B @BASEBOARD_FAB2_LIB.BASEBOARD_FAB2(SCH_1):FM_DIS_ADR_DLY

RES_0402-10.0K,1%,1/16W,CHIP,GA  I112  R2N23
   1 P3V3_STBY      A @BASEBOARD_FAB2_LIB.BASEBOARD_FAB2(SCH_1):P3V3_STBY
   2 FM_QAT_EN_N      B @BASEBOARD_FAB2_LIB.BASEBOARD_FAB2(SCH_1):FM_QAT_EN_N

RES_0402-1.00K,1%,1/16W,EMPTY,A  I113  R2N24
   1 FM_QAT_EN_N      A @BASEBOARD_FAB2_LIB.BASEBOARD_FAB2(SCH_1):FM_QAT_EN_N
   2    GND      B @BASEBOARD_FAB2_LIB.BASEBOARD_FAB2(SCH_1):GND

RES_0402-2.21K,1%,1/16W,CHIP,GA  I117  R9A12
   1 FM_PCH_SATA_RAID_KEY_R      A @BASEBOARD_FAB2_LIB.BASEBOARD_FAB2(SCH_1):FM_PCH_SATA_RAID_KEY_R
   2 P3V3_STBY      B @BASEBOARD_FAB2_LIB.BASEBOARD_FAB2(SCH_1):P3V3_STBY

RES_0402-33.2,1%,1/16W,CHIP,G2A  I118  R9A13
   1 FM_PCH_SATA_RAID_KEY_R      A @BASEBOARD_FAB2_LIB.BASEBOARD_FAB2(SCH_1):FM_PCH_SATA_RAID_KEY_R
   2 FM_PCH_SATA_RAID_KEY      B @BASEBOARD_FAB2_LIB.BASEBOARD_FAB2(SCH_1):FM_PCH_SATA_RAID_KEY

RES_0402-1.00K,1%,1/16W,CHIP,GA  I120  R8D21
   1 P3V3_STBY      A @BASEBOARD_FAB2_LIB.BASEBOARD_FAB2(SCH_1):P3V3_STBY
   2 FM_IE_DISABLE_N      B @BASEBOARD_FAB2_LIB.BASEBOARD_FAB2(SCH_1):FM_IE_DISABLE_N

RES_0402-4.75K,1%,1/16W,CHIP,GA  I121  R7D30
   1 P3V3_STBY      A @BASEBOARD_FAB2_LIB.BASEBOARD_FAB2(SCH_1):P3V3_STBY
   2 FM_CPLD_UART_CH_LOCK_N      B @BASEBOARD_FAB2_LIB.BASEBOARD_FAB2(SCH_1):FM_CPLD_UART_CH_LOCK_N

CONN12_C73564003_PIP-CONN,C735A  I124  J8G2
   1 TP_JUMPER_BLOCK_1_1    IO1 @BASEBOARD_FAB2_LIB.BASEBOARD_FAB2(SCH_1):TP_JUMPER_BLOCK_1_1
  10 FM_DIS_ADR_DLY   IO10 @BASEBOARD_FAB2_LIB.BASEBOARD_FAB2(SCH_1):FM_DIS_ADR_DLY
  11    GND   IO11 @BASEBOARD_FAB2_LIB.BASEBOARD_FAB2(SCH_1):GND
  12    GND   IO12 @BASEBOARD_FAB2_LIB.BASEBOARD_FAB2(SCH_1):GND
   2 TP_JUMPER_BLOCK_1_2    IO2 @BASEBOARD_FAB2_LIB.BASEBOARD_FAB2(SCH_1):TP_JUMPER_BLOCK_1_2
   3 RST_BMC_SRST_N    IO3 @BASEBOARD_FAB2_LIB.BASEBOARD_FAB2(SCH_1):RST_BMC_SRST_N
   4 FM_IE_DISABLE_N    IO4 @BASEBOARD_FAB2_LIB.BASEBOARD_FAB2(SCH_1):FM_IE_DISABLE_N
   5    GND    IO5 @BASEBOARD_FAB2_LIB.BASEBOARD_FAB2(SCH_1):GND
   6    GND    IO6 @BASEBOARD_FAB2_LIB.BASEBOARD_FAB2(SCH_1):GND
   7 TP_JUMPER_BLOCK_1_7    IO7 @BASEBOARD_FAB2_LIB.BASEBOARD_FAB2(SCH_1):TP_JUMPER_BLOCK_ 1_7
   8 TP_JUMPER_BLOCK_1_8    IO8 @BASEBOARD_FAB2_LIB.BASEBOARD_FAB2(SCH_1):TP_JUMPER_BLOCK_1_8
   9 FM_CPLD_UART_CH_LOCK_N    IO9 @BASEBOARD_FAB2_LIB.BASEBOARD_FAB2(SCH_1):FM_CPLD_UART_CH_LOCK_N

RES_0402-2.21K,1%,1/16W,CHIP,GA  I129  R9A16
   1 PU_KEY_CONN_PIN2_R      A @BASEBOARD_FAB2_LIB.BASEBOARD_FAB2(SCH_1):PU_KEY_CONN_PIN2_R
   2 P3V3_STBY      B @BASEBOARD_FAB2_LIB.BASEBOARD_FAB2(SCH_1):P3V3_STBY

CONN4_D42317002_PIP-CONN,D4231A  I131  J9A1
   1    GND    IO1 @BASEBOARD_FAB2_LIB.BASEBOARD_FAB2(SCH_1):GND
   2 PU_KEY_CONN_PIN2_R    IO2 @BASEBOARD_FAB2_LIB.BASEBOARD_FAB2(SCH_1):PU_KEY_CONN_PIN2_R
   3    GND    IO3 @BASEBOARD_FAB2_LIB.BASEBOARD_FAB2(SCH_1):GND
   4 FM_PCH_SATA_RAID_KEY_R    IO4 @BASEBOARD_FAB2_LIB.BASEBOARD_FAB2(SCH_1):FM_PCH_SATA_RAID_KEY_R


DRAWING: @BASEBOARD_FAB2_LIB.BASEBOARD_FAB2(SCH_1):PAGE136 

RES_0402-10.0K,1%,1/16W,CHIP,GA  I101  R7G26
   1 P3V3_STBY      A @BASEBOARD_FAB2_LIB.BASEBOARD_FAB2(SCH_1):P3V3_STBY
   2 FM_ME_RECOVER_N      B @BASEBOARD_FAB2_LIB.BASEBOARD_FAB2(SCH_1):FM_ME_RECOVER_N

RES_0402-1.00K,1%,1/16W,CHIP,GA  I102  R7G28
   1 PD_ME_RCVR_N      A @BASEBOARD_FAB2_LIB.BASEBOARD_FAB2(SCH_1):PD_ME_RCVR_N
   2    GND      B @BASEBOARD_FAB2_LIB.BASEBOARD_FAB2(SCH_1):GND

RES_0402-33.2,1%,1/16W,CHIP,G2A  I126  R8E20
   1 FM_BIOS_TOP_SWAP_SPKR_R      A @BASEBOARD_FAB2_LIB.BASEBOARD_FAB2(SCH_1):FM_BIOS_TOP_SWAP_SPKR_R
   2 FM_BIOS_TOP_SWAP_SPKR      B @BASEBOARD_FAB2_LIB.BASEBOARD_FAB2(SCH_1):FM_BIOS_TOP_SWAP_SPKR

CAP_A_0402V-0.1UF,16V,10%,X7R,A  I128  C8E8
   1 P3V3_STBY      A @BASEBOARD_FAB2_LIB.BASEBOARD_FAB2(SCH_1):P3V3_STBY
   2    GND      B @BASEBOARD_FAB2_LIB.BASEBOARD_FAB2(SCH_1):GND

TTL1G126_A_SOT-74HC1G126,IC,A7B  I130  U8E3
   1 RST_PLTRST_TOP_SWAP     OE @BASEBOARD_FAB2_LIB.BASEBOARD_FAB2(SCH_1):RST_PLTRST_TOP_SWAP
   2 FM_BIOS_TOP_SWAP      A @BASEBOARD_FAB2_LIB.BASEBOARD_FAB2(SCH_1):FM_BIOS_TOP_SWAP
   4 FM_BIOS_TOP_SWAP_SPKR_R      Y @BASEBOARD_FAB2_LIB.BASEBOARD_FAB2(SCH_1):FM_BIOS_TOP_SWAP_SPKR_R

RES_0402-4.75K,1%,1/16W,CHIP,GA  I133  R8E14
   1 P3V3_STBY      A @BASEBOARD_FAB2_LIB.BASEBOARD_FAB2(SCH_1):P3V3_STBY
   2 RST_PLTRST_TOP_SWAP      B @BASEBOARD_FAB2_LIB.BASEBOARD_FAB2(SCH_1):RST_PLTRST_TOP_SWAP

FET_N_SOT23LF-2N7002,FET,C7925A  I134  Q8E1
   1 RST_PLTRST_N   GATE @BASEBOARD_FAB2_LIB.BASEBOARD_FAB2(SCH_1):RST_PLTRST_N
   2    GND    SRC @BASEBOARD_FAB2_LIB.BASEBOARD_FAB2(SCH_1):GND
   3 RST_PLTRST_TOP_SWAP    DRN @BASEBOARD_FAB2_LIB.BASEBOARD_FAB2(SCH_1):RST_PLTRST_TOP_SWAP

RES_0402-1.00K,1%,1/16W,CHIP,GA  I139  R7G31
   1 P3V3_STBY      A @BASEBOARD_FAB2_LIB.BASEBOARD_FAB2(SCH_1):P3V3_STBY
   2 PU_BIOS_RECOVER_BOOT      B @BASEBOARD_FAB2_LIB.BASEBOARD_FAB2(SCH_1):PU_BIOS_RECOVER_BOOT

RES_0402-20.0K,1%,1/16W,CHIP,GA  I140  R8E16
   1 FM_BIOS_TOP_SWAP      A @BASEBOARD_FAB2_LIB.BASEBOARD_FAB2(SCH_1):FM_BIOS_TOP_SWAP
   2    GND      B @BASEBOARD_FAB2_LIB.BASEBOARD_FAB2(SCH_1):GND

RES_0402-10.0K,1%,1/16W,CHIP,GA  I147  R2N28
   1 P3V3_STBY      A @BASEBOARD_FAB2_LIB.BASEBOARD_FAB2(SCH_1):P3V3_STBY
   2 FM_PASSWORD_CLEAR_N      B @BASEBOARD_FAB2_LIB.BASEBOARD_FAB2(SCH_1):FM_PASSWORD_CLEAR_N

RES_0402-1.00K,1%,1/16W,CHIP,GA  I148  R7G29
   1 PD_PASSWORD_CLEAR      A @BASEBOARD_FAB2_LIB.BASEBOARD_FAB2(SCH_1):PD_PASSWORD_CLEAR
   2    GND      B @BASEBOARD_FAB2_LIB.BASEBOARD_FAB2(SCH_1):GND

RES_0402-1.00K,1%,1/16W,CHIP,GA  I155  R7G27
   1 P3V3_STBY      A @BASEBOARD_FAB2_LIB.BASEBOARD_FAB2(SCH_1):P3V3_STBY
   2 PU_BIOS_USB_RECOVERY      B @BASEBOARD_FAB2_LIB.BASEBOARD_FAB2(SCH_1):PU_BIOS_USB_RECOVERY

RES_0402-10.0K,1%,1/16W,CHIP,GA  I156  R3T14
   1 FM_BIOS_USB_RECOVERY      A @BASEBOARD_FAB2_LIB.BASEBOARD_FAB2(SCH_1):FM_BIOS_USB_RECOVERY
   2    GND      B @BASEBOARD_FAB2_LIB.BASEBOARD_FAB2(SCH_1):GND

CONN12_C73564003_PIP-CONN,C735A  I174  J7G3
   1 TP_ME_RCVR_BOOT    IO1 @BASEBOARD_FAB2_LIB.BASEBOARD_FAB2(SCH_1):TP_ME_RCVR_BOOT
  10 FM_BIOS_TOP_SWAP   IO10 @BASEBOARD_FAB2_LIB.BASEBOARD_FAB2(SCH_1):FM_BIOS_TOP_SWAP
  11 PD_PASSWORD_CLEAR   IO11 @BASEBOARD_FAB2_LIB.BASEBOARD_FAB2(SCH_1):PD_PASSWORD_CLEAR
  12 PU_BIOS_RECOVER_BOOT   IO12 @BASEBOARD_FAB2_LIB.BASEBOARD_FAB2(SCH_1):PU_BIOS_RECOVER_BOOT
   2 TP_BIOS_USB_RECOVERY    IO2 @BASEBOARD_FAB2_LIB.BASEBOARD_FAB2(SCH_1):TP_BIOS_USB_RECOVERY
   3 FM_ME_RECOVER_N    IO3 @BASEBOARD_FAB2_LIB.BASEBOARD_FAB2(SCH_1):FM_ME_RECOVER_N
   4 FM_BIOS_USB_RECOVERY    IO4 @BASEBOARD_FAB2_LIB.BASEBOARD_FAB2(SCH_1):FM_BIOS_USB_RECOVERY
   5 PD_ME_RCVR_N    IO5 @BASEBOARD_FAB2_LIB.BASEBOARD_FAB2(SCH_1):PD_ME_RCVR_N
   6 PU_BIOS_USB_RECOVERY    IO6 @BASEBOARD_FAB2_LIB.BASEBOARD_FAB2(SCH_1):PU_BIOS_USB_RECOVERY
   7 TP_PASSWORD_CLEAR    IO7 @BASEBOARD_FAB2_LIB.BASEBOARD_FAB2(SCH_1):TP_PASSWORD_CLEAR
   8 TP_BIOS_RECOVER_BOOT    IO8 @BASEBOARD_FAB2_LIB.BASEBOARD_FAB2(SCH_1):TP_BIOS_RECOVER_BOOT
   9 FM_PASSWORD_CLEAR_N    IO9 @BASEBOARD_FAB2_LIB.BASEBOARD_FAB2(SCH_1):FM_PASSWORD_CLEAR_N


DRAWING: @BASEBOARD_FAB2_LIB.BASEBOARD_FAB2(SCH_1):PAGE137 

RES_0402-1.0M,1%,1/16W,EMPTY,GA  I11  R7C11
   1    GND      A @BASEBOARD_FAB2_LIB.BASEBOARD_FAB2(SCH_1):GND
   2 RST_RTCRST_N      B @BASEBOARD_FAB2_LIB.BASEBOARD_FAB2(SCH_1):RST_RTCRST_N

RES_0402-20.0K,1%,1/16W,CHIP,GA  I13  R7C10
   1 P3V3_RTC_STBY      A @BASEBOARD_FAB2_LIB.BASEBOARD_FAB2(SCH_1):P3V3_RTC_STBY
   2 RST_RTCRST_N      B @BASEBOARD_FAB2_LIB.BASEBOARD_FAB2(SCH_1):RST_RTCRST_N

CAP_A_0402V-1.0UF,6.3V,10%,X6SA  I14  C7C19
   1 RST_RTCRST_N      A @BASEBOARD_FAB2_LIB.BASEBOARD_FAB2(SCH_1):RST_RTCRST_N
   2    GND      B @BASEBOARD_FAB2_LIB.BASEBOARD_FAB2(SCH_1):GND

RES_0402-1.00K,1%,1/16W,CHIP,GA  I15  R1U63
   1 PD_RST_RTCRST_N      A @BASEBOARD_FAB2_LIB.BASEBOARD_FAB2(SCH_1):PD_RST_RTCRST_N
   2    GND      B @BASEBOARD_FAB2_LIB.BASEBOARD_FAB2(SCH_1):GND

RES_0402-20.0K,1%,1/16W,CHIP,GA  I19  R3N4
   1 P3V3_RTC_STBY      A @BASEBOARD_FAB2_LIB.BASEBOARD_FAB2(SCH_1):P3V3_RTC_STBY
   2 RST_SRTCRST_N      B @BASEBOARD_FAB2_LIB.BASEBOARD_FAB2(SCH_1):RST_SRTCRST_N

CAP_A_0402V-1.0UF,6.3V,10%,X6SA  I20  C3N32
   1 RST_SRTCRST_N      A @BASEBOARD_FAB2_LIB.BASEBOARD_FAB2(SCH_1):RST_SRTCRST_N
   2    GND      B @BASEBOARD_FAB2_LIB.BASEBOARD_FAB2(SCH_1):GND

RES_0402-10.0K,1%,1/16W,CHIP,GA  I67  R7C13
   1 P3V3_STBY      A @BASEBOARD_FAB2_LIB.BASEBOARD_FAB2(SCH_1):P3V3_STBY
   2 FM_UART_PRES_N      B @BASEBOARD_FAB2_LIB.BASEBOARD_FAB2(SCH_1):FM_UART_PRES_N

RES_0402-1.00K,1%,1/16W,CHIP,GA  I69  R1U64
   1 PD_IE_DEBUG_MODE      A @BASEBOARD_FAB2_LIB.BASEBOARD_FAB2(SCH_1):PD_IE_DEBUG_MODE
   2    GND      B @BASEBOARD_FAB2_LIB.BASEBOARD_FAB2(SCH_1):GND

CONN12_C73564003_PIP-CONN,C735A  I128  J9G1
   1 PU_UV_HIGH_SET    IO1 @BASEBOARD_FAB2_LIB.BASEBOARD_FAB2(SCH_1):PU_UV_HIGH_SET
  10 SPI_BMC_BT_CS0_N   IO10 @BASEBOARD_FAB2_LIB.BASEBOARD_FAB2(SCH_1):SPI_BMC_BT_CS0_N
  11 PD_IE_DEBUG_MODE   IO11 @BASEBOARD_FAB2_LIB.BASEBOARD_FAB2(SCH_1):PD_IE_DEBUG_MODE
  12 PD_SPI_BMC_BT_CS0_N   IO12 @BASEBOARD_FAB2_LIB.BASEBOARD_FAB2(SCH_1):PD_SPI_BMC_BT_CS0_N
   2 TP_RST_RTCRST_N    IO2 @BASEBOARD_FAB2_LIB.BASEBOARD_FAB2(SCH_1):TP_RST_RTCRST_N
   3 UV_HIGH_SET    IO3 @BASEBOARD_FAB2_LIB.BASEBOARD_FAB2(SCH_1):UV_HIGH_SET
   4 RST_RTCRST_N    IO4 @BASEBOARD_FAB2_LIB.BASEBOARD_FAB2(SCH_1):RST_RTCRST_N
   5 PD_UV_HIGH_SET    IO5 @BASEBOARD_FAB2_LIB.BASEBOARD_FAB2(SCH_1):PD_UV_HIGH_SET
   6 PD_RST_RTCRST_N    IO6 @BASEBOARD_FAB2_LIB.BASEBOARD_FAB2(SCH_1):PD_RST_RTCRST_N
   7 TP_IE_DEBUG_MODE    IO7 @BASEBOARD_FAB2_LIB.BASEBOARD_FAB2(SCH_1):TP_IE_DEBUG_MODE
   8 PU_SPI_BMC_BT_CS0_N    IO8 @BASEBOARD_FAB2_LIB.BASEBOARD_FAB2(SCH_1):PU_SPI_BMC_BT_CS0_N
   9 FM_UART_PRES_N    IO9 @BASEBOARD_FAB2_LIB.BASEBOARD_FAB2(SCH_1):FM_UART_PRES_N

RES_0402-0.0,5%,1/16W,CHIP,G21A  I133  R25W154
   1 SPI_BMC_BT_WP0_N      A @BASEBOARD_FAB2_LIB.BASEBOARD_FAB2(SCH_1):SPI_BMC_BT_WP0_N
   2 TPM_SPI_BMC_WP_N      B @BASEBOARD_FAB2_LIB.BASEBOARD_FAB2(SCH_1):TPM_SPI_BMC_WP_N

RES_0402-4.75K,1%,1/16W,CHIP,GA  I140  R25W94
   1    GND      A @BASEBOARD_FAB2_LIB.BASEBOARD_FAB2(SCH_1):GND
   2 PD_SPI_BMC_BT_CS0_N      B @BASEBOARD_FAB2_LIB.BASEBOARD_FAB2(SCH_1):PD_SPI_BMC_BT_CS0_N

RES_0402-4.75K,1%,1/16W,CHIP,GA  I142  RN8F1
   1 P3V3_STBY      A @BASEBOARD_FAB2_LIB.BASEBOARD_FAB2(SCH_1):P3V3_STBY
   2 PU_SPI_BMC_BT_CS0_N      B @BASEBOARD_FAB2_LIB.BASEBOARD_FAB2(SCH_1):PU_SPI_BMC_BT_CS0_N

RES_0402-10.0K,1%,1/16W,CHIP,GA  I144  R6W2
   1 PD_UV_HIGH_SET      A @BASEBOARD_FAB2_LIB.BASEBOARD_FAB2(SCH_1):PD_UV_HIGH_SET
   2    GND      B @BASEBOARD_FAB2_LIB.BASEBOARD_FAB2(SCH_1):GND

RES_0402-4.75K,1%,1/16W,CHIP,GA  I149  R6W1
   1 P3V3_STBY      A @BASEBOARD_FAB2_LIB.BASEBOARD_FAB2(SCH_1):P3V3_STBY
   2 PU_UV_HIGH_SET      B @BASEBOARD_FAB2_LIB.BASEBOARD_FAB2(SCH_1):PU_UV_HIGH_SET


DRAWING: @BASEBOARD_FAB2_LIB.BASEBOARD_FAB2(SCH_1):PAGE138 

RES_0402-665,1.0%,1/16W,CHIP,GA  I83  R2T53
   1 P3V3_STBY      A @BASEBOARD_FAB2_LIB.BASEBOARD_FAB2(SCH_1):P3V3_STBY
   2 SMB_BMC_PMBUS_STBY_LVC3_SDA      B @BASEBOARD_FAB2_LIB.BASEBOARD_FAB2(SCH_1):SMB_BMC_PMBUS_STBY_LVC3_SDA

RES_0402-665,1.0%,1/16W,CHIP,GA  I84  R2T54
   1 P3V3_STBY      A @BASEBOARD_FAB2_LIB.BASEBOARD_FAB2(SCH_1):P3V3_STBY
   2 SMB_BMC_PMBUS_STBY_LVC3_SCL      B @BASEBOARD_FAB2_LIB.BASEBOARD_FAB2(SCH_1):SMB_BMC_PMBUS_STBY_LVC3_SCL

RES_0402-1.37K,1%,1/16W,CHIP,GA  I87  R8D17
   1 P3V3_STBY      A @BASEBOARD_FAB2_LIB.BASEBOARD_FAB2(SCH_1):P3V3_STBY
   2 SMB_VR_STBY_LVC3_SDA      B @BASEBOARD_FAB2_LIB.BASEBOARD_FAB2(SCH_1):SMB_VR_STBY_LVC3_SDA

RES_0402-1.37K,1%,1/16W,CHIP,GA  I88  R8D15
   1 P3V3_STBY      A @BASEBOARD_FAB2_LIB.BASEBOARD_FAB2(SCH_1):P3V3_STBY
   2 SMB_VR_STBY_LVC3_SCL      B @BASEBOARD_FAB2_LIB.BASEBOARD_FAB2(SCH_1):SMB_VR_STBY_LVC3_SCL

RES_0402-665,1.0%,1/16W,CHIP,GA  I89  R2N8
   1 P3V3_STBY      A @BASEBOARD_FAB2_LIB.BASEBOARD_FAB2(SCH_1):P3V3_STBY
   2 SMB_SMLINK0_STBY_LVC3_SDA      B @BASEBOARD_FAB2_LIB.BASEBOARD_FAB2(SCH_1):SMB_SMLINK0_STBY_LVC3_SDA

RES_0402-665,1.0%,1/16W,CHIP,GA  I90  R2N5
   1 P3V3_STBY      A @BASEBOARD_FAB2_LIB.BASEBOARD_FAB2(SCH_1):P3V3_STBY
   2 SMB_SMLINK0_STBY_LVC3_SCL      B @BASEBOARD_FAB2_LIB.BASEBOARD_FAB2(SCH_1):SMB_SMLINK0_STBY_LVC3_SCL

RES_0402-665,1.0%,1/16W,CHIP,GA  I97  R2U11
   1 P3V3_STBY      A @BASEBOARD_FAB2_LIB.BASEBOARD_FAB2(SCH_1):P3V3_STBY
   2 SMB_LAN_STBY_LVC3_SDA      B @BASEBOARD_FAB2_LIB.BASEBOARD_FAB2(SCH_1):SMB_LAN_STBY_LVC3_SDA

RES_0402-665,1.0%,1/16W,CHIP,GA  I98  R2U3
   1 P3V3_STBY      A @BASEBOARD_FAB2_LIB.BASEBOARD_FAB2(SCH_1):P3V3_STBY
   2 SMB_LAN_STBY_LVC3_SCL      B @BASEBOARD_FAB2_LIB.BASEBOARD_FAB2(SCH_1):SMB_LAN_STBY_LVC3_SCL

RES_0402-20.0,1%,1/16W,EMPTY,GA  I158  R2U8
   1 SMB_LAN_STBY_LVC3_SCL      A @BASEBOARD_FAB2_LIB.BASEBOARD_FAB2(SCH_1):SMB_LAN_STBY_LVC3_SCL
   2 SMB_OCP_FRU_STBY_LVC3_SCL      B @BASEBOARD_FAB2_LIB.BASEBOARD_FAB2(SCH_1):SMB_OCP_FRU_STBY_LVC3_SCL

RES_0402-20.0,1%,1/16W,EMPTY,GA  I159  R2U12
   1 SMB_LAN_STBY_LVC3_SDA      A @BASEBOARD_FAB2_LIB.BASEBOARD_FAB2(SCH_1):SMB_LAN_STBY_LVC3_SDA
   2 SMB_OCP_FRU_STBY_LVC3_SDA      B @BASEBOARD_FAB2_LIB.BASEBOARD_FAB2(SCH_1):SMB_OCP_FRU_STBY_LVC3_SDA

RES_0402-20.0,1%,1/16W,CHIP,G2A  I163  R8D7
   1 SMB_VR_STBY_LVC3_SDA_R1      A @BASEBOARD_FAB2_LIB.BASEBOARD_FAB2(SCH_1):SMB_VR_STBY_LVC3_SDA_R1
   2 SMB_VR_STBY_LVC3_SDA      B @BASEBOARD_FAB2_LIB.BASEBOARD_FAB2(SCH_1):SMB_VR_STBY_LVC3_SDA

RES_0402-20.0,1%,1/16W,CHIP,G2A  I164  R8D4
   1 SMB_VR_STBY_LVC3_SCL_R1      A @BASEBOARD_FAB2_LIB.BASEBOARD_FAB2(SCH_1):SMB_VR_STBY_LVC3_SCL_R1
   2 SMB_VR_STBY_LVC3_SCL      B @BASEBOARD_FAB2_LIB.BASEBOARD_FAB2(SCH_1):SMB_VR_STBY_LVC3_SCL

RES_0402-20.0,1%,1/16W,CHIP,G2A  I165  R2U9
   1 SMB_LAN_STBY_LVC3_SDA_R1      A @BASEBOARD_FAB2_LIB.BASEBOARD_FAB2(SCH_1):SMB_LAN_STBY_LVC3_SDA_R1
   2 SMB_LAN_STBY_LVC3_SDA      B @BASEBOARD_FAB2_LIB.BASEBOARD_FAB2(SCH_1):SMB_LAN_STBY_LVC3_SDA

RES_0402-20.0,1%,1/16W,CHIP,G2A  I166  R2U6
   1 SMB_LAN_STBY_LVC3_SCL_R1      A @BASEBOARD_FAB2_LIB.BASEBOARD_FAB2(SCH_1):SMB_LAN_STBY_LVC3_SCL_R1
   2 SMB_LAN_STBY_LVC3_SCL      B @BASEBOARD_FAB2_LIB.BASEBOARD_FAB2(SCH_1):SMB_LAN_STBY_LVC3_SCL

RES_0402-20.0,1%,1/16W,CHIP,G2A  I167  R8C20
   1 SMB_HOST_STBY_LVC3_SDA_R1      A @BASEBOARD_FAB2_LIB.BASEBOARD_FAB2(SCH_1):SMB_HOST_STBY_LVC3_SDA_R1
   2 SMB_HOST_STBY_LVC3_SDA      B @BASEBOARD_FAB2_LIB.BASEBOARD_FAB2(SCH_1):SMB_HOST_STBY_LVC3_SDA

RES_0402-20.0,1%,1/16W,CHIP,G2A  I168  R8C14
   1 SMB_HOST_STBY_LVC3_SCL_R1      A @BASEBOARD_FAB2_LIB.BASEBOARD_FAB2(SCH_1):SMB_HOST_STBY_LVC3_SCL_R1
   2 SMB_HOST_STBY_LVC3_SCL      B @BASEBOARD_FAB2_LIB.BASEBOARD_FAB2(SCH_1):SMB_HOST_STBY_LVC3_SCL

RES_0402-20.0,1%,1/16W,CHIP,G2A  I169  R8C11
   1 SMB_SMLINK0_STBY_LVC3_SDA_R1      A @BASEBOARD_FAB2_LIB.BASEBOARD_FAB2(SCH_1):SMB_SMLINK0_STBY_LVC3_SDA_R1
   2 SMB_SMLINK0_STBY_LVC3_SDA      B @BASEBOARD_FAB2_LIB.BASEBOARD_FAB2(SCH_1):SMB_SMLINK0_STBY_LVC3_SDA

RES_0402-20.0,1%,1/16W,CHIP,G2A  I170  R8C12
   1 SMB_SMLINK0_STBY_LVC3_SCL_R1      A @BASEBOARD_FAB2_LIB.BASEBOARD_FAB2(SCH_1):SMB_SMLINK0_STBY_LVC3_SCL_R1
   2 SMB_SMLINK0_STBY_LVC3_SCL      B @BASEBOARD_FAB2_LIB.BASEBOARD_FAB2(SCH_1):SMB_SMLINK0_STBY_LVC3_SCL

RES_0402-0.0,5%,1/16W,CHIP,G21A  I171  R2N20
   1 SMB_LAN_STBY_LVC3_SDA_R2      A @BASEBOARD_FAB2_LIB.BASEBOARD_FAB2(SCH_1):SMB_LAN_STBY_LVC3_SDA_R2
   2 SMB_LAN_STBY_LVC3_SDA      B @BASEBOARD_FAB2_LIB.BASEBOARD_FAB2(SCH_1):SMB_LAN_STBY_LVC3_SDA

RES_0402-0.0,5%,1/16W,CHIP,G21A  I175  R2N21
   1 SMB_LAN_STBY_LVC3_SCL_R2      A @BASEBOARD_FAB2_LIB.BASEBOARD_FAB2(SCH_1):SMB_LAN_STBY_LVC3_SCL_R2
   2 SMB_LAN_STBY_LVC3_SCL      B @BASEBOARD_FAB2_LIB.BASEBOARD_FAB2(SCH_1):SMB_LAN_STBY_LVC3_SCL

RES_0402-3.3K,5%,1/16W,CHIP,G2A  I186  R8B24
   1 P3V3_STBY      A @BASEBOARD_FAB2_LIB.BASEBOARD_FAB2(SCH_1):P3V3_STBY
   2 SMB_HOST_STBY_LVC3_SDA_R5      B @BASEBOARD_FAB2_LIB.BASEBOARD_FAB2(SCH_1):SMB_HOST_STBY_LVC3_SDA_R5

RES_0402-3.3K,5%,1/16W,CHIP,G2A  I187  R8B26
   1 P3V3_STBY      A @BASEBOARD_FAB2_LIB.BASEBOARD_FAB2(SCH_1):P3V3_STBY
   2 SMB_HOST_STBY_LVC3_SCL_R5      B @BASEBOARD_FAB2_LIB.BASEBOARD_FAB2(SCH_1):SMB_HOST_STBY_LVC3_SCL_R5

RES_0402-20.0,1%,1/16W,CHIP,G2A  I194  R8W5
   1 SMB_HOST_STBY_LVC3_SCL      A @BASEBOARD_FAB2_LIB.BASEBOARD_FAB2(SCH_1):SMB_HOST_STBY_LVC3_SCL
   2 SMB_HOST_STBY_LVC3_SCL_R5      B @BASEBOARD_FAB2_LIB.BASEBOARD_FAB2(SCH_1):SMB_HOST_STBY_LVC3_SCL_R5

RES_0402-20.0,1%,1/16W,CHIP,G2A  I195  R8W4
   1 SMB_HOST_STBY_LVC3_SDA      A @BASEBOARD_FAB2_LIB.BASEBOARD_FAB2(SCH_1):SMB_HOST_STBY_LVC3_SDA
   2 SMB_HOST_STBY_LVC3_SDA_R5      B @BASEBOARD_FAB2_LIB.BASEBOARD_FAB2(SCH_1):SMB_HOST_STBY_LVC3_SDA_R5

RES_0402-3.3K,5%,1/16W,CHIP,G2A  I198  R24W1
   1 P3V3_STBY      A @BASEBOARD_FAB2_LIB.BASEBOARD_FAB2(SCH_1):P3V3_STBY
   2 SMB_SLOTX24_PCH_STBY_LVC3_SDA      B @BASEBOARD_FAB2_LIB.BASEBOARD_FAB2(SCH_1):SMB_SLOTX24_PCH_STBY_LVC3_SDA

RES_0402-3.3K,5%,1/16W,CHIP,G2A  I199  R24W2
   1 P3V3_STBY      A @BASEBOARD_FAB2_LIB.BASEBOARD_FAB2(SCH_1):P3V3_STBY
   2 SMB_SLOTX24_PCH_STBY_LVC3_SCL      B @BASEBOARD_FAB2_LIB.BASEBOARD_FAB2(SCH_1):SMB_SLOTX24_PCH_STBY_LVC3_SCL

RES_0402-1.37K,1%,1/16W,CHIP,GA  I202  R8W7
   1 P3V3_STBY      A @BASEBOARD_FAB2_LIB.BASEBOARD_FAB2(SCH_1):P3V3_STBY
   2 SMB_VR_STBY_LVC3_SCL_R1      B @BASEBOARD_FAB2_LIB.BASEBOARD_FAB2(SCH_1):SMB_VR_STBY_LVC3_SCL_R1

RES_0402-1.37K,1%,1/16W,CHIP,GA  I205  R8W6
   1 P3V3_STBY      A @BASEBOARD_FAB2_LIB.BASEBOARD_FAB2(SCH_1):P3V3_STBY
   2 SMB_VR_STBY_LVC3_SDA_R1      B @BASEBOARD_FAB2_LIB.BASEBOARD_FAB2(SCH_1):SMB_VR_STBY_LVC3_SDA_R1


DRAWING: @BASEBOARD_FAB2_LIB.BASEBOARD_FAB2(SCH_1):PAGE139 

SPRINGVILLE_SM1-IC,G47144-004  I72  EU9E1
  37 A_CBOT   CBOT @BASEBOARD_FAB2_LIB.BASEBOARD_FAB2(SCH_1):A_CBOT
  40 A_CTOP   CTOP @BASEBOARD_FAB2_LIB.BASEBOARD_FAB2(SCH_1):A_CTOP
  28 PU_DEV_OFF_N DEV_OFF_N @BASEBOARD_FAB2_LIB.BASEBOARD_FAB2(SCH_1):PU_DEV_OFF_N
  65    GND    GND @BASEBOARD_FAB2_LIB.BASEBOARD_FAB2(SCH_1):GND
  19 PU_JTAG_SPRV_TCK JTAG_CLK @BASEBOARD_FAB2_LIB.BASEBOARD_FAB2(SCH_1):PU_JTAG_SPRV_TCK
  29 PU_JTAG_SPRV_TDI JTAG_TDI @BASEBOARD_FAB2_LIB.BASEBOARD_FAB2(SCH_1):PU_JTAG_SPRV_TDI
   4 PU_JTAG_SPRV_TDO JTAG_TDO @BASEBOARD_FAB2_LIB.BASEBOARD_FAB2(SCH_1):PU_JTAG_SPRV_TDO
  18 PU_JTAG_SPRV_TMS JTAG_TMS @BASEBOARD_FAB2_LIB.BASEBOARD_FAB2(SCH_1):PU_JTAG_SPRV_TMS
   1 PU_SPRV_LAN_PWR_GOOD LAN_PWR_GOOD @BASEBOARD_FAB2_LIB.BASEBOARD_FAB2(SCH_1):PU_SPRV_LAN_PWR_GOOD
  31 LED_LAN_0_N   LED0 @BASEBOARD_FAB2_LIB.BASEBOARD_FAB2(SCH_1):LED_LAN_0_N
  30 LED_LAN_1_N   LED1 @BASEBOARD_FAB2_LIB.BASEBOARD_FAB2(SCH_1):LED_LAN_1_N
  33 LED_LAN_2_N   LED2 @BASEBOARD_FAB2_LIB.BASEBOARD_FAB2(SCH_1):LED_LAN_2_N
  57 NIC_MDI_SPRV_RJ45_0_DN MDI_MINUS0_SFP_I2C_DATA @BASEBOARD_FAB2_LIB.BASEBOARD_FAB2(SCH_1):NIC_MDI_SPRV_RJ45_0_DN
  54 NIC_MDI_SPRV_RJ45_1_DN MDI_MINUS1_SRDS_SIG_DET @BASEBOARD_FAB2_LIB.BASEBOARD_FAB2(SCH_1):NIC_MDI_SPRV_RJ45_1_DN
  52 NIC_SET_N_MDI_2_DN MDI_MINUS2_SETN @BASEBOARD_FAB2_LIB.BASEBOARD_FAB2(SCH_1):NIC_SET_N_MDI_2_DN
  49 NIC_SER_N_MDI_3_DN MDI_MINUS3_SERN @BASEBOARD_FAB2_LIB.BASEBOARD_FAB2(SCH_1):NIC_SER_N_MDI_3_DN
  58 NIC_MDI_SPRV_RJ45_0_DP MDI_PLUS0_NC @BASEBOARD_FAB2_LIB.BASEBOARD_FAB2(SCH_1):NIC_MDI_SPRV_RJ45_0_DP
  55 NIC_MDI_SPRV_RJ45_1_DP MDI_PLUS1_SFP_I2C_CLK @BASEBOARD_FAB2_LIB.BASEBOARD_FAB2(SCH_1):NIC_MDI_SPRV_RJ45_1_DP
  53 NIC_SET_P_MDI_2_DP MDI_PLUS2_SETP @BASEBOARD_FAB2_LIB.BASEBOARD_FAB2(SCH_1):NIC_SET_P_MDI_2_DP
  50 NIC_SER_P_MDI_3_DP MDI_PLUS3_SERP @BASEBOARD_FAB2_LIB.BASEBOARD_FAB2(SCH_1):NIC_SER_P_MDI_3_DP
  22     NC     NC     NC
  43 RMII_PCH_SPRNGVLLE_ARB_OUT NC_SI_ARB_IN @BASEBOARD_FAB2_LIB.BASEBOARD_FAB2(SCH_1):RMII_PCH_SPRNGVLLE_ARB_OUT
  44 RMII_PCH_SPRNGVLLE_ARB_IN_R NC_SI_ARB_OUT @BASEBOARD_FAB2_LIB.BASEBOARD_FAB2(SCH_1):RMII_PCH_SPRNGVLLE_ARB_IN_R
   2 CLK_50M_CKMNG_SPRVLLE NC_SI_CLK_IN @BASEBOARD_FAB2_LIB.BASEBOARD_FAB2(SCH_1):CLK_50M_CKMNG_SPRVLLE
   3 RMII_BMC_PCH_SPRNGVLLE_CRSDV_R NC_SI_CRS_DV @BASEBOARD_FAB2_LIB.BASEBOARD_FAB2(SCH_1):RMII_BMC_PCH_SPRNGVLLE_CRSDV_R
   6 RMII_SPRNGVLLE_BMC_PCH_RXD0_R NC_SI_RXD0 @BASEBOARD_FAB2_LIB.BASEBOARD_FAB2(SCH_1):RMII_SPRNGVLLE_BMC_PCH_RXD0_R
   5 RMII_SPRNGVLLE_BMC_PCH_RXD1_R NC_SI_RXD1 @BASEBOARD_FAB2_LIB.BASEBOARD_FAB2(SCH_1):RMII_SPRNGVLLE_BMC_PCH_RXD1_R
   9 RMII_BMC_PCH_SPRNGVLLE_TXD0 NC_SI_TXD0 @BASEBOARD_FAB2_LIB.BASEBOARD_FAB2(SCH_1):RMII_BMC_PCH_SPRNGVLLE_TXD0
   8 RMII_BMC_PCH_SPRNGVLLE_TXD1 NC_SI_TXD1 @BASEBOARD_FAB2_LIB.BASEBOARD_FAB2(SCH_1):RMII_BMC_PCH_SPRNGVLLE_TXD1
   7 RMII_BMC_PCH_SPRNGVLLE_TXEN NC_SI_TX_EN @BASEBOARD_FAB2_LIB.BASEBOARD_FAB2(SCH_1):RMII_BMC_PCH_SPRNGVLLE_TXEN
  15 SPI_NIC_CS_R_N NVM_CS_N @BASEBOARD_FAB2_LIB.BASEBOARD_FAB2(SCH_1):SPI_NIC_CS_R_N
  12 SPI_NIC_MOSI_R NVM_SI @BASEBOARD_FAB2_LIB.BASEBOARD_FAB2(SCH_1):SPI_NIC_MOSI_R
  13 SPI_NIC_SCLK_R NVM_SK @BASEBOARD_FAB2_LIB.BASEBOARD_FAB2(SCH_1):SPI_NIC_SCLK_R
  14 SPI_NIC_MISO NVM_SO @BASEBOARD_FAB2_LIB.BASEBOARD_FAB2(SCH_1):SPI_NIC_MISO
  25 CLK_100M_SPRV_DN PECLKN @BASEBOARD_FAB2_LIB.BASEBOARD_FAB2(SCH_1):CLK_100M_SPRV_DN
  26 CLK_100M_SPRV_DP PECLKP @BASEBOARD_FAB2_LIB.BASEBOARD_FAB2(SCH_1):CLK_100M_SPRV_DP
  23 PE_PCH_SPRV_TX_C_DN  PE_RN @BASEBOARD_FAB2_LIB.BASEBOARD_FAB2(SCH_1):PE_PCH_SPRV_TX_C_DN
  24 PE_PCH_SPRV_TX_C_DP  PE_RP @BASEBOARD_FAB2_LIB.BASEBOARD_FAB2(SCH_1):PE_PCH_SPRV_TX_C_DP
  17 RST_PLTRST_SPRV_R_N PE_RST_N @BASEBOARD_FAB2_LIB.BASEBOARD_FAB2(SCH_1):RST_PLTRST_SPRV_R_N
  20 PE_PCH_SPRV_RX_DN  PE_TN @BASEBOARD_FAB2_LIB.BASEBOARD_FAB2(SCH_1):PE_PCH_SPRV_RX_DN
  21 PE_PCH_SPRV_RX_DP  PE_TP @BASEBOARD_FAB2_LIB.BASEBOARD_FAB2(SCH_1):PE_PCH_SPRV_RX_DP
  16 FM_PE_SPRV_WAKE_N PE_WAKE_N @BASEBOARD_FAB2_LIB.BASEBOARD_FAB2(SCH_1):FM_PE_SPRV_WAKE_N
  48 PD_SPRV_RSET   RSET @BASEBOARD_FAB2_LIB.BASEBOARD_FAB2(SCH_1):PD_SPRV_RSET
  63 TP_SPRV_SDP0   SDP0 @BASEBOARD_FAB2_LIB.BASEBOARD_FAB2(SCH_1):TP_SPRV_SDP0
  61 FM_1GB_LOM_DISABLE_N SDP1_PCIE_DIS_SDP1 @BASEBOARD_FAB2_LIB.BASEBOARD_FAB2(SCH_1):FM_1GB_LOM_DISABLE_N
  62 TP_SPRV_SDP2   SDP2 @BASEBOARD_FAB2_LIB.BASEBOARD_FAB2(SCH_1):TP_SPRV_SDP2
  60 TP_SPRV_SDP3   SDP3 @BASEBOARD_FAB2_LIB.BASEBOARD_FAB2(SCH_1):TP_SPRV_SDP3
  35 IRQ_LOM_ALERT_N SMB_ALRT_N @BASEBOARD_FAB2_LIB.BASEBOARD_FAB2(SCH_1):IRQ_LOM_ALERT_N
  34 SMB_SPRINGVILLE_STBY_LVC3_SCL SMB_CLK @BASEBOARD_FAB2_LIB.BASEBOARD_FAB2(SCH_1):SMB_SPRINGVILLE_STBY_LVC3_SCL
  36 SMB_SPRINGVILLE_STBY_LVC3_SDA SMB_DATA @BASEBOARD_FAB2_LIB.BASEBOARD_FAB2(SCH_1):SMB_SPRINGVILLE_STBY_LVC3_SDA
  42 P0V9_LAN VDD0P9<3> @BASEBOARD_FAB2_LIB.BASEBOARD_FAB2(SCH_1):P0V9_LAN
  11 P0V9_LAN VDD0P9<2> @BASEBOARD_FAB2_LIB.BASEBOARD_FAB2(SCH_1):P0V9_LAN
  32 P0V9_LAN VDD0P9<1> @BASEBOARD_FAB2_LIB.BASEBOARD_FAB2(SCH_1):P0V9_LAN
  59 P0V9_LAN VDD0P9<0> @BASEBOARD_FAB2_LIB.BASEBOARD_FAB2(SCH_1):P0V9_LAN
  38 P0V9_LAN_I210 VDD0P9_OUT @BASEBOARD_FAB2_LIB.BASEBOARD_FAB2(SCH_1):P0V9_LAN_I210
  47 P1V5_LAN VDD1P5<1> @BASEBOARD_FAB2_LIB.BASEBOARD_FAB2(SCH_1):P1V5_LAN
  56 P1V5_LAN_I210 VDD1P5<0> @BASEBOARD_FAB2_LIB.BASEBOARD_FAB2(SCH_1):P1V5_LAN_I210
  39 P1V5_LAN VDD1P5_OUT @BASEBOARD_FAB2_LIB.BASEBOARD_FAB2(SCH_1):P1V5_LAN
  10 P3V3_STBY VDD3P3<4> @BASEBOARD_FAB2_LIB.BASEBOARD_FAB2(SCH_1):P3V3_STBY
  27 P3V3_STBY VDD3P3<3> @BASEBOARD_FAB2_LIB.BASEBOARD_FAB2(SCH_1):P3V3_STBY
  41 P3V3_STBY VDD3P3<2> @BASEBOARD_FAB2_LIB.BASEBOARD_FAB2(SCH_1):P3V3_STBY
  51 P3V3_STBY_P1V5_LAN_I210 VDD3P3<1> @BASEBOARD_FAB2_LIB.BASEBOARD_FAB2(SCH_1):P3V3_STBY_P1V5_LAN_I210
  64 P3V3_STBY VDD3P3<0> @BASEBOARD_FAB2_LIB.BASEBOARD_FAB2(SCH_1):P3V3_STBY
  46 XTAL_25MHZ_IN_R  XTAL1 @BASEBOARD_FAB2_LIB.BASEBOARD_FAB2(SCH_1):XTAL_25MHZ_IN_R
  45 XTAL_25MHZ_OUT  XTAL2 @BASEBOARD_FAB2_LIB.BASEBOARD_FAB2(SCH_1):XTAL_25MHZ_OUT

CAP_0402LF-0.039UF,25V,10%,X7RA  I76  C9E7
   1 A_CTOP      A @BASEBOARD_FAB2_LIB.BASEBOARD_FAB2(SCH_1):A_CTOP
   2 A_CBOT      B @BASEBOARD_FAB2_LIB.BASEBOARD_FAB2(SCH_1):A_CBOT

CAP_A_0402V-0.1UF,16V,10%,X7R,A  I87  C9E5
   1 PE_PCH_SPRV_RX_DN      A @BASEBOARD_FAB2_LIB.BASEBOARD_FAB2(SCH_1):PE_PCH_SPRV_RX_DN
   2 PE_PCH_SPRV_RX_C_DN      B @BASEBOARD_FAB2_LIB.BASEBOARD_FAB2(SCH_1):PE_PCH_SPRV_RX_C_DN

CAP_A_0402V-0.1UF,16V,10%,X7R,A  I88  C9E4
   1 PE_PCH_SPRV_RX_DP      A @BASEBOARD_FAB2_LIB.BASEBOARD_FAB2(SCH_1):PE_PCH_SPRV_RX_DP
   2 PE_PCH_SPRV_RX_C_DP      B @BASEBOARD_FAB2_LIB.BASEBOARD_FAB2(SCH_1):PE_PCH_SPRV_RX_C_DP

CAP_A_0402V-0.1UF,16V,10%,X7R,A  I89  C2M23
   1 PE_PCH_SPRV_TX_DP      A @BASEBOARD_FAB2_LIB.BASEBOARD_FAB2(SCH_1):PE_PCH_SPRV_TX_DP
   2 PE_PCH_SPRV_TX_C_DP      B @BASEBOARD_FAB2_LIB.BASEBOARD_FAB2(SCH_1):PE_PCH_SPRV_TX_C_DP

CAP_A_0402V-0.1UF,16V,10%,X7R,A  I90  C2M24
   1 PE_PCH_SPRV_TX_DN      A @BASEBOARD_FAB2_LIB.BASEBOARD_FAB2(SCH_1):PE_PCH_SPRV_TX_DN
   2 PE_PCH_SPRV_TX_C_DN      B @BASEBOARD_FAB2_LIB.BASEBOARD_FAB2(SCH_1):PE_PCH_SPRV_TX_C_DN

CRYSTAL_2013-25.000MHZ,IC,D717A  I109  Y9E1
   1 XTAL_25MHZ_IN      A @BASEBOARD_FAB2_LIB.BASEBOARD_FAB2(SCH_1):XTAL_25MHZ_IN
   3 XTAL_25MHZ_OUT_R      B @BASEBOARD_FAB2_LIB.BASEBOARD_FAB2(SCH_1):XTAL_25MHZ_OUT_R

RES_0402-0.0,5%,1/16W,CHIP,G21A  I110  R9E20
   1 XTAL_25MHZ_IN      A @BASEBOARD_FAB2_LIB.BASEBOARD_FAB2(SCH_1):XTAL_25MHZ_IN
   2 XTAL_25MHZ_IN_R      B @BASEBOARD_FAB2_LIB.BASEBOARD_FAB2(SCH_1):XTAL_25MHZ_IN_R

RES_0402-33.2,1%,1/16W,CHIP,G2A  I128  R9E9
   1 SPI_NIC_MOSI_R      A @BASEBOARD_FAB2_LIB.BASEBOARD_FAB2(SCH_1):SPI_NIC_MOSI_R
   2 SPI_NIC_MOSI      B @BASEBOARD_FAB2_LIB.BASEBOARD_FAB2(SCH_1):SPI_NIC_MOSI

RES_0402-33.2,1%,1/16W,CHIP,G2A  I129  R9E5
   1 SPI_NIC_CS_R_N      A @BASEBOARD_FAB2_LIB.BASEBOARD_FAB2(SCH_1):SPI_NIC_CS_R_N
   2 SPI_NIC_CS_N      B @BASEBOARD_FAB2_LIB.BASEBOARD_FAB2(SCH_1):SPI_NIC_CS_N

RES_0402-33.2,1%,1/16W,CHIP,G2A  I130  R9E8
   1 SPI_NIC_SCLK_R      A @BASEBOARD_FAB2_LIB.BASEBOARD_FAB2(SCH_1):SPI_NIC_SCLK_R
   2 SPI_NIC_SCLK      B @BASEBOARD_FAB2_LIB.BASEBOARD_FAB2(SCH_1):SPI_NIC_SCLK

CAP_0603-10UF,6.3V,20%,X6S,E15A  I134  C1T4
   1 P0V9_LAN      A @BASEBOARD_FAB2_LIB.BASEBOARD_FAB2(SCH_1):P0V9_LAN
   2    GND      B @BASEBOARD_FAB2_LIB.BASEBOARD_FAB2(SCH_1):GND

CAP_0603-10UF,6.3V,20%,X6S,E15A  I135  C1R30
   1 P1V5_LAN      A @BASEBOARD_FAB2_LIB.BASEBOARD_FAB2(SCH_1):P1V5_LAN
   2    GND      B @BASEBOARD_FAB2_LIB.BASEBOARD_FAB2(SCH_1):GND

CAP_0603-10UF,6.3V,20%,X6S,E15A  I136  C1R22
   1 P3V3_STBY      A @BASEBOARD_FAB2_LIB.BASEBOARD_FAB2(SCH_1):P3V3_STBY
   2    GND      B @BASEBOARD_FAB2_LIB.BASEBOARD_FAB2(SCH_1):GND

CAP_0603-10UF,6.3V,20%,X6S,E15A  I142  C1R13
   1 P3V3_STBY      A @BASEBOARD_FAB2_LIB.BASEBOARD_FAB2(SCH_1):P3V3_STBY
   2    GND      B @BASEBOARD_FAB2_LIB.BASEBOARD_FAB2(SCH_1):GND

CAP_A_0402V-0.1UF,16V,10%,X7R,A  I143  C1R20
   1 P3V3_STBY      A @BASEBOARD_FAB2_LIB.BASEBOARD_FAB2(SCH_1):P3V3_STBY
   2    GND      B @BASEBOARD_FAB2_LIB.BASEBOARD_FAB2(SCH_1):GND

CAP_A_0402V-0.1UF,16V,10%,X7R,A  I144  C1T3
   1 P3V3_STBY      A @BASEBOARD_FAB2_LIB.BASEBOARD_FAB2(SCH_1):P3V3_STBY
   2    GND      B @BASEBOARD_FAB2_LIB.BASEBOARD_FAB2(SCH_1):GND

CAP_A_0402V-0.1UF,16V,10%,X7R,A  I145  C1R14
   1 P3V3_STBY      A @BASEBOARD_FAB2_LIB.BASEBOARD_FAB2(SCH_1):P3V3_STBY
   2    GND      B @BASEBOARD_FAB2_LIB.BASEBOARD_FAB2(SCH_1):GND

CAP_A_0402V-0.1UF,16V,10%,X7R,A  I146  C1R21
   1 P3V3_STBY      A @BASEBOARD_FAB2_LIB.BASEBOARD_FAB2(SCH_1):P3V3_STBY
   2    GND      B @BASEBOARD_FAB2_LIB.BASEBOARD_FAB2(SCH_1):GND

CAP_A_0402V-0.1UF,16V,10%,X7R,A  I149  C1R26
   1 P1V5_LAN      A @BASEBOARD_FAB2_LIB.BASEBOARD_FAB2(SCH_1):P1V5_LAN
   2    GND      B @BASEBOARD_FAB2_LIB.BASEBOARD_FAB2(SCH_1):GND

CAP_A_0402V-0.1UF,16V,10%,X7R,A  I150  C1R29
   1 P1V5_LAN      A @BASEBOARD_FAB2_LIB.BASEBOARD_FAB2(SCH_1):P1V5_LAN
   2    GND      B @BASEBOARD_FAB2_LIB.BASEBOARD_FAB2(SCH_1):GND

CAP_A_0402V-0.1UF,16V,10%,X7R,A  I151  C1R19
   1 P1V5_LAN      A @BASEBOARD_FAB2_LIB.BASEBOARD_FAB2(SCH_1):P1V5_LAN
   2    GND      B @BASEBOARD_FAB2_LIB.BASEBOARD_FAB2(SCH_1):GND

CAP_A_0402V-0.1UF,16V,10%,X7R,A  I152  C1R31
   1 P1V5_LAN      A @BASEBOARD_FAB2_LIB.BASEBOARD_FAB2(SCH_1):P1V5_LAN
   2    GND      B @BASEBOARD_FAB2_LIB.BASEBOARD_FAB2(SCH_1):GND

CAP_0603-10UF,6.3V,20%,X6S,E15A  I153  C1R17
   1 P1V5_LAN      A @BASEBOARD_FAB2_LIB.BASEBOARD_FAB2(SCH_1):P1V5_LAN
   2    GND      B @BASEBOARD_FAB2_LIB.BASEBOARD_FAB2(SCH_1):GND

CAP_A_0402V-0.1UF,16V,10%,X7R,A  I157  C1R18
   1 P0V9_LAN      A @BASEBOARD_FAB2_LIB.BASEBOARD_FAB2(SCH_1):P0V9_LAN
   2    GND      B @BASEBOARD_FAB2_LIB.BASEBOARD_FAB2(SCH_1):GND

CAP_A_0402V-0.1UF,16V,10%,X7R,A  I158  C1T5
   1 P0V9_LAN      A @BASEBOARD_FAB2_LIB.BASEBOARD_FAB2(SCH_1):P0V9_LAN
   2    GND      B @BASEBOARD_FAB2_LIB.BASEBOARD_FAB2(SCH_1):GND

CAP_A_0402V-0.1UF,16V,10%,X7R,A  I159  C1R24
   1 P0V9_LAN      A @BASEBOARD_FAB2_LIB.BASEBOARD_FAB2(SCH_1):P0V9_LAN
   2    GND      B @BASEBOARD_FAB2_LIB.BASEBOARD_FAB2(SCH_1):GND

CAP_A_0402V-0.1UF,16V,10%,X7R,A  I160  C1R15
   1 P0V9_LAN      A @BASEBOARD_FAB2_LIB.BASEBOARD_FAB2(SCH_1):P0V9_LAN
   2    GND      B @BASEBOARD_FAB2_LIB.BASEBOARD_FAB2(SCH_1):GND

CAP_0603-10UF,6.3V,20%,X6S,E15A  I161  C1R16
   1 P0V9_LAN      A @BASEBOARD_FAB2_LIB.BASEBOARD_FAB2(SCH_1):P0V9_LAN
   2    GND      B @BASEBOARD_FAB2_LIB.BASEBOARD_FAB2(SCH_1):GND

CAP_A_0603V-22.0UF,4V,20%,EMPTA  I163  C9E1
   1 P0V9_LAN      A @BASEBOARD_FAB2_LIB.BASEBOARD_FAB2(SCH_1):P0V9_LAN
   2    GND      B @BASEBOARD_FAB2_LIB.BASEBOARD_FAB2(SCH_1):GND

RES_0402-3.32K,1%,1/16W,CHIP,GA  I173  R9F5
   1 P3V3_STBY      A @BASEBOARD_FAB2_LIB.BASEBOARD_FAB2(SCH_1):P3V3_STBY
   2 PU_SPRV_LAN_PWR_GOOD      B @BASEBOARD_FAB2_LIB.BASEBOARD_FAB2(SCH_1):PU_SPRV_LAN_PWR_GOOD

RES_0402-4.99K,1%,1/16W,CHIP,GA  I174  R9E23
   1 PD_SPRV_RSET      A @BASEBOARD_FAB2_LIB.BASEBOARD_FAB2(SCH_1):PD_SPRV_RSET
   2    GND      B @BASEBOARD_FAB2_LIB.BASEBOARD_FAB2(SCH_1):GND

RES_0402-10.0K,1%,1/16W,CHIP,GA  I177  R9E2
   1 P3V3_STBY      A @BASEBOARD_FAB2_LIB.BASEBOARD_FAB2(SCH_1):P3V3_STBY
   2 PU_JTAG_SPRV_TCK      B @BASEBOARD_FAB2_LIB.BASEBOARD_FAB2(SCH_1):PU_JTAG_SPRV_TCK

RES_0402-10.0K,1%,1/16W,CHIP,GA  I178  R9E3
   1 P3V3_STBY      A @BASEBOARD_FAB2_LIB.BASEBOARD_FAB2(SCH_1):P3V3_STBY
   2 PU_JTAG_SPRV_TMS      B @BASEBOARD_FAB2_LIB.BASEBOARD_FAB2(SCH_1):PU_JTAG_SPRV_TMS

RES_0402-10.0K,1%,1/16W,CHIP,GA  I179  R9E1
   1 P3V3_STBY      A @BASEBOARD_FAB2_LIB.BASEBOARD_FAB2(SCH_1):P3V3_STBY
   2 PU_JTAG_SPRV_TDI      B @BASEBOARD_FAB2_LIB.BASEBOARD_FAB2(SCH_1):PU_JTAG_SPRV_TDI

RES_0402-10.0K,1%,1/16W,CHIP,GA  I181  R9E22
   1 PU_JTAG_SPRV_TDO      A @BASEBOARD_FAB2_LIB.BASEBOARD_FAB2(SCH_1):PU_JTAG_SPRV_TDO
   2 P3V3_STBY      B @BASEBOARD_FAB2_LIB.BASEBOARD_FAB2(SCH_1):P3V3_STBY

RES_0402-3.32K,1%,1/16W,CHIP,GA  I193  R9E7
   1 P3V3_STBY      A @BASEBOARD_FAB2_LIB.BASEBOARD_FAB2(SCH_1):P3V3_STBY
   2 IRQ_LOM_ALERT_N      B @BASEBOARD_FAB2_LIB.BASEBOARD_FAB2(SCH_1):IRQ_LOM_ALERT_N

RES_0402-0.0,5%,1/16W,CHIP,G21A  I195  R1R1
   1 RST_PLTRST_N      A @BASEBOARD_FAB2_LIB.BASEBOARD_FAB2(SCH_1):RST_PLTRST_N
   2 RST_PLTRST_SPRV_R_N      B @BASEBOARD_FAB2_LIB.BASEBOARD_FAB2(SCH_1):RST_PLTRST_SPRV_R_N

RES_0402-10.0K,1%,1/16W,CHIP,GA  I200  R9E4
   1 P3V3_STBY      A @BASEBOARD_FAB2_LIB.BASEBOARD_FAB2(SCH_1):P3V3_STBY
   2 RST_PLTRST_SPRV_R_N      B @BASEBOARD_FAB2_LIB.BASEBOARD_FAB2(SCH_1):RST_PLTRST_SPRV_R_N

RES_0402-0.0,5%,1/16W,CHIP,G21A  I201  R9E18
   1 XTAL_25MHZ_OUT_R      A @BASEBOARD_FAB2_LIB.BASEBOARD_FAB2(SCH_1):XTAL_25MHZ_OUT_R
   2 XTAL_25MHZ_OUT      B @BASEBOARD_FAB2_LIB.BASEBOARD_FAB2(SCH_1):XTAL_25MHZ_OUT

RES_0402-10.0K,1%,1/16W,CHIP,GA  I212  R9E13
   1 RMII_BMC_PCH_SPRNGVLLE_TXEN      A @BASEBOARD_FAB2_LIB.BASEBOARD_FAB2(SCH_1):RMII_BMC_PCH_SPRNGVLLE_TXEN
   2    GND      B @BASEBOARD_FAB2_LIB.BASEBOARD_FAB2(SCH_1):GND

RES_0402-10.0K,1%,1/16W,CHIP,GA  I213  R1R12
   1 CLK_50M_CKMNG_SPRVLLE      A @BASEBOARD_FAB2_LIB.BASEBOARD_FAB2(SCH_1):CLK_50M_CKMNG_SPRVLLE
   2    GND      B @BASEBOARD_FAB2_LIB.BASEBOARD_FAB2(SCH_1):GND

RES_0402-10.0K,1%,1/16W,CHIP,GA  I214  R1T1
   1 RMII_BMC_PCH_SPRNGVLLE_CRSDV      A @BASEBOARD_FAB2_LIB.BASEBOARD_FAB2(SCH_1):RMII_BMC_PCH_SPRNGVLLE_CRSDV
   2    GND      B @BASEBOARD_FAB2_LIB.BASEBOARD_FAB2(SCH_1):GND

RES_0402-22.1,1.0%,1/16W,CHIP,A  I225  R9F1
   1 RMII_BMC_PCH_SPRNGVLLE_CRSDV_R      A @BASEBOARD_FAB2_LIB.BASEBOARD_FAB2(SCH_1):RMII_BMC_PCH_SPRNGVLLE_CRSDV_R
   2 RMII_BMC_PCH_SPRNGVLLE_CRSDV      B @BASEBOARD_FAB2_LIB.BASEBOARD_FAB2(SCH_1):RMII_BMC_PCH_SPRNGVLLE_CRSDV

RES_0402-22.1,1.0%,1/16W,CHIP,A  I228  R9E19
   1 RMII_SPRNGVLLE_BMC_PCH_RXD1_R      A @BASEBOARD_FAB2_LIB.BASEBOARD_FAB2(SCH_1):RMII_SPRNGVLLE_BMC_PCH_RXD1_R
   2 RMII_SPRNGVLLE_BMC_PCH_RXD1      B @BASEBOARD_FAB2_LIB.BASEBOARD_FAB2(SCH_1):RMII_SPRNGVLLE_BMC_PCH_RXD1

RES_0402-22.1,1.0%,1/16W,CHIP,A  I229  R9E17
   1 RMII_SPRNGVLLE_BMC_PCH_RXD0_R      A @BASEBOARD_FAB2_LIB.BASEBOARD_FAB2(SCH_1):RMII_SPRNGVLLE_BMC_PCH_RXD0_R
   2 RMII_SPRNGVLLE_BMC_PCH_RXD0      B @BASEBOARD_FAB2_LIB.BASEBOARD_FAB2(SCH_1):RMII_SPRNGVLLE_BMC_PCH_RXD0

RES_0402-33.2,1%,1/16W,CHIP,G2A  I235  R9E16
   1 RMII_PCH_SPRNGVLLE_ARB_IN_R      A @BASEBOARD_FAB2_LIB.BASEBOARD_FAB2(SCH_1):RMII_PCH_SPRNGVLLE_ARB_IN_R
   2 RMII_PCH_SPRNGVLLE_ARB_IN      B @BASEBOARD_FAB2_LIB.BASEBOARD_FAB2(SCH_1):RMII_PCH_SPRNGVLLE_ARB_IN

RES_0603-0,5.0%,1/10W,CHIP,G22A  I237  R1R15
   1 P0V9_LAN      A @BASEBOARD_FAB2_LIB.BASEBOARD_FAB2(SCH_1):P0V9_LAN
   2 P0V9_LAN_I210      B @BASEBOARD_FAB2_LIB.BASEBOARD_FAB2(SCH_1):P0V9_LAN_I210

RES_0603-0,5.0%,1/10W,CHIP,G22A  I238  R1T32
   1 P1V5_LAN      A @BASEBOARD_FAB2_LIB.BASEBOARD_FAB2(SCH_1):P1V5_LAN
   2 P1V5_LAN_I210      B @BASEBOARD_FAB2_LIB.BASEBOARD_FAB2(SCH_1):P1V5_LAN_I210

RES_0603-0,5.0%,1/10W,CHIP,G22A  I239  R1T34
   1 P3V3_STBY      A @BASEBOARD_FAB2_LIB.BASEBOARD_FAB2(SCH_1):P3V3_STBY
   2 P3V3_STBY_P1V5_LAN_I210      B @BASEBOARD_FAB2_LIB.BASEBOARD_FAB2(SCH_1):P3V3_STBY_P1V5_LAN_I210

RES_0603-0,5.0%,1/10W,EMPTY,G2A  I240  R1T33
   1 P1V5_LAN      A @BASEBOARD_FAB2_LIB.BASEBOARD_FAB2(SCH_1):P1V5_LAN
   2 P3V3_STBY_P1V5_LAN_I210      B @BASEBOARD_FAB2_LIB.BASEBOARD_FAB2(SCH_1):P3V3_STBY_P1V5_LAN_I210

CAP_A_0603V-22.0UF,4V,20%,EMPTA  I241  C9E12
   1 P0V9_LAN      A @BASEBOARD_FAB2_LIB.BASEBOARD_FAB2(SCH_1):P0V9_LAN
   2    GND      B @BASEBOARD_FAB2_LIB.BASEBOARD_FAB2(SCH_1):GND

SC22U16V5MX-4-GP_SMD-BCG5-SC22A  I244  C22W34
   1 P3V3_STBY      1 @BASEBOARD_FAB2_LIB.BASEBOARD_FAB2(SCH_1):P3V3_STBY
   2    GND      2 @BASEBOARD_FAB2_LIB.BASEBOARD_FAB2(SCH_1):GND

SC22U16V5MX-4-GP_SMD-BCG5-SC22A  I245  C9F2
   1 P3V3_STBY      1 @BASEBOARD_FAB2_LIB.BASEBOARD_FAB2(SCH_1):P3V3_STBY
   2    GND      2 @BASEBOARD_FAB2_LIB.BASEBOARD_FAB2(SCH_1):GND

SC22U16V5MX-4-GP_SMD-BCG5-SC22A  I246  C22W35
   1 P1V5_LAN      1 @BASEBOARD_FAB2_LIB.BASEBOARD_FAB2(SCH_1):P1V5_LAN
   2    GND      2 @BASEBOARD_FAB2_LIB.BASEBOARD_FAB2(SCH_1):GND

SC22U16V5MX-4-GP_SMD-BCG5-SC22A  I248  C9E6
   1 P1V5_LAN      1 @BASEBOARD_FAB2_LIB.BASEBOARD_FAB2(SCH_1):P1V5_LAN
   2    GND      2 @BASEBOARD_FAB2_LIB.BASEBOARD_FAB2(SCH_1):GND

CAP_0402LF-15.0PF,50V,5%,COG,AA  I249  C9E9
   1 XTAL_25MHZ_IN      A @BASEBOARD_FAB2_LIB.BASEBOARD_FAB2(SCH_1):XTAL_25MHZ_IN
   2    GND      B @BASEBOARD_FAB2_LIB.BASEBOARD_FAB2(SCH_1):GND

CAP_0402LF-15.0PF,50V,5%,COG,AA  I250  C9E8
   1 XTAL_25MHZ_OUT_R      A @BASEBOARD_FAB2_LIB.BASEBOARD_FAB2(SCH_1):XTAL_25MHZ_OUT_R
   2    GND      B @BASEBOARD_FAB2_LIB.BASEBOARD_FAB2(SCH_1):GND

RES_0402-10.0K,1%,1/16W,CHIP,GA  I252  R9W36
   1 P3V3_STBY      A @BASEBOARD_FAB2_LIB.BASEBOARD_FAB2(SCH_1):P3V3_STBY
   2 PU_DEV_OFF_N      B @BASEBOARD_FAB2_LIB.BASEBOARD_FAB2(SCH_1):PU_DEV_OFF_N


DRAWING: @BASEBOARD_FAB2_LIB.BASEBOARD_FAB2(SCH_1):PAGE140 

M25PE16_SM-IC,H77797-001  I1  U9E1
   1 SPI_NIC_CS_N    S_N @BASEBOARD_FAB2_LIB.BASEBOARD_FAB2(SCH_1):SPI_NIC_CS_N
   7 PU_NV_HOLD_N RESET_N @BASEBOARD_FAB2_LIB.BASEBOARD_FAB2(SCH_1):PU_NV_HOLD_N
   6 SPI_NIC_SCLK      C @BASEBOARD_FAB2_LIB.BASEBOARD_FAB2(SCH_1):SPI_NIC_SCLK
   5 SPI_NIC_MOSI    DQ0 @BASEBOARD_FAB2_LIB.BASEBOARD_FAB2(SCH_1):SPI_NIC_MOSI
   2 SPI_NIC_MISO_R    DQ1 @BASEBOARD_FAB2_LIB.BASEBOARD_FAB2(SCH_1):SPI_NIC_MISO_R
   8 P3V3_STBY    VCC @BASEBOARD_FAB2_LIB.BASEBOARD_FAB2(SCH_1):P3V3_STBY
   4    GND    VSS @BASEBOARD_FAB2_LIB.BASEBOARD_FAB2(SCH_1):GND
   3 PU_NV_WP_N    W_N @BASEBOARD_FAB2_LIB.BASEBOARD_FAB2(SCH_1):PU_NV_WP_N

CAP_A_0402V-0.1UF,16V,10%,X7R,A  I3  C1R25
   1 P3V3_STBY      A @BASEBOARD_FAB2_LIB.BASEBOARD_FAB2(SCH_1):P3V3_STBY
   2    GND      B @BASEBOARD_FAB2_LIB.BASEBOARD_FAB2(SCH_1):GND

RES_0402-3.32K,1%,1/16W,CHIP,GA  I10  R1R9
   1 P3V3_STBY      A @BASEBOARD_FAB2_LIB.BASEBOARD_FAB2(SCH_1):P3V3_STBY
   2 PU_NV_HOLD_N      B @BASEBOARD_FAB2_LIB.BASEBOARD_FAB2(SCH_1):PU_NV_HOLD_N

RES_0402-3.32K,1%,1/16W,CHIP,GA  I11  R1R3
   1 P3V3_STBY      A @BASEBOARD_FAB2_LIB.BASEBOARD_FAB2(SCH_1):P3V3_STBY
   2 PU_NV_WP_N      B @BASEBOARD_FAB2_LIB.BASEBOARD_FAB2(SCH_1):PU_NV_WP_N

RES_0402-20.0K,1%,1/16W,CHIP,GA  I12  R1R7
   1 P3V3_STBY      A @BASEBOARD_FAB2_LIB.BASEBOARD_FAB2(SCH_1):P3V3_STBY
   2 SPI_NIC_MOSI      B @BASEBOARD_FAB2_LIB.BASEBOARD_FAB2(SCH_1):SPI_NIC_MOSI

RES_0402-3.32K,1%,1/16W,EMPTY,A  I14  R1R6
   1 SPI_NIC_MOSI      A @BASEBOARD_FAB2_LIB.BASEBOARD_FAB2(SCH_1):SPI_NIC_MOSI
   2    GND      B @BASEBOARD_FAB2_LIB.BASEBOARD_FAB2(SCH_1):GND

RES_0402-33.2,1%,1/16W,CHIP,G2A  I17  R9E6
   1 SPI_NIC_MISO_R      A @BASEBOARD_FAB2_LIB.BASEBOARD_FAB2(SCH_1):SPI_NIC_MISO_R
   2 SPI_NIC_MISO      B @BASEBOARD_FAB2_LIB.BASEBOARD_FAB2(SCH_1):SPI_NIC_MISO


DRAWING: @BASEBOARD_FAB2_LIB.BASEBOARD_FAB2(SCH_1):PAGE141 

CAP_A_0402V-0.1UF,16V,10%,X7R,A  I46  C9G4
   1 GND_LAN_TRCT1234_C      A @BASEBOARD_FAB2_LIB.BASEBOARD_FAB2(SCH_1):GND_LAN_TRCT1234_C
   2    GND      B @BASEBOARD_FAB2_LIB.BASEBOARD_FAB2(SCH_1):GND

CAP_A_0402V-0.1UF,16V,10%,X7R,A  I47  C9G6
   1 GND_LAN_TRCT1234_C      A @BASEBOARD_FAB2_LIB.BASEBOARD_FAB2(SCH_1):GND_LAN_TRCT1234_C
   2    GND      B @BASEBOARD_FAB2_LIB.BASEBOARD_FAB2(SCH_1):GND

CAP_0402-1.0UF,16V,10%,X7S,G71A  I48  C9G5
   1 GND_LAN_TRCT1234_C      A @BASEBOARD_FAB2_LIB.BASEBOARD_FAB2(SCH_1):GND_LAN_TRCT1234_C
   2    GND      B @BASEBOARD_FAB2_LIB.BASEBOARD_FAB2(SCH_1):GND

RES_0402-0.0,5%,1/16W,CHIP,G21A  I75  R9G9
   1 NIC_SER_P_MDI_3_DP      A @BASEBOARD_FAB2_LIB.BASEBOARD_FAB2(SCH_1):NIC_SER_P_MDI_3_DP
   2 NIC_MDI_SPRV_RJ45_3_R_DP      B @BASEBOARD_FAB2_LIB.BASEBOARD_FAB2(SCH_1):NIC_MDI_SPRV_RJ45_3_R_DP

RES_0402-0.0,5%,1/16W,CHIP,G21A  I76  R9G11
   1 NIC_SER_N_MDI_3_DN      A @BASEBOARD_FAB2_LIB.BASEBOARD_FAB2(SCH_1):NIC_SER_N_MDI_3_DN
   2 NIC_MDI_SPRV_RJ45_3_R_DN      B @BASEBOARD_FAB2_LIB.BASEBOARD_FAB2(SCH_1):NIC_MDI_SPRV_RJ45_3_R_DN

RES_0402-0.0,5%,1/16W,CHIP,G21A  I77  R9G18
   1 NIC_SET_P_MDI_2_DP      A @BASEBOARD_FAB2_LIB.BASEBOARD_FAB2(SCH_1):NIC_SET_P_MDI_2_DP
   2 NIC_MDI_SPRV_RJ45_2_R_DP      B @BASEBOARD_FAB2_LIB.BASEBOARD_FAB2(SCH_1):NIC_MDI_SPRV_RJ45_2_R_DP

RES_0402-0.0,5%,1/16W,CHIP,G21A  I78  R9G17
   1 NIC_SET_N_MDI_2_DN      A @BASEBOARD_FAB2_LIB.BASEBOARD_FAB2(SCH_1):NIC_SET_N_MDI_2_DN
   2 NIC_MDI_SPRV_RJ45_2_R_DN      B @BASEBOARD_FAB2_LIB.BASEBOARD_FAB2(SCH_1):NIC_MDI_SPRV_RJ45_2_R_DN

RES_0402-0.0,5%,1/16W,CHIP,G21A  I79  R9G19
   1 NIC_MDI_SPRV_RJ45_1_DP      A @BASEBOARD_FAB2_LIB.BASEBOARD_FAB2(SCH_1):NIC_MDI_SPRV_RJ45_1_DP
   2 NIC_MDI_SPRV_RJ45_1_R_DP      B @BASEBOARD_FAB2_LIB.BASEBOARD_FAB2(SCH_1):NIC_MDI_SPRV_RJ45_1_R_DP

RES_0402-0.0,5%,1/16W,CHIP,G21A  I80  R9G20
   1 NIC_MDI_SPRV_RJ45_1_DN      A @BASEBOARD_FAB2_LIB.BASEBOARD_FAB2(SCH_1):NIC_MDI_SPRV_RJ45_1_DN
   2 NIC_MDI_SPRV_RJ45_1_R_DN      B @BASEBOARD_FAB2_LIB.BASEBOARD_FAB2(SCH_1):NIC_MDI_SPRV_RJ45_1_R_DN

RES_0402-0.0,5%,1/16W,CHIP,G21A  I81  R9G24
   1 NIC_MDI_SPRV_RJ45_0_DP      A @BASEBOARD_FAB2_LIB.BASEBOARD_FAB2(SCH_1):NIC_MDI_SPRV_RJ45_0_DP
   2 NIC_MDI_SPRV_RJ45_0_R_DP      B @BASEBOARD_FAB2_LIB.BASEBOARD_FAB2(SCH_1):NIC_MDI_SPRV_RJ45_0_R_DP

RES_0402-0.0,5%,1/16W,CHIP,G21A  I82  R9G22
   1 NIC_MDI_SPRV_RJ45_0_DN      A @BASEBOARD_FAB2_LIB.BASEBOARD_FAB2(SCH_1):NIC_MDI_SPRV_RJ45_0_DN
   2 NIC_MDI_SPRV_RJ45_0_R_DN      B @BASEBOARD_FAB2_LIB.BASEBOARD_FAB2(SCH_1):NIC_MDI_SPRV_RJ45_0_R_DN

CAP_0402LF-4700PF,50V,10%,EMPTA  I99  C9G9
   1 NIC_SER_P_MDI_3_DP      A @BASEBOARD_FAB2_LIB.BASEBOARD_FAB2(SCH_1):NIC_SER_P_MDI_3_DP
   2 NIC_MDI_MNG_RX_DP      B @BASEBOARD_FAB2_LIB.BASEBOARD_FAB2(SCH_1):NIC_MDI_MNG_RX_DP

CAP_0402LF-4700PF,50V,10%,EMPTA  I100  C9G12
   1 NIC_SER_N_MDI_3_DN      A @BASEBOARD_FAB2_LIB.BASEBOARD_FAB2(SCH_1):NIC_SER_N_MDI_3_DN
   2 NIC_MDI_MNG_RX_DN      B @BASEBOARD_FAB2_LIB.BASEBOARD_FAB2(SCH_1):NIC_MDI_MNG_RX_DN

CAP_0402LF-4700PF,50V,10%,EMPTA  I101  C9G16
   1 NIC_SET_P_MDI_2_DP      A @BASEBOARD_FAB2_LIB.BASEBOARD_FAB2(SCH_1):NIC_SET_P_MDI_2_DP
   2 NIC_MDI_MNG_TX_DP      B @BASEBOARD_FAB2_LIB.BASEBOARD_FAB2(SCH_1):NIC_MDI_MNG_TX_DP

CAP_0402LF-4700PF,50V,10%,EMPTA  I102  C9G13
   1 NIC_SET_N_MDI_2_DN      A @BASEBOARD_FAB2_LIB.BASEBOARD_FAB2(SCH_1):NIC_SET_N_MDI_2_DN
   2 NIC_MDI_MNG_TX_DN      B @BASEBOARD_FAB2_LIB.BASEBOARD_FAB2(SCH_1):NIC_MDI_MNG_TX_DN

SKT-RJ45-LED-XFOR-1-GP_SOCKET-A  I129  JA9G1
  L1 LED_LAN_2_R_N     L1 @BASEBOARD_FAB2_LIB.BASEBOARD_FAB2(SCH_1):LED_LAN_2_R_N
  L2 LED_LAN_0_R_N     L2 @BASEBOARD_FAB2_LIB.BASEBOARD_FAB2(SCH_1):LED_LAN_0_R_N
  L3 LED_LAN_1_R_N     L3 @BASEBOARD_FAB2_LIB.BASEBOARD_FAB2(SCH_1):LED_LAN_1_R_N
  L4 NIC_LED_ACT_ANODE_R     L4 @BASEBOARD_FAB2_LIB.BASEBOARD_FAB2(SCH_1):NIC_LED_ACT_ANODE_R
  R1 GND_LAN_TRCT1234_C     R1 @BASEBOARD_FAB2_LIB.BASEBOARD_FAB2(SCH_1):GND_LAN_TRCT1234_C
  R2 NIC_MDI_SPRV_RJ45_0_R_DP     R2 @BASEBOARD_FAB2_LIB.BASEBOARD_FAB2(SCH_1):NIC_MDI_SPRV_RJ45_0_R_DP
  R3 NIC_MDI_SPRV_RJ45_0_R_DN     R3 @BASEBOARD_FAB2_LIB.BASEBOARD_FAB2(SCH_1):NIC_MDI_SPRV_RJ45_0_R_DN
  R4 NIC_MDI_SPRV_RJ45_1_R_DP     R4 @BASEBOARD_FAB2_LIB.BASEBOARD_FAB2(SCH_1):NIC_MDI_SPRV_RJ45_1_R_DP
  R5 NIC_MDI_SPRV_RJ45_1_R_DN     R5 @BASEBOARD_FAB2_LIB.BASEBOARD_FAB2(SCH_1):NIC_MDI_SPRV_RJ45_1_R_DN
  R6    GND     R6 @BASEBOARD_FAB2_LIB.BASEBOARD_FAB2(SCH_1):GND
  R7 NIC_MDI_SPRV_RJ45_2_R_DP     R7 @BASEBOARD_FAB2_LIB.BASEBOARD_FAB2(SCH_1):NIC_MDI_SPRV_RJ45_2_R_DP
  R8 NIC_MDI_SPRV_RJ45_2_R_DN     R8 @BASEBOARD_FAB2_LIB.BASEBOARD_FAB2(SCH_1):NIC_MDI_SPRV_RJ45_2_R_DN
  R9 NIC_MDI_SPRV_RJ45_3_R_DP     R9 @BASEBOARD_FAB2_LIB.BASEBOARD_FAB2(SCH_1):NIC_MDI_SPRV_RJ45_3_R_DP
 R10 NIC_MDI_SPRV_RJ45_3_R_DN    R10 @BASEBOARD_FAB2_LIB.BASEBOARD_FAB2(SCH_1):NIC_MDI_SPRV_RJ45_3_R_DN
 R11 GND_LAN_TRCT1234_C    R11 @BASEBOARD_FAB2_LIB.BASEBOARD_FAB2(SCH_1):GND_LAN_TRCT1234_C
   1    GND      1 @BASEBOARD_FAB2_LIB.BASEBOARD_FAB2(SCH_1):GND
   2    GND      2 @BASEBOARD_FAB2_LIB.BASEBOARD_FAB2(SCH_1):GND

RES_0402-75,1.0%,1/16W,CHIP,G2A  I134  R9G2
   1 LED_LAN_2_R_N      A @BASEBOARD_FAB2_LIB.BASEBOARD_FAB2(SCH_1):LED_LAN_2_R_N
   2 LED_LAN_2_N      B @BASEBOARD_FAB2_LIB.BASEBOARD_FAB2(SCH_1):LED_LAN_2_N

RES_0402-75,1.0%,1/16W,CHIP,G2A  I135  R9G3
   1 LED_LAN_0_R_N      A @BASEBOARD_FAB2_LIB.BASEBOARD_FAB2(SCH_1):LED_LAN_0_R_N
   2 LED_LAN_0_N      B @BASEBOARD_FAB2_LIB.BASEBOARD_FAB2(SCH_1):LED_LAN_0_N

CAP_0402LF-470PF,50V,10%,X7R,AA  I138  C9G3
   1 LED_LAN_0_N      A @BASEBOARD_FAB2_LIB.BASEBOARD_FAB2(SCH_1):LED_LAN_0_N
   2    GND      B @BASEBOARD_FAB2_LIB.BASEBOARD_FAB2(SCH_1):GND

CAP_0402LF-470PF,50V,10%,X7R,AA  I140  C9G1
   1 LED_LAN_2_N      A @BASEBOARD_FAB2_LIB.BASEBOARD_FAB2(SCH_1):LED_LAN_2_N
   2    GND      B @BASEBOARD_FAB2_LIB.BASEBOARD_FAB2(SCH_1):GND

CAP_0402LF-470PF,50V,10%,X7R,AA  I152  C9G2
   1 P3V3_STBY      A @BASEBOARD_FAB2_LIB.BASEBOARD_FAB2(SCH_1):P3V3_STBY
   2    GND      B @BASEBOARD_FAB2_LIB.BASEBOARD_FAB2(SCH_1):GND

RES_0402-0.0,5%,1/16W,CHIP,G21A  I156  R9G4
   1 NIC_LED_ACT_ANODE_R      A @BASEBOARD_FAB2_LIB.BASEBOARD_FAB2(SCH_1):NIC_LED_ACT_ANODE_R
   2 P3V3_STBY      B @BASEBOARD_FAB2_LIB.BASEBOARD_FAB2(SCH_1):P3V3_STBY

RES_0402-150.0,1%,1/16W,CHIP,GA  I157  R9G1
   1 LED_LAN_1_N      A @BASEBOARD_FAB2_LIB.BASEBOARD_FAB2(SCH_1):LED_LAN_1_N
   2 LED_LAN_1_R_N      B @BASEBOARD_FAB2_LIB.BASEBOARD_FAB2(SCH_1):LED_LAN_1_R_N

CAP_0402LF-470PF,50V,10%,X7R,AA  I159  C9F22
   1 LED_LAN_1_N      A @BASEBOARD_FAB2_LIB.BASEBOARD_FAB2(SCH_1):LED_LAN_1_N
   2    GND      B @BASEBOARD_FAB2_LIB.BASEBOARD_FAB2(SCH_1):GND


DRAWING: @BASEBOARD_FAB2_LIB.BASEBOARD_FAB2(SCH_1):PAGE142 

TTL1G126_A_SOT-74HC1G126,IC,A7B  I1  U8E4
   1 PU_TRI_STATE_EN     OE @BASEBOARD_FAB2_LIB.BASEBOARD_FAB2(SCH_1):PU_TRI_STATE_EN
   2 FM_ALL_WAKE_N      A @BASEBOARD_FAB2_LIB.BASEBOARD_FAB2(SCH_1):FM_ALL_WAKE_N
   4 IRQ_LVC3_WAKE_R_N      Y @BASEBOARD_FAB2_LIB.BASEBOARD_FAB2(SCH_1):IRQ_LVC3_WAKE_R_N

RES_0402-33.2,1%,1/16W,CHIP,G2A  I2  R8E17
   1 IRQ_LVC3_WAKE_R_N      A @BASEBOARD_FAB2_LIB.BASEBOARD_FAB2(SCH_1):IRQ_LVC3_WAKE_R_N
   2 IRQ_LVC3_WAKE_N      B @BASEBOARD_FAB2_LIB.BASEBOARD_FAB2(SCH_1):IRQ_LVC3_WAKE_N

RES_0402-4.75K,1%,1/16W,CHIP,GA  I3  R8E23
   1 PU_TRI_STATE_EN      A @BASEBOARD_FAB2_LIB.BASEBOARD_FAB2(SCH_1):PU_TRI_STATE_EN
   2 P3V3_STBY      B @BASEBOARD_FAB2_LIB.BASEBOARD_FAB2(SCH_1):P3V3_STBY

RES_0402-0.0,5%,1/16W,EMPTY,G2A  I18  R8E29
   1 FM_PE_BMC_WAKE_N      A @BASEBOARD_FAB2_LIB.BASEBOARD_FAB2(SCH_1):FM_PE_BMC_WAKE_N
   2 FM_ALL_WAKE_N      B @BASEBOARD_FAB2_LIB.BASEBOARD_FAB2(SCH_1):FM_ALL_WAKE_N

CAP_A_0402V-0.1UF,16V,10%,X7R,A  I20  C8E5
   1 P3V3_STBY      A @BASEBOARD_FAB2_LIB.BASEBOARD_FAB2(SCH_1):P3V3_STBY
   2    GND      B @BASEBOARD_FAB2_LIB.BASEBOARD_FAB2(SCH_1):GND

RES_0402-0.0,5%,1/16W,CHIP,G21A  I30  R8E26
   1 FM_PE_OCP_WAKE_N      A @BASEBOARD_FAB2_LIB.BASEBOARD_FAB2(SCH_1):FM_PE_OCP_WAKE_N
   2 FM_ALL_WAKE_N      B @BASEBOARD_FAB2_LIB.BASEBOARD_FAB2(SCH_1):FM_ALL_WAKE_N

RES_0402-0.0,5%,1/16W,CHIP,G21A  I31  R8E28
   1 FM_PE_SLOTX24_WAKE_N      A @BASEBOARD_FAB2_LIB.BASEBOARD_FAB2(SCH_1):FM_PE_SLOTX24_WAKE_N
   2 FM_ALL_WAKE_N      B @BASEBOARD_FAB2_LIB.BASEBOARD_FAB2(SCH_1):FM_ALL_WAKE_N

RES_0402-0.0,5%,1/16W,CHIP,G21A  I32  R8E27
   1 FM_PE_M2_WAKE_N      A @BASEBOARD_FAB2_LIB.BASEBOARD_FAB2(SCH_1):FM_PE_M2_WAKE_N
   2 FM_ALL_WAKE_N      B @BASEBOARD_FAB2_LIB.BASEBOARD_FAB2(SCH_1):FM_ALL_WAKE_N

RES_0402-0.0,5%,1/16W,CHIP,G21A  I33  R8E21
   1 FM_PE_SPRV_WAKE_N      A @BASEBOARD_FAB2_LIB.BASEBOARD_FAB2(SCH_1):FM_PE_SPRV_WAKE_N
   2 FM_ALL_WAKE_N      B @BASEBOARD_FAB2_LIB.BASEBOARD_FAB2(SCH_1):FM_ALL_WAKE_N

2K15R2F-1-GP_SMD-RG1-2K15R2F-1A  I34  R8E36
   1 P3V3_STBY      1 @BASEBOARD_FAB2_LIB.BASEBOARD_FAB2(SCH_1):P3V3_STBY
   2 FM_PE_SLOTX24_WAKE_N      2 @BASEBOARD_FAB2_LIB.BASEBOARD_FAB2(SCH_1):FM_PE_SLOTX24_WAKE_N

2K15R2F-1-GP_SMD-RG1-2K15R2F-1A  I35  R8E30
   1 P3V3_STBY      1 @BASEBOARD_FAB2_LIB.BASEBOARD_FAB2(SCH_1):P3V3_STBY
   2 FM_ALL_WAKE_N      2 @BASEBOARD_FAB2_LIB.BASEBOARD_FAB2(SCH_1):FM_ALL_WAKE_N


DRAWING: @BASEBOARD_FAB2_LIB.BASEBOARD_FAB2(SCH_1):PAGE152 

GTL2014_SM-IC,D66151-001  I1  U9G1
  13 H_CPU1_KLM_MEMHOT_LVT3_R_N     A0 @BASEBOARD_FAB2_LIB.BASEBOARD_FAB2(SCH_1):H_CPU1_KLM_MEMHOT_LVT3_R_N
  12 H_CPU1_GHJ_MEMHOT_LVT3_R_N     A1 @BASEBOARD_FAB2_LIB.BASEBOARD_FAB2(SCH_1):H_CPU1_GHJ_MEMHOT_LVT3_R_N
  10 H_CPU0_DEF_MEMHOT_LVT3_R_N     A2 @BASEBOARD_FAB2_LIB.BASEBOARD_FAB2(SCH_1):H_CPU0_DEF_MEMHOT_LVT3_R_N
   9 H_CPU0_ABC_MEMHOT_LVT3_R_N     A3 @BASEBOARD_FAB2_LIB.BASEBOARD_FAB2(SCH_1):H_CPU0_ABC_MEMHOT_LVT3_R_N
   2 H_CPU1_MEMKLM_MEMHOT_G_R_N     B0 @BASEBOARD_FAB2_LIB.BASEBOARD_FAB2(SCH_1):H_CPU1_MEMKLM_MEMHOT_G_R_N
   3 H_CPU1_MEMGHJ_MEMHOT_G_R_N     B1 @BASEBOARD_FAB2_LIB.BASEBOARD_FAB2(SCH_1):H_CPU1_MEMGHJ_MEMHOT_G_R_N
   5 H_CPU0_MEMDEF_MEMHOT_G_R_N     B2 @BASEBOARD_FAB2_LIB.BASEBOARD_FAB2(SCH_1):H_CPU0_MEMDEF_MEMHOT_G_R_N
   6 H_CPU0_MEMABC_MEMHOT_G_R_N     B3 @BASEBOARD_FAB2_LIB.BASEBOARD_FAB2(SCH_1):H_CPU0_MEMABC_MEMHOT_G_R_N
   1 PD_DIR_2    DIR @BASEBOARD_FAB2_LIB.BASEBOARD_FAB2(SCH_1):PD_DIR_2
  11    GND GND<2> @BASEBOARD_FAB2_LIB.BASEBOARD_FAB2(SCH_1):GND
   8    GND GND<1> @BASEBOARD_FAB2_LIB.BASEBOARD_FAB2(SCH_1):GND
   7    GND GND<0> @BASEBOARD_FAB2_LIB.BASEBOARD_FAB2(SCH_1):GND
  14   P3V3    VCC @BASEBOARD_FAB2_LIB.BASEBOARD_FAB2(SCH_1):P3V3
   4 P0V7_GTL2014_2   VREF @BASEBOARD_FAB2_LIB.BASEBOARD_FAB2(SCH_1):P0V7_GTL2014_2

RES_0402-1.00K,1%,1/16W,CHIP,GA  I2  R1U30
   1 PD_DIR_2      A @BASEBOARD_FAB2_LIB.BASEBOARD_FAB2(SCH_1):PD_DIR_2
   2    GND      B @BASEBOARD_FAB2_LIB.BASEBOARD_FAB2(SCH_1):GND

RES_0402-33.2,1%,1/16W,CHIP,G2A  I6  R1U46
   1 H_CPU0_MEMABC_MEMHOT_LVT3_K_N      A @BASEBOARD_FAB2_LIB.BASEBOARD_FAB2(SCH_1):H_CPU0_MEMABC_MEMHOT_LVT3_K_N
   2 H_CPU0_MEMABC_MEMHOT_LVT3_N      B @BASEBOARD_FAB2_LIB.BASEBOARD_FAB2(SCH_1):H_CPU0_MEMABC_MEMHOT_LVT3_N

RES_0402-33.2,1%,1/16W,CHIP,G2A  I14  R9G31
   1 H_CPU0_MEMDEF_MEMHOT_LVT3_K_N      A @BASEBOARD_FAB2_LIB.BASEBOARD_FAB2(SCH_1):H_CPU0_MEMDEF_MEMHOT_LVT3_K_N
   2 H_CPU0_MEMDEF_MEMHOT_LVT3_N      B @BASEBOARD_FAB2_LIB.BASEBOARD_FAB2(SCH_1):H_CPU0_MEMDEF_MEMHOT_LVT3_N

RES_0402-33.2,1%,1/16W,CHIP,G2A  I15  R1U36
   1 H_CPU1_MEMGHJ_MEMHOT_LVT3_K_N      A @BASEBOARD_FAB2_LIB.BASEBOARD_FAB2(SCH_1):H_CPU1_MEMGHJ_MEMHOT_LVT3_K_N
   2 H_CPU1_MEMGHJ_MEMHOT_LVT3_N      B @BASEBOARD_FAB2_LIB.BASEBOARD_FAB2(SCH_1):H_CPU1_MEMGHJ_MEMHOT_LVT3_N

RES_0402-33.2,1%,1/16W,CHIP,G2A  I16  R1U34
   1 H_CPU1_MEMKLM_MEMHOT_LVT3_K_N      A @BASEBOARD_FAB2_LIB.BASEBOARD_FAB2(SCH_1):H_CPU1_MEMKLM_MEMHOT_LVT3_K_N
   2 H_CPU1_MEMKLM_MEMHOT_LVT3_N      B @BASEBOARD_FAB2_LIB.BASEBOARD_FAB2(SCH_1):H_CPU1_MEMKLM_MEMHOT_LVT3_N

CAP_0402-1.0UF,16V,10%,X6S,D97A  I18  C1U19
   1   P3V3      A @BASEBOARD_FAB2_LIB.BASEBOARD_FAB2(SCH_1):P3V3
   2    GND      B @BASEBOARD_FAB2_LIB.BASEBOARD_FAB2(SCH_1):GND

RES_0402-100.0,1%,1/16W,CHIP,GA  I26  R1U37
   1 P0V7_GTL2014_2      A @BASEBOARD_FAB2_LIB.BASEBOARD_FAB2(SCH_1):P0V7_GTL2014_2
   2    GND      B @BASEBOARD_FAB2_LIB.BASEBOARD_FAB2(SCH_1):GND

CAP_A_0402V-0.1UF,16V,10%,X7R,A  I27  C1U22
   1 P0V7_GTL2014_2      A @BASEBOARD_FAB2_LIB.BASEBOARD_FAB2(SCH_1):P0V7_GTL2014_2
   2    GND      B @BASEBOARD_FAB2_LIB.BASEBOARD_FAB2(SCH_1):GND

RES_0402-0.0,5%,1/16W,CHIP,G21A  I45  R9G34
   1 H_CPU0_MEMABC_MEMHOT_G_N      A @BASEBOARD_FAB2_LIB.BASEBOARD_FAB2(SCH_1):H_CPU0_MEMABC_MEMHOT_G_N
   2 H_CPU0_MEMABC_MEMHOT_G_R_N      B @BASEBOARD_FAB2_LIB.BASEBOARD_FAB2(SCH_1):H_CPU0_MEMABC_MEMHOT_G_R_N

RES_0402-0.0,5%,1/16W,EMPTY,G2A  I47  R9G27
   1 H_CPU0_MEMDEF_MEMHOT_G_PCH_N      A @BASEBOARD_FAB2_LIB.BASEBOARD_FAB2(SCH_1):H_CPU0_MEMDEF_MEMHOT_G_PCH_N
   2 H_CPU0_MEMDEF_MEMHOT_LVT3_K_N      B @BASEBOARD_FAB2_LIB.BASEBOARD_FAB2(SCH_1):H_CPU0_MEMDEF_MEMHOT_LVT3_K_N

RES_0402-0.0,5%,1/16W,CHIP,G21A  I49  R1U58
   1 H_CPU0_MEMDEF_MEMHOT_G_N      A @BASEBOARD_FAB2_LIB.BASEBOARD_FAB2(SCH_1):H_CPU0_MEMDEF_MEMHOT_G_N
   2 H_CPU0_MEMDEF_MEMHOT_G_R_N      B @BASEBOARD_FAB2_LIB.BASEBOARD_FAB2(SCH_1):H_CPU0_MEMDEF_MEMHOT_G_R_N

RES_0402-0.0,5%,1/16W,EMPTY,G2A  I50  R1U56
   1 H_CPU0_MEMDEF_MEMHOT_G_PCH_N      A @BASEBOARD_FAB2_LIB.BASEBOARD_FAB2(SCH_1):H_CPU0_MEMDEF_MEMHOT_G_PCH_N
   2 H_CPU0_MEMDEF_MEMHOT_G_N      B @BASEBOARD_FAB2_LIB.BASEBOARD_FAB2(SCH_1):H_CPU0_MEMDEF_MEMHOT_G_N

RES_0402-0.0,5%,1/16W,EMPTY,G2A  I51  R2U51
   1 H_CPU0_MEMABC_MEMHOT_G_PCH_N      A @BASEBOARD_FAB2_LIB.BASEBOARD_FAB2(SCH_1):H_CPU0_MEMABC_MEMHOT_G_PCH_N
   2 H_CPU0_MEMABC_MEMHOT_G_N      B @BASEBOARD_FAB2_LIB.BASEBOARD_FAB2(SCH_1):H_CPU0_MEMABC_MEMHOT_G_N

RES_0402-150.0,1%,1/16W,CHIP,GA  I53  R2U40
   1 PVCCIO_CPU0      A @BASEBOARD_FAB2_LIB.BASEBOARD_FAB2(SCH_1):PVCCIO_CPU0
   2 H_CPU0_MEMABC_MEMHOT_G_N      B @BASEBOARD_FAB2_LIB.BASEBOARD_FAB2(SCH_1):H_CPU0_MEMABC_MEMHOT_G_N

RES_0402-150.0,1%,1/16W,CHIP,GA  I54  R2U41
   1 PVCCIO_CPU0      A @BASEBOARD_FAB2_LIB.BASEBOARD_FAB2(SCH_1):PVCCIO_CPU0
   2 H_CPU0_MEMDEF_MEMHOT_G_N      B @BASEBOARD_FAB2_LIB.BASEBOARD_FAB2(SCH_1):H_CPU0_MEMDEF_MEMHOT_G_N

RES_0402-150.0,1%,1/16W,CHIP,GA  I56  R1U41
   1 PVCCIO_CPU1      A @BASEBOARD_FAB2_LIB.BASEBOARD_FAB2(SCH_1):PVCCIO_CPU1
   2 H_CPU1_MEMGHJ_MEMHOT_G_N      B @BASEBOARD_FAB2_LIB.BASEBOARD_FAB2(SCH_1):H_CPU1_MEMGHJ_MEMHOT_G_N

RES_0402-150.0,1%,1/16W,CHIP,GA  I57  R1U35
   1 PVCCIO_CPU1      A @BASEBOARD_FAB2_LIB.BASEBOARD_FAB2(SCH_1):PVCCIO_CPU1
   2 H_CPU1_MEMKLM_MEMHOT_G_N      B @BASEBOARD_FAB2_LIB.BASEBOARD_FAB2(SCH_1):H_CPU1_MEMKLM_MEMHOT_G_N

RES_0402-150.0,1%,1/16W,CHIP,GA  I58  R4P17
   1 H_CPU0_MEMABC_MEMHOT_G_N      A @BASEBOARD_FAB2_LIB.BASEBOARD_FAB2(SCH_1):H_CPU0_MEMABC_MEMHOT_G_N
   2 PVCCIO_CPU0      B @BASEBOARD_FAB2_LIB.BASEBOARD_FAB2(SCH_1):PVCCIO_CPU0

RES_0402-150.0,1%,1/16W,CHIP,GA  I59  R4P20
   1 H_CPU0_MEMDEF_MEMHOT_G_N      A @BASEBOARD_FAB2_LIB.BASEBOARD_FAB2(SCH_1):H_CPU0_MEMDEF_MEMHOT_G_N
   2 PVCCIO_CPU0      B @BASEBOARD_FAB2_LIB.BASEBOARD_FAB2(SCH_1):PVCCIO_CPU0

RES_0402-150.0,1%,1/16W,CHIP,GA  I61  R7P5
   1 H_CPU1_MEMGHJ_MEMHOT_G_N      A @BASEBOARD_FAB2_LIB.BASEBOARD_FAB2(SCH_1):H_CPU1_MEMGHJ_MEMHOT_G_N
   2 PVCCIO_CPU1      B @BASEBOARD_FAB2_LIB.BASEBOARD_FAB2(SCH_1):PVCCIO_CPU1

RES_0402-150.0,1%,1/16W,CHIP,GA  I62  R7P21
   1 H_CPU1_MEMKLM_MEMHOT_G_N      A @BASEBOARD_FAB2_LIB.BASEBOARD_FAB2(SCH_1):H_CPU1_MEMKLM_MEMHOT_G_N
   2 PVCCIO_CPU1      B @BASEBOARD_FAB2_LIB.BASEBOARD_FAB2(SCH_1):PVCCIO_CPU1

RES_0402-0.0,5%,1/16W,CHIP,G21A  I64  R1U53
   1 H_CPU1_MEMGHJ_MEMHOT_G_N      A @BASEBOARD_FAB2_LIB.BASEBOARD_FAB2(SCH_1):H_CPU1_MEMGHJ_MEMHOT_G_N
   2 H_CPU1_MEMGHJ_MEMHOT_G_R_N      B @BASEBOARD_FAB2_LIB.BASEBOARD_FAB2(SCH_1):H_CPU1_MEMGHJ_MEMHOT_G_R_N

RES_0402-0.0,5%,1/16W,CHIP,G21A  I65  R1U60
   1 H_CPU1_MEMKLM_MEMHOT_G_N      A @BASEBOARD_FAB2_LIB.BASEBOARD_FAB2(SCH_1):H_CPU1_MEMKLM_MEMHOT_G_N
   2 H_CPU1_MEMKLM_MEMHOT_G_R_N      B @BASEBOARD_FAB2_LIB.BASEBOARD_FAB2(SCH_1):H_CPU1_MEMKLM_MEMHOT_G_R_N

RES_0402-0.0,5%,1/16W,EMPTY,G2A  I66  R2U49
   1 H_CPU0_MEMABC_MEMHOT_G_PCH_N      A @BASEBOARD_FAB2_LIB.BASEBOARD_FAB2(SCH_1):H_CPU0_MEMABC_MEMHOT_G_PCH_N
   2 H_CPU0_MEMABC_MEMHOT_LVT3_K_N      B @BASEBOARD_FAB2_LIB.BASEBOARD_FAB2(SCH_1):H_CPU0_MEMABC_MEMHOT_LVT3_K_N

RES_0402-0.0,5%,1/16W,EMPTY,G2A  I67  R1U55
   1 H_CPU1_MEMGHJ_MEMHOT_G_N      A @BASEBOARD_FAB2_LIB.BASEBOARD_FAB2(SCH_1):H_CPU1_MEMGHJ_MEMHOT_G_N
   2 H_CPU1_MEMGHJ_MEMHOT_G_PCH_N      B @BASEBOARD_FAB2_LIB.BASEBOARD_FAB2(SCH_1):H_CPU1_MEMGHJ_MEMHOT_G_PCH_N

RES_0402-0.0,5%,1/16W,EMPTY,G2A  I68  R1U62
   1 H_CPU1_MEMKLM_MEMHOT_G_N      A @BASEBOARD_FAB2_LIB.BASEBOARD_FAB2(SCH_1):H_CPU1_MEMKLM_MEMHOT_G_N
   2 H_CPU1_MEMKLM_MEMHOT_G_PCH_N      B @BASEBOARD_FAB2_LIB.BASEBOARD_FAB2(SCH_1):H_CPU1_MEMKLM_MEMHOT_G_PCH_N

RES_0402-0.0,5%,1/16W,EMPTY,G2A  I69  R1U57
   1 H_CPU1_MEMGHJ_MEMHOT_LVT3_K_N      A @BASEBOARD_FAB2_LIB.BASEBOARD_FAB2(SCH_1):H_CPU1_MEMGHJ_MEMHOT_LVT3_K_N
   2 H_CPU1_MEMGHJ_MEMHOT_G_PCH_N      B @BASEBOARD_FAB2_LIB.BASEBOARD_FAB2(SCH_1):H_CPU1_MEMGHJ_MEMHOT_G_PCH_N

RES_0402-0.0,5%,1/16W,EMPTY,G2A  I70  R1U61
   1 H_CPU1_MEMKLM_MEMHOT_LVT3_K_N      A @BASEBOARD_FAB2_LIB.BASEBOARD_FAB2(SCH_1):H_CPU1_MEMKLM_MEMHOT_LVT3_K_N
   2 H_CPU1_MEMKLM_MEMHOT_G_PCH_N      B @BASEBOARD_FAB2_LIB.BASEBOARD_FAB2(SCH_1):H_CPU1_MEMKLM_MEMHOT_G_PCH_N

RES_0402-0.0,5%,1/16W,CHIP,G21A  I71  R9G28
   1 H_CPU1_KLM_MEMHOT_LVT3_R_N      A @BASEBOARD_FAB2_LIB.BASEBOARD_FAB2(SCH_1):H_CPU1_KLM_MEMHOT_LVT3_R_N
   2 H_CPU1_MEMKLM_MEMHOT_LVT3_K_N      B @BASEBOARD_FAB2_LIB.BASEBOARD_FAB2(SCH_1):H_CPU1_MEMKLM_MEMHOT_LVT3_K_N

RES_0402-0.0,5%,1/16W,CHIP,G21A  I72  R9G32
   1 H_CPU1_GHJ_MEMHOT_LVT3_R_N      A @BASEBOARD_FAB2_LIB.BASEBOARD_FAB2(SCH_1):H_CPU1_GHJ_MEMHOT_LVT3_R_N
   2 H_CPU1_MEMGHJ_MEMHOT_LVT3_K_N      B @BASEBOARD_FAB2_LIB.BASEBOARD_FAB2(SCH_1):H_CPU1_MEMGHJ_MEMHOT_LVT3_K_N

RES_0402-0.0,5%,1/16W,CHIP,G21A  I73  R9G33
   1 H_CPU0_DEF_MEMHOT_LVT3_R_N      A @BASEBOARD_FAB2_LIB.BASEBOARD_FAB2(SCH_1):H_CPU0_DEF_MEMHOT_LVT3_R_N
   2 H_CPU0_MEMDEF_MEMHOT_LVT3_K_N      B @BASEBOARD_FAB2_LIB.BASEBOARD_FAB2(SCH_1):H_CPU0_MEMDEF_MEMHOT_LVT3_K_N

RES_0402-0.0,5%,1/16W,CHIP,G21A  I74  R1U59
   1 H_CPU0_ABC_MEMHOT_LVT3_R_N      A @BASEBOARD_FAB2_LIB.BASEBOARD_FAB2(SCH_1):H_CPU0_ABC_MEMHOT_LVT3_R_N
   2 H_CPU0_MEMABC_MEMHOT_LVT3_K_N      B @BASEBOARD_FAB2_LIB.BASEBOARD_FAB2(SCH_1):H_CPU0_MEMABC_MEMHOT_LVT3_K_N

RES_0402-0.0,5%,1/16W,CHIP,G21A  I79  R2U47
   1 H_CPU0_MEMABC_MEMHOT_LVT3_N      A @BASEBOARD_FAB2_LIB.BASEBOARD_FAB2(SCH_1):H_CPU0_MEMABC_MEMHOT_LVT3_N
   2 H_CPU0_MEMABC_MEMHOT_LVT3_BMC_N      B @BASEBOARD_FAB2_LIB.BASEBOARD_FAB2(SCH_1):H_CPU0_MEMABC_MEMHOT_LVT3_BMC_N

RES_0402-0.0,5%,1/16W,CHIP,G21A  I92  R9G29
   1 H_CPU0_MEMDEF_MEMHOT_LVT3_N      A @BASEBOARD_FAB2_LIB.BASEBOARD_FAB2(SCH_1):H_CPU0_MEMDEF_MEMHOT_LVT3_N
   2 H_CPU0_MEMDEF_MEMHOT_LVT3_BMC_N      B @BASEBOARD_FAB2_LIB.BASEBOARD_FAB2(SCH_1):H_CPU0_MEMDEF_MEMHOT_LVT3_BMC_N

RES_0402-0.0,5%,1/16W,CHIP,G21A  I93  R1U54
   1 H_CPU1_MEMGHJ_MEMHOT_LVT3_N      A @BASEBOARD_FAB2_LIB.BASEBOARD_FAB2(SCH_1):H_CPU1_MEMGHJ_MEMHOT_LVT3_N
   2 H_CPU1_MEMGHJ_MEMHOT_LVT3_BMC_N      B @BASEBOARD_FAB2_LIB.BASEBOARD_FAB2(SCH_1):H_CPU1_MEMGHJ_MEMHOT_LVT3_BMC_N

RES_0402-0.0,5%,1/16W,CHIP,G21A  I94  R2U46
   1 H_CPU1_MEMKLM_MEMHOT_LVT3_N      A @BASEBOARD_FAB2_LIB.BASEBOARD_FAB2(SCH_1):H_CPU1_MEMKLM_MEMHOT_LVT3_N
   2 H_CPU1_MEMKLM_MEMHOT_LVT3_BMC_N      B @BASEBOARD_FAB2_LIB.BASEBOARD_FAB2(SCH_1):H_CPU1_MEMKLM_MEMHOT_LVT3_BMC_N

RES_0402-0.0,5%,1/16W,EMPTY,G2A  I95  R3N30
   1 H_CPU0_MEMABC_MEMHOT_LVT3_N      A @BASEBOARD_FAB2_LIB.BASEBOARD_FAB2(SCH_1):H_CPU0_MEMABC_MEMHOT_LVT3_N
   2 H_CPU0_MEMABC_MEMHOT_PCH_N      B @BASEBOARD_FAB2_LIB.BASEBOARD_FAB2(SCH_1):H_CPU0_MEMABC_MEMHOT_PCH_N

RES_0402-0.0,5%,1/16W,EMPTY,G2A  I98  R9G30
   1 H_CPU0_MEMDEF_MEMHOT_LVT3_N      A @BASEBOARD_FAB2_LIB.BASEBOARD_FAB2(SCH_1):H_CPU0_MEMDEF_MEMHOT_LVT3_N
   2 H_CPU0_MEMDEF_MEMHOT_PCH_N      B @BASEBOARD_FAB2_LIB.BASEBOARD_FAB2(SCH_1):H_CPU0_MEMDEF_MEMHOT_PCH_N

RES_0402-0.0,5%,1/16W,EMPTY,G2A  I100  R3P63
   1 H_CPU1_MEMGHJ_MEMHOT_LVT3_N      A @BASEBOARD_FAB2_LIB.BASEBOARD_FAB2(SCH_1):H_CPU1_MEMGHJ_MEMHOT_LVT3_N
   2 H_CPU1_MEMGHJ_MEMHOT_PCH_N      B @BASEBOARD_FAB2_LIB.BASEBOARD_FAB2(SCH_1):H_CPU1_MEMGHJ_MEMHOT_PCH_N

RES_0402-0.0,5%,1/16W,EMPTY,G2A  I102  R2U45
   1 H_CPU1_MEMKLM_MEMHOT_LVT3_N      A @BASEBOARD_FAB2_LIB.BASEBOARD_FAB2(SCH_1):H_CPU1_MEMKLM_MEMHOT_LVT3_N
   2 H_CPU1_MEMKLM_MEMHOT_PCH_N      B @BASEBOARD_FAB2_LIB.BASEBOARD_FAB2(SCH_1):H_CPU1_MEMKLM_MEMHOT_PCH_N

RES_0402-49.9,1%,1/16W,EMPTY,GA  I105  R1W35
   1 PVCCIO_CPU0      A @BASEBOARD_FAB2_LIB.BASEBOARD_FAB2(SCH_1):PVCCIO_CPU0
   2 P0V7_GTL2014_2      B @BASEBOARD_FAB2_LIB.BASEBOARD_FAB2(SCH_1):P0V7_GTL2014_2

374R2F-1-GP_SMD-RG-374R2F-1-GPA  I106  R1U43
   1   P3V3      1 @BASEBOARD_FAB2_LIB.BASEBOARD_FAB2(SCH_1):P3V3
   2 P0V7_GTL2014_2      2 @BASEBOARD_FAB2_LIB.BASEBOARD_FAB2(SCH_1):P0V7_GTL2014_2


DRAWING: @BASEBOARD_FAB2_LIB.BASEBOARD_FAB2(SCH_1):PAGE153 

RES_0402-4.75K,1%,1/16W,EMPTY,A  I90  R7F6
   1 P3V3_STBY      A @BASEBOARD_FAB2_LIB.BASEBOARD_FAB2(SCH_1):P3V3_STBY
   2 PU_SPI0_RST      B @BASEBOARD_FAB2_LIB.BASEBOARD_FAB2(SCH_1):PU_SPI0_RST

RES_0402-4.75K,1%,1/16W,CHIP,GA  I94  R7F5
   1 P3V3_STBY      A @BASEBOARD_FAB2_LIB.BASEBOARD_FAB2(SCH_1):P3V3_STBY
   2 SPI_CS0_PRIMARY_R_N      B @BASEBOARD_FAB2_LIB.BASEBOARD_FAB2(SCH_1):SPI_CS0_PRIMARY_R_N

RES_0402-33.2,1%,1/16W,CHIP,G2A  I98  R7F4
   1 SPI_SWITCH_MISO      A @BASEBOARD_FAB2_LIB.BASEBOARD_FAB2(SCH_1):SPI_SWITCH_MISO
   2 SPI_MISO_R0      B @BASEBOARD_FAB2_LIB.BASEBOARD_FAB2(SCH_1):SPI_MISO_R0

RES_0402-33.2,1%,1/16W,CHIP,G2A  I108  R7F37
   1 SPI_BIOS_SOCKET_IO2      A @BASEBOARD_FAB2_LIB.BASEBOARD_FAB2(SCH_1):SPI_BIOS_SOCKET_IO2
   2 PU_BIOS_SPI_WP0_N      B @BASEBOARD_FAB2_LIB.BASEBOARD_FAB2(SCH_1):PU_BIOS_SPI_WP0_N

RES_0402-33.2,1%,1/16W,CHIP,G2A  I109  R7F3
   1 SPI_BIOS_SOCKET_IO3      A @BASEBOARD_FAB2_LIB.BASEBOARD_FAB2(SCH_1):SPI_BIOS_SOCKET_IO3
   2 PU_BIOS_SPI_HOLD0_N      B @BASEBOARD_FAB2_LIB.BASEBOARD_FAB2(SCH_1):PU_BIOS_SPI_HOLD0_N

CAP_A_0402V-1.0UF,6.3V,10%,X6SA  I130  C7F2
   1 P3V3_STBY      A @BASEBOARD_FAB2_LIB.BASEBOARD_FAB2(SCH_1):P3V3_STBY
   2    GND      B @BASEBOARD_FAB2_LIB.BASEBOARD_FAB2(SCH_1):GND

CAP_A_0402V-0.01UF,25V,10%,X7RA  I131  C7F1
   1 P3V3_STBY      A @BASEBOARD_FAB2_LIB.BASEBOARD_FAB2(SCH_1):P3V3_STBY
   2    GND      B @BASEBOARD_FAB2_LIB.BASEBOARD_FAB2(SCH_1):GND

CAP_A_0402V-0.01UF,25V,10%,X7RA  I136  C3T5
   1 P3V3_STBY      A @BASEBOARD_FAB2_LIB.BASEBOARD_FAB2(SCH_1):P3V3_STBY
   2    GND      B @BASEBOARD_FAB2_LIB.BASEBOARD_FAB2(SCH_1):GND

CAP_A_0402V-1.0UF,6.3V,10%,X6SA  I138  C3T4
   1 P3V3_STBY      A @BASEBOARD_FAB2_LIB.BASEBOARD_FAB2(SCH_1):P3V3_STBY
   2    GND      B @BASEBOARD_FAB2_LIB.BASEBOARD_FAB2(SCH_1):GND

RES_0402-10.0K,1%,1/16W,CHIP,GA  I140  R7F32
   1 P3V3_STBY      A @BASEBOARD_FAB2_LIB.BASEBOARD_FAB2(SCH_1):P3V3_STBY
   2 PU_BIOS_SPI_HOLD0_N      B @BASEBOARD_FAB2_LIB.BASEBOARD_FAB2(SCH_1):PU_BIOS_SPI_HOLD0_N

W25Q256_XSOI-IC,H25002-001  I146  U7F1
   9 PU_BIOS_SPI_WP0_N WP_N_IO<2> @BASEBOARD_FAB2_LIB.BASEBOARD_FAB2(SCH_1):PU_BIOS_SPI_WP0_N
  14 TP_SPI_0_0  NC<0> @BASEBOARD_FAB2_LIB.BASEBOARD_FAB2(SCH_1):TP_SPI_0_0
  13 TP_SPI_0_1  NC<1> @BASEBOARD_FAB2_LIB.BASEBOARD_FAB2(SCH_1):TP_SPI_0_1
  12 TP_SPI_0_2  NC<2> @BASEBOARD_FAB2_LIB.BASEBOARD_FAB2(SCH_1):TP_SPI_0_2
  11 TP_SPI_0_3  NC<3> @BASEBOARD_FAB2_LIB.BASEBOARD_FAB2(SCH_1):TP_SPI_0_3
   6 TP_SPI_0_4  NC<4> @BASEBOARD_FAB2_LIB.BASEBOARD_FAB2(SCH_1):TP_SPI_0_4
   5 TP_SPI_0_5  NC<5> @BASEBOARD_FAB2_LIB.BASEBOARD_FAB2(SCH_1):TP_SPI_0_5
   4 TP_SPI_0_6  NC<6> @BASEBOARD_FAB2_LIB.BASEBOARD_FAB2(SCH_1):TP_SPI_0_6
  10    GND    GND @BASEBOARD_FAB2_LIB.BASEBOARD_FAB2(SCH_1):GND
   8 SPI_MISO_R0 DO_IO<1> @BASEBOARD_FAB2_LIB.BASEBOARD_FAB2(SCH_1):SPI_MISO_R0
  16 SPI_CLK_R0    CLK @BASEBOARD_FAB2_LIB.BASEBOARD_FAB2(SCH_1):SPI_CLK_R0
   2 P3V3_STBY    VCC @BASEBOARD_FAB2_LIB.BASEBOARD_FAB2(SCH_1):P3V3_STBY
   7 SPI_CS0_PRIMARY_R_N   CS_N @BASEBOARD_FAB2_LIB.BASEBOARD_FAB2(SCH_1):SPI_CS0_PRIMARY_R_N
  15 SPI_SWITCH_MOSI_R0 DI_IO<0> @BASEBOARD_FAB2_LIB.BASEBOARD_FAB2(SCH_1):SPI_SWITCH_MOSI_R0
   3 PU_SPI0_RST RESET_N @BASEBOARD_FAB2_LIB.BASEBOARD_FAB2(SCH_1):PU_SPI0_RST
   1 PU_BIOS_SPI_HOLD0_N HOLD_N_IO<3> @BASEBOARD_FAB2_LIB.BASEBOARD_FAB2(SCH_1):PU_BIOS_SPI_HOLD0_N

RES_0402-4.75K,1%,1/16W,EMPTY,A  I150  R3T3
   1 P3V3_STBY      A @BASEBOARD_FAB2_LIB.BASEBOARD_FAB2(SCH_1):P3V3_STBY
   2 PU_SPI1_RST      B @BASEBOARD_FAB2_LIB.BASEBOARD_FAB2(SCH_1):PU_SPI1_RST

RES_0402-4.75K,1%,1/16W,CHIP,GA  I152  R3T5
   1 P3V3_STBY      A @BASEBOARD_FAB2_LIB.BASEBOARD_FAB2(SCH_1):P3V3_STBY
   2 SPI_CS0_SECONDARY_R_N      B @BASEBOARD_FAB2_LIB.BASEBOARD_FAB2(SCH_1):SPI_CS0_SECONDARY_R_N

RES_0402-33.2,1%,1/16W,CHIP,G2A  I155  R3T2
   1 SPI_SWITCH_MISO      A @BASEBOARD_FAB2_LIB.BASEBOARD_FAB2(SCH_1):SPI_SWITCH_MISO
   2 SPI_MISO_R1      B @BASEBOARD_FAB2_LIB.BASEBOARD_FAB2(SCH_1):SPI_MISO_R1

RES_0402-33.2,1%,1/16W,CHIP,G2A  I156  R3U1
   1 SPI_BIOS_SOCKET_IO2      A @BASEBOARD_FAB2_LIB.BASEBOARD_FAB2(SCH_1):SPI_BIOS_SOCKET_IO2
   2 PU_BIOS_SPI_WP1_N      B @BASEBOARD_FAB2_LIB.BASEBOARD_FAB2(SCH_1):PU_BIOS_SPI_WP1_N

RES_0402-33.2,1%,1/16W,CHIP,G2A  I157  R3T1
   1 SPI_BIOS_SOCKET_IO3      A @BASEBOARD_FAB2_LIB.BASEBOARD_FAB2(SCH_1):SPI_BIOS_SOCKET_IO3
   2 PU_BIOS_SPI_HOLD1_N      B @BASEBOARD_FAB2_LIB.BASEBOARD_FAB2(SCH_1):PU_BIOS_SPI_HOLD1_N

RES_0402-33.2,1%,1/16W,CHIP,G2A  I166  R8F8
   1 SPI_SWITCH_CLK      A @BASEBOARD_FAB2_LIB.BASEBOARD_FAB2(SCH_1):SPI_SWITCH_CLK
   2 SPI_CLK_R0      B @BASEBOARD_FAB2_LIB.BASEBOARD_FAB2(SCH_1):SPI_CLK_R0

RES_0402-33.2,1%,1/16W,CHIP,G2A  I167  R8F7
   1 SPI_SWITCH_CLK      A @BASEBOARD_FAB2_LIB.BASEBOARD_FAB2(SCH_1):SPI_SWITCH_CLK
   2 SPI_CLK_R1      B @BASEBOARD_FAB2_LIB.BASEBOARD_FAB2(SCH_1):SPI_CLK_R1

RES_0402-10.0K,1%,1/16W,CHIP,GA  I168  R7F28
   1 P3V3_STBY      A @BASEBOARD_FAB2_LIB.BASEBOARD_FAB2(SCH_1):P3V3_STBY
   2 PU_BIOS_SPI_WP0_N      B @BASEBOARD_FAB2_LIB.BASEBOARD_FAB2(SCH_1):PU_BIOS_SPI_WP0_N

RES_0402-10.0K,1%,1/16W,EMPTY,A  I170  R7F30
   1 PU_BIOS_SPI_WP0_N      A @BASEBOARD_FAB2_LIB.BASEBOARD_FAB2(SCH_1):PU_BIOS_SPI_WP0_N
   2    GND      B @BASEBOARD_FAB2_LIB.BASEBOARD_FAB2(SCH_1):GND

RES_0402-10.0K,1%,1/16W,CHIP,GA  I174  R3T4
   1 P3V3_STBY      A @BASEBOARD_FAB2_LIB.BASEBOARD_FAB2(SCH_1):P3V3_STBY
   2 PU_BIOS_SPI_HOLD1_N      B @BASEBOARD_FAB2_LIB.BASEBOARD_FAB2(SCH_1):PU_BIOS_SPI_HOLD1_N

RES_0402-10.0K,1%,1/16W,CHIP,GA  I178  R3T12
   1 P3V3_STBY      A @BASEBOARD_FAB2_LIB.BASEBOARD_FAB2(SCH_1):P3V3_STBY
   2 PU_BIOS_SPI_WP1_N      B @BASEBOARD_FAB2_LIB.BASEBOARD_FAB2(SCH_1):PU_BIOS_SPI_WP1_N

RES_0402-10.0K,1%,1/16W,EMPTY,A  I179  R3T9
   1 PU_BIOS_SPI_WP1_N      A @BASEBOARD_FAB2_LIB.BASEBOARD_FAB2(SCH_1):PU_BIOS_SPI_WP1_N
   2    GND      B @BASEBOARD_FAB2_LIB.BASEBOARD_FAB2(SCH_1):GND

RES_0402-33.2,1%,1/16W,CHIP,G2A  I181  R7F29
   1 SPI_SWITCH_MOSI      A @BASEBOARD_FAB2_LIB.BASEBOARD_FAB2(SCH_1):SPI_SWITCH_MOSI
   2 SPI_SWITCH_MOSI_R0      B @BASEBOARD_FAB2_LIB.BASEBOARD_FAB2(SCH_1):SPI_SWITCH_MOSI_R0

RES_0402-33.2,1%,1/16W,CHIP,G2A  I184  R3T10
   1 SPI_SWITCH_MOSI      A @BASEBOARD_FAB2_LIB.BASEBOARD_FAB2(SCH_1):SPI_SWITCH_MOSI
   2 SPI_SWITCH_MOSI_R1      B @BASEBOARD_FAB2_LIB.BASEBOARD_FAB2(SCH_1):SPI_SWITCH_MOSI_R1

W25Q256FVFIG-GP_MEMORY-G4-W25QA  I185  U3T1
   1 PU_BIOS_SPI_HOLD1_N HOLD#/IO3 @BASEBOARD_FAB2_LIB.BASEBOARD_FAB2(SCH_1):PU_BIOS_SPI_HOLD1_N
   2 P3V3_STBY    VCC @BASEBOARD_FAB2_LIB.BASEBOARD_FAB2(SCH_1):P3V3_STBY
   3 PU_SPI1_RST RESET# @BASEBOARD_FAB2_LIB.BASEBOARD_FAB2(SCH_1):PU_SPI1_RST
   4 TP_SPI_1_6   NC#4 @BASEBOARD_FAB2_LIB.BASEBOARD_FAB2(SCH_1):TP_SPI_1_6
   5 TP_SPI_1_5   NC#5 @BASEBOARD_FAB2_LIB.BASEBOARD_FAB2(SCH_1):TP_SPI_1_5
   6 TP_SPI_1_4   NC#6 @BASEBOARD_FAB2_LIB.BASEBOARD_FAB2(SCH_1):TP_SPI_1_4
   7 SPI_CS0_SECONDARY_R_N    CS# @BASEBOARD_FAB2_LIB.BASEBOARD_FAB2(SCH_1):SPI_CS0_SECONDARY_R_N
   8 SPI_MISO_R1 DO/IO1 @BASEBOARD_FAB2_LIB.BASEBOARD_FAB2(SCH_1):SPI_MISO_R1
   9 PU_BIOS_SPI_WP1_N WP#/IO2 @BASEBOARD_FAB2_LIB.BASEBOARD_FAB2(SCH_1):PU_BIOS_SPI_WP1_N
  10    GND    GND @BASEBOARD_FAB2_LIB.BASEBOARD_FAB2(SCH_1):GND
  11 TP_SPI_1_3  NC#11 @BASEBOARD_FAB2_LIB.BASEBOARD_FAB2(SCH_1):TP_SPI_1_3
  12 TP_SPI_1_2  NC#12 @BASEBOARD_FAB2_LIB.BASEBOARD_FAB2(SCH_1):TP_SPI_1_2
  13 TP_SPI_1_1  NC#13 @BASEBOARD_FAB2_LIB.BASEBOARD_FAB2(SCH_1):TP_SPI_1_1
  14 TP_SPI_1_0  NC#14 @BASEBOARD_FAB2_LIB.BASEBOARD_FAB2(SCH_1):TP_SPI_1_0
  15 SPI_SWITCH_MOSI_R1 DI/IO0 @BASEBOARD_FAB2_LIB.BASEBOARD_FAB2(SCH_1):SPI_SWITCH_MOSI_R1
  16 SPI_CLK_R1    CLK @BASEBOARD_FAB2_LIB.BASEBOARD_FAB2(SCH_1):SPI_CLK_R1

RES_0402-0.0,5%,1/16W,CHIP,G21A  I187  R7W5
   1 SPI_SWITCH_CS0_N      A @BASEBOARD_FAB2_LIB.BASEBOARD_FAB2(SCH_1):SPI_SWITCH_CS0_N
   2 SPI_CS0_PRIMARY_R_N      B @BASEBOARD_FAB2_LIB.BASEBOARD_FAB2(SCH_1):SPI_CS0_PRIMARY_R_N


DRAWING: @BASEBOARD_FAB2_LIB.BASEBOARD_FAB2(SCH_1):PAGE154 

CAP_A_0402V-0.1UF,16V,10%,X7R,A  I14  C8E18
   1 P3V3_STBY      A @BASEBOARD_FAB2_LIB.BASEBOARD_FAB2(SCH_1):P3V3_STBY
   2    GND      B @BASEBOARD_FAB2_LIB.BASEBOARD_FAB2(SCH_1):GND

RES_0402-75,1.0%,1/16W,CHIP,G2A  I62  R2T9
   1 SPI_CS0_SECONDARY_N      A @BASEBOARD_FAB2_LIB.BASEBOARD_FAB2(SCH_1):SPI_CS0_SECONDARY_N
   2 SPI_CS0_SECONDARY_R_N      B @BASEBOARD_FAB2_LIB.BASEBOARD_FAB2(SCH_1):SPI_CS0_SECONDARY_R_N

PI3B3257A_TSSOPLF-IC,E16801-001  I74  U8F1
  16 P3V3_STBY    VCC @BASEBOARD_FAB2_LIB.BASEBOARD_FAB2(SCH_1):P3V3_STBY
   8    GND    GND @BASEBOARD_FAB2_LIB.BASEBOARD_FAB2(SCH_1):GND
  15    GND     EN @BASEBOARD_FAB2_LIB.BASEBOARD_FAB2(SCH_1):GND
   1 FM_BIOS_SPI_BMC_CTRL      S @BASEBOARD_FAB2_LIB.BASEBOARD_FAB2(SCH_1):FM_BIOS_SPI_BMC_CTRL
   4 SPI_SWITCH_CLK     YA @BASEBOARD_FAB2_LIB.BASEBOARD_FAB2(SCH_1):SPI_SWITCH_CLK
   7 SPI_SWITCH_MOSI     YB @BASEBOARD_FAB2_LIB.BASEBOARD_FAB2(SCH_1):SPI_SWITCH_MOSI
   9 SPI_SWITCH_CS0_N     YC @BASEBOARD_FAB2_LIB.BASEBOARD_FAB2(SCH_1):SPI_SWITCH_CS0_N
  12 SPI_SWITCH_MISO     YD @BASEBOARD_FAB2_LIB.BASEBOARD_FAB2(SCH_1):SPI_SWITCH_MISO
   2 SPI_PCH_CLK    IA0 @BASEBOARD_FAB2_LIB.BASEBOARD_FAB2(SCH_1):SPI_PCH_CLK
   3 SPI_BMC_CLK    IA1 @BASEBOARD_FAB2_LIB.BASEBOARD_FAB2(SCH_1):SPI_BMC_CLK
   5 SPI_PCH_MOSI    IB0 @BASEBOARD_FAB2_LIB.BASEBOARD_FAB2(SCH_1):SPI_PCH_MOSI
   6 SPI_BMC_DO    IB1 @BASEBOARD_FAB2_LIB.BASEBOARD_FAB2(SCH_1):SPI_BMC_DO
  11 SPI_PCH_CS0_N    IC0 @BASEBOARD_FAB2_LIB.BASEBOARD_FAB2(SCH_1):SPI_PCH_CS0_N
  10 SPI_BMC_CS0_N    IC1 @BASEBOARD_FAB2_LIB.BASEBOARD_FAB2(SCH_1):SPI_BMC_CS0_N
  14 SPI_PCH_MISO_R    ID0 @BASEBOARD_FAB2_LIB.BASEBOARD_FAB2(SCH_1):SPI_PCH_MISO_R
  13 SPI_BMC_DI    ID1 @BASEBOARD_FAB2_LIB.BASEBOARD_FAB2(SCH_1):SPI_BMC_DI

PI3B3257A_TSSOPLF-IC,E16801-001  I75  U2T1
  16 P3V3_STBY    VCC @BASEBOARD_FAB2_LIB.BASEBOARD_FAB2(SCH_1):P3V3_STBY
   8    GND    GND @BASEBOARD_FAB2_LIB.BASEBOARD_FAB2(SCH_1):GND
  15    GND     EN @BASEBOARD_FAB2_LIB.BASEBOARD_FAB2(SCH_1):GND
   1 FM_BIOS_SPI_BMC_CTRL      S @BASEBOARD_FAB2_LIB.BASEBOARD_FAB2(SCH_1):FM_BIOS_SPI_BMC_CTRL
   4 SPI_BIOS_SOCKET_IO2     YA @BASEBOARD_FAB2_LIB.BASEBOARD_FAB2(SCH_1):SPI_BIOS_SOCKET_IO2
   7 SPI_BIOS_SOCKET_IO3     YB @BASEBOARD_FAB2_LIB.BASEBOARD_FAB2(SCH_1):SPI_BIOS_SOCKET_IO3
   9 TP_SPI_SWITCH1_9     YC @BASEBOARD_FAB2_LIB.BASEBOARD_FAB2(SCH_1):TP_SPI_SWITCH1_9
  12 TP_SPI_SWITCH1_12     YD @BASEBOARD_FAB2_LIB.BASEBOARD_FAB2(SCH_1):TP_SPI_SWITCH1_12
   2 SPI_PCH_IO2_R1    IA0 @BASEBOARD_FAB2_LIB.BASEBOARD_FAB2(SCH_1):SPI_PCH_IO2_R1
   3 TP_SPI_SWITCH1_3    IA1 @BASEBOARD_FAB2_LIB.BASEBOARD_FAB2(SCH_1):TP_SPI_SWITCH1_3
   5 SPI_PCH_IO3_R1    IB0 @BASEBOARD_FAB2_LIB.BASEBOARD_FAB2(SCH_1):SPI_PCH_IO3_R1
   6 TP_SPI_SWITCH1_6    IB1 @BASEBOARD_FAB2_LIB.BASEBOARD_FAB2(SCH_1):TP_SPI_SWITCH1_6
  11 TP_SPI_SWITCH1_11    IC0 @BASEBOARD_FAB2_LIB.BASEBOARD_FAB2(SCH_1):TP_SPI_SWITCH1_11
  10 TP_SPI_SWITCH1_10    IC1 @BASEBOARD_FAB2_LIB.BASEBOARD_FAB2(SCH_1):TP_SPI_SWITCH1_10
  14 TP_SPI_SWITCH1_14    ID0 @BASEBOARD_FAB2_LIB.BASEBOARD_FAB2(SCH_1):TP_SPI_SWITCH1_14
  13 TP_SPI_SWITCH1_13    ID1 @BASEBOARD_FAB2_LIB.BASEBOARD_FAB2(SCH_1):TP_SPI_SWITCH1_13

RES_0402-0.0,5%,1/16W,CHIP,G21A  I92  R2T2
   1 SPI_PCH_IO3      A @BASEBOARD_FAB2_LIB.BASEBOARD_FAB2(SCH_1):SPI_PCH_IO3
   2 SPI_PCH_IO3_R1      B @BASEBOARD_FAB2_LIB.BASEBOARD_FAB2(SCH_1):SPI_PCH_IO3_R1

RES_0402-0.0,5%,1/16W,CHIP,G21A  I93  R2R12
   1 SPI_PCH_IO2      A @BASEBOARD_FAB2_LIB.BASEBOARD_FAB2(SCH_1):SPI_PCH_IO2
   2 SPI_PCH_IO2_R1      B @BASEBOARD_FAB2_LIB.BASEBOARD_FAB2(SCH_1):SPI_PCH_IO2_R1

CAP_A_0402V-0.1UF,16V,10%,X7R,A  I94  C2T1
   1 P3V3_STBY      A @BASEBOARD_FAB2_LIB.BASEBOARD_FAB2(SCH_1):P3V3_STBY
   2    GND      B @BASEBOARD_FAB2_LIB.BASEBOARD_FAB2(SCH_1):GND

TTL1G32_A_SOT-74LVC1G32,IC,E60B  I99  U2T3
   1 FM_DUAL_BIOS_SEL_N      A @BASEBOARD_FAB2_LIB.BASEBOARD_FAB2(SCH_1):FM_DUAL_BIOS_SEL_N
   2 SPI_SWITCH_CS0_N      B @BASEBOARD_FAB2_LIB.BASEBOARD_FAB2(SCH_1):SPI_SWITCH_CS0_N
   4 SPI_CS0_PRIMARY_N      Y @BASEBOARD_FAB2_LIB.BASEBOARD_FAB2(SCH_1):SPI_CS0_PRIMARY_N

TTL1G32_A_SOT-74LVC1G32,IC,E60B  I100  U2T2
   1 FM_BACKUP_BIOS_SEL_N      A @BASEBOARD_FAB2_LIB.BASEBOARD_FAB2(SCH_1):FM_BACKUP_BIOS_SEL_N
   2 SPI_SWITCH_CS0_N      B @BASEBOARD_FAB2_LIB.BASEBOARD_FAB2(SCH_1):SPI_SWITCH_CS0_N
   4 SPI_CS0_SECONDARY_N      Y @BASEBOARD_FAB2_LIB.BASEBOARD_FAB2(SCH_1):SPI_CS0_SECONDARY_N

RES_0402-200.0,1%,1/16W,CHIP,GA  I101  R2T13
   1 SPI_CS0_PRIMARY_N      A @BASEBOARD_FAB2_LIB.BASEBOARD_FAB2(SCH_1):SPI_CS0_PRIMARY_N
   2 SPI_CS0_PRIMARY_R_N      B @BASEBOARD_FAB2_LIB.BASEBOARD_FAB2(SCH_1):SPI_CS0_PRIMARY_R_N

RES_0402-4.75K,1%,1/16W,CHIP,GA  I105  R2T11
   1 P3V3_STBY      A @BASEBOARD_FAB2_LIB.BASEBOARD_FAB2(SCH_1):P3V3_STBY
   2 FM_DUAL_BIOS_SEL_N      B @BASEBOARD_FAB2_LIB.BASEBOARD_FAB2(SCH_1):FM_DUAL_BIOS_SEL_N

RES_0402-10.0K,1%,1/16W,CHIP,GA  I106  R2T8
   1 P3V3_STBY      A @BASEBOARD_FAB2_LIB.BASEBOARD_FAB2(SCH_1):P3V3_STBY
   2 SPI_SWITCH_CS0_N      B @BASEBOARD_FAB2_LIB.BASEBOARD_FAB2(SCH_1):SPI_SWITCH_CS0_N

RES_0402-0.0,5%,1/16W,CHIP,G21A  I119  R8F6
   1 SPI_PCH_MISO      A @BASEBOARD_FAB2_LIB.BASEBOARD_FAB2(SCH_1):SPI_PCH_MISO
   2 SPI_PCH_MISO_R      B @BASEBOARD_FAB2_LIB.BASEBOARD_FAB2(SCH_1):SPI_PCH_MISO_R

FET_N_SOT23LF-2N7002,FET,C7925A  I126  Q8F1
   1 FM_BACKUP_BIOS_SEL_N   GATE @BASEBOARD_FAB2_LIB.BASEBOARD_FAB2(SCH_1):FM_BACKUP_BIOS_SEL_N
   2    GND    SRC @BASEBOARD_FAB2_LIB.BASEBOARD_FAB2(SCH_1):GND
   3 FM_DUAL_BIOS_SEL_N    DRN @BASEBOARD_FAB2_LIB.BASEBOARD_FAB2(SCH_1):FM_DUAL_BIOS_SEL_N

RES_0402-4.75K,1%,1/16W,CHIP,GA  I127  R2T6
   1 P3V3_STBY      A @BASEBOARD_FAB2_LIB.BASEBOARD_FAB2(SCH_1):P3V3_STBY
   2 FM_BACKUP_BIOS_SEL_N      B @BASEBOARD_FAB2_LIB.BASEBOARD_FAB2(SCH_1):FM_BACKUP_BIOS_SEL_N

RES_0402-10.0K,1%,1/16W,CHIP,GA  I128  R1U6
   1 FM_BIOS_SPI_BMC_CTRL      A @BASEBOARD_FAB2_LIB.BASEBOARD_FAB2(SCH_1):FM_BIOS_SPI_BMC_CTRL
   2    GND      B @BASEBOARD_FAB2_LIB.BASEBOARD_FAB2(SCH_1):GND

CAP_A_0402V-0.1UF,16V,10%,X7R,A  I132  C2T12
   1 P3V3_STBY      A @BASEBOARD_FAB2_LIB.BASEBOARD_FAB2(SCH_1):P3V3_STBY
   2    GND      B @BASEBOARD_FAB2_LIB.BASEBOARD_FAB2(SCH_1):GND

CAP_A_0402V-0.1UF,16V,10%,X7R,A  I135  C2T8
   1 P3V3_STBY      A @BASEBOARD_FAB2_LIB.BASEBOARD_FAB2(SCH_1):P3V3_STBY
   2    GND      B @BASEBOARD_FAB2_LIB.BASEBOARD_FAB2(SCH_1):GND


DRAWING: @BASEBOARD_FAB2_LIB.BASEBOARD_FAB2(SCH_1):PAGE155 

RES_0402-0.0,5%,1/16W,CHIP,G21A  I53  R9A8
   1 SPA_SIN_SW_R      A @BASEBOARD_FAB2_LIB.BASEBOARD_FAB2(SCH_1):SPA_SIN_SW_R
   2 SPA_MID_DBG1_RX      B @BASEBOARD_FAB2_LIB.BASEBOARD_FAB2(SCH_1):SPA_MID_DBG1_RX

RES_0402-10.0,1%,1/16W,CHIP,G2A  I65  R1L32
   1 LED_POSTCODE_0      A @BASEBOARD_FAB2_LIB.BASEBOARD_FAB2(SCH_1):LED_POSTCODE_0
   2 LED_POSTCODE_0_R      B @BASEBOARD_FAB2_LIB.BASEBOARD_FAB2(SCH_1):LED_POSTCODE_0_R

RES_0402-10.0,1%,1/16W,CHIP,G2A  I66  R1L30
   1 LED_POSTCODE_1      A @BASEBOARD_FAB2_LIB.BASEBOARD_FAB2(SCH_1):LED_POSTCODE_1
   2 LED_POSTCODE_1_R      B @BASEBOARD_FAB2_LIB.BASEBOARD_FAB2(SCH_1):LED_POSTCODE_1_R

RES_0402-10.0,1%,1/16W,CHIP,G2A  I67  R1L25
   1 LED_POSTCODE_2      A @BASEBOARD_FAB2_LIB.BASEBOARD_FAB2(SCH_1):LED_POSTCODE_2
   2 LED_POSTCODE_2_R      B @BASEBOARD_FAB2_LIB.BASEBOARD_FAB2(SCH_1):LED_POSTCODE_2_R

RES_0402-10.0,1%,1/16W,CHIP,G2A  I68  R1L24
   1 LED_POSTCODE_3      A @BASEBOARD_FAB2_LIB.BASEBOARD_FAB2(SCH_1):LED_POSTCODE_3
   2 LED_POSTCODE_3_R      B @BASEBOARD_FAB2_LIB.BASEBOARD_FAB2(SCH_1):LED_POSTCODE_3_R

RES_0402-10.0,1%,1/16W,CHIP,G2A  I73  R1L20
   1 LED_POSTCODE_4      A @BASEBOARD_FAB2_LIB.BASEBOARD_FAB2(SCH_1):LED_POSTCODE_4
   2 LED_POSTCODE_4_R      B @BASEBOARD_FAB2_LIB.BASEBOARD_FAB2(SCH_1):LED_POSTCODE_4_R

RES_0402-10.0,1%,1/16W,CHIP,G2A  I74  R1L18
   1 LED_POSTCODE_5      A @BASEBOARD_FAB2_LIB.BASEBOARD_FAB2(SCH_1):LED_POSTCODE_5
   2 LED_POSTCODE_5_R      B @BASEBOARD_FAB2_LIB.BASEBOARD_FAB2(SCH_1):LED_POSTCODE_5_R

RES_0402-10.0,1%,1/16W,CHIP,G2A  I75  R1L14
   1 LED_POSTCODE_6      A @BASEBOARD_FAB2_LIB.BASEBOARD_FAB2(SCH_1):LED_POSTCODE_6
   2 LED_POSTCODE_6_R      B @BASEBOARD_FAB2_LIB.BASEBOARD_FAB2(SCH_1):LED_POSTCODE_6_R

RES_0402-10.0,1%,1/16W,CHIP,G2A  I76  R1L11
   1 LED_POSTCODE_7      A @BASEBOARD_FAB2_LIB.BASEBOARD_FAB2(SCH_1):LED_POSTCODE_7
   2 LED_POSTCODE_7_R      B @BASEBOARD_FAB2_LIB.BASEBOARD_FAB2(SCH_1):LED_POSTCODE_7_R

RES_0402-2.21K,1%,1/16W,CHIP,GA  I80  R9A7
   1 P3V3_STBY      A @BASEBOARD_FAB2_LIB.BASEBOARD_FAB2(SCH_1):P3V3_STBY
   2 SPA_SIN_SW_R      B @BASEBOARD_FAB2_LIB.BASEBOARD_FAB2(SCH_1):SPA_SIN_SW_R

CAP_A_0402V-0.1UF,16V,10%,X7R,A  I127  C9A1
   1 P5V_STBY_DGB_FS      A @BASEBOARD_FAB2_LIB.BASEBOARD_FAB2(SCH_1):P5V_STBY_DGB_FS
   2    GND      B @BASEBOARD_FAB2_LIB.BASEBOARD_FAB2(SCH_1):GND

FUSE_SMT-IC,H45581-001  I129  F1L1
   1 P5V_STBY_DBG   A<0> @BASEBOARD_FAB2_LIB.BASEBOARD_FAB2(SCH_1):P5V_STBY_DBG
   2 P5V_STBY_DGB_FS   B<0> @BASEBOARD_FAB2_LIB.BASEBOARD_FAB2(SCH_1):P5V_STBY_DGB_FS

RES_0402-100.0K,1%,1/16W,CHIP,A  I130  R1L9
   1 P12V_STBY      A @BASEBOARD_FAB2_LIB.BASEBOARD_FAB2(SCH_1):P12V_STBY
   2 FM_CPLD_DBG_PWR_EN      B @BASEBOARD_FAB2_LIB.BASEBOARD_FAB2(SCH_1):FM_CPLD_DBG_PWR_EN

CONN14_H54902001_PIP-CONN,H549A  I171  J9A2
   1 LED_POSTCODE_0_R    IO1 @BASEBOARD_FAB2_LIB.BASEBOARD_FAB2(SCH_1):LED_POSTCODE_0_R
  10 SPA_5V_SIN_SW   IO10 @BASEBOARD_FAB2_LIB.BASEBOARD_FAB2(SCH_1):SPA_5V_SIN_SW
  11 FM_DEBUG_RST_BTN_N   IO11 @BASEBOARD_FAB2_LIB.BASEBOARD_FAB2(SCH_1):FM_DEBUG_RST_BTN_N
  12 FM_UART_SWITCH_N   IO12 @BASEBOARD_FAB2_LIB.BASEBOARD_FAB2(SCH_1):FM_UART_SWITCH_N
  13    GND   IO13 @BASEBOARD_FAB2_LIB.BASEBOARD_FAB2(SCH_1):GND
  14 P5V_STBY_DGB_FS   IO14 @BASEBOARD_FAB2_LIB.BASEBOARD_FAB2(SCH_1):P5V_STBY_DGB_FS
   2 LED_POSTCODE_1_R    IO2 @BASEBOARD_FAB2_LIB.BASEBOARD_FAB2(SCH_1):LED_POSTCODE_1_R
   3 LED_POSTCODE_2_R    IO3 @BASEBOARD_FAB2_LIB.BASEBOARD_FAB2(SCH_1):LED_POSTCODE_2_R
   4 LED_POSTCODE_3_R    IO4 @BASEBOARD_FAB2_LIB.BASEBOARD_FAB2(SCH_1):LED_POSTCODE_3_R
   5 LED_POSTCODE_4_R    IO5 @BASEBOARD_FAB2_LIB.BASEBOARD_FAB2(SCH_1):LED_POSTCODE_4_R
   6 LED_POSTCODE_5_R    IO6 @BASEBOARD_FAB2_LIB.BASEBOARD_FAB2(SCH_1):LED_POSTCODE_5_R
   7 LED_POSTCODE_6_R    IO7 @BASEBOARD_FAB2_LIB.BASEBOARD_FAB2(SCH_1):LED_POSTCODE_6_R
   8 LED_POSTCODE_7_R    IO8 @BASEBOARD_FAB2_LIB.BASEBOARD_FAB2(SCH_1):LED_POSTCODE_7_R
   9 SPA_MID_DBG1_TX    IO9 @BASEBOARD_FAB2_LIB.BASEBOARD_FAB2(SCH_1):SPA_MID_DBG1_TX

TTL1G07_A_SOP-74LVC1G07,IC,C88B  I178  U9A1
   2 SPA_5V_SIN_SW_D      A @BASEBOARD_FAB2_LIB.BASEBOARD_FAB2(SCH_1):SPA_5V_SIN_SW_D
   4 SPA_SIN_SW_R      Y @BASEBOARD_FAB2_LIB.BASEBOARD_FAB2(SCH_1):SPA_SIN_SW_R

CAP_A_0402V-0.1UF,16V,10%,X7R,A  I184  C1T56
   1 P3V3_STBY      A @BASEBOARD_FAB2_LIB.BASEBOARD_FAB2(SCH_1):P3V3_STBY
   2    GND      B @BASEBOARD_FAB2_LIB.BASEBOARD_FAB2(SCH_1):GND

RES_0402-10.0,1%,1/16W,CHIP,G2A  I186  R1L2
   1 FM_CPLD_DBG_PWR_EN_N      A @BASEBOARD_FAB2_LIB.BASEBOARD_FAB2(SCH_1):FM_CPLD_DBG_PWR_EN_N
   2 FM_CPLD_DBG_PWR_EN_R_N      B @BASEBOARD_FAB2_LIB.BASEBOARD_FAB2(SCH_1):FM_CPLD_DBG_PWR_EN_R_N

FET_N_DUAL_SMLF-NTJD4001N,FET,A  I187  Q1L2
   5 FM_CPLD_DBG_PWR_EN_R_N GATE<0> @BASEBOARD_FAB2_LIB.BASEBOARD_FAB2(SCH_1):FM_CPLD_DBG_PWR_EN_R_N
   4    GND SOURCE<0> @BASEBOARD_FAB2_LIB.BASEBOARD_FAB2(SCH_1):GND
   3 FM_CPLD_DBG_PWR_EN DRAIN<0> @BASEBOARD_FAB2_LIB.BASEBOARD_FAB2(SCH_1):FM_CPLD_DBG_PWR_EN

FET_N_DUAL_SMLF-NTJD4001N,FET,A  I188  Q1L2
   2 FM_CPLD_DBG_PWR_EN GATE<0> @BASEBOARD_FAB2_LIB.BASEBOARD_FAB2(SCH_1):FM_CPLD_DBG_PWR_EN
   1 P5V_STBY_DBG SOURCE<0> @BASEBOARD_FAB2_LIB.BASEBOARD_FAB2(SCH_1):P5V_STBY_DBG
   6 P5V_STBY DRAIN<0> @BASEBOARD_FAB2_LIB.BASEBOARD_FAB2(SCH_1):P5V_STBY

RES_0402-0.0,5%,1/16W,CHIP,G21A  I196  R6W19
   1 SPA_5V_SIN_SW_D      A @BASEBOARD_FAB2_LIB.BASEBOARD_FAB2(SCH_1):SPA_5V_SIN_SW_D
   2 SPA_SIN_SW_R      B @BASEBOARD_FAB2_LIB.BASEBOARD_FAB2(SCH_1):SPA_SIN_SW_R

RES_0402-20.0K,1%,1/16W,CHIP,GA  I198  R9A5
   1 P5V_STBY      A @BASEBOARD_FAB2_LIB.BASEBOARD_FAB2(SCH_1):P5V_STBY
   2 FM_UART_SWITCH_N      B @BASEBOARD_FAB2_LIB.BASEBOARD_FAB2(SCH_1):FM_UART_SWITCH_N

RES_0402-10.0K,1%,1/16W,CHIP,GA  I201  R6W40
   1 P3V3_STBY      A @BASEBOARD_FAB2_LIB.BASEBOARD_FAB2(SCH_1):P3V3_STBY
   2 SPA_5V_SIN_SW_D      B @BASEBOARD_FAB2_LIB.BASEBOARD_FAB2(SCH_1):SPA_5V_SIN_SW_D

DIODE_SMLF-BAT54WS,IC,C73510-0A  I202  CR9W1
   1 SPA_5V_SIN_SW      C @BASEBOARD_FAB2_LIB.BASEBOARD_FAB2(SCH_1):SPA_5V_SIN_SW
   2 SPA_5V_SIN_SW_D      A @BASEBOARD_FAB2_LIB.BASEBOARD_FAB2(SCH_1):SPA_5V_SIN_SW_D


DRAWING: @BASEBOARD_FAB2_LIB.BASEBOARD_FAB2(SCH_1):PAGE156 

RES_0402-4.75K,1%,1/16W,CHIP,GA  I206  R2T34
   1 P3V3_STBY      A @BASEBOARD_FAB2_LIB.BASEBOARD_FAB2(SCH_1):P3V3_STBY
   2 FM_BMC_PWRBTN_OUT_N      B @BASEBOARD_FAB2_LIB.BASEBOARD_FAB2(SCH_1):FM_BMC_PWRBTN_OUT_N

RES_0402-4.75K,1%,1/16W,CHIP,GA  I207  R2T35
   1 P3V3_STBY      A @BASEBOARD_FAB2_LIB.BASEBOARD_FAB2(SCH_1):P3V3_STBY
   2 RST_BMC_SYSRST_BTN_OUT_N      B @BASEBOARD_FAB2_LIB.BASEBOARD_FAB2(SCH_1):RST_BMC_SYSRST_BTN_OUT_N

RES_0402-10.0K,1%,1/16W,CHIP,GA  I210  R2T22
   1 P3V3_STBY      A @BASEBOARD_FAB2_LIB.BASEBOARD_FAB2(SCH_1):P3V3_STBY
   2 RST_BMC_SYSRST_BTN_OUT_B_R_N      B @BASEBOARD_FAB2_LIB.BASEBOARD_FAB2(SCH_1):RST_BMC_SYSRST_BTN_OUT_B_R_N

RES_0402-10.0K,1%,1/16W,CHIP,GA  I211  R8F26
   1 P3V3_STBY      A @BASEBOARD_FAB2_LIB.BASEBOARD_FAB2(SCH_1):P3V3_STBY
   2 FM_PCH_PWRBTN_R_N      B @BASEBOARD_FAB2_LIB.BASEBOARD_FAB2(SCH_1):FM_PCH_PWRBTN_R_N

RES_0402-33.2,1%,1/16W,CHIP,G2A  I214  R8E24
   1 IRQ_BMC_PCH_NMI_STBY_N      A @BASEBOARD_FAB2_LIB.BASEBOARD_FAB2(SCH_1):IRQ_BMC_PCH_NMI_STBY_N
   2 IRQ_BMC_PCH_NMI_STBY_R_N      B @BASEBOARD_FAB2_LIB.BASEBOARD_FAB2(SCH_1):IRQ_BMC_PCH_NMI_STBY_R_N

RES_0402-4.75K,1%,1/16W,CHIP,GA  I215  R8E22
   1 P3V3_STBY      A @BASEBOARD_FAB2_LIB.BASEBOARD_FAB2(SCH_1):P3V3_STBY
   2 IRQ_BMC_PCH_NMI_STBY_N      B @BASEBOARD_FAB2_LIB.BASEBOARD_FAB2(SCH_1):IRQ_BMC_PCH_NMI_STBY_N

RES_0402-4.75K,1%,1/16W,CHIP,GA  I265  R2U2
   1 P3V3_STBY      A @BASEBOARD_FAB2_LIB.BASEBOARD_FAB2(SCH_1):P3V3_STBY
   2 RST_PCH_SYSRST_BTN_OUT_N      B @BASEBOARD_FAB2_LIB.BASEBOARD_FAB2(SCH_1):RST_PCH_SYSRST_BTN_OUT_N

RES_0402-4.75K,1%,1/16W,CHIP,GA  I267  R8G2
   1 P3V3_STBY      A @BASEBOARD_FAB2_LIB.BASEBOARD_FAB2(SCH_1):P3V3_STBY
   2 FM_PCH_PWRBTN_OUT_N      B @BASEBOARD_FAB2_LIB.BASEBOARD_FAB2(SCH_1):FM_PCH_PWRBTN_OUT_N

CAP_A_0402V-0.1UF,16V,10%,X7R,A  I273  C2T35
   1 P3V3_STBY      A @BASEBOARD_FAB2_LIB.BASEBOARD_FAB2(SCH_1):P3V3_STBY
   2    GND      B @BASEBOARD_FAB2_LIB.BASEBOARD_FAB2(SCH_1):GND

CAP_A_0402V-0.1UF,16V,10%,X7R,A  I275  C8F16
   1 P3V3_STBY      A @BASEBOARD_FAB2_LIB.BASEBOARD_FAB2(SCH_1):P3V3_STBY
   2    GND      B @BASEBOARD_FAB2_LIB.BASEBOARD_FAB2(SCH_1):GND

RES_0402-0.0,5%,1/16W,EMPTY,G2A  I279  R8E11
   1 FM_MEM_THERM_EVENT_LVT3_N      A @BASEBOARD_FAB2_LIB.BASEBOARD_FAB2(SCH_1):FM_MEM_THERM_EVENT_LVT3_N
   2 FM_ADR_SMI_GPIO_N      B @BASEBOARD_FAB2_LIB.BASEBOARD_FAB2(SCH_1):FM_ADR_SMI_GPIO_N

CONN3_C95678002_PIP-CONN,C9567A  I281  J9B2
   1 SMB_SMLINK0_STBY_LVC3_SDA    IO1 @BASEBOARD_FAB2_LIB.BASEBOARD_FAB2(SCH_1):SMB_SMLINK0_STBY_LVC3_SDA
   2    GND    IO2 @BASEBOARD_FAB2_LIB.BASEBOARD_FAB2(SCH_1):GND
   3 SMB_SMLINK0_STBY_LVC3_SCL    IO3 @BASEBOARD_FAB2_LIB.BASEBOARD_FAB2(SCH_1):SMB_SMLINK0_STBY_LVC3_SCL

CONN3_C95678002_PIP-CONN,C9567A  I285  J8C1
   1 SMB_HOST_STBY_LVC3_SDA    IO1 @BASEBOARD_FAB2_LIB.BASEBOARD_FAB2(SCH_1):SMB_HOST_STBY_LVC3_SDA
   2    GND    IO2 @BASEBOARD_FAB2_LIB.BASEBOARD_FAB2(SCH_1):GND
   3 SMB_HOST_STBY_LVC3_SCL    IO3 @BASEBOARD_FAB2_LIB.BASEBOARD_FAB2(SCH_1):SMB_HOST_STBY_LVC3_SCL

RES_0402-49.9,1%,1/16W,CHIP,G2A  I288  R2T18
   1 RST_BMC_SYSRST_BTN_OUT_B_R_N      A @BASEBOARD_FAB2_LIB.BASEBOARD_FAB2(SCH_1):RST_BMC_SYSRST_BTN_OUT_B_R_N
   2 RST_BMC_SYSRST_BTN_OUT_B_N      B @BASEBOARD_FAB2_LIB.BASEBOARD_FAB2(SCH_1):RST_BMC_SYSRST_BTN_OUT_B_N

RES_0402-33.2,1%,1/16W,CHIP,G2A  I289  R2T28
   1 FM_PCH_PWRBTN_R_N      A @BASEBOARD_FAB2_LIB.BASEBOARD_FAB2(SCH_1):FM_PCH_PWRBTN_R_N
   2 FM_PCH_PWRBTN_N      B @BASEBOARD_FAB2_LIB.BASEBOARD_FAB2(SCH_1):FM_PCH_PWRBTN_N

RES_0402-0.0,5%,1/16W,EMPTY,G2A  I299  R6D16
   1 FM_CPU_BMC_INIT      A @BASEBOARD_FAB2_LIB.BASEBOARD_FAB2(SCH_1):FM_CPU_BMC_INIT
   2 H_CPU0_BMCINIT      B @BASEBOARD_FAB2_LIB.BASEBOARD_FAB2(SCH_1):H_CPU0_BMCINIT

RES_0402-0.0,5%,1/16W,EMPTY,G2A  I300  R3D31
   1 FM_CPU_BMC_INIT      A @BASEBOARD_FAB2_LIB.BASEBOARD_FAB2(SCH_1):FM_CPU_BMC_INIT
   2 H_CPU1_BMCINIT      B @BASEBOARD_FAB2_LIB.BASEBOARD_FAB2(SCH_1):H_CPU1_BMCINIT

RES_0402-1.00K,1%,1/16W,CHIP,GA  I302  R6N14
   1    GND      A @BASEBOARD_FAB2_LIB.BASEBOARD_FAB2(SCH_1):GND
   2 PD_PIROM_CPU0_ADDR0      B @BASEBOARD_FAB2_LIB.BASEBOARD_FAB2(SCH_1):PD_PIROM_CPU0_ADDR0

RES_0402-1.00K,1%,1/16W,CHIP,GA  I303  R6N13
   1    GND      A @BASEBOARD_FAB2_LIB.BASEBOARD_FAB2(SCH_1):GND
   2 PD_PIROM_CPU0_ADDR1      B @BASEBOARD_FAB2_LIB.BASEBOARD_FAB2(SCH_1):PD_PIROM_CPU0_ADDR1

RES_0402-1.00K,1%,1/16W,CHIP,GA  I304  R6N15
   1    GND      A @BASEBOARD_FAB2_LIB.BASEBOARD_FAB2(SCH_1):GND
   2 PD_PIROM_CPU0_ADDR2      B @BASEBOARD_FAB2_LIB.BASEBOARD_FAB2(SCH_1):PD_PIROM_CPU0_ADDR2

RES_0402-1.00K,1%,1/16W,CHIP,GA  I312  R1C32
   1    GND      A @BASEBOARD_FAB2_LIB.BASEBOARD_FAB2(SCH_1):GND
   2 PD_PIROM_CPU1_ADDR2      B @BASEBOARD_FAB2_LIB.BASEBOARD_FAB2(SCH_1):PD_PIROM_CPU1_ADDR2

RES_0402-1.00K,1%,1/16W,CHIP,GA  I313  R1C33
   1    GND      A @BASEBOARD_FAB2_LIB.BASEBOARD_FAB2(SCH_1):GND
   2 PD_PIROM_CPU1_ADDR1      B @BASEBOARD_FAB2_LIB.BASEBOARD_FAB2(SCH_1):PD_PIROM_CPU1_ADDR1

RES_0402-10.0K,1%,1/16W,CHIP,GA  I320  R1C34
   1 P3V3_STBY      A @BASEBOARD_FAB2_LIB.BASEBOARD_FAB2(SCH_1):P3V3_STBY
   2 PU_PIROM_CPU1_ADDR0      B @BASEBOARD_FAB2_LIB.BASEBOARD_FAB2(SCH_1):PU_PIROM_CPU1_ADDR0

RES_0402-0.0,5%,1/16W,CHIP,G21A  I321  R9M21
   1 SMB_LAN_STBY_LVC3_SDA      A @BASEBOARD_FAB2_LIB.BASEBOARD_FAB2(SCH_1):SMB_LAN_STBY_LVC3_SDA
   2 SMB_PIROM_CPU1_SDA      B @BASEBOARD_FAB2_LIB.BASEBOARD_FAB2(SCH_1):SMB_PIROM_CPU1_SDA

RES_0402-0.0,5%,1/16W,CHIP,G21A  I322  R4A8
   1 SMB_LAN_STBY_LVC3_SDA      A @BASEBOARD_FAB2_LIB.BASEBOARD_FAB2(SCH_1):SMB_LAN_STBY_LVC3_SDA
   2 SMB_PIROM_CPU0_SDA      B @BASEBOARD_FAB2_LIB.BASEBOARD_FAB2(SCH_1):SMB_PIROM_CPU0_SDA

RES_0402-0.0,5%,1/16W,CHIP,G21A  I323  R9M20
   1 SMB_LAN_STBY_LVC3_SCL      A @BASEBOARD_FAB2_LIB.BASEBOARD_FAB2(SCH_1):SMB_LAN_STBY_LVC3_SCL
   2 SMB_PIROM_CPU1_SCL      B @BASEBOARD_FAB2_LIB.BASEBOARD_FAB2(SCH_1):SMB_PIROM_CPU1_SCL

RES_0402-0.0,5%,1/16W,CHIP,G21A  I324  R4A9
   1 SMB_LAN_STBY_LVC3_SCL      A @BASEBOARD_FAB2_LIB.BASEBOARD_FAB2(SCH_1):SMB_LAN_STBY_LVC3_SCL
   2 SMB_PIROM_CPU0_SCL      B @BASEBOARD_FAB2_LIB.BASEBOARD_FAB2(SCH_1):SMB_PIROM_CPU0_SCL

RES_0402-3.32K,1%,1/16W,EMPTY,A  I331  R3P54
   1 P3V3_STBY      A @BASEBOARD_FAB2_LIB.BASEBOARD_FAB2(SCH_1):P3V3_STBY
   2 FM_CPU0_SM_WP      B @BASEBOARD_FAB2_LIB.BASEBOARD_FAB2(SCH_1):FM_CPU0_SM_WP

RES_0402-1.00K,1%,1/16W,CHIP,GA  I333  R3P56
   1 FM_CPU0_SM_WP      A @BASEBOARD_FAB2_LIB.BASEBOARD_FAB2(SCH_1):FM_CPU0_SM_WP
   2    GND      B @BASEBOARD_FAB2_LIB.BASEBOARD_FAB2(SCH_1):GND

RES_0402-3.32K,1%,1/16W,EMPTY,A  I336  R1C35
   1 P3V3_STBY      A @BASEBOARD_FAB2_LIB.BASEBOARD_FAB2(SCH_1):P3V3_STBY
   2 FM_CPU1_SM_WP      B @BASEBOARD_FAB2_LIB.BASEBOARD_FAB2(SCH_1):FM_CPU1_SM_WP

RES_0402-1.00K,1%,1/16W,CHIP,GA  I337  R1C36
   1 FM_CPU1_SM_WP      A @BASEBOARD_FAB2_LIB.BASEBOARD_FAB2(SCH_1):FM_CPU1_SM_WP
   2    GND      B @BASEBOARD_FAB2_LIB.BASEBOARD_FAB2(SCH_1):GND

SN74LVC2G07DCKR-GP_DISCRET-G4-A  I340  U8F3
   1 RST_BMC_SYSRST_BTN_OUT_N     1A @BASEBOARD_FAB2_LIB.BASEBOARD_FAB2(SCH_1):RST_BMC_SYSRST_BTN_OUT_N
   2    GND    GND @BASEBOARD_FAB2_LIB.BASEBOARD_FAB2(SCH_1):GND
   3 FM_BMC_PWRBTN_OUT_N     2A @BASEBOARD_FAB2_LIB.BASEBOARD_FAB2(SCH_1):FM_BMC_PWRBTN_OUT_N
   4 FM_PCH_PWRBTN_R_N     2Y @BASEBOARD_FAB2_LIB.BASEBOARD_FAB2(SCH_1):FM_PCH_PWRBTN_R_N
   5 P3V3_STBY    VCC @BASEBOARD_FAB2_LIB.BASEBOARD_FAB2(SCH_1):P3V3_STBY
   6 RST_BMC_SYSRST_BTN_OUT_B_R_N     1Y @BASEBOARD_FAB2_LIB.BASEBOARD_FAB2(SCH_1):RST_BMC_SYSRST_BTN_OUT_B_R_N

SN74LVC2G07DCKR-GP_DISCRET-G4-A  I342  U8G1
   1 RST_PCH_SYSRST_BTN_OUT_N     1A @BASEBOARD_FAB2_LIB.BASEBOARD_FAB2(SCH_1):RST_PCH_SYSRST_BTN_OUT_N
   2    GND    GND @BASEBOARD_FAB2_LIB.BASEBOARD_FAB2(SCH_1):GND
   3 FM_PCH_PWRBTN_OUT_N     2A @BASEBOARD_FAB2_LIB.BASEBOARD_FAB2(SCH_1):FM_PCH_PWRBTN_OUT_N
   4 FM_PCH_PWRBTN_R_N     2Y @BASEBOARD_FAB2_LIB.BASEBOARD_FAB2(SCH_1):FM_PCH_PWRBTN_R_N
   5 P3V3_STBY    VCC @BASEBOARD_FAB2_LIB.BASEBOARD_FAB2(SCH_1):P3V3_STBY
   6 RST_BMC_SYSRST_BTN_OUT_B_R_N     1Y @BASEBOARD_FAB2_LIB.BASEBOARD_FAB2(SCH_1):RST_BMC_SYSRST_BTN_OUT_B_R_N


DRAWING: @BASEBOARD_FAB2_LIB.BASEBOARD_FAB2(SCH_1):PAGE157 

RES_0402-4.75K,1%,1/16W,CHIP,GA  I97  R2N27
   1   P3V3      A @BASEBOARD_FAB2_LIB.BASEBOARD_FAB2(SCH_1):P3V3
   2 FM_BMC_NMI_N      B @BASEBOARD_FAB2_LIB.BASEBOARD_FAB2(SCH_1):FM_BMC_NMI_N

RES_0402-2.21K,1%,1/16W,CHIP,GA  I296  R8F23
   1 P3V3_STBY      A @BASEBOARD_FAB2_LIB.BASEBOARD_FAB2(SCH_1):P3V3_STBY
   2 IRQ_MEZZ_LAN_ALERT_N      B @BASEBOARD_FAB2_LIB.BASEBOARD_FAB2(SCH_1):IRQ_MEZZ_LAN_ALERT_N

RES_0402-2.21K,1%,1/16W,CHIP,GA  I298  R2T29
   1 P3V3_STBY      A @BASEBOARD_FAB2_LIB.BASEBOARD_FAB2(SCH_1):P3V3_STBY
   2 IRQ_OOB_MGMT_RISER_ALERT_N      B @BASEBOARD_FAB2_LIB.BASEBOARD_FAB2(SCH_1):IRQ_OOB_MGMT_RISER_ALERT_N

RES_0402-51.1,1.0%,1/16W,CHIP,A  I302  R2N25
   1 FM_NMI_EVENT_N      A @BASEBOARD_FAB2_LIB.BASEBOARD_FAB2(SCH_1):FM_NMI_EVENT_N
   2 FM_BMC_NMI_N      B @BASEBOARD_FAB2_LIB.BASEBOARD_FAB2(SCH_1):FM_BMC_NMI_N

RES_0402-4.75K,1%,1/16W,CHIP,GA  I316  R8F24
   1 P3V3_STBY      A @BASEBOARD_FAB2_LIB.BASEBOARD_FAB2(SCH_1):P3V3_STBY
   2 FP_NMI_BTN_N      B @BASEBOARD_FAB2_LIB.BASEBOARD_FAB2(SCH_1):FP_NMI_BTN_N

RES_0402-1.00K,1%,1/16W,CHIP,GA  I326  R2T5
   1 P3V3_STBY      A @BASEBOARD_FAB2_LIB.BASEBOARD_FAB2(SCH_1):P3V3_STBY
   2 H_CPU0_FAST_WAKE      B @BASEBOARD_FAB2_LIB.BASEBOARD_FAB2(SCH_1):H_CPU0_FAST_WAKE

RES_0402-1.00K,1%,1/16W,CHIP,GA  I327  R2T7
   1 P3V3_STBY      A @BASEBOARD_FAB2_LIB.BASEBOARD_FAB2(SCH_1):P3V3_STBY
   2 H_CPU0_FAST_WAKE_LVT3_N      B @BASEBOARD_FAB2_LIB.BASEBOARD_FAB2(SCH_1):H_CPU0_FAST_WAKE_LVT3_N

NPN_SM-MMBT3904,IC,C52245-001  I330  Q2T1
   1 H_CPU0_FAST_WAKE_B_N      B @BASEBOARD_FAB2_LIB.BASEBOARD_FAB2(SCH_1):H_CPU0_FAST_WAKE_B_N
   3 H_CPU0_FAST_WAKE      C @BASEBOARD_FAB2_LIB.BASEBOARD_FAB2(SCH_1):H_CPU0_FAST_WAKE
   2    GND      E @BASEBOARD_FAB2_LIB.BASEBOARD_FAB2(SCH_1):GND

RES_0402-4.75K,1%,1/16W,CHIP,GA  I335  R8D25
   1 P3V3_STBY      A @BASEBOARD_FAB2_LIB.BASEBOARD_FAB2(SCH_1):P3V3_STBY
   2 RST_BMC_SRST_R2_N      B @BASEBOARD_FAB2_LIB.BASEBOARD_FAB2(SCH_1):RST_BMC_SRST_R2_N

FET_N_SOT23LF-2N7002,FET,C7925A  I340  Q2T2
   1 H_CPU0_FAST_WAKE   GATE @BASEBOARD_FAB2_LIB.BASEBOARD_FAB2(SCH_1):H_CPU0_FAST_WAKE
   2    GND    SRC @BASEBOARD_FAB2_LIB.BASEBOARD_FAB2(SCH_1):GND
   3 H_CPU0_FAST_WAKE_LVT3_N    DRN @BASEBOARD_FAB2_LIB.BASEBOARD_FAB2(SCH_1):H_CPU0_FAST_WAKE_LVT3_N

RES_0402-4.75K,1%,1/16W,CHIP,GA  I342  R3N12
   1 P3V3_STBY      A @BASEBOARD_FAB2_LIB.BASEBOARD_FAB2(SCH_1):P3V3_STBY
   2 FM_MP_PS_FAIL_N      B @BASEBOARD_FAB2_LIB.BASEBOARD_FAB2(SCH_1):FM_MP_PS_FAIL_N

RES_0402-4.75K,1%,1/16W,CHIP,GA  I344  R3N11
   1 P3V3_STBY      A @BASEBOARD_FAB2_LIB.BASEBOARD_FAB2(SCH_1):P3V3_STBY
   2 FM_MP_PS_REDUNDANT_LOST_N      B @BASEBOARD_FAB2_LIB.BASEBOARD_FAB2(SCH_1):FM_MP_PS_REDUNDANT_LOST_N

RES_0402-4.75K,1%,1/16W,CHIP,GA  I346  R2M2
   1 P3V3_STBY      A @BASEBOARD_FAB2_LIB.BASEBOARD_FAB2(SCH_1):P3V3_STBY
   2 FM_ADR_SMI_GPIO_N      B @BASEBOARD_FAB2_LIB.BASEBOARD_FAB2(SCH_1):FM_ADR_SMI_GPIO_N

RES_0402-4.75K,1%,1/16W,CHIP,GA  I348  R2M5
   1 P3V3_STBY      A @BASEBOARD_FAB2_LIB.BASEBOARD_FAB2(SCH_1):P3V3_STBY
   2 FM_BMC_CPLD_GPO      B @BASEBOARD_FAB2_LIB.BASEBOARD_FAB2(SCH_1):FM_BMC_CPLD_GPO

SWITCH_D90553001_SMLF-IC,D9055A  I351  S8E1
   1    GND      A @BASEBOARD_FAB2_LIB.BASEBOARD_FAB2(SCH_1):GND
   2 FP_NMI_BTN_OUT_R_N      B @BASEBOARD_FAB2_LIB.BASEBOARD_FAB2(SCH_1):FP_NMI_BTN_OUT_R_N

RES_0402-200.0,1%,1/16W,CHIP,GA  I352  R2R9
   1 FP_NMI_BTN_OUT_R_N      A @BASEBOARD_FAB2_LIB.BASEBOARD_FAB2(SCH_1):FP_NMI_BTN_OUT_R_N
   2 FP_NMI_BTN_OUT_N      B @BASEBOARD_FAB2_LIB.BASEBOARD_FAB2(SCH_1):FP_NMI_BTN_OUT_N

CAP_A_0402V-1.0UF,6.3V,10%,X6SA  I353  C2R12
   1 FP_NMI_BTN_OUT_N      A @BASEBOARD_FAB2_LIB.BASEBOARD_FAB2(SCH_1):FP_NMI_BTN_OUT_N
   2    GND      B @BASEBOARD_FAB2_LIB.BASEBOARD_FAB2(SCH_1):GND

RES_0402-4.75K,1%,1/16W,EMPTY,A  I361  R8E19
   1 P3V3_STBY      A @BASEBOARD_FAB2_LIB.BASEBOARD_FAB2(SCH_1):P3V3_STBY
   2 FM_BIOS_TOP_SWAP      B @BASEBOARD_FAB2_LIB.BASEBOARD_FAB2(SCH_1):FM_BIOS_TOP_SWAP

RES_0402-4.75K,1%,1/16W,CHIP,GA  I367  R2U4
   1 P3V3_STBY      A @BASEBOARD_FAB2_LIB.BASEBOARD_FAB2(SCH_1):P3V3_STBY
   2 FM_CPLD_BMC_PWRDN_N      B @BASEBOARD_FAB2_LIB.BASEBOARD_FAB2(SCH_1):FM_CPLD_BMC_PWRDN_N

RES_0402-1.00K,1%,1/16W,CHIP,GA  I368  R4R1
   1 H_CPU0_FAST_WAKE_N      A @BASEBOARD_FAB2_LIB.BASEBOARD_FAB2(SCH_1):H_CPU0_FAST_WAKE_N
   2 H_CPU0_FAST_WAKE_B_N      B @BASEBOARD_FAB2_LIB.BASEBOARD_FAB2(SCH_1):H_CPU0_FAST_WAKE_B_N

CAP_A_0402V-0.1UF,16V,10%,X7R,A  I370  C2T3
   1 P3V3_STBY      A @BASEBOARD_FAB2_LIB.BASEBOARD_FAB2(SCH_1):P3V3_STBY
   2    GND      B @BASEBOARD_FAB2_LIB.BASEBOARD_FAB2(SCH_1):GND

TTL1G07_A_SOP-74LVC1G07,IC,C88B  I374  U8D2
   2 PWRGD_DSW_PWROK      A @BASEBOARD_FAB2_LIB.BASEBOARD_FAB2(SCH_1):PWRGD_DSW_PWROK
   4 RST_BMC_SRST_R2_N      Y @BASEBOARD_FAB2_LIB.BASEBOARD_FAB2(SCH_1):RST_BMC_SRST_R2_N

CAP_A_0402V-0.1UF,16V,10%,X7R,A  I376  C8D1
   1 P3V3_STBY      A @BASEBOARD_FAB2_LIB.BASEBOARD_FAB2(SCH_1):P3V3_STBY
   2    GND      B @BASEBOARD_FAB2_LIB.BASEBOARD_FAB2(SCH_1):GND

RES_0402-4.75K,1%,1/16W,CHIP,GA  I382  R1L7
   1 P3V3_STBY      A @BASEBOARD_FAB2_LIB.BASEBOARD_FAB2(SCH_1):P3V3_STBY
   2 FM_BMC_CPLD_MP_RST_N      B @BASEBOARD_FAB2_LIB.BASEBOARD_FAB2(SCH_1):FM_BMC_CPLD_MP_RST_N

RES_0402-4.75K,1%,1/16W,CHIP,GA  I385  R8E32
   1 P3V3_STBY      A @BASEBOARD_FAB2_LIB.BASEBOARD_FAB2(SCH_1):P3V3_STBY
   2 FP_NMI_BTN_OUT_R_N      B @BASEBOARD_FAB2_LIB.BASEBOARD_FAB2(SCH_1):FP_NMI_BTN_OUT_R_N

RES_0402-33.2,1%,1/16W,CHIP,G2A  I386  R8D22
   1 RST_BMC_SRST_R2_N      A @BASEBOARD_FAB2_LIB.BASEBOARD_FAB2(SCH_1):RST_BMC_SRST_R2_N
   2 FM_TPM_PRES_RST_N      B @BASEBOARD_FAB2_LIB.BASEBOARD_FAB2(SCH_1):FM_TPM_PRES_RST_N

RES_0402-33.2,1%,1/16W,CHIP,G2A  I388  R8D36
   1 RST_BMC_SRST_R2_N      A @BASEBOARD_FAB2_LIB.BASEBOARD_FAB2(SCH_1):RST_BMC_SRST_R2_N
   2 RST_BMC_DDR3_BUF_IN_N      B @BASEBOARD_FAB2_LIB.BASEBOARD_FAB2(SCH_1):RST_BMC_DDR3_BUF_IN_N

TC7PZ14FU-GP_DISCRET-GA1-TC7PZA  I390  U2R1
   1 FP_NMI_BTN     1A @BASEBOARD_FAB2_LIB.BASEBOARD_FAB2(SCH_1):FP_NMI_BTN
   2    GND    GND @BASEBOARD_FAB2_LIB.BASEBOARD_FAB2(SCH_1):GND
   3 FP_NMI_BTN_OUT_N     2A @BASEBOARD_FAB2_LIB.BASEBOARD_FAB2(SCH_1):FP_NMI_BTN_OUT_N
   4 FP_NMI_BTN     2Y @BASEBOARD_FAB2_LIB.BASEBOARD_FAB2(SCH_1):FP_NMI_BTN
   5 P3V3_STBY    VCC @BASEBOARD_FAB2_LIB.BASEBOARD_FAB2(SCH_1):P3V3_STBY
   6 FP_NMI_BTN_R_N     1Y @BASEBOARD_FAB2_LIB.BASEBOARD_FAB2(SCH_1):FP_NMI_BTN_R_N

RES_0402-33.2,1%,1/16W,CHIP,G2A  I391  R2R10
   1 FP_NMI_BTN_R_N      A @BASEBOARD_FAB2_LIB.BASEBOARD_FAB2(SCH_1):FP_NMI_BTN_R_N
   2 FP_NMI_BTN_N      B @BASEBOARD_FAB2_LIB.BASEBOARD_FAB2(SCH_1):FP_NMI_BTN_N

RES_0402-0.0,5%,1/16W,EMPTY,G2A  I393  R9E14
   1 FM_TPM_PRES_RST_N      A @BASEBOARD_FAB2_LIB.BASEBOARD_FAB2(SCH_1):FM_TPM_PRES_RST_N
   2 FM_BMC_ENABLE_N      B @BASEBOARD_FAB2_LIB.BASEBOARD_FAB2(SCH_1):FM_BMC_ENABLE_N

TTL1G07_A_SOP-74LVC1G07,IC,C88B  I394  U25W9
   2 PWRGD_DSW_PWROK      A @BASEBOARD_FAB2_LIB.BASEBOARD_FAB2(SCH_1):PWRGD_DSW_PWROK
   4 RST_BMC_SRST_N      Y @BASEBOARD_FAB2_LIB.BASEBOARD_FAB2(SCH_1):RST_BMC_SRST_N

RES_0402-4.75K,1%,1/16W,CHIP,GA  I396  R25W153
   1 P3V3_STBY      A @BASEBOARD_FAB2_LIB.BASEBOARD_FAB2(SCH_1):P3V3_STBY
   2 RST_BMC_SRST_N      B @BASEBOARD_FAB2_LIB.BASEBOARD_FAB2(SCH_1):RST_BMC_SRST_N


DRAWING: @BASEBOARD_FAB2_LIB.BASEBOARD_FAB2(SCH_1):PAGE158 

CAP_A_0402V-0.1UF,16V,10%,X7R,A  I70  C1T10
   1 P3V3_STBY      A @BASEBOARD_FAB2_LIB.BASEBOARD_FAB2(SCH_1):P3V3_STBY
   2    GND      B @BASEBOARD_FAB2_LIB.BASEBOARD_FAB2(SCH_1):GND

FSA3357_SM-IC,C63273-001  I74  U9F2
   7 UART_MUX_OUT_R      A @BASEBOARD_FAB2_LIB.BASEBOARD_FAB2(SCH_1):UART_MUX_OUT_R
   1 SP2_BMC_CM_UART_TX_R     B0 @BASEBOARD_FAB2_LIB.BASEBOARD_FAB2(SCH_1):SP2_BMC_CM_UART_TX_R
   2 UART_BMC_TXD5     B1 @BASEBOARD_FAB2_LIB.BASEBOARD_FAB2(SCH_1):UART_BMC_TXD5
   3 SP1_BMC_HOST_UART_TX     B2 @BASEBOARD_FAB2_LIB.BASEBOARD_FAB2(SCH_1):SP1_BMC_HOST_UART_TX
   4    GND    GND @BASEBOARD_FAB2_LIB.BASEBOARD_FAB2(SCH_1):GND
   6 FM_UARTSW_LSB_N     S1 @BASEBOARD_FAB2_LIB.BASEBOARD_FAB2(SCH_1):FM_UARTSW_LSB_N
   5 FM_UARTSW_MSB_N     S2 @BASEBOARD_FAB2_LIB.BASEBOARD_FAB2(SCH_1):FM_UARTSW_MSB_N
   8 P3V3_STBY    VCC @BASEBOARD_FAB2_LIB.BASEBOARD_FAB2(SCH_1):P3V3_STBY

FSA3357_SM-IC,C63273-001  I75  U9F1
   7 UART_MUX_IN_R      A @BASEBOARD_FAB2_LIB.BASEBOARD_FAB2(SCH_1):UART_MUX_IN_R
   1 SP2_BMC_CM_UART_RX_R     B0 @BASEBOARD_FAB2_LIB.BASEBOARD_FAB2(SCH_1):SP2_BMC_CM_UART_RX_R
   2 UART_BMC_RXD5     B1 @BASEBOARD_FAB2_LIB.BASEBOARD_FAB2(SCH_1):UART_BMC_RXD5
   3 SP1_BMC_HOST_UART_RX     B2 @BASEBOARD_FAB2_LIB.BASEBOARD_FAB2(SCH_1):SP1_BMC_HOST_UART_RX
   4    GND    GND @BASEBOARD_FAB2_LIB.BASEBOARD_FAB2(SCH_1):GND
   6 FM_UARTSW_LSB_N     S1 @BASEBOARD_FAB2_LIB.BASEBOARD_FAB2(SCH_1):FM_UARTSW_LSB_N
   5 FM_UARTSW_MSB_N     S2 @BASEBOARD_FAB2_LIB.BASEBOARD_FAB2(SCH_1):FM_UARTSW_MSB_N
   8 P3V3_STBY    VCC @BASEBOARD_FAB2_LIB.BASEBOARD_FAB2(SCH_1):P3V3_STBY

RES_0402-100.0,1%,1/16W,CHIP,GA  I86  R9F25
   1 SPA_MID_DBG_RX      A @BASEBOARD_FAB2_LIB.BASEBOARD_FAB2(SCH_1):SPA_MID_DBG_RX
   2 UART_MUX_IN_R      B @BASEBOARD_FAB2_LIB.BASEBOARD_FAB2(SCH_1):UART_MUX_IN_R

RES_0402-0.0,5%,1/16W,CHIP,G21A  I91  R9F27
   1 UART_MUX_OUT_R      A @BASEBOARD_FAB2_LIB.BASEBOARD_FAB2(SCH_1):UART_MUX_OUT_R
   2 SPA_MID_DBG_TX      B @BASEBOARD_FAB2_LIB.BASEBOARD_FAB2(SCH_1):SPA_MID_DBG_TX

CAP_A_0402V-0.1UF,16V,10%,X7R,A  I97  C1T11
   1 P3V3_STBY      A @BASEBOARD_FAB2_LIB.BASEBOARD_FAB2(SCH_1):P3V3_STBY
   2    GND      B @BASEBOARD_FAB2_LIB.BASEBOARD_FAB2(SCH_1):GND

RES_0402-0.0,5%,1/16W,EMPTY,G2A  I99  R9F26
   1 SP2_BMC_CM_UART_TX      A @BASEBOARD_FAB2_LIB.BASEBOARD_FAB2(SCH_1):SP2_BMC_CM_UART_TX
   2 SPA_MID_DBG_TX      B @BASEBOARD_FAB2_LIB.BASEBOARD_FAB2(SCH_1):SPA_MID_DBG_TX

RES_0402-0.0,5%,1/16W,EMPTY,G2A  I100  R9F24
   1 SPA_MID_DBG_RX      A @BASEBOARD_FAB2_LIB.BASEBOARD_FAB2(SCH_1):SPA_MID_DBG_RX
   2 SP2_BMC_CM_UART_RX      B @BASEBOARD_FAB2_LIB.BASEBOARD_FAB2(SCH_1):SP2_BMC_CM_UART_RX

LED_A1LF-GREEN,IC,D14725-022  I130  DS9A4
   2 FM_UARTSW_LSB_N      C @BASEBOARD_FAB2_LIB.BASEBOARD_FAB2(SCH_1):FM_UARTSW_LSB_N
   1 FM_UARTSW_LSB_R_N      A @BASEBOARD_FAB2_LIB.BASEBOARD_FAB2(SCH_1):FM_UARTSW_LSB_R_N

RES_0402-330,5%,1/16W,CHIP,G21A  I131  R1L43
   1 FM_UARTSW_LSB_R_N      A @BASEBOARD_FAB2_LIB.BASEBOARD_FAB2(SCH_1):FM_UARTSW_LSB_R_N
   2 P3V3_STBY      B @BASEBOARD_FAB2_LIB.BASEBOARD_FAB2(SCH_1):P3V3_STBY

LED_A1LF-GREEN,IC,D14725-022  I134  DS9A7
   2 FM_UARTSW_MSB_N      C @BASEBOARD_FAB2_LIB.BASEBOARD_FAB2(SCH_1):FM_UARTSW_MSB_N
   1 FM_UARTSW_MSB_R_N      A @BASEBOARD_FAB2_LIB.BASEBOARD_FAB2(SCH_1):FM_UARTSW_MSB_R_N

RES_0402-330,5%,1/16W,CHIP,G21A  I136  R1L44
   1 FM_UARTSW_MSB_R_N      A @BASEBOARD_FAB2_LIB.BASEBOARD_FAB2(SCH_1):FM_UARTSW_MSB_R_N
   2 P3V3_STBY      B @BASEBOARD_FAB2_LIB.BASEBOARD_FAB2(SCH_1):P3V3_STBY

RES_0402-0.0,5%,1/16W,CHIP,G21A  I148  R9F65
   1 SP2_BMC_CM_UART_TX_R1      A @BASEBOARD_FAB2_LIB.BASEBOARD_FAB2(SCH_1):SP2_BMC_CM_UART_TX_R1
   2 SP2_BMC_CM_UART_TX_R      B @BASEBOARD_FAB2_LIB.BASEBOARD_FAB2(SCH_1):SP2_BMC_CM_UART_TX_R

RES_0402-0.0,5%,1/16W,EMPTY,G2A  I149  R9F68
   1 SP2_BMC_CM_UART_RX_R      A @BASEBOARD_FAB2_LIB.BASEBOARD_FAB2(SCH_1):SP2_BMC_CM_UART_RX_R
   2 SP2_BMC_CM_UART_RX      B @BASEBOARD_FAB2_LIB.BASEBOARD_FAB2(SCH_1):SP2_BMC_CM_UART_RX

RES_0402-0.0,5%,1/16W,CHIP,G21A  I150  R9F69
   1 SP2_BMC_CM_UART_RX_R      A @BASEBOARD_FAB2_LIB.BASEBOARD_FAB2(SCH_1):SP2_BMC_CM_UART_RX_R
   2 SP2_BMC_CM_UART_RX_R1      B @BASEBOARD_FAB2_LIB.BASEBOARD_FAB2(SCH_1):SP2_BMC_CM_UART_RX_R1

RES_0402-0.0,5%,1/16W,EMPTY,G2A  I152  R9F66
   1 SP2_BMC_CM_UART_TX      A @BASEBOARD_FAB2_LIB.BASEBOARD_FAB2(SCH_1):SP2_BMC_CM_UART_TX
   2 SP2_BMC_CM_UART_TX_R      B @BASEBOARD_FAB2_LIB.BASEBOARD_FAB2(SCH_1):SP2_BMC_CM_UART_TX_R

RES_0402-4.75K,1%,1/16W,CHIP,GA  I153  R9W33
   1 P3V3_STBY      A @BASEBOARD_FAB2_LIB.BASEBOARD_FAB2(SCH_1):P3V3_STBY
   2 SP1_BMC_HOST_UART_RX      B @BASEBOARD_FAB2_LIB.BASEBOARD_FAB2(SCH_1):SP1_BMC_HOST_UART_RX

RES_0402-4.75K,1%,1/16W,CHIP,GA  I154  R9W34
   1 P3V3_STBY      A @BASEBOARD_FAB2_LIB.BASEBOARD_FAB2(SCH_1):P3V3_STBY
   2 UART_BMC_RXD5      B @BASEBOARD_FAB2_LIB.BASEBOARD_FAB2(SCH_1):UART_BMC_RXD5

RES_0402-4.75K,1%,1/16W,CHIP,GA  I155  R9W35
   1 P3V3_STBY      A @BASEBOARD_FAB2_LIB.BASEBOARD_FAB2(SCH_1):P3V3_STBY
   2 SP2_BMC_CM_UART_RX_R      B @BASEBOARD_FAB2_LIB.BASEBOARD_FAB2(SCH_1):SP2_BMC_CM_UART_RX_R


DRAWING: @BASEBOARD_FAB2_LIB.BASEBOARD_FAB2(SCH_1):PAGE159 

RES_0402-2.26K,1.0%,1/16W,EMPTA  I210  R8G3
   1 P3V3_STBY      A @BASEBOARD_FAB2_LIB.BASEBOARD_FAB2(SCH_1):P3V3_STBY
   2 SMB_OCP_LAN_STBY_LVC3_SCL_R      B @BASEBOARD_FAB2_LIB.BASEBOARD_FAB2(SCH_1):SMB_OCP_LAN_STBY_LVC3_SCL_R

RES_0402-2.26K,1.0%,1/16W,EMPTA  I212  R8G6
   1 P3V3_STBY      A @BASEBOARD_FAB2_LIB.BASEBOARD_FAB2(SCH_1):P3V3_STBY
   2 SMB_OCP_LAN_STBY_LVC3_SDA_R      B @BASEBOARD_FAB2_LIB.BASEBOARD_FAB2(SCH_1):SMB_OCP_LAN_STBY_LVC3_SDA_R

RES_0402-2.26K,1.0%,1/16W,CHIPA  I214  R2U5
   1 P3V3_STBY      A @BASEBOARD_FAB2_LIB.BASEBOARD_FAB2(SCH_1):P3V3_STBY
   2 SMB_OCP_FRU_STBY_LVC3_SCL_R      B @BASEBOARD_FAB2_LIB.BASEBOARD_FAB2(SCH_1):SMB_OCP_FRU_STBY_LVC3_SCL_R

RES_0402-2.26K,1.0%,1/16W,CHIPA  I216  R2U13
   1 P3V3_STBY      A @BASEBOARD_FAB2_LIB.BASEBOARD_FAB2(SCH_1):P3V3_STBY
   2 SMB_OCP_FRU_STBY_LVC3_SDA_R      B @BASEBOARD_FAB2_LIB.BASEBOARD_FAB2(SCH_1):SMB_OCP_FRU_STBY_LVC3_SDA_R

RES_0402-20.0,1%,1/16W,CHIP,G2A  I218  R2U1
   1 SMB_BMC_PMBUS_STBY_LVC3_SCL_R      A @BASEBOARD_FAB2_LIB.BASEBOARD_FAB2(SCH_1):SMB_BMC_PMBUS_STBY_LVC3_SCL_R
   2 SMB_BMC_PMBUS_STBY_LVC3_SCL      B @BASEBOARD_FAB2_LIB.BASEBOARD_FAB2(SCH_1):SMB_BMC_PMBUS_STBY_LVC3_SCL

RES_0402-20.0,1%,1/16W,CHIP,G2A  I219  R2T49
   1 SMB_BMC_PMBUS_STBY_LVC3_SDA_R      A @BASEBOARD_FAB2_LIB.BASEBOARD_FAB2(SCH_1):SMB_BMC_PMBUS_STBY_LVC3_SDA_R
   2 SMB_BMC_PMBUS_STBY_LVC3_SDA      B @BASEBOARD_FAB2_LIB.BASEBOARD_FAB2(SCH_1):SMB_BMC_PMBUS_STBY_LVC3_SDA

RES_0402-20.0,1%,1/16W,CHIP,G2A  I220  R2U7
   1 SMB_OCP_FRU_STBY_LVC3_SCL_R      A @BASEBOARD_FAB2_LIB.BASEBOARD_FAB2(SCH_1):SMB_OCP_FRU_STBY_LVC3_SCL_R
   2 SMB_OCP_FRU_STBY_LVC3_SCL      B @BASEBOARD_FAB2_LIB.BASEBOARD_FAB2(SCH_1):SMB_OCP_FRU_STBY_LVC3_SCL

RES_0402-20.0,1%,1/16W,CHIP,G2A  I221  R2U10
   1 SMB_OCP_FRU_STBY_LVC3_SDA_R      A @BASEBOARD_FAB2_LIB.BASEBOARD_FAB2(SCH_1):SMB_OCP_FRU_STBY_LVC3_SDA_R
   2 SMB_OCP_FRU_STBY_LVC3_SDA      B @BASEBOARD_FAB2_LIB.BASEBOARD_FAB2(SCH_1):SMB_OCP_FRU_STBY_LVC3_SDA

RES_0402-0.0,5%,1/16W,CHIP,G21A  I222  R1U11
   1 SMB_VR_STBY_LVC3_SCL_R      A @BASEBOARD_FAB2_LIB.BASEBOARD_FAB2(SCH_1):SMB_VR_STBY_LVC3_SCL_R
   2 SMB_VR_STBY_LVC3_SCL      B @BASEBOARD_FAB2_LIB.BASEBOARD_FAB2(SCH_1):SMB_VR_STBY_LVC3_SCL

RES_0402-0.0,5%,1/16W,CHIP,G21A  I223  R1U8
   1 SMB_VR_STBY_LVC3_SDA_R      A @BASEBOARD_FAB2_LIB.BASEBOARD_FAB2(SCH_1):SMB_VR_STBY_LVC3_SDA_R
   2 SMB_VR_STBY_LVC3_SDA      B @BASEBOARD_FAB2_LIB.BASEBOARD_FAB2(SCH_1):SMB_VR_STBY_LVC3_SDA

RES_0402-20.0,1%,1/16W,CHIP,G2A  I224  R9G12
   1 SMB_OCP_LAN_STBY_LVC3_SDA      A @BASEBOARD_FAB2_LIB.BASEBOARD_FAB2(SCH_1):SMB_OCP_LAN_STBY_LVC3_SDA
   2 SMB_SPRINGVILLE_STBY_LVC3_SDA      B @BASEBOARD_FAB2_LIB.BASEBOARD_FAB2(SCH_1):SMB_SPRINGVILLE_STBY_LVC3_SDA

RES_0402-20.0,1%,1/16W,CHIP,G2A  I225  R1U20
   1 SMB_SMLINK0_STBY_LVC3_SDA      A @BASEBOARD_FAB2_LIB.BASEBOARD_FAB2(SCH_1):SMB_SMLINK0_STBY_LVC3_SDA
   2 SMB_SPRINGVILLE_STBY_LVC3_SDA      B @BASEBOARD_FAB2_LIB.BASEBOARD_FAB2(SCH_1):SMB_SPRINGVILLE_STBY_LVC3_SDA

RES_0402-20.0,1%,1/16W,CHIP,G2A  I226  R1U19
   1 SMB_SMLINK0_STBY_LVC3_SCL      A @BASEBOARD_FAB2_LIB.BASEBOARD_FAB2(SCH_1):SMB_SMLINK0_STBY_LVC3_SCL
   2 SMB_SPRINGVILLE_STBY_LVC3_SCL      B @BASEBOARD_FAB2_LIB.BASEBOARD_FAB2(SCH_1):SMB_SPRINGVILLE_STBY_LVC3_SCL

RES_0402-20.0,1%,1/16W,CHIP,G2A  I227  R9G13
   1 SMB_OCP_LAN_STBY_LVC3_SCL      A @BASEBOARD_FAB2_LIB.BASEBOARD_FAB2(SCH_1):SMB_OCP_LAN_STBY_LVC3_SCL
   2 SMB_SPRINGVILLE_STBY_LVC3_SCL      B @BASEBOARD_FAB2_LIB.BASEBOARD_FAB2(SCH_1):SMB_SPRINGVILLE_STBY_LVC3_SCL

RES_0402-20.0,1%,1/16W,CHIP,G2A  I228  R8G5
   1 SMB_OCP_LAN_STBY_LVC3_SDA_R      A @BASEBOARD_FAB2_LIB.BASEBOARD_FAB2(SCH_1):SMB_OCP_LAN_STBY_LVC3_SDA_R
   2 SMB_OCP_LAN_STBY_LVC3_SDA      B @BASEBOARD_FAB2_LIB.BASEBOARD_FAB2(SCH_1):SMB_OCP_LAN_STBY_LVC3_SDA

RES_0402-20.0,1%,1/16W,CHIP,G2A  I229  R8G4
   1 SMB_OCP_LAN_STBY_LVC3_SCL_R      A @BASEBOARD_FAB2_LIB.BASEBOARD_FAB2(SCH_1):SMB_OCP_LAN_STBY_LVC3_SCL_R
   2 SMB_OCP_LAN_STBY_LVC3_SCL      B @BASEBOARD_FAB2_LIB.BASEBOARD_FAB2(SCH_1):SMB_OCP_LAN_STBY_LVC3_SCL

RES_0402-20.0,1%,1/16W,CHIP,G2A  I230  R2U34
   1 SMB_HOST_STBY_LVC3_SCL_R      A @BASEBOARD_FAB2_LIB.BASEBOARD_FAB2(SCH_1):SMB_HOST_STBY_LVC3_SCL_R
   2 SMB_HOST_STBY_LVC3_SCL      B @BASEBOARD_FAB2_LIB.BASEBOARD_FAB2(SCH_1):SMB_HOST_STBY_LVC3_SCL

RES_0402-20.0,1%,1/16W,CHIP,G2A  I231  R2U33
   1 SMB_HOST_STBY_LVC3_SDA_R      A @BASEBOARD_FAB2_LIB.BASEBOARD_FAB2(SCH_1):SMB_HOST_STBY_LVC3_SDA_R
   2 SMB_HOST_STBY_LVC3_SDA      B @BASEBOARD_FAB2_LIB.BASEBOARD_FAB2(SCH_1):SMB_HOST_STBY_LVC3_SDA

RES_0402-20.0,1%,1/16W,CHIP,G2A  I232  R1U9
   1 SMB_SMLINK0_STBY_LVC3_SCL_R      A @BASEBOARD_FAB2_LIB.BASEBOARD_FAB2(SCH_1):SMB_SMLINK0_STBY_LVC3_SCL_R
   2 SMB_SMLINK0_STBY_LVC3_SCL      B @BASEBOARD_FAB2_LIB.BASEBOARD_FAB2(SCH_1):SMB_SMLINK0_STBY_LVC3_SCL

RES_0402-20.0,1%,1/16W,CHIP,G2A  I233  R1U10
   1 SMB_SMLINK0_STBY_LVC3_SDA_R      A @BASEBOARD_FAB2_LIB.BASEBOARD_FAB2(SCH_1):SMB_SMLINK0_STBY_LVC3_SDA_R
   2 SMB_SMLINK0_STBY_LVC3_SDA      B @BASEBOARD_FAB2_LIB.BASEBOARD_FAB2(SCH_1):SMB_SMLINK0_STBY_LVC3_SDA

RES_0402-2.0K,1%,1/16W,CHIP,G2A  I235  R8C15
   1 P3V3_STBY      A @BASEBOARD_FAB2_LIB.BASEBOARD_FAB2(SCH_1):P3V3_STBY
   2 SMB_HOST_STBY_LVC3_SCL_R      B @BASEBOARD_FAB2_LIB.BASEBOARD_FAB2(SCH_1):SMB_HOST_STBY_LVC3_SCL_R

RES_0402-2.0K,1%,1/16W,CHIP,G2A  I237  R8C16
   1 P3V3_STBY      A @BASEBOARD_FAB2_LIB.BASEBOARD_FAB2(SCH_1):P3V3_STBY
   2 SMB_HOST_STBY_LVC3_SDA_R      B @BASEBOARD_FAB2_LIB.BASEBOARD_FAB2(SCH_1):SMB_HOST_STBY_LVC3_SDA_R


DRAWING: @BASEBOARD_FAB2_LIB.BASEBOARD_FAB2(SCH_1):PAGE160 

RES_0402-20.0,1%,1/16W,CHIP,G2A  I4  R1T8
   1 SMB_SLOTX24_STBY_LVC3_SDA_R      A @BASEBOARD_FAB2_LIB.BASEBOARD_FAB2(SCH_1):SMB_SLOTX24_STBY_LVC3_SDA_R
   2 SMB_SLOTX24_BMC_STBY_LVC3_SDA      B @BASEBOARD_FAB2_LIB.BASEBOARD_FAB2(SCH_1):SMB_SLOTX24_BMC_STBY_LVC3_SDA

RES_0402-665,1.0%,1/16W,CHIP,GA  I46  R1T3
   1 P3V3_STBY      A @BASEBOARD_FAB2_LIB.BASEBOARD_FAB2(SCH_1):P3V3_STBY
   2 SMB_SLOTX24_STBY_LVC3_SDA_R      B @BASEBOARD_FAB2_LIB.BASEBOARD_FAB2(SCH_1):SMB_SLOTX24_STBY_LVC3_SDA_R

RES_0402-665,1.0%,1/16W,CHIP,GA  I49  R1T2
   1 P3V3_STBY      A @BASEBOARD_FAB2_LIB.BASEBOARD_FAB2(SCH_1):P3V3_STBY
   2 SMB_SLOTX24_STBY_LVC3_SCL_R      B @BASEBOARD_FAB2_LIB.BASEBOARD_FAB2(SCH_1):SMB_SLOTX24_STBY_LVC3_SCL_R

RES_0402-20.0,1%,1/16W,CHIP,G2A  I50  R1T7
   1 SMB_SLOTX24_STBY_LVC3_SCL_R      A @BASEBOARD_FAB2_LIB.BASEBOARD_FAB2(SCH_1):SMB_SLOTX24_STBY_LVC3_SCL_R
   2 SMB_SLOTX24_BMC_STBY_LVC3_SCL      B @BASEBOARD_FAB2_LIB.BASEBOARD_FAB2(SCH_1):SMB_SLOTX24_BMC_STBY_LVC3_SCL

RES_0402-20.0,1%,1/16W,CHIP,G2A  I51  R9F23
   1 SMB_LAN_STBY_LVC3_SDA_R      A @BASEBOARD_FAB2_LIB.BASEBOARD_FAB2(SCH_1):SMB_LAN_STBY_LVC3_SDA_R
   2 SMB_LAN_STBY_LVC3_SDA      B @BASEBOARD_FAB2_LIB.BASEBOARD_FAB2(SCH_1):SMB_LAN_STBY_LVC3_SDA

RES_0402-20.0,1%,1/16W,CHIP,G2A  I52  R9F22
   1 SMB_LAN_STBY_LVC3_SCL_R      A @BASEBOARD_FAB2_LIB.BASEBOARD_FAB2(SCH_1):SMB_LAN_STBY_LVC3_SCL_R
   2 SMB_LAN_STBY_LVC3_SCL      B @BASEBOARD_FAB2_LIB.BASEBOARD_FAB2(SCH_1):SMB_LAN_STBY_LVC3_SCL


DRAWING: @BASEBOARD_FAB2_LIB.BASEBOARD_FAB2(SCH_1):PAGE161 

CAP_0805-10UF,16V,10%,X6S,C953A  I3  C1E21
   1 P12V_FAN      A @BASEBOARD_FAB2_LIB.BASEBOARD_FAB2(SCH_1):P12V_FAN
   2    GND      B @BASEBOARD_FAB2_LIB.BASEBOARD_FAB2(SCH_1):GND

CAP_A_0402V-0.1UF,16V,10%,X7R,A  I4  C1E20
   1 P12V_FAN      A @BASEBOARD_FAB2_LIB.BASEBOARD_FAB2(SCH_1):P12V_FAN
   2    GND      B @BASEBOARD_FAB2_LIB.BASEBOARD_FAB2(SCH_1):GND

CAP_A_0402V-0.1UF,16V,10%,X7R,A  I26  C9M5
   1 P12V_FAN      A @BASEBOARD_FAB2_LIB.BASEBOARD_FAB2(SCH_1):P12V_FAN
   2    GND      B @BASEBOARD_FAB2_LIB.BASEBOARD_FAB2(SCH_1):GND

CAP_0805-10UF,16V,10%,X6S,C953A  I27  C9M4
   1 P12V_FAN      A @BASEBOARD_FAB2_LIB.BASEBOARD_FAB2(SCH_1):P12V_FAN
   2    GND      B @BASEBOARD_FAB2_LIB.BASEBOARD_FAB2(SCH_1):GND

DIODE_SM-SDMK0340L,IC,H71799-0A  I42  CR1F1
   1 FAN_TACH0_CPU0_D1      C @BASEBOARD_FAB2_LIB.BASEBOARD_FAB2(SCH_1):FAN_TACH0_CPU0_D1
   2 FAN_TACH0_CPU0_D2      A @BASEBOARD_FAB2_LIB.BASEBOARD_FAB2(SCH_1):FAN_TACH0_CPU0_D2

RES_0402-100.0,1%,1/16W,CHIP,GA  I43  R1F2
   1 FAN_TACH0      A @BASEBOARD_FAB2_LIB.BASEBOARD_FAB2(SCH_1):FAN_TACH0
   2 FAN_TACH0_CPU0_D2      B @BASEBOARD_FAB2_LIB.BASEBOARD_FAB2(SCH_1):FAN_TACH0_CPU0_D2

RES_0402-4.75K,1%,1/16W,CHIP,GA  I45  R1F1
   1 P3V3_STBY      A @BASEBOARD_FAB2_LIB.BASEBOARD_FAB2(SCH_1):P3V3_STBY
   2 FAN_TACH0      B @BASEBOARD_FAB2_LIB.BASEBOARD_FAB2(SCH_1):FAN_TACH0

CAP_A_0402V-0.01UF,25V,10%,X7RA  I46  C1F9
   1 FAN_TACH0      A @BASEBOARD_FAB2_LIB.BASEBOARD_FAB2(SCH_1):FAN_TACH0
   2    GND      B @BASEBOARD_FAB2_LIB.BASEBOARD_FAB2(SCH_1):GND

DIODE_SM-SDMK0340L,EMPTY,H7179A  I50  CR1E1
   1 P5V_STBY      C @BASEBOARD_FAB2_LIB.BASEBOARD_FAB2(SCH_1):P5V_STBY
   2 FAN_PWM_OUT_SYS0_R      A @BASEBOARD_FAB2_LIB.BASEBOARD_FAB2(SCH_1):FAN_PWM_OUT_SYS0_R

RES_0402-4.75K,1%,1/16W,CHIP,GA  I51  R1E12
   1 P5V_STBY      A @BASEBOARD_FAB2_LIB.BASEBOARD_FAB2(SCH_1):P5V_STBY
   2 FAN_PWM_OUT_SYS0_R      B @BASEBOARD_FAB2_LIB.BASEBOARD_FAB2(SCH_1):FAN_PWM_OUT_SYS0_R

DIODE_SM-SDMK0340L,IC,H71799-0A  I62  CR1B2
   1 FAN_TACH2_CPU1_D1      C @BASEBOARD_FAB2_LIB.BASEBOARD_FAB2(SCH_1):FAN_TACH2_CPU1_D1
   2 FAN_TACH2_CPU1_D2      A @BASEBOARD_FAB2_LIB.BASEBOARD_FAB2(SCH_1):FAN_TACH2_CPU1_D2

DIODE_SM-SDMK0340L,EMPTY,H7179A  I64  CR1B1
   1 P5V_STBY      C @BASEBOARD_FAB2_LIB.BASEBOARD_FAB2(SCH_1):P5V_STBY
   2 FAN_PWM_OUT_SYS1_R      A @BASEBOARD_FAB2_LIB.BASEBOARD_FAB2(SCH_1):FAN_PWM_OUT_SYS1_R

RES_0402-4.75K,1%,1/16W,CHIP,GA  I65  R7F33
   1 P5V_STBY      A @BASEBOARD_FAB2_LIB.BASEBOARD_FAB2(SCH_1):P5V_STBY
   2 FAN_PWM_OUT_SYS1_R      B @BASEBOARD_FAB2_LIB.BASEBOARD_FAB2(SCH_1):FAN_PWM_OUT_SYS1_R

RES_0402-100.0,1%,1/16W,CHIP,GA  I67  R1B22
   1 FAN_TACH2      A @BASEBOARD_FAB2_LIB.BASEBOARD_FAB2(SCH_1):FAN_TACH2
   2 FAN_TACH2_CPU1_D2      B @BASEBOARD_FAB2_LIB.BASEBOARD_FAB2(SCH_1):FAN_TACH2_CPU1_D2

CAP_A_0402V-0.01UF,25V,10%,X7RA  I68  C1B15
   1 FAN_TACH2      A @BASEBOARD_FAB2_LIB.BASEBOARD_FAB2(SCH_1):FAN_TACH2
   2    GND      B @BASEBOARD_FAB2_LIB.BASEBOARD_FAB2(SCH_1):GND

RES_0402-4.75K,1%,1/16W,CHIP,GA  I70  R1B21
   1 P3V3_STBY      A @BASEBOARD_FAB2_LIB.BASEBOARD_FAB2(SCH_1):P3V3_STBY
   2 FAN_TACH2      B @BASEBOARD_FAB2_LIB.BASEBOARD_FAB2(SCH_1):FAN_TACH2

TTL1G07_A_SOP-74LVC1G07,IC,C88B  I88  U8G2
   2 FAN_PWM_OUT_SYS0      A @BASEBOARD_FAB2_LIB.BASEBOARD_FAB2(SCH_1):FAN_PWM_OUT_SYS0
   4 FAN_PWM_OUT_SYS0_BUF      Y @BASEBOARD_FAB2_LIB.BASEBOARD_FAB2(SCH_1):FAN_PWM_OUT_SYS0_BUF

CAP_A_0402V-0.1UF,16V,10%,X7R,A  I90  C2U27
   1 P3V3_STBY      A @BASEBOARD_FAB2_LIB.BASEBOARD_FAB2(SCH_1):P3V3_STBY
   2    GND      B @BASEBOARD_FAB2_LIB.BASEBOARD_FAB2(SCH_1):GND

TTL1G07_A_SOP-74LVC1G07,IC,C88B  I92  U8G3
   2 FAN_PWM_OUT_SYS1      A @BASEBOARD_FAB2_LIB.BASEBOARD_FAB2(SCH_1):FAN_PWM_OUT_SYS1
   4 FAN_PWM_OUT_SYS1_BUF      Y @BASEBOARD_FAB2_LIB.BASEBOARD_FAB2(SCH_1):FAN_PWM_OUT_SYS1_BUF

CAP_A_0402V-0.1UF,16V,10%,X7R,A  I93  C2U28
   1 P3V3_STBY      A @BASEBOARD_FAB2_LIB.BASEBOARD_FAB2(SCH_1):P3V3_STBY
   2    GND      B @BASEBOARD_FAB2_LIB.BASEBOARD_FAB2(SCH_1):GND

RES_0402-221,1.0%,1/16W,CHIP,GA  I99  R2U42
   1 FAN_PWM_OUT_SYS0_BUF      A @BASEBOARD_FAB2_LIB.BASEBOARD_FAB2(SCH_1):FAN_PWM_OUT_SYS0_BUF
   2 FAN_PWM_OUT_SYS0_R      B @BASEBOARD_FAB2_LIB.BASEBOARD_FAB2(SCH_1):FAN_PWM_OUT_SYS0_R

RES_0402-221,1.0%,1/16W,CHIP,GA  I102  R2U44
   1 FAN_PWM_OUT_SYS1_BUF      A @BASEBOARD_FAB2_LIB.BASEBOARD_FAB2(SCH_1):FAN_PWM_OUT_SYS1_BUF
   2 FAN_PWM_OUT_SYS1_R      B @BASEBOARD_FAB2_LIB.BASEBOARD_FAB2(SCH_1):FAN_PWM_OUT_SYS1_R

CAP_A_0402V-0.1UF,16V,10%,X7R,A  I113  C1E22
   1 P3V3_STBY      A @BASEBOARD_FAB2_LIB.BASEBOARD_FAB2(SCH_1):P3V3_STBY
   2    GND      B @BASEBOARD_FAB2_LIB.BASEBOARD_FAB2(SCH_1):GND

RES_0402-10.0K,1%,1/16W,EMPTY,A  I120  R1E11
   1 P3V3_STBY      A @BASEBOARD_FAB2_LIB.BASEBOARD_FAB2(SCH_1):P3V3_STBY
   2 FM_ENABLE_FAN_POWER      B @BASEBOARD_FAB2_LIB.BASEBOARD_FAB2(SCH_1):FM_ENABLE_FAN_POWER

TTL1G08_SOTLF-NC7SZ08,IC,D1032B  I121  U1E2
   4 FM_ENABLE_FAN_POWER   Y<0> @BASEBOARD_FAB2_LIB.BASEBOARD_FAB2(SCH_1):FM_ENABLE_FAN_POWER
   1 FM_CTNR_PS_ON   A<0> @BASEBOARD_FAB2_LIB.BASEBOARD_FAB2(SCH_1):FM_CTNR_PS_ON
   2 FM_DISABLE_FAN_N   B<0> @BASEBOARD_FAB2_LIB.BASEBOARD_FAB2(SCH_1):FM_DISABLE_FAN_N

LOTES-CON4-S1-GP_CONN-G7-LOTESA  I139  J1F2
   1    GND      1 @BASEBOARD_FAB2_LIB.BASEBOARD_FAB2(SCH_1):GND
   2 P12V_FAN      2 @BASEBOARD_FAB2_LIB.BASEBOARD_FAB2(SCH_1):P12V_FAN
   3 FAN_TACH0_CPU0_D1      3 @BASEBOARD_FAB2_LIB.BASEBOARD_FAB2(SCH_1):FAN_TACH0_CPU0_D1
   4 FAN_PWM_OUT_SYS0_R      4 @BASEBOARD_FAB2_LIB.BASEBOARD_FAB2(SCH_1):FAN_PWM_OUT_SYS0_R
 NP1     NC    NP1     NC

LOTES-CON4-S1-GP_CONN-G7-LOTESA  I140  J10W1
   1    GND      1 @BASEBOARD_FAB2_LIB.BASEBOARD_FAB2(SCH_1):GND
   2 P12V_FAN      2 @BASEBOARD_FAB2_LIB.BASEBOARD_FAB2(SCH_1):P12V_FAN
   3 FAN_TACH2_CPU1_D1      3 @BASEBOARD_FAB2_LIB.BASEBOARD_FAB2(SCH_1):FAN_TACH2_CPU1_D1
   4 FAN_PWM_OUT_SYS1_R      4 @BASEBOARD_FAB2_LIB.BASEBOARD_FAB2(SCH_1):FAN_PWM_OUT_SYS1_R
 NP1     NC    NP1     NC


DRAWING: @BASEBOARD_FAB2_LIB.BASEBOARD_FAB2(SCH_1):PAGE162 

RES_0402-4.75K,1%,1/16W,EMPTY,A  I8  R8F16
   1 P3V3_STBY      A @BASEBOARD_FAB2_LIB.BASEBOARD_FAB2(SCH_1):P3V3_STBY
   2 PU_SPI_FLASH_RESET_2_N      B @BASEBOARD_FAB2_LIB.BASEBOARD_FAB2(SCH_1):PU_SPI_FLASH_RESET_2_N

RES_0402-4.75K,1%,1/16W,CHIP,GA  I9  R8F14
   1 P3V3_STBY      A @BASEBOARD_FAB2_LIB.BASEBOARD_FAB2(SCH_1):P3V3_STBY
   2 PU_SPI_BMC_BT_HOLD_N      B @BASEBOARD_FAB2_LIB.BASEBOARD_FAB2(SCH_1):PU_SPI_BMC_BT_HOLD_N

RES_0402-33.2,1%,1/16W,CHIP,G2A  I13  R8F12
   1 SPI_BMC_BT_DI      A @BASEBOARD_FAB2_LIB.BASEBOARD_FAB2(SCH_1):SPI_BMC_BT_DI
   2 SPI_BMC_BT_DI_R      B @BASEBOARD_FAB2_LIB.BASEBOARD_FAB2(SCH_1):SPI_BMC_BT_DI_R

RES_0402-4.75K,1%,1/16W,CHIP,GA  I22  R8F34
   1 P3V3_STBY      A @BASEBOARD_FAB2_LIB.BASEBOARD_FAB2(SCH_1):P3V3_STBY
   2 PU_SPI_BMC_BT_WP_N      B @BASEBOARD_FAB2_LIB.BASEBOARD_FAB2(SCH_1):PU_SPI_BMC_BT_WP_N

RES_0402-1.00K,1%,1/16W,EMPTY,A  I24  R8F35
   1 PU_SPI_BMC_BT_WP_N      A @BASEBOARD_FAB2_LIB.BASEBOARD_FAB2(SCH_1):PU_SPI_BMC_BT_WP_N
   2    GND      B @BASEBOARD_FAB2_LIB.BASEBOARD_FAB2(SCH_1):GND

CAP_A_0402V-0.01UF,25V,10%,X7RA  I28  C8F5
   1 P3V3_STBY      A @BASEBOARD_FAB2_LIB.BASEBOARD_FAB2(SCH_1):P3V3_STBY
   2    GND      B @BASEBOARD_FAB2_LIB.BASEBOARD_FAB2(SCH_1):GND

CAP_A_0402V-1.0UF,6.3V,10%,X6SA  I30  C8F4
   1 P3V3_STBY      A @BASEBOARD_FAB2_LIB.BASEBOARD_FAB2(SCH_1):P3V3_STBY
   2    GND      B @BASEBOARD_FAB2_LIB.BASEBOARD_FAB2(SCH_1):GND

W25Q128_SKT16-IC,H12709-001  I32  U8F2
   1 PU_SPI_BMC_BT_HOLD_N HOLD_N_IO<3> @BASEBOARD_FAB2_LIB.BASEBOARD_FAB2(SCH_1):PU_SPI_BMC_BT_HOLD_N
   2 P3V3_STBY    VCC @BASEBOARD_FAB2_LIB.BASEBOARD_FAB2(SCH_1):P3V3_STBY
   3 PU_SPI_FLASH_RESET_2_N RESET_N @BASEBOARD_FAB2_LIB.BASEBOARD_FAB2(SCH_1):PU_SPI_FLASH_RESET_2_N
   4 TP_SPI_2_0  NC<0> @BASEBOARD_FAB2_LIB.BASEBOARD_FAB2(SCH_1):TP_SPI_2_0
   5 TP_SPI_2_1  NC<1> @BASEBOARD_FAB2_LIB.BASEBOARD_FAB2(SCH_1):TP_SPI_2_1
   6 TP_SPI_2_2  NC<2> @BASEBOARD_FAB2_LIB.BASEBOARD_FAB2(SCH_1):TP_SPI_2_2
   7 SPI_BMC_BT_CS_N   CS_N @BASEBOARD_FAB2_LIB.BASEBOARD_FAB2(SCH_1):SPI_BMC_BT_CS_N
   8 SPI_BMC_BT_DI_R DO_IO<1> @BASEBOARD_FAB2_LIB.BASEBOARD_FAB2(SCH_1):SPI_BMC_BT_DI_R
   9 PU_SPI_BMC_BT_WP_N WP_N_IO<2> @BASEBOARD_FAB2_LIB.BASEBOARD_FAB2(SCH_1):PU_SPI_BMC_BT_WP_N
  10    GND    GND @BASEBOARD_FAB2_LIB.BASEBOARD_FAB2(SCH_1):GND
  11 TP_SPI_2_3  NC<3> @BASEBOARD_FAB2_LIB.BASEBOARD_FAB2(SCH_1):TP_SPI_2_3
  12 TP_SPI_2_4  NC<4> @BASEBOARD_FAB2_LIB.BASEBOARD_FAB2(SCH_1):TP_SPI_2_4
  13 TP_SPI_2_5  NC<5> @BASEBOARD_FAB2_LIB.BASEBOARD_FAB2(SCH_1):TP_SPI_2_5
  14 TP_SPI_2_6  NC<6> @BASEBOARD_FAB2_LIB.BASEBOARD_FAB2(SCH_1):TP_SPI_2_6
  15 SPI_BMC_BT_DO DI_IO<0> @BASEBOARD_FAB2_LIB.BASEBOARD_FAB2(SCH_1):SPI_BMC_BT_DO
  16 SPI_BMC_BT_CLK    CLK @BASEBOARD_FAB2_LIB.BASEBOARD_FAB2(SCH_1):SPI_BMC_BT_CLK

RES_0402-4.75K,1%,1/16W,CHIP,GA  I35  R8F13
   1 P3V3_STBY      A @BASEBOARD_FAB2_LIB.BASEBOARD_FAB2(SCH_1):P3V3_STBY
   2 SPI_BMC_BT_CS_N      B @BASEBOARD_FAB2_LIB.BASEBOARD_FAB2(SCH_1):SPI_BMC_BT_CS_N


DRAWING: @BASEBOARD_FAB2_LIB.BASEBOARD_FAB2(SCH_1):PAGE163 

RES_0402-10.0,1%,1/16W,CHIP,G2A  I2  R6N8
   1 SMB_CPU1_PE_HP_GTL_SCL      A @BASEBOARD_FAB2_LIB.BASEBOARD_FAB2(SCH_1):SMB_CPU1_PE_HP_GTL_SCL
   2 SMB_CPU1_PE_HP_GTL_R_SCL      B @BASEBOARD_FAB2_LIB.BASEBOARD_FAB2(SCH_1):SMB_CPU1_PE_HP_GTL_R_SCL

RES_0402-10.0,1%,1/16W,CHIP,G2A  I3  R6N9
   1 SMB_CPU1_PE_HP_GTL_SDA      A @BASEBOARD_FAB2_LIB.BASEBOARD_FAB2(SCH_1):SMB_CPU1_PE_HP_GTL_SDA
   2 SMB_CPU1_PE_HP_GTL_R_SDA      B @BASEBOARD_FAB2_LIB.BASEBOARD_FAB2(SCH_1):SMB_CPU1_PE_HP_GTL_R_SDA

RES_0402-240,1.0%,1/16W,CHIP,GA  I6  R9M18
   1 PVCCIO_CPU1      A @BASEBOARD_FAB2_LIB.BASEBOARD_FAB2(SCH_1):PVCCIO_CPU1
   2 SMB_CPU1_PE_HP_GTL_R_SDA      B @BASEBOARD_FAB2_LIB.BASEBOARD_FAB2(SCH_1):SMB_CPU1_PE_HP_GTL_R_SDA

RES_0402-240,1.0%,1/16W,CHIP,GA  I7  R9M19
   1 PVCCIO_CPU1      A @BASEBOARD_FAB2_LIB.BASEBOARD_FAB2(SCH_1):PVCCIO_CPU1
   2 SMB_CPU1_PE_HP_GTL_R_SCL      B @BASEBOARD_FAB2_LIB.BASEBOARD_FAB2(SCH_1):SMB_CPU1_PE_HP_GTL_R_SCL

CAP_A_0402V-0.1UF,16V,10%,X7R,A  I10  C9M8
   1 PVCCIO_CPU1      A @BASEBOARD_FAB2_LIB.BASEBOARD_FAB2(SCH_1):PVCCIO_CPU1
   2    GND      B @BASEBOARD_FAB2_LIB.BASEBOARD_FAB2(SCH_1):GND

CAP_A_0402V-0.1UF,16V,10%,X7R,A  I12  C9M7
   1 P3V3_STBY      A @BASEBOARD_FAB2_LIB.BASEBOARD_FAB2(SCH_1):P3V3_STBY
   2    GND      B @BASEBOARD_FAB2_LIB.BASEBOARD_FAB2(SCH_1):GND

RES_0402-2.0K,1%,1/16W,CHIP,G2A  I15  R9M17
   1 P3V3_STBY      A @BASEBOARD_FAB2_LIB.BASEBOARD_FAB2(SCH_1):P3V3_STBY
   2 SMB_PEHPCPU1_STBY_LVC3_R_SCL      B @BASEBOARD_FAB2_LIB.BASEBOARD_FAB2(SCH_1):SMB_PEHPCPU1_STBY_LVC3_R_SCL

RES_0402-2.0K,1%,1/16W,CHIP,G2A  I16  R9M16
   1 P3V3_STBY      A @BASEBOARD_FAB2_LIB.BASEBOARD_FAB2(SCH_1):P3V3_STBY
   2 SMB_PEHPCPU1_STBY_LVC3_R_SDA      B @BASEBOARD_FAB2_LIB.BASEBOARD_FAB2(SCH_1):SMB_PEHPCPU1_STBY_LVC3_R_SDA

RES_0402-20.0,1%,1/16W,CHIP,G2A  I20  R9M14
   1 SMB_PEHPCPU1_STBY_LVC3_R_SCL      A @BASEBOARD_FAB2_LIB.BASEBOARD_FAB2(SCH_1):SMB_PEHPCPU1_STBY_LVC3_R_SCL
   2 SMB_PEHPCPU1_STBY_LVC3_SCL      B @BASEBOARD_FAB2_LIB.BASEBOARD_FAB2(SCH_1):SMB_PEHPCPU1_STBY_LVC3_SCL

RES_0402-20.0,1%,1/16W,CHIP,G2A  I21  R9M13
   1 SMB_PEHPCPU1_STBY_LVC3_R_SDA      A @BASEBOARD_FAB2_LIB.BASEBOARD_FAB2(SCH_1):SMB_PEHPCPU1_STBY_LVC3_R_SDA
   2 SMB_PEHPCPU1_STBY_LVC3_SDA      B @BASEBOARD_FAB2_LIB.BASEBOARD_FAB2(SCH_1):SMB_PEHPCPU1_STBY_LVC3_SDA

TCA9517DGKR-GP_DISCRET-G8-TCA9A  I28  U1B2
   1 PVCCIO_CPU1   VCCA @BASEBOARD_FAB2_LIB.BASEBOARD_FAB2(SCH_1):PVCCIO_CPU1
   2 SMB_CPU1_PE_HP_GTL_R_SCL   SCLA @BASEBOARD_FAB2_LIB.BASEBOARD_FAB2(SCH_1):SMB_CPU1_PE_HP_GTL_R_SCL
   3 SMB_CPU1_PE_HP_GTL_R_SDA   SDAA @BASEBOARD_FAB2_LIB.BASEBOARD_FAB2(SCH_1):SMB_CPU1_PE_HP_GTL_R_SDA
   4    GND    GND @BASEBOARD_FAB2_LIB.BASEBOARD_FAB2(SCH_1):GND
   8 P3V3_STBY   VCCB @BASEBOARD_FAB2_LIB.BASEBOARD_FAB2(SCH_1):P3V3_STBY
   7 SMB_PEHPCPU1_STBY_LVC3_R_SCL   SCLB @BASEBOARD_FAB2_LIB.BASEBOARD_FAB2(SCH_1):SMB_PEHPCPU1_STBY_LVC3_R_SCL
   6 SMB_PEHPCPU1_STBY_LVC3_R_SDA   SDAB @BASEBOARD_FAB2_LIB.BASEBOARD_FAB2(SCH_1):SMB_PEHPCPU1_STBY_LVC3_R_SDA
   5 TP_SMB_PEHPCPU1_EN     EN @BASEBOARD_FAB2_LIB.BASEBOARD_FAB2(SCH_1):TP_SMB_PEHPCPU1_EN


DRAWING: @BASEBOARD_FAB2_LIB.BASEBOARD_FAB2(SCH_1):PAGE164 

RES_0402-1.00K,1%,1/16W,CHIP,GA  I7  R1T11
   1 FM_BOARD_REV_ID2      A @BASEBOARD_FAB2_LIB.BASEBOARD_FAB2(SCH_1):FM_BOARD_REV_ID2
   2    GND      B @BASEBOARD_FAB2_LIB.BASEBOARD_FAB2(SCH_1):GND

RES_0402-2.7K,1%,1/16W,EMPTY,GA  I11  R1T5
   1 P3V3_STBY      A @BASEBOARD_FAB2_LIB.BASEBOARD_FAB2(SCH_1):P3V3_STBY
   2 FM_BOARD_REV_ID2      B @BASEBOARD_FAB2_LIB.BASEBOARD_FAB2(SCH_1):FM_BOARD_REV_ID2

RES_0402-1.00K,1%,1/16W,CHIP,GA  I21  R1U17
   1 FM_BOARD_SKU_ID2      A @BASEBOARD_FAB2_LIB.BASEBOARD_FAB2(SCH_1):FM_BOARD_SKU_ID2
   2    GND      B @BASEBOARD_FAB2_LIB.BASEBOARD_FAB2(SCH_1):GND

RES_0402-1.00K,1%,1/16W,CHIP,GA  I32  R2N18
   1 FM_BOARD_SKU_ID4      A @BASEBOARD_FAB2_LIB.BASEBOARD_FAB2(SCH_1):FM_BOARD_SKU_ID4
   2    GND      B @BASEBOARD_FAB2_LIB.BASEBOARD_FAB2(SCH_1):GND

RES_0402-2.7K,1%,1/16W,CHIP,G2A  I34  R1U23
   1 P3V3_STBY      A @BASEBOARD_FAB2_LIB.BASEBOARD_FAB2(SCH_1):P3V3_STBY
   2 FM_BOARD_SKU_ID0      B @BASEBOARD_FAB2_LIB.BASEBOARD_FAB2(SCH_1):FM_BOARD_SKU_ID0

RES_0402-1.00K,1%,1/16W,CHIP,GA  I37  R1U16
   1 FM_BOARD_SKU_ID1      A @BASEBOARD_FAB2_LIB.BASEBOARD_FAB2(SCH_1):FM_BOARD_SKU_ID1
   2    GND      B @BASEBOARD_FAB2_LIB.BASEBOARD_FAB2(SCH_1):GND

RES_0402-1.00K,1%,1/16W,CHIP,GA  I40  R1U18
   1 FM_BOARD_SKU_ID0      A @BASEBOARD_FAB2_LIB.BASEBOARD_FAB2(SCH_1):FM_BOARD_SKU_ID0
   2    GND      B @BASEBOARD_FAB2_LIB.BASEBOARD_FAB2(SCH_1):GND

RES_0402-2.7K,1%,1/16W,CHIP,G2A  I41  R1U21
   1 P3V3_STBY      A @BASEBOARD_FAB2_LIB.BASEBOARD_FAB2(SCH_1):P3V3_STBY
   2 FM_BOARD_SKU_ID3      B @BASEBOARD_FAB2_LIB.BASEBOARD_FAB2(SCH_1):FM_BOARD_SKU_ID3

RES_0402-2.7K,1%,1/16W,CHIP,G2A  I43  R1U22
   1 P3V3_STBY      A @BASEBOARD_FAB2_LIB.BASEBOARD_FAB2(SCH_1):P3V3_STBY
   2 FM_BOARD_SKU_ID1      B @BASEBOARD_FAB2_LIB.BASEBOARD_FAB2(SCH_1):FM_BOARD_SKU_ID1

RES_0402-2.7K,1%,1/16W,CHIP,G2A  I46  R2N17
   1 P3V3_STBY      A @BASEBOARD_FAB2_LIB.BASEBOARD_FAB2(SCH_1):P3V3_STBY
   2 FM_BOARD_SKU_ID4      B @BASEBOARD_FAB2_LIB.BASEBOARD_FAB2(SCH_1):FM_BOARD_SKU_ID4

RES_0402-2.7K,1%,1/16W,CHIP,G2A  I47  R1U24
   1 P3V3_STBY      A @BASEBOARD_FAB2_LIB.BASEBOARD_FAB2(SCH_1):P3V3_STBY
   2 FM_BOARD_SKU_ID2      B @BASEBOARD_FAB2_LIB.BASEBOARD_FAB2(SCH_1):FM_BOARD_SKU_ID2

RES_0402-1.00K,1%,1/16W,CHIP,GA  I48  R1U15
   1 FM_BOARD_SKU_ID3      A @BASEBOARD_FAB2_LIB.BASEBOARD_FAB2(SCH_1):FM_BOARD_SKU_ID3
   2    GND      B @BASEBOARD_FAB2_LIB.BASEBOARD_FAB2(SCH_1):GND

RES_0402-2.7K,1%,1/16W,CHIP,G2A  I51  R1T6
   1 P3V3_STBY      A @BASEBOARD_FAB2_LIB.BASEBOARD_FAB2(SCH_1):P3V3_STBY
   2 FM_BOARD_REV_ID1      B @BASEBOARD_FAB2_LIB.BASEBOARD_FAB2(SCH_1):FM_BOARD_REV_ID1

RES_0402-1.00K,1%,1/16W,CHIP,GA  I53  R1T12
   1 FM_BOARD_REV_ID1      A @BASEBOARD_FAB2_LIB.BASEBOARD_FAB2(SCH_1):FM_BOARD_REV_ID1
   2    GND      B @BASEBOARD_FAB2_LIB.BASEBOARD_FAB2(SCH_1):GND

CAP_A_0402V-0.1UF,16V,10%,X7R,A  I66  C6W14
   1 P3V3_STBY      A @BASEBOARD_FAB2_LIB.BASEBOARD_FAB2(SCH_1):P3V3_STBY
   2    GND      B @BASEBOARD_FAB2_LIB.BASEBOARD_FAB2(SCH_1):GND

RES_0402-4.75K,1%,1/16W,EMPTY,A  I76  R6W47
   1 PCA9554_A0      A @BASEBOARD_FAB2_LIB.BASEBOARD_FAB2(SCH_1):PCA9554_A0
   2    GND      B @BASEBOARD_FAB2_LIB.BASEBOARD_FAB2(SCH_1):GND

RES_0402-4.75K,1%,1/16W,CHIP,GA  I78  R6W44
   1 P3V3_STBY      A @BASEBOARD_FAB2_LIB.BASEBOARD_FAB2(SCH_1):P3V3_STBY
   2 PCA9554_A0      B @BASEBOARD_FAB2_LIB.BASEBOARD_FAB2(SCH_1):PCA9554_A0

RES_0402-4.75K,1%,1/16W,CHIP,GA  I87  R6W41
   1 P3V3_STBY      A @BASEBOARD_FAB2_LIB.BASEBOARD_FAB2(SCH_1):P3V3_STBY
   2 PCA9554_INT_N      B @BASEBOARD_FAB2_LIB.BASEBOARD_FAB2(SCH_1):PCA9554_INT_N

RES_0402-4.75K,1%,1/16W,CHIP,GA  I93  R6W46
   1 PCA9554_A1      A @BASEBOARD_FAB2_LIB.BASEBOARD_FAB2(SCH_1):PCA9554_A1
   2    GND      B @BASEBOARD_FAB2_LIB.BASEBOARD_FAB2(SCH_1):GND

RES_0402-4.75K,1%,1/16W,CHIP,GA  I94  R6W45
   1 PCA9554_A2      A @BASEBOARD_FAB2_LIB.BASEBOARD_FAB2(SCH_1):PCA9554_A2
   2    GND      B @BASEBOARD_FAB2_LIB.BASEBOARD_FAB2(SCH_1):GND

RES_0402-4.75K,1%,1/16W,EMPTY,A  I95  R6W42
   1 P3V3_STBY      A @BASEBOARD_FAB2_LIB.BASEBOARD_FAB2(SCH_1):P3V3_STBY
   2 PCA9554_A2      B @BASEBOARD_FAB2_LIB.BASEBOARD_FAB2(SCH_1):PCA9554_A2

RES_0402-4.75K,1%,1/16W,EMPTY,A  I96  R6W43
   1 P3V3_STBY      A @BASEBOARD_FAB2_LIB.BASEBOARD_FAB2(SCH_1):P3V3_STBY
   2 PCA9554_A1      B @BASEBOARD_FAB2_LIB.BASEBOARD_FAB2(SCH_1):PCA9554_A1

PCA9554PWR-GP_DISCRET-G1-PCA95A  I97  U6W11
   1 PCA9554_A0     A0 @BASEBOARD_FAB2_LIB.BASEBOARD_FAB2(SCH_1):PCA9554_A0
   2 PCA9554_A1     A1 @BASEBOARD_FAB2_LIB.BASEBOARD_FAB2(SCH_1):PCA9554_A1
   3 PCA9554_A2     A2 @BASEBOARD_FAB2_LIB.BASEBOARD_FAB2(SCH_1):PCA9554_A2
   4 FM_MB_SLOT_ID0     P0 @BASEBOARD_FAB2_LIB.BASEBOARD_FAB2(SCH_1):FM_MB_SLOT_ID0
   5 FM_MB_SLOT_ID1     P1 @BASEBOARD_FAB2_LIB.BASEBOARD_FAB2(SCH_1):FM_MB_SLOT_ID1
   6 FM_MB_SLOT_ID2     P2 @BASEBOARD_FAB2_LIB.BASEBOARD_FAB2(SCH_1):FM_MB_SLOT_ID2
   7 FM_CPU_BMC_INIT     P3 @BASEBOARD_FAB2_LIB.BASEBOARD_FAB2(SCH_1):FM_CPU_BMC_INIT
   8    GND    GND @BASEBOARD_FAB2_LIB.BASEBOARD_FAB2(SCH_1):GND
   9     NC     P4     NC
  10     NC     P5     NC
  11     NC     P6     NC
  12     NC     P7     NC
  13 PCA9554_INT_N   INT# @BASEBOARD_FAB2_LIB.BASEBOARD_FAB2(SCH_1):PCA9554_INT_N
  14 SMB_SENSOR_STBY_LVC3_SCL    SCL @BASEBOARD_FAB2_LIB.BASEBOARD_FAB2(SCH_1):SMB_SENSOR_STBY_LVC3_SCL
  15 SMB_SENSOR_STBY_LVC3_SDA    SDA @BASEBOARD_FAB2_LIB.BASEBOARD_FAB2(SCH_1):SMB_SENSOR_STBY_LVC3_SDA
  16 P3V3_STBY    VCC @BASEBOARD_FAB2_LIB.BASEBOARD_FAB2(SCH_1):P3V3_STBY

RES_0402-2.7K,1%,1/16W,CHIP,G2A  I100  R1T4
   1 P3V3_STBY      A @BASEBOARD_FAB2_LIB.BASEBOARD_FAB2(SCH_1):P3V3_STBY
   2 FM_BOARD_REV_ID0      B @BASEBOARD_FAB2_LIB.BASEBOARD_FAB2(SCH_1):FM_BOARD_REV_ID0

RES_0402-1.00K,1%,1/16W,CHIP,GA  I101  R1T10
   1 FM_BOARD_REV_ID0      A @BASEBOARD_FAB2_LIB.BASEBOARD_FAB2(SCH_1):FM_BOARD_REV_ID0
   2    GND      B @BASEBOARD_FAB2_LIB.BASEBOARD_FAB2(SCH_1):GND


DRAWING: @BASEBOARD_FAB2_LIB.BASEBOARD_FAB2(SCH_1):PAGE166 

RES_0402-4.75K,1%,1/16W,CHIP,GA  I28  R7C17
   1 PVCCIO_CPU0      A @BASEBOARD_FAB2_LIB.BASEBOARD_FAB2(SCH_1):PVCCIO_CPU0
   2 PECI_BMC      B @BASEBOARD_FAB2_LIB.BASEBOARD_FAB2(SCH_1):PECI_BMC

RES_0402-348,1%,1/16W,CHIP,G21A  I32  R7D15
   1 PECI_PCH      A @BASEBOARD_FAB2_LIB.BASEBOARD_FAB2(SCH_1):PECI_PCH
   2    GND      B @BASEBOARD_FAB2_LIB.BASEBOARD_FAB2(SCH_1):GND

PI5A3157BC6E-GP_DISCRET-GC2-PIA  I34  U7W1
   1 PECI_BMC     B1 @BASEBOARD_FAB2_LIB.BASEBOARD_FAB2(SCH_1):PECI_BMC
   2    GND    GND @BASEBOARD_FAB2_LIB.BASEBOARD_FAB2(SCH_1):GND
   3 PECI_PCH     B0 @BASEBOARD_FAB2_LIB.BASEBOARD_FAB2(SCH_1):PECI_PCH
   4 PECI_CPU_G      A @BASEBOARD_FAB2_LIB.BASEBOARD_FAB2(SCH_1):PECI_CPU_G
   5 P3V3_STBY    VCC @BASEBOARD_FAB2_LIB.BASEBOARD_FAB2(SCH_1):P3V3_STBY
   6 PECI_SEL      S @BASEBOARD_FAB2_LIB.BASEBOARD_FAB2(SCH_1):PECI_SEL

CAP_A_0402V-0.1UF,16V,10%,X7R,A  I36  C7W1
   1 P3V3_STBY      A @BASEBOARD_FAB2_LIB.BASEBOARD_FAB2(SCH_1):P3V3_STBY
   2    GND      B @BASEBOARD_FAB2_LIB.BASEBOARD_FAB2(SCH_1):GND

RES_0402-10.0K,1%,1/16W,EMPTY,A  I42  R7W2
   1 PECI_CPU_G      A @BASEBOARD_FAB2_LIB.BASEBOARD_FAB2(SCH_1):PECI_CPU_G
   2    GND      B @BASEBOARD_FAB2_LIB.BASEBOARD_FAB2(SCH_1):GND

RES_0402-10.0K,1%,1/16W,EMPTY,A  I46  R7W3
   1 P3V3_STBY      A @BASEBOARD_FAB2_LIB.BASEBOARD_FAB2(SCH_1):P3V3_STBY
   2 PECI_SEL      B @BASEBOARD_FAB2_LIB.BASEBOARD_FAB2(SCH_1):PECI_SEL


DRAWING: @BASEBOARD_FAB2_LIB.BASEBOARD_FAB2(SCH_1):PAGE167 

TMP421_TSSOP-IC,G62962-001  I1  U9B4
   3 PU_TMP421_1_A1   A<1> @BASEBOARD_FAB2_LIB.BASEBOARD_FAB2(SCH_1):PU_TMP421_1_A1
   4 PD_TMP421_1_A0   A<0> @BASEBOARD_FAB2_LIB.BASEBOARD_FAB2(SCH_1):PD_TMP421_1_A0
   2 ISENSE_TMP421_1_DXN    DXN @BASEBOARD_FAB2_LIB.BASEBOARD_FAB2(SCH_1):ISENSE_TMP421_1_DXN
   1 ISENSE_TMP421_1_DXP    DXP @BASEBOARD_FAB2_LIB.BASEBOARD_FAB2(SCH_1):ISENSE_TMP421_1_DXP
   5    GND    GND @BASEBOARD_FAB2_LIB.BASEBOARD_FAB2(SCH_1):GND
   7 SMB_SENSOR_TMP421_1_SCL    SCL @BASEBOARD_FAB2_LIB.BASEBOARD_FAB2(SCH_1):SMB_SENSOR_TMP421_1_SCL
   6 SMB_SENSOR_TMP421_1_SDA    SDA @BASEBOARD_FAB2_LIB.BASEBOARD_FAB2(SCH_1):SMB_SENSOR_TMP421_1_SDA
   8 P3V3_STBY     VP @BASEBOARD_FAB2_LIB.BASEBOARD_FAB2(SCH_1):P3V3_STBY

RES_0402-49.9,1%,1/16W,CHIP,G2A  I5  R9B5
   1 ISENSE_TMP421_1_BC      A @BASEBOARD_FAB2_LIB.BASEBOARD_FAB2(SCH_1):ISENSE_TMP421_1_BC
   2 ISENSE_TMP421_1_DXN      B @BASEBOARD_FAB2_LIB.BASEBOARD_FAB2(SCH_1):ISENSE_TMP421_1_DXN

RES_0402-49.9,1%,1/16W,CHIP,G2A  I6  R9B4
   1 ISENSE_TMP421_1_E      A @BASEBOARD_FAB2_LIB.BASEBOARD_FAB2(SCH_1):ISENSE_TMP421_1_E
   2 ISENSE_TMP421_1_DXP      B @BASEBOARD_FAB2_LIB.BASEBOARD_FAB2(SCH_1):ISENSE_TMP421_1_DXP

CAP_0402LF-47.0PF,50V,5%,EMPTYA  I7  C1M4
   1 ISENSE_TMP421_1_DXP      A @BASEBOARD_FAB2_LIB.BASEBOARD_FAB2(SCH_1):ISENSE_TMP421_1_DXP
   2 ISENSE_TMP421_1_DXN      B @BASEBOARD_FAB2_LIB.BASEBOARD_FAB2(SCH_1):ISENSE_TMP421_1_DXN

RES_0402-20.0,1%,1/16W,CHIP,G2A  I8  R1M9
   1 SMB_SENSOR_TMP421_1_SDA      A @BASEBOARD_FAB2_LIB.BASEBOARD_FAB2(SCH_1):SMB_SENSOR_TMP421_1_SDA
   2 SMB_SENSOR_STBY_LVC3_SDA      B @BASEBOARD_FAB2_LIB.BASEBOARD_FAB2(SCH_1):SMB_SENSOR_STBY_LVC3_SDA

RES_0402-1.00K,1%,1/16W,CHIP,GA  I10  R9B8
   1 PD_TMP421_1_A0      A @BASEBOARD_FAB2_LIB.BASEBOARD_FAB2(SCH_1):PD_TMP421_1_A0
   2    GND      B @BASEBOARD_FAB2_LIB.BASEBOARD_FAB2(SCH_1):GND

CAP_0402LF-47.0PF,50V,5%,EMPTYA  I24  C1E19
   1 ISENSE_TMP421_2_DXP      A @BASEBOARD_FAB2_LIB.BASEBOARD_FAB2(SCH_1):ISENSE_TMP421_2_DXP
   2 ISENSE_TMP421_2_DXN      B @BASEBOARD_FAB2_LIB.BASEBOARD_FAB2(SCH_1):ISENSE_TMP421_2_DXN

RES_0402-49.9,1%,1/16W,CHIP,G2A  I25  R9R5
   1 ISENSE_TMP421_2_E      A @BASEBOARD_FAB2_LIB.BASEBOARD_FAB2(SCH_1):ISENSE_TMP421_2_E
   2 ISENSE_TMP421_2_DXP      B @BASEBOARD_FAB2_LIB.BASEBOARD_FAB2(SCH_1):ISENSE_TMP421_2_DXP

RES_0402-49.9,1%,1/16W,CHIP,G2A  I26  R9R6
   1 ISENSE_TMP421_2_BC      A @BASEBOARD_FAB2_LIB.BASEBOARD_FAB2(SCH_1):ISENSE_TMP421_2_BC
   2 ISENSE_TMP421_2_DXN      B @BASEBOARD_FAB2_LIB.BASEBOARD_FAB2(SCH_1):ISENSE_TMP421_2_DXN

TMP421_TSSOP-IC,G62962-001  I30  U1E1
   3 PD_TMP421_2_A1   A<1> @BASEBOARD_FAB2_LIB.BASEBOARD_FAB2(SCH_1):PD_TMP421_2_A1
   4 PU_TMP421_2_A0   A<0> @BASEBOARD_FAB2_LIB.BASEBOARD_FAB2(SCH_1):PU_TMP421_2_A0
   2 ISENSE_TMP421_2_DXN    DXN @BASEBOARD_FAB2_LIB.BASEBOARD_FAB2(SCH_1):ISENSE_TMP421_2_DXN
   1 ISENSE_TMP421_2_DXP    DXP @BASEBOARD_FAB2_LIB.BASEBOARD_FAB2(SCH_1):ISENSE_TMP421_2_DXP
   5    GND    GND @BASEBOARD_FAB2_LIB.BASEBOARD_FAB2(SCH_1):GND
   7 SMB_SENSOR_TMP421_2_SCL    SCL @BASEBOARD_FAB2_LIB.BASEBOARD_FAB2(SCH_1):SMB_SENSOR_TMP421_2_SCL
   6 SMB_SENSOR_TMP421_2_SDA    SDA @BASEBOARD_FAB2_LIB.BASEBOARD_FAB2(SCH_1):SMB_SENSOR_TMP421_2_SDA
   8 P3V3_STBY     VP @BASEBOARD_FAB2_LIB.BASEBOARD_FAB2(SCH_1):P3V3_STBY

RES_0402-1.00K,1%,1/16W,CHIP,GA  I34  R1E9
   1 P3V3_STBY      A @BASEBOARD_FAB2_LIB.BASEBOARD_FAB2(SCH_1):P3V3_STBY
   2 PU_TMP421_2_A0      B @BASEBOARD_FAB2_LIB.BASEBOARD_FAB2(SCH_1):PU_TMP421_2_A0

RES_0402-1.00K,1%,1/16W,CHIP,GA  I35  R9B6
   1 P3V3_STBY      A @BASEBOARD_FAB2_LIB.BASEBOARD_FAB2(SCH_1):P3V3_STBY
   2 PU_TMP421_1_A1      B @BASEBOARD_FAB2_LIB.BASEBOARD_FAB2(SCH_1):PU_TMP421_1_A1

RES_0402-1.00K,1%,1/16W,CHIP,GA  I38  R1E10
   1 P3V3_STBY      A @BASEBOARD_FAB2_LIB.BASEBOARD_FAB2(SCH_1):P3V3_STBY
   2 PD_TMP421_2_A1      B @BASEBOARD_FAB2_LIB.BASEBOARD_FAB2(SCH_1):PD_TMP421_2_A1

CAP_A_0402V-0.1UF,16V,10%,X7R,A  I39  C9B7
   1 P3V3_STBY      A @BASEBOARD_FAB2_LIB.BASEBOARD_FAB2(SCH_1):P3V3_STBY
   2    GND      B @BASEBOARD_FAB2_LIB.BASEBOARD_FAB2(SCH_1):GND

CAP_A_0402V-0.1UF,16V,10%,X7R,A  I41  C9R14
   1 P3V3_STBY      A @BASEBOARD_FAB2_LIB.BASEBOARD_FAB2(SCH_1):P3V3_STBY
   2    GND      B @BASEBOARD_FAB2_LIB.BASEBOARD_FAB2(SCH_1):GND

CAP_A_0402V-0.1UF,16V,10%,X7R,A  I42  C9R13
   1 P3V3_STBY      A @BASEBOARD_FAB2_LIB.BASEBOARD_FAB2(SCH_1):P3V3_STBY
   2    GND      B @BASEBOARD_FAB2_LIB.BASEBOARD_FAB2(SCH_1):GND

AT24C64_SOICLF-IC,C47049-001-GA  I49  U8D4
   1    GND     A0 @BASEBOARD_FAB2_LIB.BASEBOARD_FAB2(SCH_1):GND
   2    GND     A1 @BASEBOARD_FAB2_LIB.BASEBOARD_FAB2(SCH_1):GND
   3 PU_AT24C64_A2     A2 @BASEBOARD_FAB2_LIB.BASEBOARD_FAB2(SCH_1):PU_AT24C64_A2
   6 SMB_SENSOR_STBY_LVC3_SCL_R2    SCL @BASEBOARD_FAB2_LIB.BASEBOARD_FAB2(SCH_1):SMB_SENSOR_STBY_LVC3_SCL_R2
   7 PD_FRU_WP     WP @BASEBOARD_FAB2_LIB.BASEBOARD_FAB2(SCH_1):PD_FRU_WP
   5 SMB_SENSOR_STBY_LVC3_SDA_R2    SDA @BASEBOARD_FAB2_LIB.BASEBOARD_FAB2(SCH_1):SMB_SENSOR_STBY_LVC3_SDA_R2

RES_0402-1.00K,1%,1/16W,CHIP,GA  I50  R8D27
   1 PD_FRU_WP      A @BASEBOARD_FAB2_LIB.BASEBOARD_FAB2(SCH_1):PD_FRU_WP
   2    GND      B @BASEBOARD_FAB2_LIB.BASEBOARD_FAB2(SCH_1):GND

RES_0402-20.0,1%,1/16W,CHIP,G2A  I58  R9G15
   1 SMB_SENSOR_BMC_STBY_LVC3_SDA      A @BASEBOARD_FAB2_LIB.BASEBOARD_FAB2(SCH_1):SMB_SENSOR_BMC_STBY_LVC3_SDA
   2 SMB_SENSOR_STBY_LVC3_SDA      B @BASEBOARD_FAB2_LIB.BASEBOARD_FAB2(SCH_1):SMB_SENSOR_STBY_LVC3_SDA

RES_0402-1.00K,1%,1/16W,CHIP,GA  I70  R8D28
   1 P3V3_STBY      A @BASEBOARD_FAB2_LIB.BASEBOARD_FAB2(SCH_1):P3V3_STBY
   2 PU_AT24C64_A2      B @BASEBOARD_FAB2_LIB.BASEBOARD_FAB2(SCH_1):PU_AT24C64_A2

RES_0402-20.0,1%,1/16W,CHIP,G2A  I74  R1M8
   1 SMB_SENSOR_TMP421_1_SCL      A @BASEBOARD_FAB2_LIB.BASEBOARD_FAB2(SCH_1):SMB_SENSOR_TMP421_1_SCL
   2 SMB_SENSOR_STBY_LVC3_SCL      B @BASEBOARD_FAB2_LIB.BASEBOARD_FAB2(SCH_1):SMB_SENSOR_STBY_LVC3_SCL

RES_0402-20.0,1%,1/16W,CHIP,G2A  I75  R9R7
   1 SMB_SENSOR_TMP421_2_SCL      A @BASEBOARD_FAB2_LIB.BASEBOARD_FAB2(SCH_1):SMB_SENSOR_TMP421_2_SCL
   2 SMB_SENSOR_STBY_LVC3_SCL      B @BASEBOARD_FAB2_LIB.BASEBOARD_FAB2(SCH_1):SMB_SENSOR_STBY_LVC3_SCL

RES_0402-20.0,1%,1/16W,CHIP,G2A  I76  R9R8
   1 SMB_SENSOR_TMP421_2_SDA      A @BASEBOARD_FAB2_LIB.BASEBOARD_FAB2(SCH_1):SMB_SENSOR_TMP421_2_SDA
   2 SMB_SENSOR_STBY_LVC3_SDA      B @BASEBOARD_FAB2_LIB.BASEBOARD_FAB2(SCH_1):SMB_SENSOR_STBY_LVC3_SDA

RES_0402-20.0,1%,1/16W,CHIP,G2A  I77  R9G14
   1 SMB_SENSOR_BMC_STBY_LVC3_SCL      A @BASEBOARD_FAB2_LIB.BASEBOARD_FAB2(SCH_1):SMB_SENSOR_BMC_STBY_LVC3_SCL
   2 SMB_SENSOR_STBY_LVC3_SCL      B @BASEBOARD_FAB2_LIB.BASEBOARD_FAB2(SCH_1):SMB_SENSOR_STBY_LVC3_SCL

RES_0402-665,1.0%,1/16W,CHIP,GA  I80  R2U38
   1 P3V3_STBY      A @BASEBOARD_FAB2_LIB.BASEBOARD_FAB2(SCH_1):P3V3_STBY
   2 SMB_SENSOR_STBY_LVC3_SCL      B @BASEBOARD_FAB2_LIB.BASEBOARD_FAB2(SCH_1):SMB_SENSOR_STBY_LVC3_SCL

RES_0402-665,1.0%,1/16W,CHIP,GA  I83  R2U39
   1 P3V3_STBY      A @BASEBOARD_FAB2_LIB.BASEBOARD_FAB2(SCH_1):P3V3_STBY
   2 SMB_SENSOR_STBY_LVC3_SDA      B @BASEBOARD_FAB2_LIB.BASEBOARD_FAB2(SCH_1):SMB_SENSOR_STBY_LVC3_SDA

RES_0402-20.0,1%,1/16W,CHIP,G2A  I84  R8D24
   1 SMB_SENSOR_STBY_LVC3_SCL      A @BASEBOARD_FAB2_LIB.BASEBOARD_FAB2(SCH_1):SMB_SENSOR_STBY_LVC3_SCL
   2 SMB_SENSOR_STBY_LVC3_SCL_R2      B @BASEBOARD_FAB2_LIB.BASEBOARD_FAB2(SCH_1):SMB_SENSOR_STBY_LVC3_SCL_R2

RES_0402-20.0,1%,1/16W,CHIP,G2A  I85  R8D23
   1 SMB_SENSOR_STBY_LVC3_SDA_R2      A @BASEBOARD_FAB2_LIB.BASEBOARD_FAB2(SCH_1):SMB_SENSOR_STBY_LVC3_SDA_R2
   2 SMB_SENSOR_STBY_LVC3_SDA      B @BASEBOARD_FAB2_LIB.BASEBOARD_FAB2(SCH_1):SMB_SENSOR_STBY_LVC3_SDA

2SB2907A-B0-00001-GP_DISCRET-GA  I93  Q9B1
   C ISENSE_TMP421_1_BC      C @BASEBOARD_FAB2_LIB.BASEBOARD_FAB2(SCH_1):ISENSE_TMP421_1_BC
   B ISENSE_TMP421_1_BC      B @BASEBOARD_FAB2_LIB.BASEBOARD_FAB2(SCH_1):ISENSE_TMP421_1_BC
   E ISENSE_TMP421_1_E      E @BASEBOARD_FAB2_LIB.BASEBOARD_FAB2(SCH_1):ISENSE_TMP421_1_E

2SB2907A-B0-00001-GP_DISCRET-GA  I94  Q1E1
   C ISENSE_TMP421_2_BC      C @BASEBOARD_FAB2_LIB.BASEBOARD_FAB2(SCH_1):ISENSE_TMP421_2_BC
   B ISENSE_TMP421_2_BC      B @BASEBOARD_FAB2_LIB.BASEBOARD_FAB2(SCH_1):ISENSE_TMP421_2_BC
   E ISENSE_TMP421_2_E      E @BASEBOARD_FAB2_LIB.BASEBOARD_FAB2(SCH_1):ISENSE_TMP421_2_E


DRAWING: @BASEBOARD_FAB2_LIB.BASEBOARD_FAB2(SCH_1):PAGE168 

DIODE_SM-1N4148W,IC,D89194-001  I2  CR1L1
   1 FM_DB_UART_SEL1_N      C @BASEBOARD_FAB2_LIB.BASEBOARD_FAB2(SCH_1):FM_DB_UART_SEL1_N
   2 FM_DB_UART_SEL0_N      A @BASEBOARD_FAB2_LIB.BASEBOARD_FAB2(SCH_1):FM_DB_UART_SEL0_N

DIODE_SM-1N4148W,IC,D89194-001  I3  CR1L2
   1 FM_DB_UART_SEL2_N      C @BASEBOARD_FAB2_LIB.BASEBOARD_FAB2(SCH_1):FM_DB_UART_SEL2_N
   2 FM_DB_UART_SEL1_N      A @BASEBOARD_FAB2_LIB.BASEBOARD_FAB2(SCH_1):FM_DB_UART_SEL1_N

DIODE_SM-1N4148W,IC,D89194-001  I4  CR1L3
   1 FM_DB_UART_SEL3_N      C @BASEBOARD_FAB2_LIB.BASEBOARD_FAB2(SCH_1):FM_DB_UART_SEL3_N
   2 FM_DB_UART_SEL2_N      A @BASEBOARD_FAB2_LIB.BASEBOARD_FAB2(SCH_1):FM_DB_UART_SEL2_N

DIODE_SM-1N4148W,IC,D89194-001  I5  CR1L4
   1 FM_DB_UART_SEL4_N      C @BASEBOARD_FAB2_LIB.BASEBOARD_FAB2(SCH_1):FM_DB_UART_SEL4_N
   2 FM_DB_UART_SEL3_N      A @BASEBOARD_FAB2_LIB.BASEBOARD_FAB2(SCH_1):FM_DB_UART_SEL3_N

RES_0402-0.0,5%,1/16W,CHIP,G21A  I6  R1L6
   1 FM_UART_SWITCH_N      A @BASEBOARD_FAB2_LIB.BASEBOARD_FAB2(SCH_1):FM_UART_SWITCH_N
   2 FM_DB_UART_SEL0_N      B @BASEBOARD_FAB2_LIB.BASEBOARD_FAB2(SCH_1):FM_DB_UART_SEL0_N

NPN_SM-MMBT3904,IC,C52245-001  I8  Q1L3
   1 FM_DB_UART_SEL4_N      B @BASEBOARD_FAB2_LIB.BASEBOARD_FAB2(SCH_1):FM_DB_UART_SEL4_N
   3 FM_DB_PRESENT      C @BASEBOARD_FAB2_LIB.BASEBOARD_FAB2(SCH_1):FM_DB_PRESENT
   2    GND      E @BASEBOARD_FAB2_LIB.BASEBOARD_FAB2(SCH_1):GND

RES_0402-1.00K,1%,1/16W,CHIP,GA  I11  R1L36
   1 P3V3_STBY      A @BASEBOARD_FAB2_LIB.BASEBOARD_FAB2(SCH_1):P3V3_STBY
   2 FM_DB_PRESENT      B @BASEBOARD_FAB2_LIB.BASEBOARD_FAB2(SCH_1):FM_DB_PRESENT

FET_N_DUAL_SMLF-2N7002DW,FET,DA  I18  Q1L4
   5 TP_FET_Q56_4 GATE<0> @BASEBOARD_FAB2_LIB.BASEBOARD_FAB2(SCH_1):TP_FET_Q56_4
   4 TP_FET_Q56_4 SOURCE<0> @BASEBOARD_FAB2_LIB.BASEBOARD_FAB2(SCH_1):TP_FET_Q56_4
   3 TP_FET_Q56_3 DRAIN<0> @BASEBOARD_FAB2_LIB.BASEBOARD_FAB2(SCH_1):TP_FET_Q56_3

FET_N_DUAL_SMLF-2N7002DW,FET,DA  I19  Q1L4
   2 FM_DB_PRESENT GATE<0> @BASEBOARD_FAB2_LIB.BASEBOARD_FAB2(SCH_1):FM_DB_PRESENT
   1    GND SOURCE<0> @BASEBOARD_FAB2_LIB.BASEBOARD_FAB2(SCH_1):GND
   6 FM_POST_CARD_PRES_BMC_N DRAIN<0> @BASEBOARD_FAB2_LIB.BASEBOARD_FAB2(SCH_1):FM_POST_CARD_PRES_BMC_N

RES_0402-1.00K,1%,1/16W,CHIP,GA  I22  R1L38
   1 P3V3_STBY      A @BASEBOARD_FAB2_LIB.BASEBOARD_FAB2(SCH_1):P3V3_STBY
   2 FM_POST_CARD_PRES_BMC_N      B @BASEBOARD_FAB2_LIB.BASEBOARD_FAB2(SCH_1):FM_POST_CARD_PRES_BMC_N

FET_N_SOT23LF-2N7002,FET,C7925A  I43  Q6W4
   1 DEBUG_CARD2_PRSNT   GATE @BASEBOARD_FAB2_LIB.BASEBOARD_FAB2(SCH_1):DEBUG_CARD2_PRSNT
   2    GND    SRC @BASEBOARD_FAB2_LIB.BASEBOARD_FAB2(SCH_1):GND
   3 FM_POST_CARD_PRES_BMC_N    DRN @BASEBOARD_FAB2_LIB.BASEBOARD_FAB2(SCH_1):FM_POST_CARD_PRES_BMC_N

RES_0402-1.00K,1%,1/16W,CHIP,GA  I46  R6W16
   1 P3V3_STBY      A @BASEBOARD_FAB2_LIB.BASEBOARD_FAB2(SCH_1):P3V3_STBY
   2 FM_SOL_UART_CH_SEL      B @BASEBOARD_FAB2_LIB.BASEBOARD_FAB2(SCH_1):FM_SOL_UART_CH_SEL

NPN_SM-MMBT3904,IC,C52245-001  I47  Q6W2
   1 FM_UART_SEL_N      B @BASEBOARD_FAB2_LIB.BASEBOARD_FAB2(SCH_1):FM_UART_SEL_N
   3 FM_SOL_UART_CH_SEL      C @BASEBOARD_FAB2_LIB.BASEBOARD_FAB2(SCH_1):FM_SOL_UART_CH_SEL
   2    GND      E @BASEBOARD_FAB2_LIB.BASEBOARD_FAB2(SCH_1):GND

RES_0402-40.2K,1%,1/16W,CHIP,GA  I48  R6W49
   1 FM_UART_SWITCH_N      A @BASEBOARD_FAB2_LIB.BASEBOARD_FAB2(SCH_1):FM_UART_SWITCH_N
   2 FM_UART_SEL_N      B @BASEBOARD_FAB2_LIB.BASEBOARD_FAB2(SCH_1):FM_UART_SEL_N


DRAWING: @BASEBOARD_FAB2_LIB.BASEBOARD_FAB2(SCH_1):PAGE169 

CAP_0402LF-47.0PF,50V,5%,COG,AA  I56  C1U21
   1 A_P1V05_STBY_PCH_SENSOR      A @BASEBOARD_FAB2_LIB.BASEBOARD_FAB2(SCH_1):A_P1V05_STBY_PCH_SENSOR
   2    GND      B @BASEBOARD_FAB2_LIB.BASEBOARD_FAB2(SCH_1):GND

FERRITE_SMLF-30,FB,693286-021  I57  FB1U3
   1 A_P1V05_STBY_PCH_SENSOR      A @BASEBOARD_FAB2_LIB.BASEBOARD_FAB2(SCH_1):A_P1V05_STBY_PCH_SENSOR
   2 P1V05_PCH_STBY      B @BASEBOARD_FAB2_LIB.BASEBOARD_FAB2(SCH_1):P1V05_PCH_STBY

CAP_0402LF-47.0PF,50V,5%,COG,AA  I68  C9G21
   1 A_P5V_STBY_SCALED      A @BASEBOARD_FAB2_LIB.BASEBOARD_FAB2(SCH_1):A_P5V_STBY_SCALED
   2    GND      B @BASEBOARD_FAB2_LIB.BASEBOARD_FAB2(SCH_1):GND

CAP_0402LF-47.0PF,50V,5%,COG,AA  I80  C9G17
   1 A_P12V_STBY_SCALED      A @BASEBOARD_FAB2_LIB.BASEBOARD_FAB2(SCH_1):A_P12V_STBY_SCALED
   2    GND      B @BASEBOARD_FAB2_LIB.BASEBOARD_FAB2(SCH_1):GND

RES_0402-5.11K,1%,1/16W,CHIP,GA  I82  R1U32
   1 P12V_STBY      A @BASEBOARD_FAB2_LIB.BASEBOARD_FAB2(SCH_1):P12V_STBY
   2 A_P12V_STBY_SCALED      B @BASEBOARD_FAB2_LIB.BASEBOARD_FAB2(SCH_1):A_P12V_STBY_SCALED

CAP_0402LF-47.0PF,50V,5%,COG,AA  I86  C9G20
   1 A_P3V3_STBY_SCALED      A @BASEBOARD_FAB2_LIB.BASEBOARD_FAB2(SCH_1):A_P3V3_STBY_SCALED
   2    GND      B @BASEBOARD_FAB2_LIB.BASEBOARD_FAB2(SCH_1):GND

RES_0402-5.11K,1%,1/16W,CHIP,GA  I88  R1U39
   1 P3V3_STBY      A @BASEBOARD_FAB2_LIB.BASEBOARD_FAB2(SCH_1):P3V3_STBY
   2 A_P3V3_STBY_SCALED      B @BASEBOARD_FAB2_LIB.BASEBOARD_FAB2(SCH_1):A_P3V3_STBY_SCALED

RES_0402-100.0K,1%,1/16W,CHIP,A  I106  R9G26
   1 A_P3V_BAT_SCALED      A @BASEBOARD_FAB2_LIB.BASEBOARD_FAB2(SCH_1):A_P3V_BAT_SCALED
   2    GND      B @BASEBOARD_FAB2_LIB.BASEBOARD_FAB2(SCH_1):GND

CAP_0402LF-10.0PF,50V,5%,COG,AA  I108  C9G22
   1 A_P3V_BAT_SCALED      A @BASEBOARD_FAB2_LIB.BASEBOARD_FAB2(SCH_1):A_P3V_BAT_SCALED
   2    GND      B @BASEBOARD_FAB2_LIB.BASEBOARD_FAB2(SCH_1):GND

RES_0402-5.11K,1%,1/16W,CHIP,GA  I115  R1U47
   1 P5V_STBY      A @BASEBOARD_FAB2_LIB.BASEBOARD_FAB2(SCH_1):P5V_STBY
   2 A_P5V_STBY_SCALED      B @BASEBOARD_FAB2_LIB.BASEBOARD_FAB2(SCH_1):A_P5V_STBY_SCALED

RES_0402-200.0K,1%,1/16W,CHIP,A  I126  R1U50
   1 A_P3V_BAT_R      A @BASEBOARD_FAB2_LIB.BASEBOARD_FAB2(SCH_1):A_P3V_BAT_R
   2 P3V_BAT_SOURCE_R      B @BASEBOARD_FAB2_LIB.BASEBOARD_FAB2(SCH_1):P3V_BAT_SOURCE_R

CAP_0402LF-47.0PF,50V,5%,COG,AA  I139  C9G15
   1 A_P5V_SCALED      A @BASEBOARD_FAB2_LIB.BASEBOARD_FAB2(SCH_1):A_P5V_SCALED
   2    GND      B @BASEBOARD_FAB2_LIB.BASEBOARD_FAB2(SCH_1):GND

RES_0402-5.11K,1%,1/16W,CHIP,GA  I141  R1U29
   1    P5V      A @BASEBOARD_FAB2_LIB.BASEBOARD_FAB2(SCH_1):P5V
   2 A_P5V_SCALED      B @BASEBOARD_FAB2_LIB.BASEBOARD_FAB2(SCH_1):A_P5V_SCALED

CAP_0402LF-47.0PF,50V,5%,COG,AA  I146  C9G14
   1 A_P3V3_SCALED      A @BASEBOARD_FAB2_LIB.BASEBOARD_FAB2(SCH_1):A_P3V3_SCALED
   2    GND      B @BASEBOARD_FAB2_LIB.BASEBOARD_FAB2(SCH_1):GND

RES_0402-5.11K,1%,1/16W,CHIP,GA  I148  R1U26
   1   P3V3      A @BASEBOARD_FAB2_LIB.BASEBOARD_FAB2(SCH_1):P3V3
   2 A_P3V3_SCALED      B @BASEBOARD_FAB2_LIB.BASEBOARD_FAB2(SCH_1):A_P3V3_SCALED

CAP_0402LF-47.0PF,50V,5%,COG,AA  I153  C9G18
   1 A_PVNN_STBY_PCH_SENSOR      A @BASEBOARD_FAB2_LIB.BASEBOARD_FAB2(SCH_1):A_PVNN_STBY_PCH_SENSOR
   2    GND      B @BASEBOARD_FAB2_LIB.BASEBOARD_FAB2(SCH_1):GND

FERRITE_SMLF-30,FB,693286-021  I155  FB1U4
   1 A_PVNN_STBY_PCH_SENSOR      A @BASEBOARD_FAB2_LIB.BASEBOARD_FAB2(SCH_1):A_PVNN_STBY_PCH_SENSOR
   2 PVNN_PCH_STBY      B @BASEBOARD_FAB2_LIB.BASEBOARD_FAB2(SCH_1):PVNN_PCH_STBY

FET_N_DUAL_SMLF-NTJD4001N,FET,A  I157  Q9G1
   5 FM_BATTERY_SENSE_EN GATE<0> @BASEBOARD_FAB2_LIB.BASEBOARD_FAB2(SCH_1):FM_BATTERY_SENSE_EN
   4 A_P3V_BAT_SCALED SOURCE<0> @BASEBOARD_FAB2_LIB.BASEBOARD_FAB2(SCH_1):A_P3V_BAT_SCALED
   3 P3V_BAT_SOURCE_R DRAIN<0> @BASEBOARD_FAB2_LIB.BASEBOARD_FAB2(SCH_1):P3V_BAT_SOURCE_R

FET_N_DUAL_SMLF-NTJD4001N,FET,A  I162  Q9G1
   2 FM_BATTERY_SENSE_EN_N GATE<0> @BASEBOARD_FAB2_LIB.BASEBOARD_FAB2(SCH_1):FM_BATTERY_SENSE_EN_N
   1    GND SOURCE<0> @BASEBOARD_FAB2_LIB.BASEBOARD_FAB2(SCH_1):GND
   6 FM_BATTERY_SENSE_EN DRAIN<0> @BASEBOARD_FAB2_LIB.BASEBOARD_FAB2(SCH_1):FM_BATTERY_SENSE_EN

RES_0402-2.7K,1%,1/16W,CHIP,G2A  I163  R1U49
   1 P3V3_STBY      A @BASEBOARD_FAB2_LIB.BASEBOARD_FAB2(SCH_1):P3V3_STBY
   2 FM_BATTERY_SENSE_EN      B @BASEBOARD_FAB2_LIB.BASEBOARD_FAB2(SCH_1):FM_BATTERY_SENSE_EN

RES_0402-2.7K,1%,1/16W,CHIP,G2A  I164  R9G35
   1 P3V3_STBY      A @BASEBOARD_FAB2_LIB.BASEBOARD_FAB2(SCH_1):P3V3_STBY
   2 FM_BATTERY_SENSE_EN_N      B @BASEBOARD_FAB2_LIB.BASEBOARD_FAB2(SCH_1):FM_BATTERY_SENSE_EN_N

1K82R2F-1-GP_SMD-RG-1K82R2F-1-A  I169  R1U28
   1 A_P5V_SCALED      1 @BASEBOARD_FAB2_LIB.BASEBOARD_FAB2(SCH_1):A_P5V_SCALED
   2    GND      2 @BASEBOARD_FAB2_LIB.BASEBOARD_FAB2(SCH_1):GND

1K82R2F-1-GP_SMD-RG-1K82R2F-1-A  I170  R1U44
   1 A_P5V_STBY_SCALED      1 @BASEBOARD_FAB2_LIB.BASEBOARD_FAB2(SCH_1):A_P5V_STBY_SCALED
   2    GND      2 @BASEBOARD_FAB2_LIB.BASEBOARD_FAB2(SCH_1):GND

649R2F-GP_RCL_GP-649R2F-GP,64.A  I171  R1U33
   1 A_P12V_STBY_SCALED      1 @BASEBOARD_FAB2_LIB.BASEBOARD_FAB2(SCH_1):A_P12V_STBY_SCALED
   2    GND      2 @BASEBOARD_FAB2_LIB.BASEBOARD_FAB2(SCH_1):GND

RES_0402-3.48K,1.0%,1/16W,CHIPA  I172  R1U38
   1 A_P3V3_STBY_SCALED      A @BASEBOARD_FAB2_LIB.BASEBOARD_FAB2(SCH_1):A_P3V3_STBY_SCALED
   2    GND      B @BASEBOARD_FAB2_LIB.BASEBOARD_FAB2(SCH_1):GND

RES_0402-3.48K,1.0%,1/16W,CHIPA  I173  R1U27
   1 A_P3V3_SCALED      A @BASEBOARD_FAB2_LIB.BASEBOARD_FAB2(SCH_1):A_P3V3_SCALED
   2    GND      B @BASEBOARD_FAB2_LIB.BASEBOARD_FAB2(SCH_1):GND


DRAWING: @BASEBOARD_FAB2_LIB.BASEBOARD_FAB2(SCH_1):PAGE170 

RES_0402-4.75K,1%,1/16W,CHIP,GA  I2  R2P3
   1 P3V3_STBY      A @BASEBOARD_FAB2_LIB.BASEBOARD_FAB2(SCH_1):P3V3_STBY
   2 IRQ_FORCE_NM_THROTTLE_R_N      B @BASEBOARD_FAB2_LIB.BASEBOARD_FAB2(SCH_1):IRQ_FORCE_NM_THROTTLE_R_N

TTL1G07_A_SOP-74LVC1G07,IC,C88B  I4  U8D3
   2 IRQ_SML1_PMBUS_ALERT_BUF_N      A @BASEBOARD_FAB2_LIB.BASEBOARD_FAB2(SCH_1):IRQ_SML1_PMBUS_ALERT_BUF_N
   4 IRQ_FORCE_NM_THROTTLE_R_N      Y @BASEBOARD_FAB2_LIB.BASEBOARD_FAB2(SCH_1):IRQ_FORCE_NM_THROTTLE_R_N

CAP_A_0402V-0.1UF,16V,10%,X7R,A  I8  C2P1
   1 P3V3_STBY      A @BASEBOARD_FAB2_LIB.BASEBOARD_FAB2(SCH_1):P3V3_STBY
   2    GND      B @BASEBOARD_FAB2_LIB.BASEBOARD_FAB2(SCH_1):GND

TTL08_QFN15-74LVC08A,IC,D90404B  I10  U8E1
   3 FM_FAST_PROCHOT_AND_OUT_0_N   Y<0> @BASEBOARD_FAB2_LIB.BASEBOARD_FAB2(SCH_1):FM_FAST_PROCHOT_AND_OUT_0_N
   2 FM_OC_DETECT_N   B<0> @BASEBOARD_FAB2_LIB.BASEBOARD_FAB2(SCH_1):FM_OC_DETECT_N
   1 IRQ_FORCE_NM_THROTTLE_N   A<0> @BASEBOARD_FAB2_LIB.BASEBOARD_FAB2(SCH_1):IRQ_FORCE_NM_THROTTLE_N

TTL08_QFN15-74LVC08A,IC,D90404B  I11  U8E1
   6 FM_FAST_PROCHOT_AND_OUT_1_N   Y<0> @BASEBOARD_FAB2_LIB.BASEBOARD_FAB2(SCH_1):FM_FAST_PROCHOT_AND_OUT_1_N
   5 FM_HSC_TIMER_EXP_N   B<0> @BASEBOARD_FAB2_LIB.BASEBOARD_FAB2(SCH_1):FM_HSC_TIMER_EXP_N
   4 IRQ_UV_DETECT_N   A<0> @BASEBOARD_FAB2_LIB.BASEBOARD_FAB2(SCH_1):IRQ_UV_DETECT_N

TTL08_QFN15-74LVC08A,IC,D90404B  I12  U8E1
  11 FM_FAST_PROCHOT_THROTTLE_IN_N   Y<0> @BASEBOARD_FAB2_LIB.BASEBOARD_FAB2(SCH_1):FM_FAST_PROCHOT_THROTTLE_IN_N
  13 FM_FAST_PROCHOT_AND_OUT_1_N   B<0> @BASEBOARD_FAB2_LIB.BASEBOARD_FAB2(SCH_1):FM_FAST_PROCHOT_AND_OUT_1_N
  12 FM_FAST_PROCHOT_AND_OUT_0_N   A<0> @BASEBOARD_FAB2_LIB.BASEBOARD_FAB2(SCH_1):FM_FAST_PROCHOT_AND_OUT_0_N

TTL1G126_A_SOT-74HC1G126,IC,A7B  I20  U1R2
   1 FM_FAST_PROCHOT_EN     OE @BASEBOARD_FAB2_LIB.BASEBOARD_FAB2(SCH_1):FM_FAST_PROCHOT_EN
   2 FM_FAST_PROCHOT_THROTTLE_DLY_N      A @BASEBOARD_FAB2_LIB.BASEBOARD_FAB2(SCH_1):FM_FAST_PROCHOT_THROTTLE_DLY_N
   4 FM_FAST_PROCHOT_THROTTLE_DLY_BU      Y @BASEBOARD_FAB2_LIB.BASEBOARD_FAB2(SCH_1):FM_FAST_PROCHOT_THROTTLE_DLY_BUF_N

CAP_A_0402V-0.1UF,16V,10%,X7R,A  I30  C1R27
   1 P3V3_STBY      A @BASEBOARD_FAB2_LIB.BASEBOARD_FAB2(SCH_1):P3V3_STBY
   2    GND      B @BASEBOARD_FAB2_LIB.BASEBOARD_FAB2(SCH_1):GND

CAP_A_0402V-0.1UF,16V,10%,X7R,A  I33  C8D2
   1 P3V3_STBY      A @BASEBOARD_FAB2_LIB.BASEBOARD_FAB2(SCH_1):P3V3_STBY
   2    GND      B @BASEBOARD_FAB2_LIB.BASEBOARD_FAB2(SCH_1):GND

TTL1G126_A_SOT-74HC1G126,IC,A7B  I38  U8D5
   1 FM_PMBUS_ALERT_BUF_EN     OE @BASEBOARD_FAB2_LIB.BASEBOARD_FAB2(SCH_1):FM_PMBUS_ALERT_BUF_EN
   2 IRQ_SML1_PMBUS_ALERT_N      A @BASEBOARD_FAB2_LIB.BASEBOARD_FAB2(SCH_1):IRQ_SML1_PMBUS_ALERT_N
   4 IRQ_SML1_PMBUS_ALERT_BUF_N      Y @BASEBOARD_FAB2_LIB.BASEBOARD_FAB2(SCH_1):IRQ_SML1_PMBUS_ALERT_BUF_N

CAP_A_0402V-0.1UF,16V,10%,X7R,A  I40  C8E2
   1 P3V3_STBY      A @BASEBOARD_FAB2_LIB.BASEBOARD_FAB2(SCH_1):P3V3_STBY
   2    GND      B @BASEBOARD_FAB2_LIB.BASEBOARD_FAB2(SCH_1):GND

CAP_0402LF-470PF,50V,10%,EMPTYA  I42  C8D3
   1 IRQ_SML1_PMBUS_ALERT_N      A @BASEBOARD_FAB2_LIB.BASEBOARD_FAB2(SCH_1):IRQ_SML1_PMBUS_ALERT_N
   2    GND      B @BASEBOARD_FAB2_LIB.BASEBOARD_FAB2(SCH_1):GND

TTL1G07_A_SOP-74LVC1G07,IC,C88B  I46  U1R1
   2 FM_FAST_PROCHOT_THROTTLE_DLY_BU      A @BASEBOARD_FAB2_LIB.BASEBOARD_FAB2(SCH_1):FM_FAST_PROCHOT_THROTTLE_DLY_BUF_N
   4 FM_THROTTLE_R1_N      Y @BASEBOARD_FAB2_LIB.BASEBOARD_FAB2(SCH_1):FM_THROTTLE_R1_N

CAP_A_0402V-0.1UF,16V,10%,X7R,A  I49  C1R28
   1 P3V3_STBY      A @BASEBOARD_FAB2_LIB.BASEBOARD_FAB2(SCH_1):P3V3_STBY
   2    GND      B @BASEBOARD_FAB2_LIB.BASEBOARD_FAB2(SCH_1):GND

RES_0402-0.0,5%,1/16W,CHIP,G21A  I51  R1R8
   1 FM_THROTTLE_R1_N      A @BASEBOARD_FAB2_LIB.BASEBOARD_FAB2(SCH_1):FM_THROTTLE_R1_N
   2 FM_THROTTLE_N      B @BASEBOARD_FAB2_LIB.BASEBOARD_FAB2(SCH_1):FM_THROTTLE_N

RES_0402-4.75K,1%,1/16W,CHIP,GA  I54  R2T3
   1 P3V3_STBY      A @BASEBOARD_FAB2_LIB.BASEBOARD_FAB2(SCH_1):P3V3_STBY
   2 FM_FAST_PROCHOT_EN_N      B @BASEBOARD_FAB2_LIB.BASEBOARD_FAB2(SCH_1):FM_FAST_PROCHOT_EN_N

RES_0402-4.75K,1%,1/16W,CHIP,GA  I56  R2P5
   1 P3V3_STBY      A @BASEBOARD_FAB2_LIB.BASEBOARD_FAB2(SCH_1):P3V3_STBY
   2 FM_PMBUS_ALERT_BUF_EN      B @BASEBOARD_FAB2_LIB.BASEBOARD_FAB2(SCH_1):FM_PMBUS_ALERT_BUF_EN

FET_N_SOT23LF-2N7002,FET,C7925A  I58  Q2P1
   1 FM_PMBUS_ALERT_BUF_EN_N   GATE @BASEBOARD_FAB2_LIB.BASEBOARD_FAB2(SCH_1):FM_PMBUS_ALERT_BUF_EN_N
   2    GND    SRC @BASEBOARD_FAB2_LIB.BASEBOARD_FAB2(SCH_1):GND
   3 FM_PMBUS_ALERT_BUF_EN    DRN @BASEBOARD_FAB2_LIB.BASEBOARD_FAB2(SCH_1):FM_PMBUS_ALERT_BUF_EN

RES_0402-4.75K,1%,1/16W,CHIP,GA  I61  R2P13
   1 P3V3_STBY      A @BASEBOARD_FAB2_LIB.BASEBOARD_FAB2(SCH_1):P3V3_STBY
   2 FM_PMBUS_ALERT_BUF_EN_N      B @BASEBOARD_FAB2_LIB.BASEBOARD_FAB2(SCH_1):FM_PMBUS_ALERT_BUF_EN_N

RES_0402-1.00K,1%,1/16W,EMPTY,A  I63  R2P11
   1 FM_PMBUS_ALERT_BUF_EN_N      A @BASEBOARD_FAB2_LIB.BASEBOARD_FAB2(SCH_1):FM_PMBUS_ALERT_BUF_EN_N
   2    GND      B @BASEBOARD_FAB2_LIB.BASEBOARD_FAB2(SCH_1):GND

RES_0402-4.75K,1%,1/16W,CHIP,GA  I65  R9F3
   1 P3V3_STBY      A @BASEBOARD_FAB2_LIB.BASEBOARD_FAB2(SCH_1):P3V3_STBY
   2 FM_FAST_PROCHOT_EN      B @BASEBOARD_FAB2_LIB.BASEBOARD_FAB2(SCH_1):FM_FAST_PROCHOT_EN

FET_N_SOT23LF-2N7002,FET,C7925A  I67  Q8F2
   1 FM_FAST_PROCHOT_EN_N   GATE @BASEBOARD_FAB2_LIB.BASEBOARD_FAB2(SCH_1):FM_FAST_PROCHOT_EN_N
   2    GND    SRC @BASEBOARD_FAB2_LIB.BASEBOARD_FAB2(SCH_1):GND
   3 FM_FAST_PROCHOT_EN    DRN @BASEBOARD_FAB2_LIB.BASEBOARD_FAB2(SCH_1):FM_FAST_PROCHOT_EN

RES_0402-4.75K,1%,1/16W,CHIP,GA  I71  R8D26
   1 P3V3_STBY      A @BASEBOARD_FAB2_LIB.BASEBOARD_FAB2(SCH_1):P3V3_STBY
   2 IRQ_SML1_PMBUS_ALERT_BUF_N      B @BASEBOARD_FAB2_LIB.BASEBOARD_FAB2(SCH_1):IRQ_SML1_PMBUS_ALERT_BUF_N

RES_0402-4.75K,1%,1/16W,CHIP,GA  I73  R1R5
   1 P3V3_STBY      A @BASEBOARD_FAB2_LIB.BASEBOARD_FAB2(SCH_1):P3V3_STBY
   2 FM_FAST_PROCHOT_THROTTLE_DLY_BU      B @BASEBOARD_FAB2_LIB.BASEBOARD_FAB2(SCH_1):FM_FAST_PROCHOT_THROTTLE_DLY_BUF_N

RES_0402-33.2,1%,1/16W,CHIP,G2A  I74  R2P4
   1 IRQ_FORCE_NM_THROTTLE_R_N      A @BASEBOARD_FAB2_LIB.BASEBOARD_FAB2(SCH_1):IRQ_FORCE_NM_THROTTLE_R_N
   2 IRQ_FORCE_NM_THROTTLE_N      B @BASEBOARD_FAB2_LIB.BASEBOARD_FAB2(SCH_1):IRQ_FORCE_NM_THROTTLE_N

RES_0402-4.75K,1%,1/16W,CHIP,GA  I75  R2P8
   1 P3V3_STBY      A @BASEBOARD_FAB2_LIB.BASEBOARD_FAB2(SCH_1):P3V3_STBY
   2 IRQ_SML1_PMBUS_ALERT_N      B @BASEBOARD_FAB2_LIB.BASEBOARD_FAB2(SCH_1):IRQ_SML1_PMBUS_ALERT_N


DRAWING: @BASEBOARD_FAB2_LIB.BASEBOARD_FAB2(SCH_1):PAGE172 

CAP_A_0402V-0.01UF,25V,10%,X7RA  I5  C2L49
   1 SATA6G_S1_RX_C_DP      A @BASEBOARD_FAB2_LIB.BASEBOARD_FAB2(SCH_1):SATA6G_S1_RX_C_DP
   2 SATA6G_S1_RX_DP      B @BASEBOARD_FAB2_LIB.BASEBOARD_FAB2(SCH_1):SATA6G_S1_RX_DP

CAP_A_0402V-0.01UF,25V,10%,X7RA  I6  C2L52
   1 SATA6G_S1_TX_C_DP      A @BASEBOARD_FAB2_LIB.BASEBOARD_FAB2(SCH_1):SATA6G_S1_TX_C_DP
   2 SATA6G_S1_TX_DP      B @BASEBOARD_FAB2_LIB.BASEBOARD_FAB2(SCH_1):SATA6G_S1_TX_DP

CAP_A_0402V-0.01UF,25V,10%,X7RA  I7  C2L50
   1 SATA6G_S1_RX_C_DN      A @BASEBOARD_FAB2_LIB.BASEBOARD_FAB2(SCH_1):SATA6G_S1_RX_C_DN
   2 SATA6G_S1_RX_DN      B @BASEBOARD_FAB2_LIB.BASEBOARD_FAB2(SCH_1):SATA6G_S1_RX_DN

CAP_A_0402V-0.01UF,25V,10%,X7RA  I8  C2L51
   1 SATA6G_S1_TX_C_DN      A @BASEBOARD_FAB2_LIB.BASEBOARD_FAB2(SCH_1):SATA6G_S1_TX_C_DN
   2 SATA6G_S1_TX_DN      B @BASEBOARD_FAB2_LIB.BASEBOARD_FAB2(SCH_1):SATA6G_S1_TX_DN

CAP_0805-10UF,16V,10%,X6S,C953A  I36  C9B2
   1 P12V_HDD_SATA      A @BASEBOARD_FAB2_LIB.BASEBOARD_FAB2(SCH_1):P12V_HDD_SATA
   2    GND      B @BASEBOARD_FAB2_LIB.BASEBOARD_FAB2(SCH_1):GND

CAP_0805-10UF,16V,10%,X6S,C953A  I39  C9B1
   1 P5V_HDD_SATA      A @BASEBOARD_FAB2_LIB.BASEBOARD_FAB2(SCH_1):P5V_HDD_SATA
   2    GND      B @BASEBOARD_FAB2_LIB.BASEBOARD_FAB2(SCH_1):GND

FUSE_SM-IC,C94311-016  I66  F9B1
   1   P12V   A<0> @BASEBOARD_FAB2_LIB.BASEBOARD_FAB2(SCH_1):P12V
   2 P12V_HDD_SATA   B<0> @BASEBOARD_FAB2_LIB.BASEBOARD_FAB2(SCH_1):P12V_HDD_SATA

SKT-SATA7P-6P-165-GP-U1_SOCKETA  I67  J2W1
  S1    GND     S1 @BASEBOARD_FAB2_LIB.BASEBOARD_FAB2(SCH_1):GND
  S2 SATA6G_S1_TX_C_DP     S2 @BASEBOARD_FAB2_LIB.BASEBOARD_FAB2(SCH_1):SATA6G_S1_TX_C_DP
  S3 SATA6G_S1_TX_C_DN     S3 @BASEBOARD_FAB2_LIB.BASEBOARD_FAB2(SCH_1):SATA6G_S1_TX_C_DN
  S4    GND     S4 @BASEBOARD_FAB2_LIB.BASEBOARD_FAB2(SCH_1):GND
  S5 SATA6G_S1_RX_C_DN     S5 @BASEBOARD_FAB2_LIB.BASEBOARD_FAB2(SCH_1):SATA6G_S1_RX_C_DN
  S6 SATA6G_S1_RX_C_DP     S6 @BASEBOARD_FAB2_LIB.BASEBOARD_FAB2(SCH_1):SATA6G_S1_RX_C_DP
  S7    GND     S7 @BASEBOARD_FAB2_LIB.BASEBOARD_FAB2(SCH_1):GND
  P1 P5V_HDD_SATA     P1 @BASEBOARD_FAB2_LIB.BASEBOARD_FAB2(SCH_1):P5V_HDD_SATA
  P2 P5V_HDD_SATA     P2 @BASEBOARD_FAB2_LIB.BASEBOARD_FAB2(SCH_1):P5V_HDD_SATA
  P3    GND     P3 @BASEBOARD_FAB2_LIB.BASEBOARD_FAB2(SCH_1):GND
  P4    GND     P4 @BASEBOARD_FAB2_LIB.BASEBOARD_FAB2(SCH_1):GND
  P5 P12V_HDD_SATA     P5 @BASEBOARD_FAB2_LIB.BASEBOARD_FAB2(SCH_1):P12V_HDD_SATA
  P6 P12V_HDD_SATA     P6 @BASEBOARD_FAB2_LIB.BASEBOARD_FAB2(SCH_1):P12V_HDD_SATA
 NP1     NC    NP1     NC
 NP2     NC    NP2     NC
  H1    GND     H1 @BASEBOARD_FAB2_LIB.BASEBOARD_FAB2(SCH_1):GND
  H2    GND     H2 @BASEBOARD_FAB2_LIB.BASEBOARD_FAB2(SCH_1):GND

SKT-SATA7P-6P-165-GP-U1_SOCKETA  I68  J2W2
  S1    GND     S1 @BASEBOARD_FAB2_LIB.BASEBOARD_FAB2(SCH_1):GND
  S2 SATA6G_S1_TX_C_DP     S2 @BASEBOARD_FAB2_LIB.BASEBOARD_FAB2(SCH_1):SATA6G_S1_TX_C_DP
  S3 SATA6G_S1_TX_C_DN     S3 @BASEBOARD_FAB2_LIB.BASEBOARD_FAB2(SCH_1):SATA6G_S1_TX_C_DN
  S4    GND     S4 @BASEBOARD_FAB2_LIB.BASEBOARD_FAB2(SCH_1):GND
  S5 SATA6G_S1_RX_C_DN     S5 @BASEBOARD_FAB2_LIB.BASEBOARD_FAB2(SCH_1):SATA6G_S1_RX_C_DN
  S6 SATA6G_S1_RX_C_DP     S6 @BASEBOARD_FAB2_LIB.BASEBOARD_FAB2(SCH_1):SATA6G_S1_RX_C_DP
  S7    GND     S7 @BASEBOARD_FAB2_LIB.BASEBOARD_FAB2(SCH_1):GND
  P1 P5V_HDD_SATA     P1 @BASEBOARD_FAB2_LIB.BASEBOARD_FAB2(SCH_1):P5V_HDD_SATA
  P2 P5V_HDD_SATA     P2 @BASEBOARD_FAB2_LIB.BASEBOARD_FAB2(SCH_1):P5V_HDD_SATA
  P3    GND     P3 @BASEBOARD_FAB2_LIB.BASEBOARD_FAB2(SCH_1):GND
  P4    GND     P4 @BASEBOARD_FAB2_LIB.BASEBOARD_FAB2(SCH_1):GND
  P5 P12V_HDD_SATA     P5 @BASEBOARD_FAB2_LIB.BASEBOARD_FAB2(SCH_1):P12V_HDD_SATA
  P6 P12V_HDD_SATA     P6 @BASEBOARD_FAB2_LIB.BASEBOARD_FAB2(SCH_1):P12V_HDD_SATA
 NP1     NC    NP1     NC
 NP2     NC    NP2     NC
  H1    GND     H1 @BASEBOARD_FAB2_LIB.BASEBOARD_FAB2(SCH_1):GND
  H2    GND     H2 @BASEBOARD_FAB2_LIB.BASEBOARD_FAB2(SCH_1):GND

FUSE-3A75V-GP_DISCRET-G5-FUSE-A  I71  F8B1
   1 P5V_HDD_SATA      1 @BASEBOARD_FAB2_LIB.BASEBOARD_FAB2(SCH_1):P5V_HDD_SATA
   2    P5V      2 @BASEBOARD_FAB2_LIB.BASEBOARD_FAB2(SCH_1):P5V


DRAWING: @BASEBOARD_FAB2_LIB.BASEBOARD_FAB2(SCH_1):PAGE173 

CONN72_G97614002_A_CP-CONN,G97A  I163  J8A1
 1A3    GND GND<23> @BASEBOARD_FAB2_LIB.BASEBOARD_FAB2(SCH_1):GND
 1A6    GND GND<22> @BASEBOARD_FAB2_LIB.BASEBOARD_FAB2(SCH_1):GND
 1A9    GND GND<21> @BASEBOARD_FAB2_LIB.BASEBOARD_FAB2(SCH_1):GND
 1B3    GND GND<20> @BASEBOARD_FAB2_LIB.BASEBOARD_FAB2(SCH_1):GND
 1B6    GND GND<19> @BASEBOARD_FAB2_LIB.BASEBOARD_FAB2(SCH_1):GND
 1B9    GND GND<18> @BASEBOARD_FAB2_LIB.BASEBOARD_FAB2(SCH_1):GND
 1C3    GND GND<17> @BASEBOARD_FAB2_LIB.BASEBOARD_FAB2(SCH_1):GND
 1C6    GND GND<16> @BASEBOARD_FAB2_LIB.BASEBOARD_FAB2(SCH_1):GND
 1C9    GND GND<15> @BASEBOARD_FAB2_LIB.BASEBOARD_FAB2(SCH_1):GND
 1D3    GND GND<14> @BASEBOARD_FAB2_LIB.BASEBOARD_FAB2(SCH_1):GND
 1D6    GND GND<13> @BASEBOARD_FAB2_LIB.BASEBOARD_FAB2(SCH_1):GND
 1D9    GND GND<12> @BASEBOARD_FAB2_LIB.BASEBOARD_FAB2(SCH_1):GND
 2A3    GND GND<11> @BASEBOARD_FAB2_LIB.BASEBOARD_FAB2(SCH_1):GND
 2A6    GND GND<10> @BASEBOARD_FAB2_LIB.BASEBOARD_FAB2(SCH_1):GND
 2A9    GND GND<9> @BASEBOARD_FAB2_LIB.BASEBOARD_FAB2(SCH_1):GND
 2B3    GND GND<8> @BASEBOARD_FAB2_LIB.BASEBOARD_FAB2(SCH_1):GND
 2B6    GND GND<7> @BASEBOARD_FAB2_LIB.BASEBOARD_FAB2(SCH_1):GND
 2B9    GND GND<6> @BASEBOARD_FAB2_LIB.BASEBOARD_FAB2(SCH_1):GND
 2C3    GND GND<5> @BASEBOARD_FAB2_LIB.BASEBOARD_FAB2(SCH_1):GND
 2C6    GND GND<4> @BASEBOARD_FAB2_LIB.BASEBOARD_FAB2(SCH_1):GND
 2C9    GND GND<3> @BASEBOARD_FAB2_LIB.BASEBOARD_FAB2(SCH_1):GND
 2D3    GND GND<2> @BASEBOARD_FAB2_LIB.BASEBOARD_FAB2(SCH_1):GND
 2D6    GND GND<1> @BASEBOARD_FAB2_LIB.BASEBOARD_FAB2(SCH_1):GND
 2D9    GND GND<0> @BASEBOARD_FAB2_LIB.BASEBOARD_FAB2(SCH_1):GND
 1B5 SATA6G_P0_RX_C_DN RXA0_DN @BASEBOARD_FAB2_LIB.BASEBOARD_FAB2(SCH_1):SATA6G_P0_RX_C_DN
 1B4 SATA6G_P0_RX_C_DP RXA0_DP @BASEBOARD_FAB2_LIB.BASEBOARD_FAB2(SCH_1):SATA6G_P0_RX_C_DP
 1A5 SATA6G_P1_RX_C_DN RXA1_DN @BASEBOARD_FAB2_LIB.BASEBOARD_FAB2(SCH_1):SATA6G_P1_RX_C_DN
 1A4 SATA6G_P1_RX_C_DP RXA1_DP @BASEBOARD_FAB2_LIB.BASEBOARD_FAB2(SCH_1):SATA6G_P1_RX_C_DP
 1B8 SATA6G_P2_RX_C_DN RXA2_DN @BASEBOARD_FAB2_LIB.BASEBOARD_FAB2(SCH_1):SATA6G_P2_RX_C_DN
 1B7 SATA6G_P2_RX_C_DP RXA2_DP @BASEBOARD_FAB2_LIB.BASEBOARD_FAB2(SCH_1):SATA6G_P2_RX_C_DP
 1A8 SATA6G_P3_RX_C_DN RXA3_DN @BASEBOARD_FAB2_LIB.BASEBOARD_FAB2(SCH_1):SATA6G_P3_RX_C_DN
 1A7 SATA6G_P3_RX_C_DP RXA3_DP @BASEBOARD_FAB2_LIB.BASEBOARD_FAB2(SCH_1):SATA6G_P3_RX_C_DP
 2B5 SATA6G_P4_RX_C_DN RXB0_DN @BASEBOARD_FAB2_LIB.BASEBOARD_FAB2(SCH_1):SATA6G_P4_RX_C_DN
 2B4 SATA6G_P4_RX_C_DP RXB0_DP @BASEBOARD_FAB2_LIB.BASEBOARD_FAB2(SCH_1):SATA6G_P4_RX_C_DP
 2A5 SATA6G_P5_RX_C_DN RXB1_DN @BASEBOARD_FAB2_LIB.BASEBOARD_FAB2(SCH_1):SATA6G_P5_RX_C_DN
 2A4 SATA6G_P5_RX_C_DP RXB1_DP @BASEBOARD_FAB2_LIB.BASEBOARD_FAB2(SCH_1):SATA6G_P5_RX_C_DP
 2B8 SATA6G_P6_RX_C_DN RXB2_DN @BASEBOARD_FAB2_LIB.BASEBOARD_FAB2(SCH_1):SATA6G_P6_RX_C_DN
 2B7 SATA6G_P6_RX_C_DP RXB2_DP @BASEBOARD_FAB2_LIB.BASEBOARD_FAB2(SCH_1):SATA6G_P6_RX_C_DP
 2A8 SATA6G_P7_RX_C_DN RXB3_DN @BASEBOARD_FAB2_LIB.BASEBOARD_FAB2(SCH_1):SATA6G_P7_RX_C_DN
 2A7 SATA6G_P7_RX_C_DP RXB3_DP @BASEBOARD_FAB2_LIB.BASEBOARD_FAB2(SCH_1):SATA6G_P7_RX_C_DP
 1A2 SGPIO_PCH_SATA_CLOCK_R SIDEBANDA_0 @BASEBOARD_FAB2_LIB.BASEBOARD_FAB2(SCH_1):SGPIO_PCH_SATA_CLOCK_R
 1B2 SGPIO_PCH_SATA_LOAD_R SIDEBANDA_1 @BASEBOARD_FAB2_LIB.BASEBOARD_FAB2(SCH_1):SGPIO_PCH_SATA_LOAD_R
 1C2    GND SIDEBANDA_2 @BASEBOARD_FAB2_LIB.BASEBOARD_FAB2(SCH_1):GND
 1B1    GND SIDEBANDA_3 @BASEBOARD_FAB2_LIB.BASEBOARD_FAB2(SCH_1):GND
 1C1 SGPIO_PCH_SATA_DOUT0_R SIDEBANDA_4 @BASEBOARD_FAB2_LIB.BASEBOARD_FAB2(SCH_1):SGPIO_PCH_SATA_DOUT0_R
 1D1 PU_DATAIN1_SATA_0_R SIDEBANDA_5 @BASEBOARD_FAB2_LIB.BASEBOARD_FAB2(SCH_1):PU_DATAIN1_SATA_0_R
 1D2 PD_SATA0_CONTROLLER_TYPE_R SIDEBANDA_6 @BASEBOARD_FAB2_LIB.BASEBOARD_FAB2(SCH_1):PD_SATA0_CONTROLLER_TYPE_R
 1A1 TP_FM_QAT_CBL_PRSNT0_R_N SIDEBANDA_7 @BASEBOARD_FAB2_LIB.BASEBOARD_FAB2(SCH_1):TP_FM_QAT_CBL_PRSNT0_R_N
 2A2 TP_SGPIO_SATA_CLOCK1_R SIDEBANDB_0 @BASEBOARD_FAB2_LIB.BASEBOARD_FAB2(SCH_1):TP_SGPIO_SATA_CLOCK1_R
 2B2 TP_SGPIO_SATA_LOAD1_R SIDEBANDB_1 @BASEBOARD_FAB2_LIB.BASEBOARD_FAB2(SCH_1):TP_SGPIO_SATA_LOAD1_R
 2C2    GND SIDEBANDB_2 @BASEBOARD_FAB2_LIB.BASEBOARD_FAB2(SCH_1):GND
 2B1    GND SIDEBANDB_3 @BASEBOARD_FAB2_LIB.BASEBOARD_FAB2(SCH_1):GND
 2C1 TP_SGPIO_SATA_DATA1_R SIDEBANDB_4 @BASEBOARD_FAB2_LIB.BASEBOARD_FAB2(SCH_1):TP_SGPIO_SATA_DATA1_R
 2D1 PU_DATAIN1_SATA_1_R SIDEBANDB_5 @BASEBOARD_FAB2_LIB.BASEBOARD_FAB2(SCH_1):PU_DATAIN1_SATA_1_R
 2D2 PD_SATA1_CONTROLLER_TYPE_R SIDEBANDB_6 @BASEBOARD_FAB2_LIB.BASEBOARD_FAB2(SCH_1):PD_SATA1_CONTROLLER_TYPE_R
 2A1 TP_FM_QAT_CBL_PRSNT1_N_R SIDEBANDB_7 @BASEBOARD_FAB2_LIB.BASEBOARD_FAB2(SCH_1):TP_FM_QAT_CBL_PRSNT1_N_R
 1D5 SATA6G_P0_TX_C_DN TXA0_DN @BASEBOARD_FAB2_LIB.BASEBOARD_FAB2(SCH_1):SATA6G_P0_TX_C_DN
 1D4 SATA6G_P0_TX_C_DP TXA0_DP @BASEBOARD_FAB2_LIB.BASEBOARD_FAB2(SCH_1):SATA6G_P0_TX_C_DP
 1C5 SATA6G_P1_TX_C_DN TXA1_DN @BASEBOARD_FAB2_LIB.BASEBOARD_FAB2(SCH_1):SATA6G_P1_TX_C_DN
 1C4 SATA6G_P1_TX_C_DP TXA1_DP @BASEBOARD_FAB2_LIB.BASEBOARD_FAB2(SCH_1):SATA6G_P1_TX_C_DP
 1D8 SATA6G_P2_TX_C_DN TXA2_DN @BASEBOARD_FAB2_LIB.BASEBOARD_FAB2(SCH_1):SATA6G_P2_TX_C_DN
 1D7 SATA6G_P2_TX_C_DP TXA2_DP @BASEBOARD_FAB2_LIB.BASEBOARD_FAB2(SCH_1):SATA6G_P2_TX_C_DP
 1C8 SATA6G_P3_TX_C_DN TXA3_DN @BASEBOARD_FAB2_LIB.BASEBOARD_FAB2(SCH_1):SATA6G_P3_TX_C_DN
 1C7 SATA6G_P3_TX_C_DP TXA3_DP @BASEBOARD_FAB2_LIB.BASEBOARD_FAB2(SCH_1):SATA6G_P3_TX_C_DP
 2D5 SATA6G_P4_TX_C_DN TXB0_DN @BASEBOARD_FAB2_LIB.BASEBOARD_FAB2(SCH_1):SATA6G_P4_TX_C_DN
 2D4 SATA6G_P4_TX_C_DP TXB0_DP @BASEBOARD_FAB2_LIB.BASEBOARD_FAB2(SCH_1):SATA6G_P4_TX_C_DP
 2C5 SATA6G_P5_TX_C_DN TXB1_DN @BASEBOARD_FAB2_LIB.BASEBOARD_FAB2(SCH_1):SATA6G_P5_TX_C_DN
 2C4 SATA6G_P5_TX_C_DP TXB1_DP @BASEBOARD_FAB2_LIB.BASEBOARD_FAB2(SCH_1):SATA6G_P5_TX_C_DP
 2D8 SATA6G_P6_TX_C_DN TXB2_DN @BASEBOARD_FAB2_LIB.BASEBOARD_FAB2(SCH_1):SATA6G_P6_TX_C_DN
 2D7 SATA6G_P6_TX_C_DP TXB2_DP @BASEBOARD_FAB2_LIB.BASEBOARD_FAB2(SCH_1):SATA6G_P6_TX_C_DP
 2C8 SATA6G_P7_TX_C_DN TXB3_DN @BASEBOARD_FAB2_LIB.BASEBOARD_FAB2(SCH_1):SATA6G_P7_TX_C_DN
 2C7 SATA6G_P7_TX_C_DP TXB3_DP @BASEBOARD_FAB2_LIB.BASEBOARD_FAB2(SCH_1):SATA6G_P7_TX_C_DP

CAP_A_0402V-0.01UF,25V,10%,X7RA  I165  C2L13
   1 SATA6G_PCH_PCIE_UP_SATA_RXN<2>      A @BASEBOARD_FAB2_LIB.BASEBOARD_FAB2(SCH_1):SATA6G_PCH_PCIE_UP_SATA_RXN(2)
   2 SATA6G_P2_RX_C_DN      B @BASEBOARD_FAB2_LIB.BASEBOARD_FAB2(SCH_1):SATA6G_P2_RX_C_DN

CAP_A_0402V-0.01UF,25V,10%,X7RA  I166  C2L6
   1 SATA6G_PCH_PCIE_UP_SATA_RXN<1>      A @BASEBOARD_FAB2_LIB.BASEBOARD_FAB2(SCH_1):SATA6G_PCH_PCIE_UP_SATA_RXN(1)
   2 SATA6G_P1_RX_C_DN      B @BASEBOARD_FAB2_LIB.BASEBOARD_FAB2(SCH_1):SATA6G_P1_RX_C_DN

CAP_A_0402V-0.01UF,25V,10%,X7RA  I172  C2L19
   1 SATA6G_PCH_PCIE_UP_SATA_RXP<0>      A @BASEBOARD_FAB2_LIB.BASEBOARD_FAB2(SCH_1):SATA6G_PCH_PCIE_UP_SATA_RXP(0)
   2 SATA6G_P0_RX_C_DP      B @BASEBOARD_FAB2_LIB.BASEBOARD_FAB2(SCH_1):SATA6G_P0_RX_C_DP

CAP_A_0402V-0.01UF,25V,10%,X7RA  I173  C2L10
   1 SATA6G_PCH_PCIE_UP_SATA_RXP<1>      A @BASEBOARD_FAB2_LIB.BASEBOARD_FAB2(SCH_1):SATA6G_PCH_PCIE_UP_SATA_RXP(1)
   2 SATA6G_P1_RX_C_DP      B @BASEBOARD_FAB2_LIB.BASEBOARD_FAB2(SCH_1):SATA6G_P1_RX_C_DP

CAP_A_0402V-0.01UF,25V,10%,X7RA  I174  C2L17
   1 SATA6G_PCH_PCIE_UP_SATA_RXN<0>      A @BASEBOARD_FAB2_LIB.BASEBOARD_FAB2(SCH_1):SATA6G_PCH_PCIE_UP_SATA_RXN(0)
   2 SATA6G_P0_RX_C_DN      B @BASEBOARD_FAB2_LIB.BASEBOARD_FAB2(SCH_1):SATA6G_P0_RX_C_DN

CAP_A_0402V-0.01UF,25V,10%,X7RA  I191  C2L15
   1 SATA6G_PCH_PCIE_UP_SATA_RXP<2>      A @BASEBOARD_FAB2_LIB.BASEBOARD_FAB2(SCH_1):SATA6G_PCH_PCIE_UP_SATA_RXP(2)
   2 SATA6G_P2_RX_C_DP      B @BASEBOARD_FAB2_LIB.BASEBOARD_FAB2(SCH_1):SATA6G_P2_RX_C_DP

CAP_A_0402V-0.01UF,25V,10%,X7RA  I192  C2L4
   1 SATA6G_PCH_PCIE_UP_SATA_RXP<3>      A @BASEBOARD_FAB2_LIB.BASEBOARD_FAB2(SCH_1):SATA6G_PCH_PCIE_UP_SATA_RXP(3)
   2 SATA6G_P3_RX_C_DP      B @BASEBOARD_FAB2_LIB.BASEBOARD_FAB2(SCH_1):SATA6G_P3_RX_C_DP

CAP_A_0402V-0.01UF,25V,10%,X7RA  I194  C2L3
   1 SATA6G_PCH_PCIE_UP_SATA_RXN<3>      A @BASEBOARD_FAB2_LIB.BASEBOARD_FAB2(SCH_1):SATA6G_PCH_PCIE_UP_SATA_RXN(3)
   2 SATA6G_P3_RX_C_DN      B @BASEBOARD_FAB2_LIB.BASEBOARD_FAB2(SCH_1):SATA6G_P3_RX_C_DN

CAP_A_0402V-0.01UF,25V,10%,X7RA  I195  C2L20
   1 SATA6G_PCH_PCIE_UP_SATA_RXP<4>      A @BASEBOARD_FAB2_LIB.BASEBOARD_FAB2(SCH_1):SATA6G_PCH_PCIE_UP_SATA_RXP(4)
   2 SATA6G_P4_RX_C_DP      B @BASEBOARD_FAB2_LIB.BASEBOARD_FAB2(SCH_1):SATA6G_P4_RX_C_DP

CAP_A_0402V-0.01UF,25V,10%,X7RA  I196  C2L12
   1 SATA6G_PCH_PCIE_UP_SATA_RXP<5>      A @BASEBOARD_FAB2_LIB.BASEBOARD_FAB2(SCH_1):SATA6G_PCH_PCIE_UP_SATA_RXP(5)
   2 SATA6G_P5_RX_C_DP      B @BASEBOARD_FAB2_LIB.BASEBOARD_FAB2(SCH_1):SATA6G_P5_RX_C_DP

CAP_A_0402V-0.01UF,25V,10%,X7RA  I197  C2L18
   1 SATA6G_PCH_PCIE_UP_SATA_RXN<4>      A @BASEBOARD_FAB2_LIB.BASEBOARD_FAB2(SCH_1):SATA6G_PCH_PCIE_UP_SATA_RXN(4)
   2 SATA6G_P4_RX_C_DN      B @BASEBOARD_FAB2_LIB.BASEBOARD_FAB2(SCH_1):SATA6G_P4_RX_C_DN

CAP_A_0402V-0.01UF,25V,10%,X7RA  I205  C2L16
   1 SATA6G_PCH_PCIE_UP_SATA_RXP<6>      A @BASEBOARD_FAB2_LIB.BASEBOARD_FAB2(SCH_1):SATA6G_PCH_PCIE_UP_SATA_RXP(6)
   2 SATA6G_P6_RX_C_DP      B @BASEBOARD_FAB2_LIB.BASEBOARD_FAB2(SCH_1):SATA6G_P6_RX_C_DP

CAP_A_0402V-0.01UF,25V,10%,X7RA  I206  C2L7
   1 SATA6G_PCH_PCIE_UP_SATA_RXP<7>      A @BASEBOARD_FAB2_LIB.BASEBOARD_FAB2(SCH_1):SATA6G_PCH_PCIE_UP_SATA_RXP(7)
   2 SATA6G_P7_RX_C_DP      B @BASEBOARD_FAB2_LIB.BASEBOARD_FAB2(SCH_1):SATA6G_P7_RX_C_DP

CAP_A_0402V-0.01UF,25V,10%,X7RA  I207  C2L9
   1 SATA6G_PCH_PCIE_UP_SATA_RXN<5>      A @BASEBOARD_FAB2_LIB.BASEBOARD_FAB2(SCH_1):SATA6G_PCH_PCIE_UP_SATA_RXN(5)
   2 SATA6G_P5_RX_C_DN      B @BASEBOARD_FAB2_LIB.BASEBOARD_FAB2(SCH_1):SATA6G_P5_RX_C_DN

CAP_A_0402V-0.01UF,25V,10%,X7RA  I208  C2L14
   1 SATA6G_PCH_PCIE_UP_SATA_RXN<6>      A @BASEBOARD_FAB2_LIB.BASEBOARD_FAB2(SCH_1):SATA6G_PCH_PCIE_UP_SATA_RXN(6)
   2 SATA6G_P6_RX_C_DN      B @BASEBOARD_FAB2_LIB.BASEBOARD_FAB2(SCH_1):SATA6G_P6_RX_C_DN

CAP_A_0402V-0.01UF,25V,10%,X7RA  I209  C2L5
   1 SATA6G_PCH_PCIE_UP_SATA_RXN<7>      A @BASEBOARD_FAB2_LIB.BASEBOARD_FAB2(SCH_1):SATA6G_PCH_PCIE_UP_SATA_RXN(7)
   2 SATA6G_P7_RX_C_DN      B @BASEBOARD_FAB2_LIB.BASEBOARD_FAB2(SCH_1):SATA6G_P7_RX_C_DN

CAP_A_0402V-0.01UF,25V,10%,X7RA  I220  C2L40
   1 SATA6G_P0_TX_C_DN      A @BASEBOARD_FAB2_LIB.BASEBOARD_FAB2(SCH_1):SATA6G_P0_TX_C_DN
   2 SATA6G_PCH_PCIE_UP_SATA_TXN<0>      B @BASEBOARD_FAB2_LIB.BASEBOARD_FAB2(SCH_1):SATA6G_PCH_PCIE_UP_SATA_TXN(0)

CAP_A_0402V-0.01UF,25V,10%,X7RA  I221  C2L39
   1 SATA6G_P0_TX_C_DP      A @BASEBOARD_FAB2_LIB.BASEBOARD_FAB2(SCH_1):SATA6G_P0_TX_C_DP
   2 SATA6G_PCH_PCIE_UP_SATA_TXP<0>      B @BASEBOARD_FAB2_LIB.BASEBOARD_FAB2(SCH_1):SATA6G_PCH_PCIE_UP_SATA_TXP(0)

CAP_A_0402V-0.01UF,25V,10%,X7RA  I222  C2L43
   1 SATA6G_P1_TX_C_DP      A @BASEBOARD_FAB2_LIB.BASEBOARD_FAB2(SCH_1):SATA6G_P1_TX_C_DP
   2 SATA6G_PCH_PCIE_UP_SATA_TXP<1>      B @BASEBOARD_FAB2_LIB.BASEBOARD_FAB2(SCH_1):SATA6G_PCH_PCIE_UP_SATA_TXP(1)

CAP_A_0402V-0.01UF,25V,10%,X7RA  I228  C2L44
   1 SATA6G_P1_TX_C_DN      A @BASEBOARD_FAB2_LIB.BASEBOARD_FAB2(SCH_1):SATA6G_P1_TX_C_DN
   2 SATA6G_PCH_PCIE_UP_SATA_TXN<1>      B @BASEBOARD_FAB2_LIB.BASEBOARD_FAB2(SCH_1):SATA6G_PCH_PCIE_UP_SATA_TXN(1)

CAP_A_0402V-0.01UF,25V,10%,X7RA  I233  C2L42
   1 SATA6G_P2_TX_C_DN      A @BASEBOARD_FAB2_LIB.BASEBOARD_FAB2(SCH_1):SATA6G_P2_TX_C_DN
   2 SATA6G_PCH_PCIE_UP_SATA_TXN<2>      B @BASEBOARD_FAB2_LIB.BASEBOARD_FAB2(SCH_1):SATA6G_PCH_PCIE_UP_SATA_TXN(2)

CAP_A_0402V-0.01UF,25V,10%,X7RA  I234  C2L22
   1 SATA6G_P3_TX_C_DN      A @BASEBOARD_FAB2_LIB.BASEBOARD_FAB2(SCH_1):SATA6G_P3_TX_C_DN
   2 SATA6G_PCH_PCIE_UP_SATA_TXN<3>      B @BASEBOARD_FAB2_LIB.BASEBOARD_FAB2(SCH_1):SATA6G_PCH_PCIE_UP_SATA_TXN(3)

CAP_A_0402V-0.01UF,25V,10%,X7RA  I238  C2L37
   1 SATA6G_P4_TX_C_DN      A @BASEBOARD_FAB2_LIB.BASEBOARD_FAB2(SCH_1):SATA6G_P4_TX_C_DN
   2 SATA6G_PCH_PCIE_UP_SATA_TXN<4>      B @BASEBOARD_FAB2_LIB.BASEBOARD_FAB2(SCH_1):SATA6G_PCH_PCIE_UP_SATA_TXN(4)

CAP_A_0402V-0.01UF,25V,10%,X7RA  I239  C2L47
   1 SATA6G_P4_TX_C_DP      A @BASEBOARD_FAB2_LIB.BASEBOARD_FAB2(SCH_1):SATA6G_P4_TX_C_DP
   2 SATA6G_PCH_PCIE_UP_SATA_TXP<4>      B @BASEBOARD_FAB2_LIB.BASEBOARD_FAB2(SCH_1):SATA6G_PCH_PCIE_UP_SATA_TXP(4)

CAP_A_0402V-0.01UF,25V,10%,X7RA  I240  C2L27
   1 SATA6G_P5_TX_C_DP      A @BASEBOARD_FAB2_LIB.BASEBOARD_FAB2(SCH_1):SATA6G_P5_TX_C_DP
   2 SATA6G_PCH_PCIE_UP_SATA_TXP<5>      B @BASEBOARD_FAB2_LIB.BASEBOARD_FAB2(SCH_1):SATA6G_PCH_PCIE_UP_SATA_TXP(5)

CAP_A_0402V-0.01UF,25V,10%,X7RA  I241  C2L23
   1 SATA6G_P3_TX_C_DP      A @BASEBOARD_FAB2_LIB.BASEBOARD_FAB2(SCH_1):SATA6G_P3_TX_C_DP
   2 SATA6G_PCH_PCIE_UP_SATA_TXP<3>      B @BASEBOARD_FAB2_LIB.BASEBOARD_FAB2(SCH_1):SATA6G_PCH_PCIE_UP_SATA_TXP(3)

CAP_A_0402V-0.01UF,25V,10%,X7RA  I242  C2L41
   1 SATA6G_P2_TX_C_DP      A @BASEBOARD_FAB2_LIB.BASEBOARD_FAB2(SCH_1):SATA6G_P2_TX_C_DP
   2 SATA6G_PCH_PCIE_UP_SATA_TXP<2>      B @BASEBOARD_FAB2_LIB.BASEBOARD_FAB2(SCH_1):SATA6G_PCH_PCIE_UP_SATA_TXP(2)

CAP_A_0402V-0.01UF,25V,10%,X7RA  I255  C2L26
   1 SATA6G_P5_TX_C_DN      A @BASEBOARD_FAB2_LIB.BASEBOARD_FAB2(SCH_1):SATA6G_P5_TX_C_DN
   2 SATA6G_PCH_PCIE_UP_SATA_TXN<5>      B @BASEBOARD_FAB2_LIB.BASEBOARD_FAB2(SCH_1):SATA6G_PCH_PCIE_UP_SATA_TXN(5)

CAP_A_0402V-0.01UF,25V,10%,X7RA  I256  C2L38
   1 SATA6G_P6_TX_C_DN      A @BASEBOARD_FAB2_LIB.BASEBOARD_FAB2(SCH_1):SATA6G_P6_TX_C_DN
   2 SATA6G_PCH_PCIE_UP_SATA_TXN<6>      B @BASEBOARD_FAB2_LIB.BASEBOARD_FAB2(SCH_1):SATA6G_PCH_PCIE_UP_SATA_TXN(6)

CAP_A_0402V-0.01UF,25V,10%,X7RA  I257  C2L48
   1 SATA6G_P6_TX_C_DP      A @BASEBOARD_FAB2_LIB.BASEBOARD_FAB2(SCH_1):SATA6G_P6_TX_C_DP
   2 SATA6G_PCH_PCIE_UP_SATA_TXP<6>      B @BASEBOARD_FAB2_LIB.BASEBOARD_FAB2(SCH_1):SATA6G_PCH_PCIE_UP_SATA_TXP(6)

CAP_A_0402V-0.01UF,25V,10%,X7RA  I258  C2L24
   1 SATA6G_P7_TX_C_DP      A @BASEBOARD_FAB2_LIB.BASEBOARD_FAB2(SCH_1):SATA6G_P7_TX_C_DP
   2 SATA6G_PCH_PCIE_UP_SATA_TXP<7>      B @BASEBOARD_FAB2_LIB.BASEBOARD_FAB2(SCH_1):SATA6G_PCH_PCIE_UP_SATA_TXP(7)

CAP_A_0402V-0.01UF,25V,10%,X7RA  I259  C2L21
   1 SATA6G_P7_TX_C_DN      A @BASEBOARD_FAB2_LIB.BASEBOARD_FAB2(SCH_1):SATA6G_P7_TX_C_DN
   2 SATA6G_PCH_PCIE_UP_SATA_TXN<7>      B @BASEBOARD_FAB2_LIB.BASEBOARD_FAB2(SCH_1):SATA6G_PCH_PCIE_UP_SATA_TXN(7)

RES_0402-2.0K,1%,1/16W,CHIP,G2A  I261  R2L23
   1   P3V3      A @BASEBOARD_FAB2_LIB.BASEBOARD_FAB2(SCH_1):P3V3
   2 PU_DATAIN1_SATA_1_R      B @BASEBOARD_FAB2_LIB.BASEBOARD_FAB2(SCH_1):PU_DATAIN1_SATA_1_R

RES_0402-2.0K,1%,1/16W,CHIP,G2A  I263  R2L21
   1   P3V3      A @BASEBOARD_FAB2_LIB.BASEBOARD_FAB2(SCH_1):P3V3
   2 PU_DATAIN1_SATA_0_R      B @BASEBOARD_FAB2_LIB.BASEBOARD_FAB2(SCH_1):PU_DATAIN1_SATA_0_R

RES_0402-1.00K,1%,1/16W,CHIP,GA  I264  R2L22
   1 PD_SATA1_CONTROLLER_TYPE_R      A @BASEBOARD_FAB2_LIB.BASEBOARD_FAB2(SCH_1):PD_SATA1_CONTROLLER_TYPE_R
   2    GND      B @BASEBOARD_FAB2_LIB.BASEBOARD_FAB2(SCH_1):GND

RES_0402-1.00K,1%,1/16W,CHIP,GA  I266  R2L18
   1 PD_SATA0_CONTROLLER_TYPE_R      A @BASEBOARD_FAB2_LIB.BASEBOARD_FAB2(SCH_1):PD_SATA0_CONTROLLER_TYPE_R
   2    GND      B @BASEBOARD_FAB2_LIB.BASEBOARD_FAB2(SCH_1):GND


DRAWING: @BASEBOARD_FAB2_LIB.BASEBOARD_FAB2(SCH_1):PAGE175 

RES_0402-200.0,1%,1/16W,CHIP,GA  I4  R1L31
   1 FP_PWR_BTN_R_N      A @BASEBOARD_FAB2_LIB.BASEBOARD_FAB2(SCH_1):FP_PWR_BTN_R_N
   2 FP_PWR_BTN_R1_N      B @BASEBOARD_FAB2_LIB.BASEBOARD_FAB2(SCH_1):FP_PWR_BTN_R1_N

RES_0402-4.75K,1%,1/16W,CHIP,GA  I5  R1L27
   1 P3V3_STBY      A @BASEBOARD_FAB2_LIB.BASEBOARD_FAB2(SCH_1):P3V3_STBY
   2 FP_PWR_BTN_R_N      B @BASEBOARD_FAB2_LIB.BASEBOARD_FAB2(SCH_1):FP_PWR_BTN_R_N

CAP_A_0402V-1.0UF,6.3V,10%,X6SA  I11  C1L18
   1 FP_PWR_BTN_R1_N      A @BASEBOARD_FAB2_LIB.BASEBOARD_FAB2(SCH_1):FP_PWR_BTN_R1_N
   2    GND      B @BASEBOARD_FAB2_LIB.BASEBOARD_FAB2(SCH_1):GND

RES_0402-33.2,1%,1/16W,CHIP,G2A  I13  R1L26
   1 FM_PWR_BTN_R_N      A @BASEBOARD_FAB2_LIB.BASEBOARD_FAB2(SCH_1):FM_PWR_BTN_R_N
   2 FM_PWR_BTN_N      B @BASEBOARD_FAB2_LIB.BASEBOARD_FAB2(SCH_1):FM_PWR_BTN_N

CAP_A_0402V-1.0UF,6.3V,10%,X6SA  I19  C1L10
   1 FP_RST_BTN_R_N      A @BASEBOARD_FAB2_LIB.BASEBOARD_FAB2(SCH_1):FP_RST_BTN_R_N
   2    GND      B @BASEBOARD_FAB2_LIB.BASEBOARD_FAB2(SCH_1):GND

RES_0402-200.0,1%,1/16W,CHIP,GA  I22  R1L22
   1 FM_DEBUG_RST_BTN_N      A @BASEBOARD_FAB2_LIB.BASEBOARD_FAB2(SCH_1):FM_DEBUG_RST_BTN_N
   2 FP_RST_BTN_R_N      B @BASEBOARD_FAB2_LIB.BASEBOARD_FAB2(SCH_1):FP_RST_BTN_R_N

CAP_A_0402V-0.1UF,16V,10%,X7R,A  I37  C1L17
   1 P3V3_STBY      A @BASEBOARD_FAB2_LIB.BASEBOARD_FAB2(SCH_1):P3V3_STBY
   2    GND      B @BASEBOARD_FAB2_LIB.BASEBOARD_FAB2(SCH_1):GND

CAP_A_0402V-0.1UF,16V,10%,X7R,A  I38  C1L9
   1 P3V3_STBY      A @BASEBOARD_FAB2_LIB.BASEBOARD_FAB2(SCH_1):P3V3_STBY
   2    GND      B @BASEBOARD_FAB2_LIB.BASEBOARD_FAB2(SCH_1):GND

CAP_A_0402V-0.1UF,16V,10%,X7R,A  I40  C9A3
   1 P3V3_STBY      A @BASEBOARD_FAB2_LIB.BASEBOARD_FAB2(SCH_1):P3V3_STBY
   2    GND      B @BASEBOARD_FAB2_LIB.BASEBOARD_FAB2(SCH_1):GND

RES_0402-221,1.0%,1/16W,CHIP,GA  I45  R1L33
   1 FM_BEEP_LED_P      A @BASEBOARD_FAB2_LIB.BASEBOARD_FAB2(SCH_1):FM_BEEP_LED_P
   2 P3V3_STBY      B @BASEBOARD_FAB2_LIB.BASEBOARD_FAB2(SCH_1):P3V3_STBY

FET_N_SOT23LF-2N7002,FET,C7925A  I49  Q9A3
   1 FM_BIOS_TOP_SWAP_SPKR   GATE @BASEBOARD_FAB2_LIB.BASEBOARD_FAB2(SCH_1):FM_BIOS_TOP_SWAP_SPKR
   2    GND    SRC @BASEBOARD_FAB2_LIB.BASEBOARD_FAB2(SCH_1):GND
   3 FM_SPEAKER_PCH_N    DRN @BASEBOARD_FAB2_LIB.BASEBOARD_FAB2(SCH_1):FM_SPEAKER_PCH_N

LED_1NC-BLUE,IC,C96565-012  I50  DS9A1
   1 FP_ID_LED_P5V_STBY_N      C @BASEBOARD_FAB2_LIB.BASEBOARD_FAB2(SCH_1):FP_ID_LED_P5V_STBY_N
   2 FP_ID_LED_XOR_R      A @BASEBOARD_FAB2_LIB.BASEBOARD_FAB2(SCH_1):FP_ID_LED_XOR_R

TTL1G86_SOTLF-74AHCT1G86,IC,D3B  I57  U1L2
   1 PWRGD_P3V3_R      A @BASEBOARD_FAB2_LIB.BASEBOARD_FAB2(SCH_1):PWRGD_P3V3_R
   2 FP_PWR_ID_LED_N      B @BASEBOARD_FAB2_LIB.BASEBOARD_FAB2(SCH_1):FP_PWR_ID_LED_N
   4 FP_ID_LED_P5V_STBY_N      Y @BASEBOARD_FAB2_LIB.BASEBOARD_FAB2(SCH_1):FP_ID_LED_P5V_STBY_N

RES_0402-470.0,5%,1/16W,CHIP,GA  I58  R1L8
   1 P5V_STBY      A @BASEBOARD_FAB2_LIB.BASEBOARD_FAB2(SCH_1):P5V_STBY
   2 FP_ID_LED_XOR_R      B @BASEBOARD_FAB2_LIB.BASEBOARD_FAB2(SCH_1):FP_ID_LED_XOR_R

RES_0402-0.0,5%,1/16W,CHIP,G21A  I63  R1L12
   1 PWRGD_P3V3      A @BASEBOARD_FAB2_LIB.BASEBOARD_FAB2(SCH_1):PWRGD_P3V3
   2 PWRGD_P3V3_R      B @BASEBOARD_FAB2_LIB.BASEBOARD_FAB2(SCH_1):PWRGD_P3V3_R

CAP_A_0402V-0.1UF,16V,10%,X7R,A  I64  C1L4
   1 P5V_STBY      A @BASEBOARD_FAB2_LIB.BASEBOARD_FAB2(SCH_1):P5V_STBY
   2    GND      B @BASEBOARD_FAB2_LIB.BASEBOARD_FAB2(SCH_1):GND

LED_1NCLF-YELLOW,IC,C96565-003  I67  DS9A3
   1 FM_SPEAKER_PCH_N      C @BASEBOARD_FAB2_LIB.BASEBOARD_FAB2(SCH_1):FM_SPEAKER_PCH_N
   2 FM_BEEP_LED_P      A @BASEBOARD_FAB2_LIB.BASEBOARD_FAB2(SCH_1):FM_BEEP_LED_P

SWITCH_D37771002_SM-IC,D37771-A  I78  S9A1
   4    GND   PIN4 @BASEBOARD_FAB2_LIB.BASEBOARD_FAB2(SCH_1):GND
   3    GND   PIN3 @BASEBOARD_FAB2_LIB.BASEBOARD_FAB2(SCH_1):GND
   1 FM_DEBUG_RST_BTN_N   PIN1 @BASEBOARD_FAB2_LIB.BASEBOARD_FAB2(SCH_1):FM_DEBUG_RST_BTN_N
   2 FM_DEBUG_RST_BTN_N   PIN2 @BASEBOARD_FAB2_LIB.BASEBOARD_FAB2(SCH_1):FM_DEBUG_RST_BTN_N

SWITCH_D37771002_SM-IC,D37771-A  I92  S9A2
   4 FP_PWR_BTN_R_N   PIN4 @BASEBOARD_FAB2_LIB.BASEBOARD_FAB2(SCH_1):FP_PWR_BTN_R_N
   3 FP_PWR_BTN_R_N   PIN3 @BASEBOARD_FAB2_LIB.BASEBOARD_FAB2(SCH_1):FP_PWR_BTN_R_N
   1    GND   PIN1 @BASEBOARD_FAB2_LIB.BASEBOARD_FAB2(SCH_1):GND
   2    GND   PIN2 @BASEBOARD_FAB2_LIB.BASEBOARD_FAB2(SCH_1):GND

TC7PZ14FU-GP_DISCRET-GA1-TC7PZA  I93  U9A3
   1 FP_RST_BTN_R_N     1A @BASEBOARD_FAB2_LIB.BASEBOARD_FAB2(SCH_1):FP_RST_BTN_R_N
   2    GND    GND @BASEBOARD_FAB2_LIB.BASEBOARD_FAB2(SCH_1):GND
   3 FP_RST_BTN_BUF1_N     2A @BASEBOARD_FAB2_LIB.BASEBOARD_FAB2(SCH_1):FP_RST_BTN_BUF1_N
   4 RST_SYSTEM_BTN_BUF_N     2Y @BASEBOARD_FAB2_LIB.BASEBOARD_FAB2(SCH_1):RST_SYSTEM_BTN_BUF_N
   5 P3V3_STBY    VCC @BASEBOARD_FAB2_LIB.BASEBOARD_FAB2(SCH_1):P3V3_STBY
   6 FP_RST_BTN_BUF1_N     1Y @BASEBOARD_FAB2_LIB.BASEBOARD_FAB2(SCH_1):FP_RST_BTN_BUF1_N

RES_0402-100.0,1%,1/16W,CHIP,GA  I95  R9A9
   1 RST_SYSTEM_BTN_BUF_N      A @BASEBOARD_FAB2_LIB.BASEBOARD_FAB2(SCH_1):RST_SYSTEM_BTN_BUF_N
   2 RST_SYSTEM_BTN_N      B @BASEBOARD_FAB2_LIB.BASEBOARD_FAB2(SCH_1):RST_SYSTEM_BTN_N

TC7PZ14FU-GP_DISCRET-GA1-TC7PZA  I97  U9A4
   1 FP_PWR_BTN_R1_N     1A @BASEBOARD_FAB2_LIB.BASEBOARD_FAB2(SCH_1):FP_PWR_BTN_R1_N
   2    GND    GND @BASEBOARD_FAB2_LIB.BASEBOARD_FAB2(SCH_1):GND
   3 FP_PWR_BTN_BUF1_N     2A @BASEBOARD_FAB2_LIB.BASEBOARD_FAB2(SCH_1):FP_PWR_BTN_BUF1_N
   4 FM_PWR_BTN_R_N     2Y @BASEBOARD_FAB2_LIB.BASEBOARD_FAB2(SCH_1):FM_PWR_BTN_R_N
   5 P3V3_STBY    VCC @BASEBOARD_FAB2_LIB.BASEBOARD_FAB2(SCH_1):P3V3_STBY
   6 FP_PWR_BTN_BUF1_N     1Y @BASEBOARD_FAB2_LIB.BASEBOARD_FAB2(SCH_1):FP_PWR_BTN_BUF1_N

RES_0402-4.75K,1%,1/16W,CHIP,GA  I99  R1L19
   1 P3V3_STBY      A @BASEBOARD_FAB2_LIB.BASEBOARD_FAB2(SCH_1):P3V3_STBY
   2 FM_DEBUG_RST_BTN_N      B @BASEBOARD_FAB2_LIB.BASEBOARD_FAB2(SCH_1):FM_DEBUG_RST_BTN_N


DRAWING: @BASEBOARD_FAB2_LIB.BASEBOARD_FAB2(SCH_1):PAGE176 

RES_0402-0.0,5%,1/16W,CHIP,G21A  I16  R1M5
   1 USB2_P01_DP      A @BASEBOARD_FAB2_LIB.BASEBOARD_FAB2(SCH_1):USB2_P01_DP
   2 USB2_P01_ESD_DP      B @BASEBOARD_FAB2_LIB.BASEBOARD_FAB2(SCH_1):USB2_P01_ESD_DP

RES_0402-0.0,5%,1/16W,CHIP,G21A  I31  R1M6
   1 USB2_P01_DN      A @BASEBOARD_FAB2_LIB.BASEBOARD_FAB2(SCH_1):USB2_P01_DN
   2 USB2_P01_ESD_DN      B @BASEBOARD_FAB2_LIB.BASEBOARD_FAB2(SCH_1):USB2_P01_ESD_DN

CONN9_H51826001_PIP2-CONN,H518A  I69  J9B1
   2 USB2_P01_ESD_DN     DN @BASEBOARD_FAB2_LIB.BASEBOARD_FAB2(SCH_1):USB2_P01_ESD_DN
   3 USB2_P01_ESD_DP     DP @BASEBOARD_FAB2_LIB.BASEBOARD_FAB2(SCH_1):USB2_P01_ESD_DP
   4    GND    GND @BASEBOARD_FAB2_LIB.BASEBOARD_FAB2(SCH_1):GND
   7 DEBUG_CARD2_PRSNT GND_DRAIN @BASEBOARD_FAB2_LIB.BASEBOARD_FAB2(SCH_1):DEBUG_CARD2_PRSNT
 MH1    GND    MH1 @BASEBOARD_FAB2_LIB.BASEBOARD_FAB2(SCH_1):GND
 MH2    GND    MH2 @BASEBOARD_FAB2_LIB.BASEBOARD_FAB2(SCH_1):GND
 MH3    GND    MH3 @BASEBOARD_FAB2_LIB.BASEBOARD_FAB2(SCH_1):GND
 MH4    GND    MH4 @BASEBOARD_FAB2_LIB.BASEBOARD_FAB2(SCH_1):GND
   5 SMB_DEBUG_STBY_LVC3_SCL_CONN STDA_SSRXN @BASEBOARD_FAB2_LIB.BASEBOARD_FAB2(SCH_1):SMB_DEBUG_STBY_LVC3_SCL_CONN
   6 SMB_DEBUG_STBY_LVC3_SDA_CONN STDA_SSRXP @BASEBOARD_FAB2_LIB.BASEBOARD_FAB2(SCH_1):SMB_DEBUG_STBY_LVC3_SDA_CONN
   8 SPA_MID_DBG2_TX STDA_SSTXN @BASEBOARD_FAB2_LIB.BASEBOARD_FAB2(SCH_1):SPA_MID_DBG2_TX
   9 SPA_MID_DBG2_RX STDA_SSTXP @BASEBOARD_FAB2_LIB.BASEBOARD_FAB2(SCH_1):SPA_MID_DBG2_RX
   1 P5V_USB   VBUS @BASEBOARD_FAB2_LIB.BASEBOARD_FAB2(SCH_1):P5V_USB

DIODEAC_DUAL_ARRAY_SM9-ESD3V3UA  I98  CR1M2
   1 USB2_P01_ESD_DP    AC0 @BASEBOARD_FAB2_LIB.BASEBOARD_FAB2(SCH_1):USB2_P01_ESD_DP
   2 USB2_P01_ESD_DN    AC1 @BASEBOARD_FAB2_LIB.BASEBOARD_FAB2(SCH_1):USB2_P01_ESD_DN
   4 TP_USB_ESD_AC2    AC2 @BASEBOARD_FAB2_LIB.BASEBOARD_FAB2(SCH_1):TP_USB_ESD_AC2
   5 TP_USB_ESD_AC3    AC3 @BASEBOARD_FAB2_LIB.BASEBOARD_FAB2(SCH_1):TP_USB_ESD_AC3
   3    GND GND<0> @BASEBOARD_FAB2_LIB.BASEBOARD_FAB2(SCH_1):GND
   9 USB2_P01_ESD_DP   OUT0 @BASEBOARD_FAB2_LIB.BASEBOARD_FAB2(SCH_1):USB2_P01_ESD_DP
   8 USB2_P01_ESD_DN   OUT1 @BASEBOARD_FAB2_LIB.BASEBOARD_FAB2(SCH_1):USB2_P01_ESD_DN
   7 TP_USB_ESD_OUT2   OUT2 @BASEBOARD_FAB2_LIB.BASEBOARD_FAB2(SCH_1):TP_USB_ESD_OUT2
   6 TP_USB_ESD_OUT3   OUT3 @BASEBOARD_FAB2_LIB.BASEBOARD_FAB2(SCH_1):TP_USB_ESD_OUT3

TPS2061_SM-IC,H66405-001  I100  U1M3
   4 FM_USB_P0_EN_R_N   EN_N @BASEBOARD_FAB2_LIB.BASEBOARD_FAB2(SCH_1):FM_USB_P0_EN_R_N
   2    GND    GND @BASEBOARD_FAB2_LIB.BASEBOARD_FAB2(SCH_1):GND
   5 P5V_TPS2061     IN @BASEBOARD_FAB2_LIB.BASEBOARD_FAB2(SCH_1):P5V_TPS2061
   3 FM_OC0_USB_N   OC_N @BASEBOARD_FAB2_LIB.BASEBOARD_FAB2(SCH_1):FM_OC0_USB_N
   1 P5V_USB    OUT @BASEBOARD_FAB2_LIB.BASEBOARD_FAB2(SCH_1):P5V_USB

RES_0402-10.0K,1%,1/16W,CHIP,GA  I105  R1M24
   1 P3V3_STBY      A @BASEBOARD_FAB2_LIB.BASEBOARD_FAB2(SCH_1):P3V3_STBY
   2 FM_OC0_USB_N      B @BASEBOARD_FAB2_LIB.BASEBOARD_FAB2(SCH_1):FM_OC0_USB_N

CAP_A_0402V-0.1UF,16V,10%,X7R,A  I108  C1M38
   1 P5V_TPS2061      A @BASEBOARD_FAB2_LIB.BASEBOARD_FAB2(SCH_1):P5V_TPS2061
   2    GND      B @BASEBOARD_FAB2_LIB.BASEBOARD_FAB2(SCH_1):GND

RES_0402-10.0K,1%,1/16W,CHIP,GA  I111  R1M25
   1 FM_USB_P0_EN_R_N      A @BASEBOARD_FAB2_LIB.BASEBOARD_FAB2(SCH_1):FM_USB_P0_EN_R_N
   2    GND      B @BASEBOARD_FAB2_LIB.BASEBOARD_FAB2(SCH_1):GND

CAPP_7343HLF-330UF,10V,20%,POSA  I113  C9B8
   1 P5V_USB      A @BASEBOARD_FAB2_LIB.BASEBOARD_FAB2(SCH_1):P5V_USB
   2    GND      B @BASEBOARD_FAB2_LIB.BASEBOARD_FAB2(SCH_1):GND

RES_0805-0.0,5%,1/8W,CHIP,G221A  I132  R1W10
   1 P5V_STBY      A @BASEBOARD_FAB2_LIB.BASEBOARD_FAB2(SCH_1):P5V_STBY
   2 P5V_TPS2061      B @BASEBOARD_FAB2_LIB.BASEBOARD_FAB2(SCH_1):P5V_TPS2061

RES_0805-0.0,5%,1/8W,EMPTY,G22A  I133  R1W11
   1    P5V      A @BASEBOARD_FAB2_LIB.BASEBOARD_FAB2(SCH_1):P5V
   2 P5V_TPS2061      B @BASEBOARD_FAB2_LIB.BASEBOARD_FAB2(SCH_1):P5V_TPS2061

RES_0402-0.0,5%,1/16W,CHIP,G21A  I137  R1W12
   1 FM_CPLD_USB_P0_EN_N      A @BASEBOARD_FAB2_LIB.BASEBOARD_FAB2(SCH_1):FM_CPLD_USB_P0_EN_N
   2 FM_USB_P0_EN_R_N      B @BASEBOARD_FAB2_LIB.BASEBOARD_FAB2(SCH_1):FM_USB_P0_EN_R_N

RES_0402-0.0,5%,1/16W,CHIP,G21A  I138  R1W13
   1 FM_USB_P0_EN_BOOT_BIOS_STRAP_N      A @BASEBOARD_FAB2_LIB.BASEBOARD_FAB2(SCH_1):FM_USB_P0_EN_BOOT_BIOS_STRAP_N
   2 FM_USB_P0_EN_R_N      B @BASEBOARD_FAB2_LIB.BASEBOARD_FAB2(SCH_1):FM_USB_P0_EN_R_N

CAP_A_0402V-0.1UF,16V,10%,X7R,A  I139  C6W10
   1 P3V3_STBY      A @BASEBOARD_FAB2_LIB.BASEBOARD_FAB2(SCH_1):P3V3_STBY
   2    GND      B @BASEBOARD_FAB2_LIB.BASEBOARD_FAB2(SCH_1):GND

RES_0402-0.0,5%,1/16W,CHIP,G21A  I142  R1W33
   1 SMB_DEBUG_STBY_LVC3_SCL_R1      A @BASEBOARD_FAB2_LIB.BASEBOARD_FAB2(SCH_1):SMB_DEBUG_STBY_LVC3_SCL_R1
   2 SMB_DEBUG_STBY_LVC3_SCL      B @BASEBOARD_FAB2_LIB.BASEBOARD_FAB2(SCH_1):SMB_DEBUG_STBY_LVC3_SCL

RES_0402-0.0,5%,1/16W,CHIP,G21A  I143  R1W34
   1 SMB_DEBUG_STBY_LVC3_SDA_R1      A @BASEBOARD_FAB2_LIB.BASEBOARD_FAB2(SCH_1):SMB_DEBUG_STBY_LVC3_SDA_R1
   2 SMB_DEBUG_STBY_LVC3_SDA      B @BASEBOARD_FAB2_LIB.BASEBOARD_FAB2(SCH_1):SMB_DEBUG_STBY_LVC3_SDA

TTL1G126_A_SOT-74HC1G126,IC,A7B  I146  U6W4
   1 DEBUG_CARD2_PRSNT     OE @BASEBOARD_FAB2_LIB.BASEBOARD_FAB2(SCH_1):DEBUG_CARD2_PRSNT
   2 SPA_MID_DBG2_RX      A @BASEBOARD_FAB2_LIB.BASEBOARD_FAB2(SCH_1):SPA_MID_DBG2_RX
   4 SPA_MID_DBG2_RX_BUF      Y @BASEBOARD_FAB2_LIB.BASEBOARD_FAB2(SCH_1):SPA_MID_DBG2_RX_BUF

RES_0603-100.0K,1%,1/10W,CHIP,A  I147  R6W30
   1 P3V3_STBY      A @BASEBOARD_FAB2_LIB.BASEBOARD_FAB2(SCH_1):P3V3_STBY
   2 SPA_MID_DBG2_RX_BUF      B @BASEBOARD_FAB2_LIB.BASEBOARD_FAB2(SCH_1):SPA_MID_DBG2_RX_BUF

TTL1G126_A_SOT-74HC1G126,IC,A7B  I148  U6W5
   1 DEBUG_CARD2_PRSNT     OE @BASEBOARD_FAB2_LIB.BASEBOARD_FAB2(SCH_1):DEBUG_CARD2_PRSNT
   2 SPA_MID_DBG_TX      A @BASEBOARD_FAB2_LIB.BASEBOARD_FAB2(SCH_1):SPA_MID_DBG_TX
   4 SPA_MID_DBG2_TX_R      Y @BASEBOARD_FAB2_LIB.BASEBOARD_FAB2(SCH_1):SPA_MID_DBG2_TX_R

RES_0402-20.0K,1%,1/16W,CHIP,GA  I156  R6W38
   1 DEBUG_CARD2_PRSNT      A @BASEBOARD_FAB2_LIB.BASEBOARD_FAB2(SCH_1):DEBUG_CARD2_PRSNT
   2    GND      B @BASEBOARD_FAB2_LIB.BASEBOARD_FAB2(SCH_1):GND

TTL1G126_A_SOT-74HC1G126,IC,A7B  I157  U6W6
   1 SPA_MID_DBG1_TX_EN     OE @BASEBOARD_FAB2_LIB.BASEBOARD_FAB2(SCH_1):SPA_MID_DBG1_TX_EN
   2 SPA_MID_DBG_TX      A @BASEBOARD_FAB2_LIB.BASEBOARD_FAB2(SCH_1):SPA_MID_DBG_TX
   4 SPA_MID_DBG1_TX_R      Y @BASEBOARD_FAB2_LIB.BASEBOARD_FAB2(SCH_1):SPA_MID_DBG1_TX_R

RES_0402-10.0K,1%,1/16W,CHIP,GA  I158  R6W39
   1 SPA_MID_DBG1_TX_EN      A @BASEBOARD_FAB2_LIB.BASEBOARD_FAB2(SCH_1):SPA_MID_DBG1_TX_EN
   2 P3V3_STBY      B @BASEBOARD_FAB2_LIB.BASEBOARD_FAB2(SCH_1):P3V3_STBY

RES_0402-10.0,1%,1/16W,CHIP,G2A  I160  R6W37
   1 SPA_MID_DBG2_TX_R      A @BASEBOARD_FAB2_LIB.BASEBOARD_FAB2(SCH_1):SPA_MID_DBG2_TX_R
   2 SPA_MID_DBG2_TX      B @BASEBOARD_FAB2_LIB.BASEBOARD_FAB2(SCH_1):SPA_MID_DBG2_TX

RES_0402-10.0,1%,1/16W,CHIP,G2A  I161  R6W36
   1 SPA_MID_DBG1_TX_R      A @BASEBOARD_FAB2_LIB.BASEBOARD_FAB2(SCH_1):SPA_MID_DBG1_TX_R
   2 SPA_MID_DBG1_TX      B @BASEBOARD_FAB2_LIB.BASEBOARD_FAB2(SCH_1):SPA_MID_DBG1_TX

PCA9617_SSOP-IC,G81764-001-GNDA  I162  U1W3
   5 DEBUG_CARD2_PRSNT     EN @BASEBOARD_FAB2_LIB.BASEBOARD_FAB2(SCH_1):DEBUG_CARD2_PRSNT
   2 SMB_DEBUG_STBY_LVC3_SCL_CONN   SCLA @BASEBOARD_FAB2_LIB.BASEBOARD_FAB2(SCH_1):SMB_DEBUG_STBY_LVC3_SCL_CONN
   7 SMB_DEBUG_STBY_LVC3_SCL_R1   SCLB @BASEBOARD_FAB2_LIB.BASEBOARD_FAB2(SCH_1):SMB_DEBUG_STBY_LVC3_SCL_R1
   3 SMB_DEBUG_STBY_LVC3_SDA_CONN   SDAA @BASEBOARD_FAB2_LIB.BASEBOARD_FAB2(SCH_1):SMB_DEBUG_STBY_LVC3_SDA_CONN
   6 SMB_DEBUG_STBY_LVC3_SDA_R1   SDAB @BASEBOARD_FAB2_LIB.BASEBOARD_FAB2(SCH_1):SMB_DEBUG_STBY_LVC3_SDA_R1
   1 P3V3_STBY   VCCA @BASEBOARD_FAB2_LIB.BASEBOARD_FAB2(SCH_1):P3V3_STBY
   8 P3V3_STBY   VCCB @BASEBOARD_FAB2_LIB.BASEBOARD_FAB2(SCH_1):P3V3_STBY

CAP_A_0402V-0.1UF,16V,10%,X7R,A  I163  C1W18
   1 P3V3_STBY      A @BASEBOARD_FAB2_LIB.BASEBOARD_FAB2(SCH_1):P3V3_STBY
   2    GND      B @BASEBOARD_FAB2_LIB.BASEBOARD_FAB2(SCH_1):GND

CAP_A_0402V-0.1UF,16V,10%,X7R,A  I166  C1W19
   1 P3V3_STBY      A @BASEBOARD_FAB2_LIB.BASEBOARD_FAB2(SCH_1):P3V3_STBY
   2    GND      B @BASEBOARD_FAB2_LIB.BASEBOARD_FAB2(SCH_1):GND

RES_0402-4.75K,1%,1/16W,CHIP,GA  I172  R1W36
   1 P3V3_STBY      A @BASEBOARD_FAB2_LIB.BASEBOARD_FAB2(SCH_1):P3V3_STBY
   2 SMB_DEBUG_STBY_LVC3_SCL_CONN      B @BASEBOARD_FAB2_LIB.BASEBOARD_FAB2(SCH_1):SMB_DEBUG_STBY_LVC3_SCL_CONN

RES_0402-4.75K,1%,1/16W,CHIP,GA  I173  R1W37
   1 P3V3_STBY      A @BASEBOARD_FAB2_LIB.BASEBOARD_FAB2(SCH_1):P3V3_STBY
   2 SMB_DEBUG_STBY_LVC3_SDA_CONN      B @BASEBOARD_FAB2_LIB.BASEBOARD_FAB2(SCH_1):SMB_DEBUG_STBY_LVC3_SDA_CONN

RES_0402-0.0,5%,1/16W,CHIP,G21A  I175  R1W39
   1 SMB_DEBUG_STBY_LVC3_SDA_CONN      A @BASEBOARD_FAB2_LIB.BASEBOARD_FAB2(SCH_1):SMB_DEBUG_STBY_LVC3_SDA_CONN
   2 SMB_DEBUG_STBY_LVC3_SDA_R1      B @BASEBOARD_FAB2_LIB.BASEBOARD_FAB2(SCH_1):SMB_DEBUG_STBY_LVC3_SDA_R1

RES_0402-0.0,5%,1/16W,CHIP,G21A  I176  R1W38
   1 SMB_DEBUG_STBY_LVC3_SCL_CONN      A @BASEBOARD_FAB2_LIB.BASEBOARD_FAB2(SCH_1):SMB_DEBUG_STBY_LVC3_SCL_CONN
   2 SMB_DEBUG_STBY_LVC3_SCL_R1      B @BASEBOARD_FAB2_LIB.BASEBOARD_FAB2(SCH_1):SMB_DEBUG_STBY_LVC3_SCL_R1

RES_0402-4.75K,1%,1/16W,CHIP,GA  I178  R6W50
   1 P3V3_STBY      A @BASEBOARD_FAB2_LIB.BASEBOARD_FAB2(SCH_1):P3V3_STBY
   2 SPA_MID_DBG2_RX      B @BASEBOARD_FAB2_LIB.BASEBOARD_FAB2(SCH_1):SPA_MID_DBG2_RX

CHOKE_4PIN_SMLF-90 OHM,IND,752A  I181  L1M2
   1 USB2_P01_DN     A1 @BASEBOARD_FAB2_LIB.BASEBOARD_FAB2(SCH_1):USB2_P01_DN
   2 USB2_P01_DP     A2 @BASEBOARD_FAB2_LIB.BASEBOARD_FAB2(SCH_1):USB2_P01_DP
   3 USB2_P01_ESD_DP     B1 @BASEBOARD_FAB2_LIB.BASEBOARD_FAB2(SCH_1):USB2_P01_ESD_DP
   4 USB2_P01_ESD_DN     B2 @BASEBOARD_FAB2_LIB.BASEBOARD_FAB2(SCH_1):USB2_P01_ESD_DN

NC7SB3157_SMLF-IC,C99406-001  I182  U6W12
   6 DEBUG_CARD2_PRSNT      S @BASEBOARD_FAB2_LIB.BASEBOARD_FAB2(SCH_1):DEBUG_CARD2_PRSNT
   3 SPA_MID_DBG1_RX     B0 @BASEBOARD_FAB2_LIB.BASEBOARD_FAB2(SCH_1):SPA_MID_DBG1_RX
   1 SPA_MID_DBG2_RX_BUF     B1 @BASEBOARD_FAB2_LIB.BASEBOARD_FAB2(SCH_1):SPA_MID_DBG2_RX_BUF
   4 SPA_MID_DBG_RX      A @BASEBOARD_FAB2_LIB.BASEBOARD_FAB2(SCH_1):SPA_MID_DBG_RX
   5 P3V3_STBY    VCC @BASEBOARD_FAB2_LIB.BASEBOARD_FAB2(SCH_1):P3V3_STBY
   2    GND    GND @BASEBOARD_FAB2_LIB.BASEBOARD_FAB2(SCH_1):GND


DRAWING: @BASEBOARD_FAB2_LIB.BASEBOARD_FAB2(SCH_1):PAGE177 

RES_0402-0.0,5%,1/16W,CHIP,G21A  I3  R1M13
   1 LED_PCH_SSATA_HDD_N      A @BASEBOARD_FAB2_LIB.BASEBOARD_FAB2(SCH_1):LED_PCH_SSATA_HDD_N
   2 LED_SAS_ACT_R_N      B @BASEBOARD_FAB2_LIB.BASEBOARD_FAB2(SCH_1):LED_SAS_ACT_R_N

RES_0402-0.0,5%,1/16W,CHIP,G21A  I6  R1M10
   1 LED_PCH_SATA_HDD_N      A @BASEBOARD_FAB2_LIB.BASEBOARD_FAB2(SCH_1):LED_PCH_SATA_HDD_N
   2 LED_SATA_ACT_R_N      B @BASEBOARD_FAB2_LIB.BASEBOARD_FAB2(SCH_1):LED_SATA_ACT_R_N

RES_0402-10.0K,1%,1/16W,CHIP,GA  I8  R1M12
   1   P3V3      A @BASEBOARD_FAB2_LIB.BASEBOARD_FAB2(SCH_1):P3V3
   2 LED_SAS_ACT_R_N      B @BASEBOARD_FAB2_LIB.BASEBOARD_FAB2(SCH_1):LED_SAS_ACT_R_N

RES_0402-10.0K,1%,1/16W,CHIP,GA  I9  R1M11
   1   P3V3      A @BASEBOARD_FAB2_LIB.BASEBOARD_FAB2(SCH_1):P3V3
   2 LED_SATA_ACT_R_N      B @BASEBOARD_FAB2_LIB.BASEBOARD_FAB2(SCH_1):LED_SATA_ACT_R_N

CAP_A_0402V-1.0UF,6.3V,10%,X6SA  I20  C1M3
   1   P3V3      A @BASEBOARD_FAB2_LIB.BASEBOARD_FAB2(SCH_1):P3V3
   2    GND      B @BASEBOARD_FAB2_LIB.BASEBOARD_FAB2(SCH_1):GND

LED_A1LF-GREEN,IC,C97278-010  I31  DS9A6
   2    GND      C @BASEBOARD_FAB2_LIB.BASEBOARD_FAB2(SCH_1):GND
   1 LED_P5V_STBY      A @BASEBOARD_FAB2_LIB.BASEBOARD_FAB2(SCH_1):LED_P5V_STBY

RES_0402-301.0,1%,1/16W,CHIP,GA  I33  R1L37
   1 P5V_STBY      A @BASEBOARD_FAB2_LIB.BASEBOARD_FAB2(SCH_1):P5V_STBY
   2 LED_P5V_STBY      B @BASEBOARD_FAB2_LIB.BASEBOARD_FAB2(SCH_1):LED_P5V_STBY

LED_1NCLF-GREEN,IC,C96565-011  I42  DS9A2
   1 FP_LED_HDD_ACTIVITY_AND_N      C @BASEBOARD_FAB2_LIB.BASEBOARD_FAB2(SCH_1):FP_LED_HDD_ACTIVITY_AND_N
   2 FP_LED_HDD_ACTIVITY_AND_R_N      A @BASEBOARD_FAB2_LIB.BASEBOARD_FAB2(SCH_1):FP_LED_HDD_ACTIVITY_AND_R_N

RES_0402-64.9,1.0%,1/16W,CHIP,A  I43  R1L21
   1   P3V3      A @BASEBOARD_FAB2_LIB.BASEBOARD_FAB2(SCH_1):P3V3
   2 FP_LED_HDD_ACTIVITY_AND_R_N      B @BASEBOARD_FAB2_LIB.BASEBOARD_FAB2(SCH_1):FP_LED_HDD_ACTIVITY_AND_R_N

TTL1G08_SOTLF-NC7SZ08,IC,D1032C  I70  U1M1
   4 FP_LED_HDD_ACTIVITY_AND_N   Y<0> @BASEBOARD_FAB2_LIB.BASEBOARD_FAB2(SCH_1):FP_LED_HDD_ACTIVITY_AND_N
   1 LED_SATA_ACT_R_N   A<0> @BASEBOARD_FAB2_LIB.BASEBOARD_FAB2(SCH_1):LED_SATA_ACT_R_N
   2 LED_SAS_ACT_R_N   B<0> @BASEBOARD_FAB2_LIB.BASEBOARD_FAB2(SCH_1):LED_SAS_ACT_R_N

LED_A1-RED,IC,D14725-005  I71  DS9F1
   2 FM_RED_LED_CATHODE      C @BASEBOARD_FAB2_LIB.BASEBOARD_FAB2(SCH_1):FM_RED_LED_CATHODE
   1 FM_RED_LED_ANODE      A @BASEBOARD_FAB2_LIB.BASEBOARD_FAB2(SCH_1):FM_RED_LED_ANODE

RES_0402-221,1.0%,1/16W,CHIP,GA  I72  R9F28
   1 P3V3_STBY      A @BASEBOARD_FAB2_LIB.BASEBOARD_FAB2(SCH_1):P3V3_STBY
   2 FM_RED_LED_ANODE      B @BASEBOARD_FAB2_LIB.BASEBOARD_FAB2(SCH_1):FM_RED_LED_ANODE

RES_0402-4.75K,1%,1/16W,CHIP,GA  I76  R9F30
   1 P3V3_STBY      A @BASEBOARD_FAB2_LIB.BASEBOARD_FAB2(SCH_1):P3V3_STBY
   2 FM_BMC_FAULT_LED_N      B @BASEBOARD_FAB2_LIB.BASEBOARD_FAB2(SCH_1):FM_BMC_FAULT_LED_N

FET_N_DUAL_SMLF-NTJD4001N,FET,A  I79  Q9F1
   5 FM_BMC_FAULT_LED GATE<0> @BASEBOARD_FAB2_LIB.BASEBOARD_FAB2(SCH_1):FM_BMC_FAULT_LED
   4    GND SOURCE<0> @BASEBOARD_FAB2_LIB.BASEBOARD_FAB2(SCH_1):GND
   3 FM_RED_LED_CATHODE DRAIN<0> @BASEBOARD_FAB2_LIB.BASEBOARD_FAB2(SCH_1):FM_RED_LED_CATHODE

FET_N_DUAL_SMLF-NTJD4001N,FET,A  I80  Q9F1
   2 FM_BMC_FAULT_LED_N GATE<0> @BASEBOARD_FAB2_LIB.BASEBOARD_FAB2(SCH_1):FM_BMC_FAULT_LED_N
   1    GND SOURCE<0> @BASEBOARD_FAB2_LIB.BASEBOARD_FAB2(SCH_1):GND
   6 FM_BMC_FAULT_LED DRAIN<0> @BASEBOARD_FAB2_LIB.BASEBOARD_FAB2(SCH_1):FM_BMC_FAULT_LED

RES_0402-4.75K,1%,1/16W,CHIP,GA  I82  R9F52
   1 P3V3_STBY      A @BASEBOARD_FAB2_LIB.BASEBOARD_FAB2(SCH_1):P3V3_STBY
   2 FM_BMC_FAULT_LED      B @BASEBOARD_FAB2_LIB.BASEBOARD_FAB2(SCH_1):FM_BMC_FAULT_LED


DRAWING: @BASEBOARD_FAB2_LIB.BASEBOARD_FAB2(SCH_1):PAGE178 

RES_0402-49.9,1%,1/16W,CHIP,G2A  I1  R8D20
   1 SGPIO_PCH_SATA_LOAD      A @BASEBOARD_FAB2_LIB.BASEBOARD_FAB2(SCH_1):SGPIO_PCH_SATA_LOAD
   2 SGPIO_PCH_SATA_LOAD_R      B @BASEBOARD_FAB2_LIB.BASEBOARD_FAB2(SCH_1):SGPIO_PCH_SATA_LOAD_R

RES_0402-2.0K,1%,1/16W,CHIP,G2A  I2  R2L12
   1 P3V3_STBY      A @BASEBOARD_FAB2_LIB.BASEBOARD_FAB2(SCH_1):P3V3_STBY
   2 SGPIO_PCH_SATA_LOAD_R      B @BASEBOARD_FAB2_LIB.BASEBOARD_FAB2(SCH_1):SGPIO_PCH_SATA_LOAD_R

RES_0402-49.9,1%,1/16W,CHIP,G2A  I8  R8D19
   1 SGPIO_PCH_SATA_DOUT0      A @BASEBOARD_FAB2_LIB.BASEBOARD_FAB2(SCH_1):SGPIO_PCH_SATA_DOUT0
   2 SGPIO_PCH_SATA_DOUT0_R      B @BASEBOARD_FAB2_LIB.BASEBOARD_FAB2(SCH_1):SGPIO_PCH_SATA_DOUT0_R

RES_0402-49.9,1%,1/16W,CHIP,G2A  I11  R2N31
   1 SGPIO_PCH_SATA_CLOCK      A @BASEBOARD_FAB2_LIB.BASEBOARD_FAB2(SCH_1):SGPIO_PCH_SATA_CLOCK
   2 SGPIO_PCH_SATA_CLOCK_R      B @BASEBOARD_FAB2_LIB.BASEBOARD_FAB2(SCH_1):SGPIO_PCH_SATA_CLOCK_R

RES_0402-2.0K,1%,1/16W,CHIP,G2A  I12  R2L15
   1 P3V3_STBY      A @BASEBOARD_FAB2_LIB.BASEBOARD_FAB2(SCH_1):P3V3_STBY
   2 SGPIO_PCH_SATA_DOUT0_R      B @BASEBOARD_FAB2_LIB.BASEBOARD_FAB2(SCH_1):SGPIO_PCH_SATA_DOUT0_R

RES_0402-2.0K,1%,1/16W,CHIP,G2A  I13  R2L11
   1 P3V3_STBY      A @BASEBOARD_FAB2_LIB.BASEBOARD_FAB2(SCH_1):P3V3_STBY
   2 SGPIO_PCH_SATA_CLOCK_R      B @BASEBOARD_FAB2_LIB.BASEBOARD_FAB2(SCH_1):SGPIO_PCH_SATA_CLOCK_R

RES_0402-2.0K,1%,1/16W,CHIP,G2A  I17  R2L6
   1 P3V3_STBY      A @BASEBOARD_FAB2_LIB.BASEBOARD_FAB2(SCH_1):P3V3_STBY
   2 SGPIO_PCH_SSATA_CLOCK_R      B @BASEBOARD_FAB2_LIB.BASEBOARD_FAB2(SCH_1):SGPIO_PCH_SSATA_CLOCK_R

RES_0402-2.0K,1%,1/16W,CHIP,G2A  I18  R2L4
   1 P3V3_STBY      A @BASEBOARD_FAB2_LIB.BASEBOARD_FAB2(SCH_1):P3V3_STBY
   2 SGPIO_PCH_SSATA_DOUT0_R      B @BASEBOARD_FAB2_LIB.BASEBOARD_FAB2(SCH_1):SGPIO_PCH_SSATA_DOUT0_R

RES_0402-2.0K,1%,1/16W,CHIP,G2A  I20  R2L5
   1 P3V3_STBY      A @BASEBOARD_FAB2_LIB.BASEBOARD_FAB2(SCH_1):P3V3_STBY
   2 SGPIO_PCH_SSATA_LOAD_R      B @BASEBOARD_FAB2_LIB.BASEBOARD_FAB2(SCH_1):SGPIO_PCH_SSATA_LOAD_R

RES_0402-49.9,1%,1/16W,CHIP,G2A  I21  R8B29
   1 SGPIO_PCH_SSATA_DOUT0      A @BASEBOARD_FAB2_LIB.BASEBOARD_FAB2(SCH_1):SGPIO_PCH_SSATA_DOUT0
   2 SGPIO_PCH_SSATA_DOUT0_R      B @BASEBOARD_FAB2_LIB.BASEBOARD_FAB2(SCH_1):SGPIO_PCH_SSATA_DOUT0_R

RES_0402-49.9,1%,1/16W,CHIP,G2A  I22  R2N19
   1 SGPIO_PCH_SSATA_LOAD      A @BASEBOARD_FAB2_LIB.BASEBOARD_FAB2(SCH_1):SGPIO_PCH_SSATA_LOAD
   2 SGPIO_PCH_SSATA_LOAD_R      B @BASEBOARD_FAB2_LIB.BASEBOARD_FAB2(SCH_1):SGPIO_PCH_SSATA_LOAD_R

RES_0402-49.9,1%,1/16W,CHIP,G2A  I23  R2N22
   1 SGPIO_PCH_SSATA_CLOCK      A @BASEBOARD_FAB2_LIB.BASEBOARD_FAB2(SCH_1):SGPIO_PCH_SSATA_CLOCK
   2 SGPIO_PCH_SSATA_CLOCK_R      B @BASEBOARD_FAB2_LIB.BASEBOARD_FAB2(SCH_1):SGPIO_PCH_SSATA_CLOCK_R


DRAWING: @BASEBOARD_FAB2_LIB.BASEBOARD_FAB2(SCH_1):PAGE184 

SCONN11_H67026001_SM-CONN,H670A  I87  J8E1
   1 SPI_PCH_TPM_CLK_R    IO1 @BASEBOARD_FAB2_LIB.BASEBOARD_FAB2(SCH_1):SPI_PCH_TPM_CLK_R
   2 RST_PLTRST_BUF_N    IO2 @BASEBOARD_FAB2_LIB.BASEBOARD_FAB2(SCH_1):RST_PLTRST_BUF_N
   3 SPI_PCH_TPM_MOSI_R    IO3 @BASEBOARD_FAB2_LIB.BASEBOARD_FAB2(SCH_1):SPI_PCH_TPM_MOSI_R
   4 SPI_PCH_TPM_MISO_R    IO4 @BASEBOARD_FAB2_LIB.BASEBOARD_FAB2(SCH_1):SPI_PCH_TPM_MISO_R
   5 SPI_PCH_TPM_CS_R_N    IO5 @BASEBOARD_FAB2_LIB.BASEBOARD_FAB2(SCH_1):SPI_PCH_TPM_CS_R_N
   6 SMB_SENSOR_STBY_LVC3_SDA    IO6 @BASEBOARD_FAB2_LIB.BASEBOARD_FAB2(SCH_1):SMB_SENSOR_STBY_LVC3_SDA
   7 P3V3_STBY    IO7 @BASEBOARD_FAB2_LIB.BASEBOARD_FAB2(SCH_1):P3V3_STBY
   8 FM_TPM_PRES_RST_N    IO8 @BASEBOARD_FAB2_LIB.BASEBOARD_FAB2(SCH_1):FM_TPM_PRES_RST_N
   9 IRQ_SPI_TPM_N_R    IO9 @BASEBOARD_FAB2_LIB.BASEBOARD_FAB2(SCH_1):IRQ_SPI_TPM_N_R
  10 SMB_SENSOR_STBY_LVC3_SCL   IO10 @BASEBOARD_FAB2_LIB.BASEBOARD_FAB2(SCH_1):SMB_SENSOR_STBY_LVC3_SCL
  11    GND   IO11 @BASEBOARD_FAB2_LIB.BASEBOARD_FAB2(SCH_1):GND
 MP1    GND    MP1 @BASEBOARD_FAB2_LIB.BASEBOARD_FAB2(SCH_1):GND
 MP2    GND    MP2 @BASEBOARD_FAB2_LIB.BASEBOARD_FAB2(SCH_1):GND

RES_0402-33.2,1%,1/16W,CHIP,G2A  I88  R8E9
   1 SPI_PCH_CLK      A @BASEBOARD_FAB2_LIB.BASEBOARD_FAB2(SCH_1):SPI_PCH_CLK
   2 SPI_PCH_TPM_CLK_R      B @BASEBOARD_FAB2_LIB.BASEBOARD_FAB2(SCH_1):SPI_PCH_TPM_CLK_R

RES_0402-0.0,5%,1/16W,CHIP,G21A  I92  R8D35
   1 SPI_PCH_TPM_CS_N      A @BASEBOARD_FAB2_LIB.BASEBOARD_FAB2(SCH_1):SPI_PCH_TPM_CS_N
   2 SPI_PCH_TPM_CS_R_N      B @BASEBOARD_FAB2_LIB.BASEBOARD_FAB2(SCH_1):SPI_PCH_TPM_CS_R_N

RES_0402-33.2,1%,1/16W,CHIP,G2A  I93  R8E13
   1 SPI_PCH_MISO      A @BASEBOARD_FAB2_LIB.BASEBOARD_FAB2(SCH_1):SPI_PCH_MISO
   2 SPI_PCH_TPM_MISO_R      B @BASEBOARD_FAB2_LIB.BASEBOARD_FAB2(SCH_1):SPI_PCH_TPM_MISO_R

RES_0402-33.2,1%,1/16W,CHIP,G2A  I95  R8E10
   1 SPI_PCH_MOSI      A @BASEBOARD_FAB2_LIB.BASEBOARD_FAB2(SCH_1):SPI_PCH_MOSI
   2 SPI_PCH_TPM_MOSI_R      B @BASEBOARD_FAB2_LIB.BASEBOARD_FAB2(SCH_1):SPI_PCH_TPM_MOSI_R

RES_0402-0.0,5%,1/16W,CHIP,G21A  I99  R8E1
   1 IRQ_SPI_TPM_N_R      A @BASEBOARD_FAB2_LIB.BASEBOARD_FAB2(SCH_1):IRQ_SPI_TPM_N_R
   2 IRQ_PIRQA_SPI_TPM_N      B @BASEBOARD_FAB2_LIB.BASEBOARD_FAB2(SCH_1):IRQ_PIRQA_SPI_TPM_N

STANDOFF_TH1-SO,H72821-001  I104  RM8D1
   1    GND    IO1 @BASEBOARD_FAB2_LIB.BASEBOARD_FAB2(SCH_1):GND


DRAWING: @BASEBOARD_FAB2_LIB.BASEBOARD_FAB2(SCH_1):PAGE185 

CAP_0402-0.22UF,16V,10%,X7R,A3A  I96  C8F7
   1 P3E_PCH_TX_0_DP      A @BASEBOARD_FAB2_LIB.BASEBOARD_FAB2(SCH_1):P3E_PCH_TX_0_DP
   2 P3E_PCH_M2_SATA6G_TX_R_DP      B @BASEBOARD_FAB2_LIB.BASEBOARD_FAB2(SCH_1):P3E_PCH_M2_SATA6G_TX_R_DP

RES_0402-0.0,5%,1/16W,CHIP,G21A  I105  R8F18
   1 P3E_PCH_RX_0_DP      A @BASEBOARD_FAB2_LIB.BASEBOARD_FAB2(SCH_1):P3E_PCH_RX_0_DP
   2 P3E_PCH_M2_SATA6G_RX_R_DP      B @BASEBOARD_FAB2_LIB.BASEBOARD_FAB2(SCH_1):P3E_PCH_M2_SATA6G_RX_R_DP

RES_0402-0.0,5%,1/16W,CHIP,G21A  I106  R8F21
   1 P3E_PCH_RX_0_DN      A @BASEBOARD_FAB2_LIB.BASEBOARD_FAB2(SCH_1):P3E_PCH_RX_0_DN
   2 P3E_PCH_M2_SATA6G_RX_R_DN      B @BASEBOARD_FAB2_LIB.BASEBOARD_FAB2(SCH_1):P3E_PCH_M2_SATA6G_RX_R_DN

TTL1G07_A_SOP-74LVC1G07,IC,C88B  I110  U2P1
   2 FM_M2_SSD_PEDET      A @BASEBOARD_FAB2_LIB.BASEBOARD_FAB2(SCH_1):FM_M2_SSD_PEDET
   4 FM_M2_DET_LVC3      Y @BASEBOARD_FAB2_LIB.BASEBOARD_FAB2(SCH_1):FM_M2_DET_LVC3

RES_0402-10.0K,1%,1/16W,CHIP,GA  I111  R2P15
   1   P3V3      A @BASEBOARD_FAB2_LIB.BASEBOARD_FAB2(SCH_1):P3V3
   2 FM_M2_SSD_PEDET      B @BASEBOARD_FAB2_LIB.BASEBOARD_FAB2(SCH_1):FM_M2_SSD_PEDET

RES_0402-10.0K,1%,1/16W,CHIP,GA  I113  R2P16
   1 P3V3_STBY      A @BASEBOARD_FAB2_LIB.BASEBOARD_FAB2(SCH_1):P3V3_STBY
   2 FM_M2_DET_LVC3      B @BASEBOARD_FAB2_LIB.BASEBOARD_FAB2(SCH_1):FM_M2_DET_LVC3

RES_0402-0.0,5%,1/16W,CHIP,G21A  I115  R2P14
   1 FM_M2_DET_LVC3      A @BASEBOARD_FAB2_LIB.BASEBOARD_FAB2(SCH_1):FM_M2_DET_LVC3
   2 FM_SSATA_PCIE_M2_SEL      B @BASEBOARD_FAB2_LIB.BASEBOARD_FAB2(SCH_1):FM_SSATA_PCIE_M2_SEL

CAP_A_0402V-0.1UF,16V,10%,X7R,A  I117  C2P9
   1 P3V3_STBY      A @BASEBOARD_FAB2_LIB.BASEBOARD_FAB2(SCH_1):P3V3_STBY
   2    GND      B @BASEBOARD_FAB2_LIB.BASEBOARD_FAB2(SCH_1):GND

CAP_A_0402V-0.1UF,16V,10%,X7R,A  I120  C2T29
   1   P3V3      A @BASEBOARD_FAB2_LIB.BASEBOARD_FAB2(SCH_1):P3V3
   2    GND      B @BASEBOARD_FAB2_LIB.BASEBOARD_FAB2(SCH_1):GND

CAP_A_0402V-0.1UF,16V,10%,X7R,A  I123  C2T26
   1   P3V3      A @BASEBOARD_FAB2_LIB.BASEBOARD_FAB2(SCH_1):P3V3
   2    GND      B @BASEBOARD_FAB2_LIB.BASEBOARD_FAB2(SCH_1):GND

CAP_A_0402V-0.1UF,16V,10%,X7R,A  I124  C2T21
   1   P3V3      A @BASEBOARD_FAB2_LIB.BASEBOARD_FAB2(SCH_1):P3V3
   2    GND      B @BASEBOARD_FAB2_LIB.BASEBOARD_FAB2(SCH_1):GND

CAP_A_0402V-0.1UF,16V,10%,X7R,A  I126  C2T16
   1   P3V3      A @BASEBOARD_FAB2_LIB.BASEBOARD_FAB2(SCH_1):P3V3
   2    GND      B @BASEBOARD_FAB2_LIB.BASEBOARD_FAB2(SCH_1):GND

CAP_A_0402V-0.1UF,16V,10%,X7R,A  I127  C2T15
   1   P3V3      A @BASEBOARD_FAB2_LIB.BASEBOARD_FAB2(SCH_1):P3V3
   2    GND      B @BASEBOARD_FAB2_LIB.BASEBOARD_FAB2(SCH_1):GND

CAP_A_0402V-0.1UF,16V,10%,X7R,A  I129  C2T24
   1   P3V3      A @BASEBOARD_FAB2_LIB.BASEBOARD_FAB2(SCH_1):P3V3
   2    GND      B @BASEBOARD_FAB2_LIB.BASEBOARD_FAB2(SCH_1):GND

CAP_A_0402V-0.1UF,16V,10%,X7R,A  I131  C2T2
   1   P3V3      A @BASEBOARD_FAB2_LIB.BASEBOARD_FAB2(SCH_1):P3V3
   2    GND      B @BASEBOARD_FAB2_LIB.BASEBOARD_FAB2(SCH_1):GND

CAP_A_0402V-0.1UF,16V,10%,X7R,A  I132  C2T4
   1   P3V3      A @BASEBOARD_FAB2_LIB.BASEBOARD_FAB2(SCH_1):P3V3
   2    GND      B @BASEBOARD_FAB2_LIB.BASEBOARD_FAB2(SCH_1):GND

CAP_A_0402V-0.1UF,16V,10%,X7R,A  I135  C2T5
   1   P3V3      A @BASEBOARD_FAB2_LIB.BASEBOARD_FAB2(SCH_1):P3V3
   2    GND      B @BASEBOARD_FAB2_LIB.BASEBOARD_FAB2(SCH_1):GND

RES_0402-10.0K,1%,1/16W,CHIP,GA  I136  R8F36
   1   P3V3      A @BASEBOARD_FAB2_LIB.BASEBOARD_FAB2(SCH_1):P3V3
   2 PU_M2_CLK_REQ_N      B @BASEBOARD_FAB2_LIB.BASEBOARD_FAB2(SCH_1):PU_M2_CLK_REQ_N

CAP_A_0402V-0.01UF,25V,10%,X7RA  I138  C8F6
   1 SATA6G_S0_TX_DP      A @BASEBOARD_FAB2_LIB.BASEBOARD_FAB2(SCH_1):SATA6G_S0_TX_DP
   2 P3E_PCH_M2_SATA6G_TX_R_DP      B @BASEBOARD_FAB2_LIB.BASEBOARD_FAB2(SCH_1):P3E_PCH_M2_SATA6G_TX_R_DP

CAP_A_0402V-0.01UF,25V,10%,X7RA  I139  C8F11
   1 SATA6G_S0_TX_DN      A @BASEBOARD_FAB2_LIB.BASEBOARD_FAB2(SCH_1):SATA6G_S0_TX_DN
   2 P3E_PCH_M2_SATA6G_TX_R_DN      B @BASEBOARD_FAB2_LIB.BASEBOARD_FAB2(SCH_1):P3E_PCH_M2_SATA6G_TX_R_DN

CAP_0402-0.22UF,16V,10%,X7R,A3A  I140  C8F12
   1 P3E_PCH_TX_0_DN      A @BASEBOARD_FAB2_LIB.BASEBOARD_FAB2(SCH_1):P3E_PCH_TX_0_DN
   2 P3E_PCH_M2_SATA6G_TX_R_DN      B @BASEBOARD_FAB2_LIB.BASEBOARD_FAB2(SCH_1):P3E_PCH_M2_SATA6G_TX_R_DN

CAP_A_0402V-0.01UF,25V,10%,X7RA  I141  C8F13
   1 SATA6G_S0_RX_DP      A @BASEBOARD_FAB2_LIB.BASEBOARD_FAB2(SCH_1):SATA6G_S0_RX_DP
   2 P3E_PCH_M2_SATA6G_RX_R_DP      B @BASEBOARD_FAB2_LIB.BASEBOARD_FAB2(SCH_1):P3E_PCH_M2_SATA6G_RX_R_DP

CAP_A_0402V-0.01UF,25V,10%,X7RA  I142  C8F15
   1 SATA6G_S0_RX_DN      A @BASEBOARD_FAB2_LIB.BASEBOARD_FAB2(SCH_1):SATA6G_S0_RX_DN
   2 P3E_PCH_M2_SATA6G_RX_R_DN      B @BASEBOARD_FAB2_LIB.BASEBOARD_FAB2(SCH_1):P3E_PCH_M2_SATA6G_RX_R_DN

SKT-MINI67P-41-GP_SOCKET-G4-SKA  I143  J8F1
   1    GND      1 @BASEBOARD_FAB2_LIB.BASEBOARD_FAB2(SCH_1):GND
   3    GND      3 @BASEBOARD_FAB2_LIB.BASEBOARD_FAB2(SCH_1):GND
   5 P3E_PCH_M2_RX_DN<3>      5 @BASEBOARD_FAB2_LIB.BASEBOARD_FAB2(SCH_1):P3E_PCH_M2_RX_DN(3)
   7 P3E_PCH_M2_RX_DP<3>      7 @BASEBOARD_FAB2_LIB.BASEBOARD_FAB2(SCH_1):P3E_PCH_M2_RX_DP(3)
   9    GND      9 @BASEBOARD_FAB2_LIB.BASEBOARD_FAB2(SCH_1):GND
  11 P3E_PCH_M2_TX_C_DN<3>     11 @BASEBOARD_FAB2_LIB.BASEBOARD_FAB2(SCH_1):P3E_PCH_M2_TX_C_DN(3)
  13 P3E_PCH_M2_TX_C_DP<3>     13 @BASEBOARD_FAB2_LIB.BASEBOARD_FAB2(SCH_1):P3E_PCH_M2_TX_C_DP(3)
  15    GND     15 @BASEBOARD_FAB2_LIB.BASEBOARD_FAB2(SCH_1):GND
  17 P3E_PCH_M2_RX_DN<2>     17 @BASEBOARD_FAB2_LIB.BASEBOARD_FAB2(SCH_1):P3E_PCH_M2_RX_DN(2)
  19 P3E_PCH_M2_RX_DP<2>     19 @BASEBOARD_FAB2_LIB.BASEBOARD_FAB2(SCH_1):P3E_PCH_M2_RX_DP(2)
  21    GND     21 @BASEBOARD_FAB2_LIB.BASEBOARD_FAB2(SCH_1):GND
  23 P3E_PCH_M2_TX_C_DN<2>     23 @BASEBOARD_FAB2_LIB.BASEBOARD_FAB2(SCH_1):P3E_PCH_M2_TX_C_DN(2)
  25 P3E_PCH_M2_TX_C_DP<2>     25 @BASEBOARD_FAB2_LIB.BASEBOARD_FAB2(SCH_1):P3E_PCH_M2_TX_C_DP(2)
  27    GND     27 @BASEBOARD_FAB2_LIB.BASEBOARD_FAB2(SCH_1):GND
  29 P3E_PCH_M2_RX_DN<1>     29 @BASEBOARD_FAB2_LIB.BASEBOARD_FAB2(SCH_1):P3E_PCH_M2_RX_DN(1)
  31 P3E_PCH_M2_RX_DP<1>     31 @BASEBOARD_FAB2_LIB.BASEBOARD_FAB2(SCH_1):P3E_PCH_M2_RX_DP(1)
  33    GND     33 @BASEBOARD_FAB2_LIB.BASEBOARD_FAB2(SCH_1):GND
  35 P3E_PCH_M2_TX_C_DN<1>     35 @BASEBOARD_FAB2_LIB.BASEBOARD_FAB2(SCH_1):P3E_PCH_M2_TX_C_DN(1)
  37 P3E_PCH_M2_TX_C_DP<1>     37 @BASEBOARD_FAB2_LIB.BASEBOARD_FAB2(SCH_1):P3E_PCH_M2_TX_C_DP(1)
  39    GND     39 @BASEBOARD_FAB2_LIB.BASEBOARD_FAB2(SCH_1):GND
  41 P3E_PCH_M2_SATA6G_RX_R_DP     41 @BASEBOARD_FAB2_LIB.BASEBOARD_FAB2(SCH_1):P3E_PCH_M2_SATA6G_RX_R_DP
  43 P3E_PCH_M2_SATA6G_RX_R_DN     43 @BASEBOARD_FAB2_LIB.BASEBOARD_FAB2(SCH_1):P3E_PCH_M2_SATA6G_RX_R_DN
  45    GND     45 @BASEBOARD_FAB2_LIB.BASEBOARD_FAB2(SCH_1):GND
  47 P3E_PCH_M2_SATA6G_TX_R_DN     47 @BASEBOARD_FAB2_LIB.BASEBOARD_FAB2(SCH_1):P3E_PCH_M2_SATA6G_TX_R_DN
  49 P3E_PCH_M2_SATA6G_TX_R_DP     49 @BASEBOARD_FAB2_LIB.BASEBOARD_FAB2(SCH_1):P3E_PCH_M2_SATA6G_TX_R_DP
  51    GND     51 @BASEBOARD_FAB2_LIB.BASEBOARD_FAB2(SCH_1):GND
  53 CLK_100M_M2_DN     53 @BASEBOARD_FAB2_LIB.BASEBOARD_FAB2(SCH_1):CLK_100M_M2_DN
  55 CLK_100M_M2_DP     55 @BASEBOARD_FAB2_LIB.BASEBOARD_FAB2(SCH_1):CLK_100M_M2_DP
  57    GND     57 @BASEBOARD_FAB2_LIB.BASEBOARD_FAB2(SCH_1):GND
  67     NC     67     NC
  69 FM_M2_SSD_PEDET     69 @BASEBOARD_FAB2_LIB.BASEBOARD_FAB2(SCH_1):FM_M2_SSD_PEDET
  71    GND     71 @BASEBOARD_FAB2_LIB.BASEBOARD_FAB2(SCH_1):GND
  73    GND     73 @BASEBOARD_FAB2_LIB.BASEBOARD_FAB2(SCH_1):GND
  75    GND     75 @BASEBOARD_FAB2_LIB.BASEBOARD_FAB2(SCH_1):GND
   2   P3V3      2 @BASEBOARD_FAB2_LIB.BASEBOARD_FAB2(SCH_1):P3V3
   4   P3V3      4 @BASEBOARD_FAB2_LIB.BASEBOARD_FAB2(SCH_1):P3V3
   6 NC_M2<0>      6 @BASEBOARD_FAB2_LIB.BASEBOARD_FAB2(SCH_1):NC_M2(0)
   8 NC_M2<1>      8 @BASEBOARD_FAB2_LIB.BASEBOARD_FAB2(SCH_1):NC_M2(1)
  10 TP_LED_M2_ACT_N     10 @BASEBOARD_FAB2_LIB.BASEBOARD_FAB2(SCH_1):TP_LED_M2_ACT_N
  12   P3V3     12 @BASEBOARD_FAB2_LIB.BASEBOARD_FAB2(SCH_1):P3V3
  14   P3V3     14 @BASEBOARD_FAB2_LIB.BASEBOARD_FAB2(SCH_1):P3V3
  16   P3V3     16 @BASEBOARD_FAB2_LIB.BASEBOARD_FAB2(SCH_1):P3V3
  18   P3V3     18 @BASEBOARD_FAB2_LIB.BASEBOARD_FAB2(SCH_1):P3V3
  20     NC     20     NC
  22     NC     22     NC
  24     NC     24     NC
  26     NC     26     NC
  28     NC     28     NC
  30     NC     30     NC
  32     NC     32     NC
  34     NC     34     NC
  36     NC     36     NC
  38 TP_M2_DEVSLP     38 @BASEBOARD_FAB2_LIB.BASEBOARD_FAB2(SCH_1):TP_M2_DEVSLP
  40 SMB_M2_SCL     40 @BASEBOARD_FAB2_LIB.BASEBOARD_FAB2(SCH_1):SMB_M2_SCL
  42 SMB_M2_SDA     42 @BASEBOARD_FAB2_LIB.BASEBOARD_FAB2(SCH_1):SMB_M2_SDA
  44 SMB_M2_ALT_N     44 @BASEBOARD_FAB2_LIB.BASEBOARD_FAB2(SCH_1):SMB_M2_ALT_N
  46     NC     46     NC
  48     NC     48     NC
  50 RST_PCIE_M2_DEV_IC_N     50 @BASEBOARD_FAB2_LIB.BASEBOARD_FAB2(SCH_1):RST_PCIE_M2_DEV_IC_N
  52 PU_M2_CLK_REQ_N     52 @BASEBOARD_FAB2_LIB.BASEBOARD_FAB2(SCH_1):PU_M2_CLK_REQ_N
  54 FM_PE_M2_WAKE_N     54 @BASEBOARD_FAB2_LIB.BASEBOARD_FAB2(SCH_1):FM_PE_M2_WAKE_N
  56     NC     56     NC
  58     NC     58     NC
  68 TP_M2_32M_SUSCLK     68 @BASEBOARD_FAB2_LIB.BASEBOARD_FAB2(SCH_1):TP_M2_32M_SUSCLK
  70   P3V3     70 @BASEBOARD_FAB2_LIB.BASEBOARD_FAB2(SCH_1):P3V3
  72   P3V3     72 @BASEBOARD_FAB2_LIB.BASEBOARD_FAB2(SCH_1):P3V3
  74   P3V3     74 @BASEBOARD_FAB2_LIB.BASEBOARD_FAB2(SCH_1):P3V3
  76    GND     76 @BASEBOARD_FAB2_LIB.BASEBOARD_FAB2(SCH_1):GND
  77    GND     77 @BASEBOARD_FAB2_LIB.BASEBOARD_FAB2(SCH_1):GND
 NP1     NC    NP1     NC
 NP2     NC    NP2     NC

CAP_0402-0.22UF,16V,10%,X7R,A3A  I167  C2T11
   1 P3E_PCH_M2_TX_C_DN<1>      A @BASEBOARD_FAB2_LIB.BASEBOARD_FAB2(SCH_1):P3E_PCH_M2_TX_C_DN(1)
   2 P3E_PCH_M2_TX_DN<1>      B @BASEBOARD_FAB2_LIB.BASEBOARD_FAB2(SCH_1):P3E_PCH_M2_TX_DN(1)

CAP_0402-0.22UF,16V,10%,X7R,A3A  I168  C2T10
   1 P3E_PCH_M2_TX_C_DP<1>      A @BASEBOARD_FAB2_LIB.BASEBOARD_FAB2(SCH_1):P3E_PCH_M2_TX_C_DP(1)
   2 P3E_PCH_M2_TX_DP<1>      B @BASEBOARD_FAB2_LIB.BASEBOARD_FAB2(SCH_1):P3E_PCH_M2_TX_DP(1)

CAP_0402-0.22UF,16V,10%,X7R,A3A  I171  C2T14
   1 P3E_PCH_M2_TX_C_DN<2>      A @BASEBOARD_FAB2_LIB.BASEBOARD_FAB2(SCH_1):P3E_PCH_M2_TX_C_DN(2)
   2 P3E_PCH_M2_TX_DN<2>      B @BASEBOARD_FAB2_LIB.BASEBOARD_FAB2(SCH_1):P3E_PCH_M2_TX_DN(2)

CAP_0402-0.22UF,16V,10%,X7R,A3A  I172  C2T13
   1 P3E_PCH_M2_TX_C_DP<2>      A @BASEBOARD_FAB2_LIB.BASEBOARD_FAB2(SCH_1):P3E_PCH_M2_TX_C_DP(2)
   2 P3E_PCH_M2_TX_DP<2>      B @BASEBOARD_FAB2_LIB.BASEBOARD_FAB2(SCH_1):P3E_PCH_M2_TX_DP(2)

CAP_0402-0.22UF,16V,10%,X7R,A3A  I179  C2T20
   1 P3E_PCH_M2_TX_C_DP<3>      A @BASEBOARD_FAB2_LIB.BASEBOARD_FAB2(SCH_1):P3E_PCH_M2_TX_C_DP(3)
   2 P3E_PCH_M2_TX_DP<3>      B @BASEBOARD_FAB2_LIB.BASEBOARD_FAB2(SCH_1):P3E_PCH_M2_TX_DP(3)

CAP_0402-0.22UF,16V,10%,X7R,A3A  I180  C2T23
   1 P3E_PCH_M2_TX_C_DN<3>      A @BASEBOARD_FAB2_LIB.BASEBOARD_FAB2(SCH_1):P3E_PCH_M2_TX_C_DN(3)
   2 P3E_PCH_M2_TX_DN<3>      B @BASEBOARD_FAB2_LIB.BASEBOARD_FAB2(SCH_1):P3E_PCH_M2_TX_DN(3)

RES_0402-0.0,5%,1/16W,CHIP,G21A  I183  R32W10
   1 SMB_M2_SCL      A @BASEBOARD_FAB2_LIB.BASEBOARD_FAB2(SCH_1):SMB_M2_SCL
   2 SMB_M2_SCL_R      B @BASEBOARD_FAB2_LIB.BASEBOARD_FAB2(SCH_1):SMB_M2_SCL_R

RES_0402-0.0,5%,1/16W,CHIP,G21A  I184  R32W11
   1 SMB_M2_SDA      A @BASEBOARD_FAB2_LIB.BASEBOARD_FAB2(SCH_1):SMB_M2_SDA
   2 SMB_M2_SDA_R      B @BASEBOARD_FAB2_LIB.BASEBOARD_FAB2(SCH_1):SMB_M2_SDA_R

RES_0402-0.0,5%,1/16W,CHIP,G21A  I187  R32W12
   1 SMB_M2_ALT_N      A @BASEBOARD_FAB2_LIB.BASEBOARD_FAB2(SCH_1):SMB_M2_ALT_N
   2 SMB_M2_ALT_R_N      B @BASEBOARD_FAB2_LIB.BASEBOARD_FAB2(SCH_1):SMB_M2_ALT_R_N

CAP_A_0402V-0.1UF,16V,10%,X7R,A  I188  C32W1
   1 P1V8_M2      A @BASEBOARD_FAB2_LIB.BASEBOARD_FAB2(SCH_1):P1V8_M2
   2    GND      B @BASEBOARD_FAB2_LIB.BASEBOARD_FAB2(SCH_1):GND

CAP_A_0402V-0.1UF,16V,10%,X7R,A  I190  C32W3
   1 P1V8_M2      A @BASEBOARD_FAB2_LIB.BASEBOARD_FAB2(SCH_1):P1V8_M2
   2    GND      B @BASEBOARD_FAB2_LIB.BASEBOARD_FAB2(SCH_1):GND

TCA9517DGKR-GP_DISCRET-G8-TCA9A  I191  U32W1
   1 P1V8_M2   VCCA @BASEBOARD_FAB2_LIB.BASEBOARD_FAB2(SCH_1):P1V8_M2
   2 SMB_M2_SCL_R   SCLA @BASEBOARD_FAB2_LIB.BASEBOARD_FAB2(SCH_1):SMB_M2_SCL_R
   3 SMB_M2_SDA_R   SDAA @BASEBOARD_FAB2_LIB.BASEBOARD_FAB2(SCH_1):SMB_M2_SDA_R
   4    GND    GND @BASEBOARD_FAB2_LIB.BASEBOARD_FAB2(SCH_1):GND
   8 P3V3_STBY   VCCB @BASEBOARD_FAB2_LIB.BASEBOARD_FAB2(SCH_1):P3V3_STBY
   7 SMB_OCP_LAN_STBY_LVC3_SCL   SCLB @BASEBOARD_FAB2_LIB.BASEBOARD_FAB2(SCH_1):SMB_OCP_LAN_STBY_LVC3_SCL
   6 SMB_OCP_LAN_STBY_LVC3_SDA   SDAB @BASEBOARD_FAB2_LIB.BASEBOARD_FAB2(SCH_1):SMB_OCP_LAN_STBY_LVC3_SDA
   5 PD_SMB_M2_EN     EN @BASEBOARD_FAB2_LIB.BASEBOARD_FAB2(SCH_1):PD_SMB_M2_EN

CAP_A_0402V-0.1UF,16V,10%,X7R,A  I193  C32W2
   1 P3V3_STBY      A @BASEBOARD_FAB2_LIB.BASEBOARD_FAB2(SCH_1):P3V3_STBY
   2    GND      B @BASEBOARD_FAB2_LIB.BASEBOARD_FAB2(SCH_1):GND

CAP_A_0402V-0.1UF,16V,10%,X7R,A  I196  C32W4
   1 P3V3_STBY      A @BASEBOARD_FAB2_LIB.BASEBOARD_FAB2(SCH_1):P3V3_STBY
   2    GND      B @BASEBOARD_FAB2_LIB.BASEBOARD_FAB2(SCH_1):GND

RES_0402-10.0K,1%,1/16W,CHIP,GA  I200  R32W9
   1 PD_SMB_M2_EN      A @BASEBOARD_FAB2_LIB.BASEBOARD_FAB2(SCH_1):PD_SMB_M2_EN
   2    GND      B @BASEBOARD_FAB2_LIB.BASEBOARD_FAB2(SCH_1):GND

TCA9517DGKR-GP_DISCRET-G8-TCA9A  I204  U32W2
   1 P1V8_M2   VCCA @BASEBOARD_FAB2_LIB.BASEBOARD_FAB2(SCH_1):P1V8_M2
   2 SMB_M2_ALT_R_N   SCLA @BASEBOARD_FAB2_LIB.BASEBOARD_FAB2(SCH_1):SMB_M2_ALT_R_N
   3     NC   SDAA     NC
   4    GND    GND @BASEBOARD_FAB2_LIB.BASEBOARD_FAB2(SCH_1):GND
   8 P3V3_STBY   VCCB @BASEBOARD_FAB2_LIB.BASEBOARD_FAB2(SCH_1):P3V3_STBY
   7 IRQ_MEZZ_LAN_ALERT_N   SCLB @BASEBOARD_FAB2_LIB.BASEBOARD_FAB2(SCH_1):IRQ_MEZZ_LAN_ALERT_N
   6     NC   SDAB     NC
   5 PD_SMB_M2_EN     EN @BASEBOARD_FAB2_LIB.BASEBOARD_FAB2(SCH_1):PD_SMB_M2_EN

RES_0402-3.3K,5%,1/16W,CHIP,G2A  I206  R32W3
   1 VREF_LMV431_1V42      A @BASEBOARD_FAB2_LIB.BASEBOARD_FAB2(SCH_1):VREF_LMV431_1V42
   2    GND      B @BASEBOARD_FAB2_LIB.BASEBOARD_FAB2(SCH_1):GND

RES_0402-1.5K,1%,1/16W,CHIP,G2A  I207  R32W2
   1 P1V8_M2      A @BASEBOARD_FAB2_LIB.BASEBOARD_FAB2(SCH_1):P1V8_M2
   2 VREF_LMV431_1V42      B @BASEBOARD_FAB2_LIB.BASEBOARD_FAB2(SCH_1):VREF_LMV431_1V42

RES_0402-4.02K,1%,1/16W,CHIP,GA  I208  R32W1
   1   P3V3      A @BASEBOARD_FAB2_LIB.BASEBOARD_FAB2(SCH_1):P3V3
   2 P1V8_M2      B @BASEBOARD_FAB2_LIB.BASEBOARD_FAB2(SCH_1):P1V8_M2

RES_0402-49.9K,1%,1/16W,CHIP,GA  I211  R32W4
   1 P1V8_M2      A @BASEBOARD_FAB2_LIB.BASEBOARD_FAB2(SCH_1):P1V8_M2
   2    GND      B @BASEBOARD_FAB2_LIB.BASEBOARD_FAB2(SCH_1):GND

LMV431AIMFX-GP_DISCRET-G5-LMV4A  I213  VR32W1
   1 VREF_LMV431_1V42    REF @BASEBOARD_FAB2_LIB.BASEBOARD_FAB2(SCH_1):VREF_LMV431_1V42
   2 P1V8_M2 CATHODE @BASEBOARD_FAB2_LIB.BASEBOARD_FAB2(SCH_1):P1V8_M2
   3    GND  ANODE @BASEBOARD_FAB2_LIB.BASEBOARD_FAB2(SCH_1):GND

RES_0402-2.0K,1%,1/16W,CHIP,G2A  I214  R32W6
   1 P1V8_M2      A @BASEBOARD_FAB2_LIB.BASEBOARD_FAB2(SCH_1):P1V8_M2
   2 SMB_M2_SDA      B @BASEBOARD_FAB2_LIB.BASEBOARD_FAB2(SCH_1):SMB_M2_SDA

RES_0402-2.0K,1%,1/16W,CHIP,G2A  I215  R32W7
   1 P1V8_M2      A @BASEBOARD_FAB2_LIB.BASEBOARD_FAB2(SCH_1):P1V8_M2
   2 SMB_M2_ALT_N      B @BASEBOARD_FAB2_LIB.BASEBOARD_FAB2(SCH_1):SMB_M2_ALT_N

RES_0402-2.0K,1%,1/16W,CHIP,G2A  I216  R32W5
   1 P1V8_M2      A @BASEBOARD_FAB2_LIB.BASEBOARD_FAB2(SCH_1):P1V8_M2
   2 SMB_M2_SCL      B @BASEBOARD_FAB2_LIB.BASEBOARD_FAB2(SCH_1):SMB_M2_SCL

CAP_0402-1.0UF,16V,10%,X6S,D97A  I217  C32W5
   1 P1V8_M2      A @BASEBOARD_FAB2_LIB.BASEBOARD_FAB2(SCH_1):P1V8_M2
   2    GND      B @BASEBOARD_FAB2_LIB.BASEBOARD_FAB2(SCH_1):GND


DRAWING: @BASEBOARD_FAB2_LIB.BASEBOARD_FAB2(SCH_1):PAGE186 

CAP_0805-10UF,16V,10%,X6S,C953A  I3  C1M27
   1 P12V_STBY      A @BASEBOARD_FAB2_LIB.BASEBOARD_FAB2(SCH_1):P12V_STBY
   2    GND      B @BASEBOARD_FAB2_LIB.BASEBOARD_FAB2(SCH_1):GND

CAP_0805-10UF,16V,10%,X6S,C953A  I6  C1M26
   1 P12V_STBY      A @BASEBOARD_FAB2_LIB.BASEBOARD_FAB2(SCH_1):P12V_STBY
   2    GND      B @BASEBOARD_FAB2_LIB.BASEBOARD_FAB2(SCH_1):GND

CAP_A_0402V-0.1UF,16V,10%,X7R,A  I7  C1M23
   1 P12V_STBY      A @BASEBOARD_FAB2_LIB.BASEBOARD_FAB2(SCH_1):P12V_STBY
   2    GND      B @BASEBOARD_FAB2_LIB.BASEBOARD_FAB2(SCH_1):GND

CAP_A_0402V-0.1UF,16V,10%,X7R,A  I8  C1M22
   1 P12V_STBY      A @BASEBOARD_FAB2_LIB.BASEBOARD_FAB2(SCH_1):P12V_STBY
   2    GND      B @BASEBOARD_FAB2_LIB.BASEBOARD_FAB2(SCH_1):GND

CAP_A_0402V-0.1UF,16V,10%,X7R,A  I10  C1M24
   1   P3V3      A @BASEBOARD_FAB2_LIB.BASEBOARD_FAB2(SCH_1):P3V3
   2    GND      B @BASEBOARD_FAB2_LIB.BASEBOARD_FAB2(SCH_1):GND

RES_0402-200.0,1%,1/16W,CHIP,GA  I220  R1M14
   1 RST_PCIE_CPU_DEV0_N      A @BASEBOARD_FAB2_LIB.BASEBOARD_FAB2(SCH_1):RST_PCIE_CPU_DEV0_N
   2 RST_PCIE_CPU_DEV0_R_N      B @BASEBOARD_FAB2_LIB.BASEBOARD_FAB2(SCH_1):RST_PCIE_CPU_DEV0_R_N

CAP_A_0402V-0.1UF,16V,10%,X7R,A  I270  C1M20
   1 P3V3_STBY      A @BASEBOARD_FAB2_LIB.BASEBOARD_FAB2(SCH_1):P3V3_STBY
   2    GND      B @BASEBOARD_FAB2_LIB.BASEBOARD_FAB2(SCH_1):GND

CAP_A_0402V-1.0UF,6.3V,10%,X6SA  I334  C1M21
   1   P3V3      A @BASEBOARD_FAB2_LIB.BASEBOARD_FAB2(SCH_1):P3V3
   2    GND      B @BASEBOARD_FAB2_LIB.BASEBOARD_FAB2(SCH_1):GND

CAP_A_0402V-1.0UF,6.3V,10%,X6SA  I335  C1M25
   1 P3V3_STBY      A @BASEBOARD_FAB2_LIB.BASEBOARD_FAB2(SCH_1):P3V3_STBY
   2    GND      B @BASEBOARD_FAB2_LIB.BASEBOARD_FAB2(SCH_1):GND

SCONN120_A28699018_SM-SCONN,A2A  I336  J9B3
   1 FM_MEZZA_PRSNT1_N    IO1 @BASEBOARD_FAB2_LIB.BASEBOARD_FAB2(SCH_1):FM_MEZZA_PRSNT1_N
  10    GND   IO10 @BASEBOARD_FAB2_LIB.BASEBOARD_FAB2(SCH_1):GND
 100    GND  IO100 @BASEBOARD_FAB2_LIB.BASEBOARD_FAB2(SCH_1):GND
 101 P3E_CPU0_PE3_OCP_RXN<10>  IO101 @BASEBOARD_FAB2_LIB.BASEBOARD_FAB2(SCH_1):P3E_CPU0_PE3_OCP_RXN(10)
 102    GND  IO102 @BASEBOARD_FAB2_LIB.BASEBOARD_FAB2(SCH_1):GND
 103    GND  IO103 @BASEBOARD_FAB2_LIB.BASEBOARD_FAB2(SCH_1):GND
 104 P3E_OCP_CPU0_PE3_C_TXP<9>  IO104 @BASEBOARD_FAB2_LIB.BASEBOARD_FAB2(SCH_1):P3E_OCP_CPU0_PE3_C_TXP(9)
 105    GND  IO105 @BASEBOARD_FAB2_LIB.BASEBOARD_FAB2(SCH_1):GND
 106 P3E_OCP_CPU0_PE3_C_TXN<9>  IO106 @BASEBOARD_FAB2_LIB.BASEBOARD_FAB2(SCH_1):P3E_OCP_CPU0_PE3_C_TXN(9)
 107 P3E_CPU0_PE3_OCP_RXP<9>  IO107 @BASEBOARD_FAB2_LIB.BASEBOARD_FAB2(SCH_1):P3E_CPU0_PE3_OCP_RXP(9)
 108    GND  IO108 @BASEBOARD_FAB2_LIB.BASEBOARD_FAB2(SCH_1):GND
 109 P3E_CPU0_PE3_OCP_RXN<9>  IO109 @BASEBOARD_FAB2_LIB.BASEBOARD_FAB2(SCH_1):P3E_CPU0_PE3_OCP_RXN(9)
  11    GND   IO11 @BASEBOARD_FAB2_LIB.BASEBOARD_FAB2(SCH_1):GND
 110    GND  IO110 @BASEBOARD_FAB2_LIB.BASEBOARD_FAB2(SCH_1):GND
 111    GND  IO111 @BASEBOARD_FAB2_LIB.BASEBOARD_FAB2(SCH_1):GND
 112 P3E_OCP_CPU0_PE3_C_TXP<8>  IO112 @BASEBOARD_FAB2_LIB.BASEBOARD_FAB2(SCH_1):P3E_OCP_CPU0_PE3_C_TXP(8)
 113    GND  IO113 @BASEBOARD_FAB2_LIB.BASEBOARD_FAB2(SCH_1):GND
 114 P3E_OCP_CPU0_PE3_C_TXN<8>  IO114 @BASEBOARD_FAB2_LIB.BASEBOARD_FAB2(SCH_1):P3E_OCP_CPU0_PE3_C_TXN(8)
 115 P3E_CPU0_PE3_OCP_RXP<8>  IO115 @BASEBOARD_FAB2_LIB.BASEBOARD_FAB2(SCH_1):P3E_CPU0_PE3_OCP_RXP(8)
 116    GND  IO116 @BASEBOARD_FAB2_LIB.BASEBOARD_FAB2(SCH_1):GND
 117 P3E_CPU0_PE3_OCP_RXN<8>  IO117 @BASEBOARD_FAB2_LIB.BASEBOARD_FAB2(SCH_1):P3E_CPU0_PE3_OCP_RXN(8)
 118    GND  IO118 @BASEBOARD_FAB2_LIB.BASEBOARD_FAB2(SCH_1):GND
 119    GND  IO119 @BASEBOARD_FAB2_LIB.BASEBOARD_FAB2(SCH_1):GND
  12 P3V3_STBY   IO12 @BASEBOARD_FAB2_LIB.BASEBOARD_FAB2(SCH_1):P3V3_STBY
 120 FM_OCP_MEZZA_PRES_N  IO120 @BASEBOARD_FAB2_LIB.BASEBOARD_FAB2(SCH_1):FM_OCP_MEZZA_PRES_N
  13 P3V3_STBY   IO13 @BASEBOARD_FAB2_LIB.BASEBOARD_FAB2(SCH_1):P3V3_STBY
  14    GND   IO14 @BASEBOARD_FAB2_LIB.BASEBOARD_FAB2(SCH_1):GND
  15    GND   IO15 @BASEBOARD_FAB2_LIB.BASEBOARD_FAB2(SCH_1):GND
  16    GND   IO16 @BASEBOARD_FAB2_LIB.BASEBOARD_FAB2(SCH_1):GND
  17    GND   IO17 @BASEBOARD_FAB2_LIB.BASEBOARD_FAB2(SCH_1):GND
  18   P3V3   IO18 @BASEBOARD_FAB2_LIB.BASEBOARD_FAB2(SCH_1):P3V3
  19   P3V3   IO19 @BASEBOARD_FAB2_LIB.BASEBOARD_FAB2(SCH_1):P3V3
   2 P12V_STBY    IO2 @BASEBOARD_FAB2_LIB.BASEBOARD_FAB2(SCH_1):P12V_STBY
  20   P3V3   IO20 @BASEBOARD_FAB2_LIB.BASEBOARD_FAB2(SCH_1):P3V3
  21   P3V3   IO21 @BASEBOARD_FAB2_LIB.BASEBOARD_FAB2(SCH_1):P3V3
  22   P3V3   IO22 @BASEBOARD_FAB2_LIB.BASEBOARD_FAB2(SCH_1):P3V3
  23   P3V3   IO23 @BASEBOARD_FAB2_LIB.BASEBOARD_FAB2(SCH_1):P3V3
  24   P3V3   IO24 @BASEBOARD_FAB2_LIB.BASEBOARD_FAB2(SCH_1):P3V3
  25   P3V3   IO25 @BASEBOARD_FAB2_LIB.BASEBOARD_FAB2(SCH_1):P3V3
  26    GND   IO26 @BASEBOARD_FAB2_LIB.BASEBOARD_FAB2(SCH_1):GND
  27 RMII_BMC_OCP_CRSDV_R   IO27 @BASEBOARD_FAB2_LIB.BASEBOARD_FAB2(SCH_1):RMII_BMC_OCP_CRSDV_R
  28 IRQ_MEZZ_LAN_ALERT_N   IO28 @BASEBOARD_FAB2_LIB.BASEBOARD_FAB2(SCH_1):IRQ_MEZZ_LAN_ALERT_N
  29 CLK_50M_CKMNG_OCP   IO29 @BASEBOARD_FAB2_LIB.BASEBOARD_FAB2(SCH_1):CLK_50M_CKMNG_OCP
   3 P5V_STBY    IO3 @BASEBOARD_FAB2_LIB.BASEBOARD_FAB2(SCH_1):P5V_STBY
  30 SMB_OCP_FRU_STBY_LVC3_SCL   IO30 @BASEBOARD_FAB2_LIB.BASEBOARD_FAB2(SCH_1):SMB_OCP_FRU_STBY_LVC3_SCL
  31 RMII_BMC_OCP_TXEN   IO31 @BASEBOARD_FAB2_LIB.BASEBOARD_FAB2(SCH_1):RMII_BMC_OCP_TXEN
  32 SMB_OCP_FRU_STBY_LVC3_SDA   IO32 @BASEBOARD_FAB2_LIB.BASEBOARD_FAB2(SCH_1):SMB_OCP_FRU_STBY_LVC3_SDA
  33 RST_PCIE_CPU_DEV0_R_N   IO33 @BASEBOARD_FAB2_LIB.BASEBOARD_FAB2(SCH_1):RST_PCIE_CPU_DEV0_R_N
  34 FM_PE_OCP_WAKE_N   IO34 @BASEBOARD_FAB2_LIB.BASEBOARD_FAB2(SCH_1):FM_PE_OCP_WAKE_N
  35 SMB_OCP_LAN_STBY_LVC3_SCL   IO35 @BASEBOARD_FAB2_LIB.BASEBOARD_FAB2(SCH_1):SMB_OCP_LAN_STBY_LVC3_SCL
  36 RMII_BMC_OCP_RXER_R   IO36 @BASEBOARD_FAB2_LIB.BASEBOARD_FAB2(SCH_1):RMII_BMC_OCP_RXER_R
  37 SMB_OCP_LAN_STBY_LVC3_SDA   IO37 @BASEBOARD_FAB2_LIB.BASEBOARD_FAB2(SCH_1):SMB_OCP_LAN_STBY_LVC3_SDA
  38    GND   IO38 @BASEBOARD_FAB2_LIB.BASEBOARD_FAB2(SCH_1):GND
  39    GND   IO39 @BASEBOARD_FAB2_LIB.BASEBOARD_FAB2(SCH_1):GND
   4 P12V_STBY    IO4 @BASEBOARD_FAB2_LIB.BASEBOARD_FAB2(SCH_1):P12V_STBY
  40 RMII_BMC_OCP_TXD0   IO40 @BASEBOARD_FAB2_LIB.BASEBOARD_FAB2(SCH_1):RMII_BMC_OCP_TXD0
  41    GND   IO41 @BASEBOARD_FAB2_LIB.BASEBOARD_FAB2(SCH_1):GND
  42 RMII_BMC_OCP_TXD1   IO42 @BASEBOARD_FAB2_LIB.BASEBOARD_FAB2(SCH_1):RMII_BMC_OCP_TXD1
  43 RMII_BMC_OCP_RXD0_R   IO43 @BASEBOARD_FAB2_LIB.BASEBOARD_FAB2(SCH_1):RMII_BMC_OCP_RXD0_R
  44    GND   IO44 @BASEBOARD_FAB2_LIB.BASEBOARD_FAB2(SCH_1):GND
  45 RMII_BMC_OCP_RXD1_R   IO45 @BASEBOARD_FAB2_LIB.BASEBOARD_FAB2(SCH_1):RMII_BMC_OCP_RXD1_R
  46    GND   IO46 @BASEBOARD_FAB2_LIB.BASEBOARD_FAB2(SCH_1):GND
  47    GND   IO47 @BASEBOARD_FAB2_LIB.BASEBOARD_FAB2(SCH_1):GND
  48 CLK_100M_MEZZ1_DP   IO48 @BASEBOARD_FAB2_LIB.BASEBOARD_FAB2(SCH_1):CLK_100M_MEZZ1_DP
  49    GND   IO49 @BASEBOARD_FAB2_LIB.BASEBOARD_FAB2(SCH_1):GND
   5 P5V_STBY    IO5 @BASEBOARD_FAB2_LIB.BASEBOARD_FAB2(SCH_1):P5V_STBY
  50 CLK_100M_MEZZ1_DN   IO50 @BASEBOARD_FAB2_LIB.BASEBOARD_FAB2(SCH_1):CLK_100M_MEZZ1_DN
  51 CLK_100M_MEZZ2_DP   IO51 @BASEBOARD_FAB2_LIB.BASEBOARD_FAB2(SCH_1):CLK_100M_MEZZ2_DP
  52    GND   IO52 @BASEBOARD_FAB2_LIB.BASEBOARD_FAB2(SCH_1):GND
  53 CLK_100M_MEZZ2_DN   IO53 @BASEBOARD_FAB2_LIB.BASEBOARD_FAB2(SCH_1):CLK_100M_MEZZ2_DN
  54    GND   IO54 @BASEBOARD_FAB2_LIB.BASEBOARD_FAB2(SCH_1):GND
  55    GND   IO55 @BASEBOARD_FAB2_LIB.BASEBOARD_FAB2(SCH_1):GND
  56 P3E_OCP_CPU0_PE3_C_TXP<15>   IO56 @BASEBOARD_FAB2_LIB.BASEBOARD_FAB2(SCH_1):P3E_OCP_CPU0_PE3_C_TXP(15)
  57    GND   IO57 @BASEBOARD_FAB2_LIB.BASEBOARD_FAB2(SCH_1):GND
  58 P3E_OCP_CPU0_PE3_C_TXN<15>   IO58 @BASEBOARD_FAB2_LIB.BASEBOARD_FAB2(SCH_1):P3E_OCP_CPU0_PE3_C_TXN(15)
  59 P3E_CPU0_PE3_OCP_RXP<15>   IO59 @BASEBOARD_FAB2_LIB.BASEBOARD_FAB2(SCH_1):P3E_CPU0_PE3_OCP_RXP(15)
   6 P12V_STBY    IO6 @BASEBOARD_FAB2_LIB.BASEBOARD_FAB2(SCH_1):P12V_STBY
  60    GND   IO60 @BASEBOARD_FAB2_LIB.BASEBOARD_FAB2(SCH_1):GND
  61 P3E_CPU0_PE3_OCP_RXN<15>   IO61 @BASEBOARD_FAB2_LIB.BASEBOARD_FAB2(SCH_1):P3E_CPU0_PE3_OCP_RXN(15)
  62    GND   IO62 @BASEBOARD_FAB2_LIB.BASEBOARD_FAB2(SCH_1):GND
  63    GND   IO63 @BASEBOARD_FAB2_LIB.BASEBOARD_FAB2(SCH_1):GND
  64 P3E_OCP_CPU0_PE3_C_TXP<14>   IO64 @BASEBOARD_FAB2_LIB.BASEBOARD_FAB2(SCH_1):P3E_OCP_CPU0_PE3_C_TXP(14)
  65    GND   IO65 @BASEBOARD_FAB2_LIB.BASEBOARD_FAB2(SCH_1):GND
  66 P3E_OCP_CPU0_PE3_C_TXN<14>   IO66 @BASEBOARD_FAB2_LIB.BASEBOARD_FAB2(SCH_1):P3E_OCP_CPU0_PE3_C_TXN(14)
  67 P3E_CPU0_PE3_OCP_RXP<14>   IO67 @BASEBOARD_FAB2_LIB.BASEBOARD_FAB2(SCH_1):P3E_CPU0_PE3_OCP_RXP(14)
  68    GND   IO68 @BASEBOARD_FAB2_LIB.BASEBOARD_FAB2(SCH_1):GND
  69 P3E_CPU0_PE3_OCP_RXN<14>   IO69 @BASEBOARD_FAB2_LIB.BASEBOARD_FAB2(SCH_1):P3E_CPU0_PE3_OCP_RXN(14)
   7 P5V_STBY    IO7 @BASEBOARD_FAB2_LIB.BASEBOARD_FAB2(SCH_1):P5V_STBY
  70    GND   IO70 @BASEBOARD_FAB2_LIB.BASEBOARD_FAB2(SCH_1):GND
  71    GND   IO71 @BASEBOARD_FAB2_LIB.BASEBOARD_FAB2(SCH_1):GND
  72 P3E_OCP_CPU0_PE3_C_TXP<13>   IO72 @BASEBOARD_FAB2_LIB.BASEBOARD_FAB2(SCH_1):P3E_OCP_CPU0_PE3_C_TXP(13)
  73    GND   IO73 @BASEBOARD_FAB2_LIB.BASEBOARD_FAB2(SCH_1):GND
  74 P3E_OCP_CPU0_PE3_C_TXN<13>   IO74 @BASEBOARD_FAB2_LIB.BASEBOARD_FAB2(SCH_1):P3E_OCP_CPU0_PE3_C_TXN(13)
  75 P3E_CPU0_PE3_OCP_RXP<13>   IO75 @BASEBOARD_FAB2_LIB.BASEBOARD_FAB2(SCH_1):P3E_CPU0_PE3_OCP_RXP(13)
  76    GND   IO76 @BASEBOARD_FAB2_LIB.BASEBOARD_FAB2(SCH_1):GND
  77 P3E_CPU0_PE3_OCP_RXN<13>   IO77 @BASEBOARD_FAB2_LIB.BASEBOARD_FAB2(SCH_1):P3E_CPU0_PE3_OCP_RXN(13)
  78    GND   IO78 @BASEBOARD_FAB2_LIB.BASEBOARD_FAB2(SCH_1):GND
  79    GND   IO79 @BASEBOARD_FAB2_LIB.BASEBOARD_FAB2(SCH_1):GND
   8    GND    IO8 @BASEBOARD_FAB2_LIB.BASEBOARD_FAB2(SCH_1):GND
  80 P3E_OCP_CPU0_PE3_C_TXP<12>   IO80 @BASEBOARD_FAB2_LIB.BASEBOARD_FAB2(SCH_1):P3E_OCP_CPU0_PE3_C_TXP(12)
  81    GND   IO81 @BASEBOARD_FAB2_LIB.BASEBOARD_FAB2(SCH_1):GND
  82 P3E_OCP_CPU0_PE3_C_TXN<12>   IO82 @BASEBOARD_FAB2_LIB.BASEBOARD_FAB2(SCH_1):P3E_OCP_CPU0_PE3_C_TXN(12)
  83 P3E_CPU0_PE3_OCP_RXP<12>   IO83 @BASEBOARD_FAB2_LIB.BASEBOARD_FAB2(SCH_1):P3E_CPU0_PE3_OCP_RXP(12)
  84    GND   IO84 @BASEBOARD_FAB2_LIB.BASEBOARD_FAB2(SCH_1):GND
  85 P3E_CPU0_PE3_OCP_RXN<12>   IO85 @BASEBOARD_FAB2_LIB.BASEBOARD_FAB2(SCH_1):P3E_CPU0_PE3_OCP_RXN(12)
  86    GND   IO86 @BASEBOARD_FAB2_LIB.BASEBOARD_FAB2(SCH_1):GND
  87    GND   IO87 @BASEBOARD_FAB2_LIB.BASEBOARD_FAB2(SCH_1):GND
  88 P3E_OCP_CPU0_PE3_C_TXP<11>   IO88 @BASEBOARD_FAB2_LIB.BASEBOARD_FAB2(SCH_1):P3E_OCP_CPU0_PE3_C_TXP(11)
  89    GND   IO89 @BASEBOARD_FAB2_LIB.BASEBOARD_FAB2(SCH_1):GND
   9    GND    IO9 @BASEBOARD_FAB2_LIB.BASEBOARD_FAB2(SCH_1):GND
  90 P3E_OCP_CPU0_PE3_C_TXN<11>   IO90 @BASEBOARD_FAB2_LIB.BASEBOARD_FAB2(SCH_1):P3E_OCP_CPU0_PE3_C_TXN(11)
  91 P3E_CPU0_PE3_OCP_RXP<11>   IO91 @BASEBOARD_FAB2_LIB.BASEBOARD_FAB2(SCH_1):P3E_CPU0_PE3_OCP_RXP(11)
  92    GND   IO92 @BASEBOARD_FAB2_LIB.BASEBOARD_FAB2(SCH_1):GND
  93 P3E_CPU0_PE3_OCP_RXN<11>   IO93 @BASEBOARD_FAB2_LIB.BASEBOARD_FAB2(SCH_1):P3E_CPU0_PE3_OCP_RXN(11)
  94    GND   IO94 @BASEBOARD_FAB2_LIB.BASEBOARD_FAB2(SCH_1):GND
  95    GND   IO95 @BASEBOARD_FAB2_LIB.BASEBOARD_FAB2(SCH_1):GND
  96 P3E_OCP_CPU0_PE3_C_TXP<10>   IO96 @BASEBOARD_FAB2_LIB.BASEBOARD_FAB2(SCH_1):P3E_OCP_CPU0_PE3_C_TXP(10)
  97    GND   IO97 @BASEBOARD_FAB2_LIB.BASEBOARD_FAB2(SCH_1):GND
  98 P3E_OCP_CPU0_PE3_C_TXN<10>   IO98 @BASEBOARD_FAB2_LIB.BASEBOARD_FAB2(SCH_1):P3E_OCP_CPU0_PE3_C_TXN(10)
  99 P3E_CPU0_PE3_OCP_RXP<10>   IO99 @BASEBOARD_FAB2_LIB.BASEBOARD_FAB2(SCH_1):P3E_CPU0_PE3_OCP_RXP(10)

RES_0402-0.0,5%,1/16W,CHIP,G21A  I337  R1M16
   1 RMII_BMC_OCP_RXD1      A @BASEBOARD_FAB2_LIB.BASEBOARD_FAB2(SCH_1):RMII_BMC_OCP_RXD1
   2 RMII_BMC_OCP_RXD1_R      B @BASEBOARD_FAB2_LIB.BASEBOARD_FAB2(SCH_1):RMII_BMC_OCP_RXD1_R

RES_0402-0.0,5%,1/16W,CHIP,G21A  I338  R1M17
   1 RMII_BMC_OCP_RXD0      A @BASEBOARD_FAB2_LIB.BASEBOARD_FAB2(SCH_1):RMII_BMC_OCP_RXD0
   2 RMII_BMC_OCP_RXD0_R      B @BASEBOARD_FAB2_LIB.BASEBOARD_FAB2(SCH_1):RMII_BMC_OCP_RXD0_R

RES_0402-0.0,5%,1/16W,CHIP,G21A  I339  R1M15
   1 RMII_BMC_OCP_CRSDV      A @BASEBOARD_FAB2_LIB.BASEBOARD_FAB2(SCH_1):RMII_BMC_OCP_CRSDV
   2 RMII_BMC_OCP_CRSDV_R      B @BASEBOARD_FAB2_LIB.BASEBOARD_FAB2(SCH_1):RMII_BMC_OCP_CRSDV_R

RES_0402-0.0,5%,1/16W,CHIP,G21A  I340  R1M18
   1 RMII_BMC_OCP_RXER_R      A @BASEBOARD_FAB2_LIB.BASEBOARD_FAB2(SCH_1):RMII_BMC_OCP_RXER_R
   2 RMII_BMC_OCP_RXER      B @BASEBOARD_FAB2_LIB.BASEBOARD_FAB2(SCH_1):RMII_BMC_OCP_RXER

CAP_A_0402V-0.1UF,16V,10%,X7R,A  I345  C9B10
   1 P5V_STBY      A @BASEBOARD_FAB2_LIB.BASEBOARD_FAB2(SCH_1):P5V_STBY
   2    GND      B @BASEBOARD_FAB2_LIB.BASEBOARD_FAB2(SCH_1):GND

RES_0402-10.0K,1%,1/16W,CHIP,GA  I356  R9W1
   1 P3V3_STBY      A @BASEBOARD_FAB2_LIB.BASEBOARD_FAB2(SCH_1):P3V3_STBY
   2 FM_MEZZA_PRSNT1_N      B @BASEBOARD_FAB2_LIB.BASEBOARD_FAB2(SCH_1):FM_MEZZA_PRSNT1_N

SC1U10V2KX-4-GP_SMD-BCG6-SC1U1A  I357  C9B9
   1 P5V_STBY      1 @BASEBOARD_FAB2_LIB.BASEBOARD_FAB2(SCH_1):P5V_STBY
   2    GND      2 @BASEBOARD_FAB2_LIB.BASEBOARD_FAB2(SCH_1):GND

887R2F-L-GP_SMD-RG-887R2F-L-GPA  I358  R9B7
   1 FM_MEZZA_PRSNT1_N      1 @BASEBOARD_FAB2_LIB.BASEBOARD_FAB2(SCH_1):FM_MEZZA_PRSNT1_N
   2    GND      2 @BASEBOARD_FAB2_LIB.BASEBOARD_FAB2(SCH_1):GND


DRAWING: @BASEBOARD_FAB2_LIB.BASEBOARD_FAB2(SCH_1):PAGE187 

SCONN80_E67482007_SM-CONN,E674A  I119  J8E3
   1 FM_MEZZB_PRSNT1_N    IO1 @BASEBOARD_FAB2_LIB.BASEBOARD_FAB2(SCH_1):FM_MEZZB_PRSNT1_N
  10 P3E_OCP_CPU0_PE3_C_TXP<7>   IO10 @BASEBOARD_FAB2_LIB.BASEBOARD_FAB2(SCH_1):P3E_OCP_CPU0_PE3_C_TXP(7)
  11    GND   IO11 @BASEBOARD_FAB2_LIB.BASEBOARD_FAB2(SCH_1):GND
  12 P3E_OCP_CPU0_PE3_C_TXN<7>   IO12 @BASEBOARD_FAB2_LIB.BASEBOARD_FAB2(SCH_1):P3E_OCP_CPU0_PE3_C_TXN(7)
  13 P3E_CPU0_PE3_OCP_RXN<6>   IO13 @BASEBOARD_FAB2_LIB.BASEBOARD_FAB2(SCH_1):P3E_CPU0_PE3_OCP_RXN(6)
  14    GND   IO14 @BASEBOARD_FAB2_LIB.BASEBOARD_FAB2(SCH_1):GND
  15 P3E_CPU0_PE3_OCP_RXP<6>   IO15 @BASEBOARD_FAB2_LIB.BASEBOARD_FAB2(SCH_1):P3E_CPU0_PE3_OCP_RXP(6)
  16    GND   IO16 @BASEBOARD_FAB2_LIB.BASEBOARD_FAB2(SCH_1):GND
  17    GND   IO17 @BASEBOARD_FAB2_LIB.BASEBOARD_FAB2(SCH_1):GND
  18 P3E_OCP_CPU0_PE3_C_TXP<6>   IO18 @BASEBOARD_FAB2_LIB.BASEBOARD_FAB2(SCH_1):P3E_OCP_CPU0_PE3_C_TXP(6)
  19    GND   IO19 @BASEBOARD_FAB2_LIB.BASEBOARD_FAB2(SCH_1):GND
   2 P12V_STBY    IO2 @BASEBOARD_FAB2_LIB.BASEBOARD_FAB2(SCH_1):P12V_STBY
  20 P3E_OCP_CPU0_PE3_C_TXN<6>   IO20 @BASEBOARD_FAB2_LIB.BASEBOARD_FAB2(SCH_1):P3E_OCP_CPU0_PE3_C_TXN(6)
  21 P3E_CPU0_PE3_OCP_RXN<5>   IO21 @BASEBOARD_FAB2_LIB.BASEBOARD_FAB2(SCH_1):P3E_CPU0_PE3_OCP_RXN(5)
  22    GND   IO22 @BASEBOARD_FAB2_LIB.BASEBOARD_FAB2(SCH_1):GND
  23 P3E_CPU0_PE3_OCP_RXP<5>   IO23 @BASEBOARD_FAB2_LIB.BASEBOARD_FAB2(SCH_1):P3E_CPU0_PE3_OCP_RXP(5)
  24    GND   IO24 @BASEBOARD_FAB2_LIB.BASEBOARD_FAB2(SCH_1):GND
  25    GND   IO25 @BASEBOARD_FAB2_LIB.BASEBOARD_FAB2(SCH_1):GND
  26 P3E_OCP_CPU0_PE3_C_TXP<5>   IO26 @BASEBOARD_FAB2_LIB.BASEBOARD_FAB2(SCH_1):P3E_OCP_CPU0_PE3_C_TXP(5)
  27    GND   IO27 @BASEBOARD_FAB2_LIB.BASEBOARD_FAB2(SCH_1):GND
  28 P3E_OCP_CPU0_PE3_C_TXN<5>   IO28 @BASEBOARD_FAB2_LIB.BASEBOARD_FAB2(SCH_1):P3E_OCP_CPU0_PE3_C_TXN(5)
  29 P3E_CPU0_PE3_OCP_RXN<4>   IO29 @BASEBOARD_FAB2_LIB.BASEBOARD_FAB2(SCH_1):P3E_CPU0_PE3_OCP_RXN(4)
   3    GND    IO3 @BASEBOARD_FAB2_LIB.BASEBOARD_FAB2(SCH_1):GND
  30    GND   IO30 @BASEBOARD_FAB2_LIB.BASEBOARD_FAB2(SCH_1):GND
  31 P3E_CPU0_PE3_OCP_RXP<4>   IO31 @BASEBOARD_FAB2_LIB.BASEBOARD_FAB2(SCH_1):P3E_CPU0_PE3_OCP_RXP(4)
  32    GND   IO32 @BASEBOARD_FAB2_LIB.BASEBOARD_FAB2(SCH_1):GND
  33    GND   IO33 @BASEBOARD_FAB2_LIB.BASEBOARD_FAB2(SCH_1):GND
  34 P3E_OCP_CPU0_PE3_C_TXP<4>   IO34 @BASEBOARD_FAB2_LIB.BASEBOARD_FAB2(SCH_1):P3E_OCP_CPU0_PE3_C_TXP(4)
  35    GND   IO35 @BASEBOARD_FAB2_LIB.BASEBOARD_FAB2(SCH_1):GND
  36 P3E_OCP_CPU0_PE3_C_TXN<4>   IO36 @BASEBOARD_FAB2_LIB.BASEBOARD_FAB2(SCH_1):P3E_OCP_CPU0_PE3_C_TXN(4)
  37 P3E_CPU0_PE3_OCP_RXP<3>   IO37 @BASEBOARD_FAB2_LIB.BASEBOARD_FAB2(SCH_1):P3E_CPU0_PE3_OCP_RXP(3)
  38    GND   IO38 @BASEBOARD_FAB2_LIB.BASEBOARD_FAB2(SCH_1):GND
  39 P3E_CPU0_PE3_OCP_RXN<3>   IO39 @BASEBOARD_FAB2_LIB.BASEBOARD_FAB2(SCH_1):P3E_CPU0_PE3_OCP_RXN(3)
   4 P12V_STBY    IO4 @BASEBOARD_FAB2_LIB.BASEBOARD_FAB2(SCH_1):P12V_STBY
  40    GND   IO40 @BASEBOARD_FAB2_LIB.BASEBOARD_FAB2(SCH_1):GND
  41    GND   IO41 @BASEBOARD_FAB2_LIB.BASEBOARD_FAB2(SCH_1):GND
  42 P3E_OCP_CPU0_PE3_C_TXP<3>   IO42 @BASEBOARD_FAB2_LIB.BASEBOARD_FAB2(SCH_1):P3E_OCP_CPU0_PE3_C_TXP(3)
  43    GND   IO43 @BASEBOARD_FAB2_LIB.BASEBOARD_FAB2(SCH_1):GND
  44 P3E_OCP_CPU0_PE3_C_TXN<3>   IO44 @BASEBOARD_FAB2_LIB.BASEBOARD_FAB2(SCH_1):P3E_OCP_CPU0_PE3_C_TXN(3)
  45 P3E_CPU0_PE3_OCP_RXP<2>   IO45 @BASEBOARD_FAB2_LIB.BASEBOARD_FAB2(SCH_1):P3E_CPU0_PE3_OCP_RXP(2)
  46    GND   IO46 @BASEBOARD_FAB2_LIB.BASEBOARD_FAB2(SCH_1):GND
  47 P3E_CPU0_PE3_OCP_RXN<2>   IO47 @BASEBOARD_FAB2_LIB.BASEBOARD_FAB2(SCH_1):P3E_CPU0_PE3_OCP_RXN(2)
  48    GND   IO48 @BASEBOARD_FAB2_LIB.BASEBOARD_FAB2(SCH_1):GND
  49    GND   IO49 @BASEBOARD_FAB2_LIB.BASEBOARD_FAB2(SCH_1):GND
   5 P3E_CPU0_PE3_OCP_RXP<7>    IO5 @BASEBOARD_FAB2_LIB.BASEBOARD_FAB2(SCH_1):P3E_CPU0_PE3_OCP_RXP(7)
  50 P3E_OCP_CPU0_PE3_C_TXP<2>   IO50 @BASEBOARD_FAB2_LIB.BASEBOARD_FAB2(SCH_1):P3E_OCP_CPU0_PE3_C_TXP(2)
  51    GND   IO51 @BASEBOARD_FAB2_LIB.BASEBOARD_FAB2(SCH_1):GND
  52 P3E_OCP_CPU0_PE3_C_TXN<2>   IO52 @BASEBOARD_FAB2_LIB.BASEBOARD_FAB2(SCH_1):P3E_OCP_CPU0_PE3_C_TXN(2)
  53 P3E_CPU0_PE3_OCP_RXP<1>   IO53 @BASEBOARD_FAB2_LIB.BASEBOARD_FAB2(SCH_1):P3E_CPU0_PE3_OCP_RXP(1)
  54    GND   IO54 @BASEBOARD_FAB2_LIB.BASEBOARD_FAB2(SCH_1):GND
  55 P3E_CPU0_PE3_OCP_RXN<1>   IO55 @BASEBOARD_FAB2_LIB.BASEBOARD_FAB2(SCH_1):P3E_CPU0_PE3_OCP_RXN(1)
  56    GND   IO56 @BASEBOARD_FAB2_LIB.BASEBOARD_FAB2(SCH_1):GND
  57    GND   IO57 @BASEBOARD_FAB2_LIB.BASEBOARD_FAB2(SCH_1):GND
  58 P3E_OCP_CPU0_PE3_C_TXP<1>   IO58 @BASEBOARD_FAB2_LIB.BASEBOARD_FAB2(SCH_1):P3E_OCP_CPU0_PE3_C_TXP(1)
  59    GND   IO59 @BASEBOARD_FAB2_LIB.BASEBOARD_FAB2(SCH_1):GND
   6 TP_RSVD_B1    IO6 @BASEBOARD_FAB2_LIB.BASEBOARD_FAB2(SCH_1):TP_RSVD_B1
  60 P3E_OCP_CPU0_PE3_C_TXN<1>   IO60 @BASEBOARD_FAB2_LIB.BASEBOARD_FAB2(SCH_1):P3E_OCP_CPU0_PE3_C_TXN(1)
  61 P3E_CPU0_PE3_OCP_RXP<0>   IO61 @BASEBOARD_FAB2_LIB.BASEBOARD_FAB2(SCH_1):P3E_CPU0_PE3_OCP_RXP(0)
  62    GND   IO62 @BASEBOARD_FAB2_LIB.BASEBOARD_FAB2(SCH_1):GND
  63 P3E_CPU0_PE3_OCP_RXN<0>   IO63 @BASEBOARD_FAB2_LIB.BASEBOARD_FAB2(SCH_1):P3E_CPU0_PE3_OCP_RXN(0)
  64    GND   IO64 @BASEBOARD_FAB2_LIB.BASEBOARD_FAB2(SCH_1):GND
  65    GND   IO65 @BASEBOARD_FAB2_LIB.BASEBOARD_FAB2(SCH_1):GND
  66 P3E_OCP_CPU0_PE3_C_TXP<0>   IO66 @BASEBOARD_FAB2_LIB.BASEBOARD_FAB2(SCH_1):P3E_OCP_CPU0_PE3_C_TXP(0)
  67    GND   IO67 @BASEBOARD_FAB2_LIB.BASEBOARD_FAB2(SCH_1):GND
  68 P3E_OCP_CPU0_PE3_C_TXN<0>   IO68 @BASEBOARD_FAB2_LIB.BASEBOARD_FAB2(SCH_1):P3E_OCP_CPU0_PE3_C_TXN(0)
  69 CLK_100M_MEZZ3_DP   IO69 @BASEBOARD_FAB2_LIB.BASEBOARD_FAB2(SCH_1):CLK_100M_MEZZ3_DP
   7 P3E_CPU0_PE3_OCP_RXN<7>    IO7 @BASEBOARD_FAB2_LIB.BASEBOARD_FAB2(SCH_1):P3E_CPU0_PE3_OCP_RXN(7)
  70    GND   IO70 @BASEBOARD_FAB2_LIB.BASEBOARD_FAB2(SCH_1):GND
  71 CLK_100M_MEZZ3_DN   IO71 @BASEBOARD_FAB2_LIB.BASEBOARD_FAB2(SCH_1):CLK_100M_MEZZ3_DN
  72    GND   IO72 @BASEBOARD_FAB2_LIB.BASEBOARD_FAB2(SCH_1):GND
  73    GND   IO73 @BASEBOARD_FAB2_LIB.BASEBOARD_FAB2(SCH_1):GND
  74 CLK_100M_MEZZ4_DP   IO74 @BASEBOARD_FAB2_LIB.BASEBOARD_FAB2(SCH_1):CLK_100M_MEZZ4_DP
  75 RST_PCIE_CPU_DEV1_R_N   IO75 @BASEBOARD_FAB2_LIB.BASEBOARD_FAB2(SCH_1):RST_PCIE_CPU_DEV1_R_N
  76 CLK_100M_MEZZ4_DN   IO76 @BASEBOARD_FAB2_LIB.BASEBOARD_FAB2(SCH_1):CLK_100M_MEZZ4_DN
  77 RST_PCIE_CPU_DEV2_R_N   IO77 @BASEBOARD_FAB2_LIB.BASEBOARD_FAB2(SCH_1):RST_PCIE_CPU_DEV2_R_N
  78    GND   IO78 @BASEBOARD_FAB2_LIB.BASEBOARD_FAB2(SCH_1):GND
  79 RST_PCIE_CPU_DEV3_R_N   IO79 @BASEBOARD_FAB2_LIB.BASEBOARD_FAB2(SCH_1):RST_PCIE_CPU_DEV3_R_N
   8    GND    IO8 @BASEBOARD_FAB2_LIB.BASEBOARD_FAB2(SCH_1):GND
  80 FM_OCP_MEZZB_PRES_N   IO80 @BASEBOARD_FAB2_LIB.BASEBOARD_FAB2(SCH_1):FM_OCP_MEZZB_PRES_N
   9    GND    IO9 @BASEBOARD_FAB2_LIB.BASEBOARD_FAB2(SCH_1):GND

RES_0402-200.0,1%,1/16W,CHIP,GA  I145  R9E10
   1 RST_PCIE_CPU_DEV1_R_N      A @BASEBOARD_FAB2_LIB.BASEBOARD_FAB2(SCH_1):RST_PCIE_CPU_DEV1_R_N
   2 RST_PCIE_CPU_DEV1_N      B @BASEBOARD_FAB2_LIB.BASEBOARD_FAB2(SCH_1):RST_PCIE_CPU_DEV1_N

RES_0402-200.0,1%,1/16W,CHIP,GA  I150  R9E11
   1 RST_PCIE_CPU_DEV2_R_N      A @BASEBOARD_FAB2_LIB.BASEBOARD_FAB2(SCH_1):RST_PCIE_CPU_DEV2_R_N
   2 RST_PCIE_CPU_DEV2_N      B @BASEBOARD_FAB2_LIB.BASEBOARD_FAB2(SCH_1):RST_PCIE_CPU_DEV2_N

RES_0402-200.0,1%,1/16W,CHIP,GA  I153  R9E12
   1 RST_PCIE_CPU_DEV3_R_N      A @BASEBOARD_FAB2_LIB.BASEBOARD_FAB2(SCH_1):RST_PCIE_CPU_DEV3_R_N
   2 RST_PCIE_CPU_DEV3_N      B @BASEBOARD_FAB2_LIB.BASEBOARD_FAB2(SCH_1):RST_PCIE_CPU_DEV3_N

RES_0402-10.0K,1%,1/16W,CHIP,GA  I174  R2W1
   1 P3V3_STBY      A @BASEBOARD_FAB2_LIB.BASEBOARD_FAB2(SCH_1):P3V3_STBY
   2 FM_MEZZB_PRSNT1_N      B @BASEBOARD_FAB2_LIB.BASEBOARD_FAB2(SCH_1):FM_MEZZB_PRSNT1_N

887R2F-L-GP_SMD-RG-887R2F-L-GPA  I175  R2R8
   1 FM_MEZZB_PRSNT1_N      1 @BASEBOARD_FAB2_LIB.BASEBOARD_FAB2(SCH_1):FM_MEZZB_PRSNT1_N
   2    GND      2 @BASEBOARD_FAB2_LIB.BASEBOARD_FAB2(SCH_1):GND


DRAWING: @BASEBOARD_FAB2_LIB.BASEBOARD_FAB2(SCH_1):PAGE188 

CAP_A_0402V-0.1UF,16V,10%,X7R,A  I2  C2R15
   1 P12V_STBY      A @BASEBOARD_FAB2_LIB.BASEBOARD_FAB2(SCH_1):P12V_STBY
   2    GND      B @BASEBOARD_FAB2_LIB.BASEBOARD_FAB2(SCH_1):GND

CAP_A_0402V-0.1UF,16V,10%,X7R,A  I3  C2R18
   1 P12V_STBY      A @BASEBOARD_FAB2_LIB.BASEBOARD_FAB2(SCH_1):P12V_STBY
   2    GND      B @BASEBOARD_FAB2_LIB.BASEBOARD_FAB2(SCH_1):GND

CAP_A_0402V-0.1UF,16V,10%,X7R,A  I21  C2P11
   1 P12V_STBY      A @BASEBOARD_FAB2_LIB.BASEBOARD_FAB2(SCH_1):P12V_STBY
   2    GND      B @BASEBOARD_FAB2_LIB.BASEBOARD_FAB2(SCH_1):GND

CAP_A_0402V-0.1UF,16V,10%,X7R,A  I23  C2P12
   1 P12V_STBY      A @BASEBOARD_FAB2_LIB.BASEBOARD_FAB2(SCH_1):P12V_STBY
   2    GND      B @BASEBOARD_FAB2_LIB.BASEBOARD_FAB2(SCH_1):GND

CAP_A_0402V-0.1UF,16V,10%,X7R,A  I25  C2R17
   1 P12V_STBY      A @BASEBOARD_FAB2_LIB.BASEBOARD_FAB2(SCH_1):P12V_STBY
   2    GND      B @BASEBOARD_FAB2_LIB.BASEBOARD_FAB2(SCH_1):GND

SCONN64_H87568002_A_SMT-CONN,HA  I27  J8E4
   1 SMB_OCP_FRU_STBY_LVC3_SCL    IO1 @BASEBOARD_FAB2_LIB.BASEBOARD_FAB2(SCH_1):SMB_OCP_FRU_STBY_LVC3_SCL
  10    GND   IO10 @BASEBOARD_FAB2_LIB.BASEBOARD_FAB2(SCH_1):GND
  11     NC   IO11     NC
  12     NC   IO12     NC
  13    GND   IO13 @BASEBOARD_FAB2_LIB.BASEBOARD_FAB2(SCH_1):GND
  14 LED_GBE_P2_0   IO14 @BASEBOARD_FAB2_LIB.BASEBOARD_FAB2(SCH_1):LED_GBE_P2_0
  15 LED_GBE_P2_1   IO15 @BASEBOARD_FAB2_LIB.BASEBOARD_FAB2(SCH_1):LED_GBE_P2_1
  16    GND   IO16 @BASEBOARD_FAB2_LIB.BASEBOARD_FAB2(SCH_1):GND
  17     NC   IO17     NC
  18     NC   IO18     NC
  19    GND   IO19 @BASEBOARD_FAB2_LIB.BASEBOARD_FAB2(SCH_1):GND
   2 SMB_OCP_FRU_STBY_LVC3_SDA    IO2 @BASEBOARD_FAB2_LIB.BASEBOARD_FAB2(SCH_1):SMB_OCP_FRU_STBY_LVC3_SDA
  20 SMB_PCH_MEZZ_LOM0_SCL   IO20 @BASEBOARD_FAB2_LIB.BASEBOARD_FAB2(SCH_1):SMB_PCH_MEZZ_LOM0_SCL
  21 SMB_PCH_MEZZ_LOM0_SDA   IO21 @BASEBOARD_FAB2_LIB.BASEBOARD_FAB2(SCH_1):SMB_PCH_MEZZ_LOM0_SDA
  22    GND   IO22 @BASEBOARD_FAB2_LIB.BASEBOARD_FAB2(SCH_1):GND
  23     NC   IO23     NC
  24     NC   IO24     NC
  25    GND   IO25 @BASEBOARD_FAB2_LIB.BASEBOARD_FAB2(SCH_1):GND
  26 SMB_PCH_MEZZ_LOM1_SCL   IO26 @BASEBOARD_FAB2_LIB.BASEBOARD_FAB2(SCH_1):SMB_PCH_MEZZ_LOM1_SCL
  27 SMB_PCH_MEZZ_LOM1_SDA   IO27 @BASEBOARD_FAB2_LIB.BASEBOARD_FAB2(SCH_1):SMB_PCH_MEZZ_LOM1_SDA
  28    GND   IO28 @BASEBOARD_FAB2_LIB.BASEBOARD_FAB2(SCH_1):GND
  29 SMB_PCH_MEZZ_LOM3_SCL   IO29 @BASEBOARD_FAB2_LIB.BASEBOARD_FAB2(SCH_1):SMB_PCH_MEZZ_LOM3_SCL
   3 EXT_MDIO_I2C_SEL    IO3 @BASEBOARD_FAB2_LIB.BASEBOARD_FAB2(SCH_1):EXT_MDIO_I2C_SEL
  30 SMB_PCH_MEZZ_LOM3_SDA   IO30 @BASEBOARD_FAB2_LIB.BASEBOARD_FAB2(SCH_1):SMB_PCH_MEZZ_LOM3_SDA
  31 FM_GBE2_LVC3_MOD_ABS   IO31 @BASEBOARD_FAB2_LIB.BASEBOARD_FAB2(SCH_1):FM_GBE2_LVC3_MOD_ABS
  32 FM_GBE3_LVC3_MOD_ABS   IO32 @BASEBOARD_FAB2_LIB.BASEBOARD_FAB2(SCH_1):FM_GBE3_LVC3_MOD_ABS
  33 P12V_STBY   IO33 @BASEBOARD_FAB2_LIB.BASEBOARD_FAB2(SCH_1):P12V_STBY
  34 P12V_STBY   IO34 @BASEBOARD_FAB2_LIB.BASEBOARD_FAB2(SCH_1):P12V_STBY
  35 P12V_STBY   IO35 @BASEBOARD_FAB2_LIB.BASEBOARD_FAB2(SCH_1):P12V_STBY
  36 TP_RSVD<0>   IO36 @BASEBOARD_FAB2_LIB.BASEBOARD_FAB2(SCH_1):TP_RSVD(0)
  37 FM_GBE0_LVC3_MOD_ABS   IO37 @BASEBOARD_FAB2_LIB.BASEBOARD_FAB2(SCH_1):FM_GBE0_LVC3_MOD_ABS
  38 FM_GBE1_LVC3_MOD_ABS   IO38 @BASEBOARD_FAB2_LIB.BASEBOARD_FAB2(SCH_1):FM_GBE1_LVC3_MOD_ABS
  39    GND   IO39 @BASEBOARD_FAB2_LIB.BASEBOARD_FAB2(SCH_1):GND
   4    GND    IO4 @BASEBOARD_FAB2_LIB.BASEBOARD_FAB2(SCH_1):GND
  40 KR_P0_OCP_TX_DP   IO40 @BASEBOARD_FAB2_LIB.BASEBOARD_FAB2(SCH_1):KR_P0_OCP_TX_DP
  41 KR_P0_OCP_TX_DN   IO41 @BASEBOARD_FAB2_LIB.BASEBOARD_FAB2(SCH_1):KR_P0_OCP_TX_DN
  42    GND   IO42 @BASEBOARD_FAB2_LIB.BASEBOARD_FAB2(SCH_1):GND
  43 LED_GBE_P0_0   IO43 @BASEBOARD_FAB2_LIB.BASEBOARD_FAB2(SCH_1):LED_GBE_P0_0
  44 LED_GBE_P0_1   IO44 @BASEBOARD_FAB2_LIB.BASEBOARD_FAB2(SCH_1):LED_GBE_P0_1
  45    GND   IO45 @BASEBOARD_FAB2_LIB.BASEBOARD_FAB2(SCH_1):GND
  46 KR_P1_OCP_TX_DP   IO46 @BASEBOARD_FAB2_LIB.BASEBOARD_FAB2(SCH_1):KR_P1_OCP_TX_DP
  47 KR_P1_OCP_TX_DN   IO47 @BASEBOARD_FAB2_LIB.BASEBOARD_FAB2(SCH_1):KR_P1_OCP_TX_DN
  48    GND   IO48 @BASEBOARD_FAB2_LIB.BASEBOARD_FAB2(SCH_1):GND
  49 TP_SHARED_KR_MDC_0   IO49 @BASEBOARD_FAB2_LIB.BASEBOARD_FAB2(SCH_1):TP_SHARED_KR_MDC_0
   5     NC    IO5     NC
  50 TP_SHARED_KR_MDIO_0   IO50 @BASEBOARD_FAB2_LIB.BASEBOARD_FAB2(SCH_1):TP_SHARED_KR_MDIO_0
  51    GND   IO51 @BASEBOARD_FAB2_LIB.BASEBOARD_FAB2(SCH_1):GND
  52 KR_P0_OCP_RX_DP   IO52 @BASEBOARD_FAB2_LIB.BASEBOARD_FAB2(SCH_1):KR_P0_OCP_RX_DP
  53 KR_P0_OCP_RX_DN   IO53 @BASEBOARD_FAB2_LIB.BASEBOARD_FAB2(SCH_1):KR_P0_OCP_RX_DN
  54    GND   IO54 @BASEBOARD_FAB2_LIB.BASEBOARD_FAB2(SCH_1):GND
  55 LED_GBE_P3_0   IO55 @BASEBOARD_FAB2_LIB.BASEBOARD_FAB2(SCH_1):LED_GBE_P3_0
  56 LED_GBE_P3_1   IO56 @BASEBOARD_FAB2_LIB.BASEBOARD_FAB2(SCH_1):LED_GBE_P3_1
  57    GND   IO57 @BASEBOARD_FAB2_LIB.BASEBOARD_FAB2(SCH_1):GND
  58 KR_P1_OCP_RX_DP   IO58 @BASEBOARD_FAB2_LIB.BASEBOARD_FAB2(SCH_1):KR_P1_OCP_RX_DP
  59 KR_P1_OCP_RX_DN   IO59 @BASEBOARD_FAB2_LIB.BASEBOARD_FAB2(SCH_1):KR_P1_OCP_RX_DN
   6     NC    IO6     NC
  60    GND   IO60 @BASEBOARD_FAB2_LIB.BASEBOARD_FAB2(SCH_1):GND
  61 SMB_PCH_MEZZ_LOM2_SCL   IO61 @BASEBOARD_FAB2_LIB.BASEBOARD_FAB2(SCH_1):SMB_PCH_MEZZ_LOM2_SCL
  62 SMB_PCH_MEZZ_LOM2_SDA   IO62 @BASEBOARD_FAB2_LIB.BASEBOARD_FAB2(SCH_1):SMB_PCH_MEZZ_LOM2_SDA
  63    GND   IO63 @BASEBOARD_FAB2_LIB.BASEBOARD_FAB2(SCH_1):GND
  64 FM_OCP_MEZZC_PRES_N   IO64 @BASEBOARD_FAB2_LIB.BASEBOARD_FAB2(SCH_1):FM_OCP_MEZZC_PRES_N
   7    GND    IO7 @BASEBOARD_FAB2_LIB.BASEBOARD_FAB2(SCH_1):GND
   8 LED_GBE_P1_0    IO8 @BASEBOARD_FAB2_LIB.BASEBOARD_FAB2(SCH_1):LED_GBE_P1_0
   9 LED_GBE_P1_1    IO9 @BASEBOARD_FAB2_LIB.BASEBOARD_FAB2(SCH_1):LED_GBE_P1_1

CAP_A_0402V-0.1UF,16V,10%,X7R,A  I40  C2R16
   1 P12V_STBY      A @BASEBOARD_FAB2_LIB.BASEBOARD_FAB2(SCH_1):P12V_STBY
   2    GND      B @BASEBOARD_FAB2_LIB.BASEBOARD_FAB2(SCH_1):GND

CAP_1206LF-22UF,16V,10%,X6S,D3A  I41  C2P10
   1 P12V_STBY      A @BASEBOARD_FAB2_LIB.BASEBOARD_FAB2(SCH_1):P12V_STBY
   2    GND      B @BASEBOARD_FAB2_LIB.BASEBOARD_FAB2(SCH_1):GND

CAP_A_0402V-0.1UF,16V,10%,X7R,A  I53  C2P16
   1 P12V_STBY      A @BASEBOARD_FAB2_LIB.BASEBOARD_FAB2(SCH_1):P12V_STBY
   2    GND      B @BASEBOARD_FAB2_LIB.BASEBOARD_FAB2(SCH_1):GND

CAP_A_0402V-0.1UF,16V,10%,X7R,A  I55  C2P15
   1 P12V_STBY      A @BASEBOARD_FAB2_LIB.BASEBOARD_FAB2(SCH_1):P12V_STBY
   2    GND      B @BASEBOARD_FAB2_LIB.BASEBOARD_FAB2(SCH_1):GND

CAP_A_0402V-0.1UF,16V,10%,X7R,A  I56  C2P14
   1 P12V_STBY      A @BASEBOARD_FAB2_LIB.BASEBOARD_FAB2(SCH_1):P12V_STBY
   2    GND      B @BASEBOARD_FAB2_LIB.BASEBOARD_FAB2(SCH_1):GND

CAP_A_0402V-0.1UF,16V,10%,X7R,A  I57  C2P13
   1 P12V_STBY      A @BASEBOARD_FAB2_LIB.BASEBOARD_FAB2(SCH_1):P12V_STBY
   2    GND      B @BASEBOARD_FAB2_LIB.BASEBOARD_FAB2(SCH_1):GND

CAP_A_0402V-0.1UF,16V,10%,X7R,A  I82  C8C15
   1 KR_P0_OCP_RX_DP      A @BASEBOARD_FAB2_LIB.BASEBOARD_FAB2(SCH_1):KR_P0_OCP_RX_DP
   2 KR_P0_OCP_RX_C_DP      B @BASEBOARD_FAB2_LIB.BASEBOARD_FAB2(SCH_1):KR_P0_OCP_RX_C_DP

CAP_A_0402V-0.1UF,16V,10%,X7R,A  I86  C8C14
   1 KR_P0_OCP_RX_DN      A @BASEBOARD_FAB2_LIB.BASEBOARD_FAB2(SCH_1):KR_P0_OCP_RX_DN
   2 KR_P0_OCP_RX_C_DN      B @BASEBOARD_FAB2_LIB.BASEBOARD_FAB2(SCH_1):KR_P0_OCP_RX_C_DN

RES_0402-2.21K,1%,1/16W,CHIP,GA  I88  R1R18
   1 P3V3_STBY      A @BASEBOARD_FAB2_LIB.BASEBOARD_FAB2(SCH_1):P3V3_STBY
   2 SMB_PCH_MEZZ_LOM0_SCL      B @BASEBOARD_FAB2_LIB.BASEBOARD_FAB2(SCH_1):SMB_PCH_MEZZ_LOM0_SCL

RES_0402-2.21K,1%,1/16W,CHIP,GA  I89  R1R19
   1 P3V3_STBY      A @BASEBOARD_FAB2_LIB.BASEBOARD_FAB2(SCH_1):P3V3_STBY
   2 SMB_PCH_MEZZ_LOM0_SDA      B @BASEBOARD_FAB2_LIB.BASEBOARD_FAB2(SCH_1):SMB_PCH_MEZZ_LOM0_SDA

RES_0402-2.21K,1%,1/16W,CHIP,GA  I90  R1R21
   1 P3V3_STBY      A @BASEBOARD_FAB2_LIB.BASEBOARD_FAB2(SCH_1):P3V3_STBY
   2 SMB_PCH_MEZZ_LOM1_SDA      B @BASEBOARD_FAB2_LIB.BASEBOARD_FAB2(SCH_1):SMB_PCH_MEZZ_LOM1_SDA

RES_0402-2.21K,1%,1/16W,CHIP,GA  I91  R1R20
   1 P3V3_STBY      A @BASEBOARD_FAB2_LIB.BASEBOARD_FAB2(SCH_1):P3V3_STBY
   2 SMB_PCH_MEZZ_LOM1_SCL      B @BASEBOARD_FAB2_LIB.BASEBOARD_FAB2(SCH_1):SMB_PCH_MEZZ_LOM1_SCL

RES_0402-2.21K,1%,1/16W,CHIP,GA  I92  R1R22
   1 P3V3_STBY      A @BASEBOARD_FAB2_LIB.BASEBOARD_FAB2(SCH_1):P3V3_STBY
   2 SMB_PCH_MEZZ_LOM3_SDA      B @BASEBOARD_FAB2_LIB.BASEBOARD_FAB2(SCH_1):SMB_PCH_MEZZ_LOM3_SDA

RES_0402-2.21K,1%,1/16W,CHIP,GA  I93  R1R16
   1 P3V3_STBY      A @BASEBOARD_FAB2_LIB.BASEBOARD_FAB2(SCH_1):P3V3_STBY
   2 SMB_PCH_MEZZ_LOM2_SCL      B @BASEBOARD_FAB2_LIB.BASEBOARD_FAB2(SCH_1):SMB_PCH_MEZZ_LOM2_SCL

RES_0402-2.21K,1%,1/16W,CHIP,GA  I94  R1R17
   1 P3V3_STBY      A @BASEBOARD_FAB2_LIB.BASEBOARD_FAB2(SCH_1):P3V3_STBY
   2 SMB_PCH_MEZZ_LOM2_SDA      B @BASEBOARD_FAB2_LIB.BASEBOARD_FAB2(SCH_1):SMB_PCH_MEZZ_LOM2_SDA

RES_0402-2.21K,1%,1/16W,CHIP,GA  I95  R1R23
   1 P3V3_STBY      A @BASEBOARD_FAB2_LIB.BASEBOARD_FAB2(SCH_1):P3V3_STBY
   2 SMB_PCH_MEZZ_LOM3_SCL      B @BASEBOARD_FAB2_LIB.BASEBOARD_FAB2(SCH_1):SMB_PCH_MEZZ_LOM3_SCL

CAP_A_0402V-0.1UF,16V,10%,X7R,A  I120  C8C13
   1 KR_P1_OCP_RX_DN      A @BASEBOARD_FAB2_LIB.BASEBOARD_FAB2(SCH_1):KR_P1_OCP_RX_DN
   2 KR_P1_OCP_RX_C_DN      B @BASEBOARD_FAB2_LIB.BASEBOARD_FAB2(SCH_1):KR_P1_OCP_RX_C_DN

CAP_A_0402V-0.1UF,16V,10%,X7R,A  I121  C8C12
   1 KR_P1_OCP_RX_DP      A @BASEBOARD_FAB2_LIB.BASEBOARD_FAB2(SCH_1):KR_P1_OCP_RX_DP
   2 KR_P1_OCP_RX_C_DP      B @BASEBOARD_FAB2_LIB.BASEBOARD_FAB2(SCH_1):KR_P1_OCP_RX_C_DP

RES_0402-4.75K,1%,1/16W,CHIP,GA  I128  R1W40
   1 P3V3_STBY      A @BASEBOARD_FAB2_LIB.BASEBOARD_FAB2(SCH_1):P3V3_STBY
   2 EXT_MDIO_I2C_SEL      B @BASEBOARD_FAB2_LIB.BASEBOARD_FAB2(SCH_1):EXT_MDIO_I2C_SEL

RES_0402-4.75K,1%,1/16W,CHIP,GA  I129  R1W41
   1    GND      A @BASEBOARD_FAB2_LIB.BASEBOARD_FAB2(SCH_1):GND
   2 EXT_MDIO_I2C_SEL      B @BASEBOARD_FAB2_LIB.BASEBOARD_FAB2(SCH_1):EXT_MDIO_I2C_SEL

RES_0402-4.75K,1%,1/16W,CHIP,GA  I131  R1W42
   1 P3V3_STBY      A @BASEBOARD_FAB2_LIB.BASEBOARD_FAB2(SCH_1):P3V3_STBY
   2 FM_GBE0_LVC3_MOD_ABS      B @BASEBOARD_FAB2_LIB.BASEBOARD_FAB2(SCH_1):FM_GBE0_LVC3_MOD_ABS

RES_0402-4.75K,1%,1/16W,CHIP,GA  I132  R1W43
   1 P3V3_STBY      A @BASEBOARD_FAB2_LIB.BASEBOARD_FAB2(SCH_1):P3V3_STBY
   2 FM_GBE1_LVC3_MOD_ABS      B @BASEBOARD_FAB2_LIB.BASEBOARD_FAB2(SCH_1):FM_GBE1_LVC3_MOD_ABS

RES_0402-4.75K,1%,1/16W,CHIP,GA  I133  R1W44
   1 P3V3_STBY      A @BASEBOARD_FAB2_LIB.BASEBOARD_FAB2(SCH_1):P3V3_STBY
   2 FM_GBE2_LVC3_MOD_ABS      B @BASEBOARD_FAB2_LIB.BASEBOARD_FAB2(SCH_1):FM_GBE2_LVC3_MOD_ABS

RES_0402-4.75K,1%,1/16W,CHIP,GA  I134  R1W45
   1 P3V3_STBY      A @BASEBOARD_FAB2_LIB.BASEBOARD_FAB2(SCH_1):P3V3_STBY
   2 FM_GBE3_LVC3_MOD_ABS      B @BASEBOARD_FAB2_LIB.BASEBOARD_FAB2(SCH_1):FM_GBE3_LVC3_MOD_ABS


DRAWING: @BASEBOARD_FAB2_LIB.BASEBOARD_FAB2(SCH_1):PAGE189 

RES_0402-0.0,5%,1/16W,CHIP,G21A  I7  R8G10
   1 JTAG_BMC_TRST_N      A @BASEBOARD_FAB2_LIB.BASEBOARD_FAB2(SCH_1):JTAG_BMC_TRST_N
   2 JTAG_TRST_N      B @BASEBOARD_FAB2_LIB.BASEBOARD_FAB2(SCH_1):JTAG_TRST_N

RES_0402-0.0,5%,1/16W,EMPTY,G2A  I8  R7G19
   1 JTAG_PCH_GBE_TDI      A @BASEBOARD_FAB2_LIB.BASEBOARD_FAB2(SCH_1):JTAG_PCH_GBE_TDI
   2 JTAG_TDI      B @BASEBOARD_FAB2_LIB.BASEBOARD_FAB2(SCH_1):JTAG_TDI

RES_0402-0.0,5%,1/16W,EMPTY,G2A  I9  R8G9
   1 JTAG_PCH_GBE_TRST_N      A @BASEBOARD_FAB2_LIB.BASEBOARD_FAB2(SCH_1):JTAG_PCH_GBE_TRST_N
   2 JTAG_TRST_N      B @BASEBOARD_FAB2_LIB.BASEBOARD_FAB2(SCH_1):JTAG_TRST_N

RES_0402-0.0,5%,1/16W,EMPTY,G2A  I13  R7G18
   1 JTAG_PCH_PLD_TDI      A @BASEBOARD_FAB2_LIB.BASEBOARD_FAB2(SCH_1):JTAG_PCH_PLD_TDI
   2 JTAG_TDI      B @BASEBOARD_FAB2_LIB.BASEBOARD_FAB2(SCH_1):JTAG_TDI

RES_0402-0.0,5%,1/16W,CHIP,G21A  I17  R8G8
   1 JTAG_BMC_TDI      A @BASEBOARD_FAB2_LIB.BASEBOARD_FAB2(SCH_1):JTAG_BMC_TDI
   2 JTAG_TDI      B @BASEBOARD_FAB2_LIB.BASEBOARD_FAB2(SCH_1):JTAG_TDI

RES_0402-0.0,5%,1/16W,CHIP,G21A  I18  R8G7
   1 JTAG_PLD_TDI      A @BASEBOARD_FAB2_LIB.BASEBOARD_FAB2(SCH_1):JTAG_PLD_TDI
   2 JTAG_PLD_TDI_MUX      B @BASEBOARD_FAB2_LIB.BASEBOARD_FAB2(SCH_1):JTAG_PLD_TDI_MUX

RES_0402-0.0,5%,1/16W,EMPTY,G2A  I19  R8G11
   1 JTAG_PCH_PLD_TMS      A @BASEBOARD_FAB2_LIB.BASEBOARD_FAB2(SCH_1):JTAG_PCH_PLD_TMS
   2 JTAG_TMS      B @BASEBOARD_FAB2_LIB.BASEBOARD_FAB2(SCH_1):JTAG_TMS

RES_0402-0.0,5%,1/16W,CHIP,G21A  I20  R8G14
   1 JTAG_BMC_TMS      A @BASEBOARD_FAB2_LIB.BASEBOARD_FAB2(SCH_1):JTAG_BMC_TMS
   2 JTAG_TMS      B @BASEBOARD_FAB2_LIB.BASEBOARD_FAB2(SCH_1):JTAG_TMS

RES_0402-0.0,5%,1/16W,EMPTY,G2A  I21  R8G12
   1 JTAG_PCH_GBE_TMS      A @BASEBOARD_FAB2_LIB.BASEBOARD_FAB2(SCH_1):JTAG_PCH_GBE_TMS
   2 JTAG_TMS      B @BASEBOARD_FAB2_LIB.BASEBOARD_FAB2(SCH_1):JTAG_TMS

RES_0402-0.0,5%,1/16W,EMPTY,G2A  I22  R8G16
   1 JTAG_PCH_PLD_TCK      A @BASEBOARD_FAB2_LIB.BASEBOARD_FAB2(SCH_1):JTAG_PCH_PLD_TCK
   2 JTAG_TCK      B @BASEBOARD_FAB2_LIB.BASEBOARD_FAB2(SCH_1):JTAG_TCK

RES_0402-0.0,5%,1/16W,CHIP,G21A  I23  R8G13
   1 JTAG_PLD_TMS      A @BASEBOARD_FAB2_LIB.BASEBOARD_FAB2(SCH_1):JTAG_PLD_TMS
   2 JTAG_PLD_TMS_MUX      B @BASEBOARD_FAB2_LIB.BASEBOARD_FAB2(SCH_1):JTAG_PLD_TMS_MUX

RES_0402-0.0,5%,1/16W,EMPTY,G2A  I24  R8G15
   1 JTAG_PCH_GBE_CLK      A @BASEBOARD_FAB2_LIB.BASEBOARD_FAB2(SCH_1):JTAG_PCH_GBE_CLK
   2 JTAG_TCK      B @BASEBOARD_FAB2_LIB.BASEBOARD_FAB2(SCH_1):JTAG_TCK

RES_0402-0.0,5%,1/16W,CHIP,G21A  I25  R8G17
   1 JTAG_BMC_TCK      A @BASEBOARD_FAB2_LIB.BASEBOARD_FAB2(SCH_1):JTAG_BMC_TCK
   2 JTAG_TCK      B @BASEBOARD_FAB2_LIB.BASEBOARD_FAB2(SCH_1):JTAG_TCK

RES_0402-0.0,5%,1/16W,CHIP,G21A  I26  R8G18
   1 JTAG_PLD_TCK      A @BASEBOARD_FAB2_LIB.BASEBOARD_FAB2(SCH_1):JTAG_PLD_TCK
   2 JTAG_PLD_TCK_MUX      B @BASEBOARD_FAB2_LIB.BASEBOARD_FAB2(SCH_1):JTAG_PLD_TCK_MUX

RES_0402-0.0,5%,1/16W,EMPTY,G2A  I27  R7G16
   1 JTAG_PCH_GBE_TDO      A @BASEBOARD_FAB2_LIB.BASEBOARD_FAB2(SCH_1):JTAG_PCH_GBE_TDO
   2 JTAG_TDO      B @BASEBOARD_FAB2_LIB.BASEBOARD_FAB2(SCH_1):JTAG_TDO

RES_0402-0.0,5%,1/16W,EMPTY,G2A  I36  R7G15
   1 JTAG_PCH_PLD_TDO      A @BASEBOARD_FAB2_LIB.BASEBOARD_FAB2(SCH_1):JTAG_PCH_PLD_TDO
   2 JTAG_TDO      B @BASEBOARD_FAB2_LIB.BASEBOARD_FAB2(SCH_1):JTAG_TDO

RES_0402-0.0,5%,1/16W,CHIP,G21A  I37  R7G17
   1 JTAG_BMC_TDO      A @BASEBOARD_FAB2_LIB.BASEBOARD_FAB2(SCH_1):JTAG_BMC_TDO
   2 JTAG_TDO      B @BASEBOARD_FAB2_LIB.BASEBOARD_FAB2(SCH_1):JTAG_TDO

RES_0402-0.0,5%,1/16W,CHIP,G21A  I38  R7G14
   1 JTAG_PLD_TDO_MUX_R      A @BASEBOARD_FAB2_LIB.BASEBOARD_FAB2(SCH_1):JTAG_PLD_TDO_MUX_R
   2 JTAG_PLD_TDO_MUX      B @BASEBOARD_FAB2_LIB.BASEBOARD_FAB2(SCH_1):JTAG_PLD_TDO_MUX

RES_0402-1.00K,1%,1/16W,CHIP,GA  I44  R3R15
   1 P3V3_STBY      A @BASEBOARD_FAB2_LIB.BASEBOARD_FAB2(SCH_1):P3V3_STBY
   2 FM_JTAG_PLD_EN_DEBUG      B @BASEBOARD_FAB2_LIB.BASEBOARD_FAB2(SCH_1):FM_JTAG_PLD_EN_DEBUG

RES_0402-10.0K,1%,1/16W,EMPTY,A  I45  R3R11
   1 FM_JTAG_PLD_EN_DEBUG      A @BASEBOARD_FAB2_LIB.BASEBOARD_FAB2(SCH_1):FM_JTAG_PLD_EN_DEBUG
   2    GND      B @BASEBOARD_FAB2_LIB.BASEBOARD_FAB2(SCH_1):GND

CONN8_C77962004_PIP-CONN,C7796A  I47  J7G2
   1 P3V3_STBY_PLD_D    IO1 @BASEBOARD_FAB2_LIB.BASEBOARD_FAB2(SCH_1):P3V3_STBY_PLD_D
   2 JTAG_TDO_R    IO2 @BASEBOARD_FAB2_LIB.BASEBOARD_FAB2(SCH_1):JTAG_TDO_R
   3 JTAG_TDI_R    IO3 @BASEBOARD_FAB2_LIB.BASEBOARD_FAB2(SCH_1):JTAG_TDI_R
   4 JTAG_TRST_N    IO4 @BASEBOARD_FAB2_LIB.BASEBOARD_FAB2(SCH_1):JTAG_TRST_N
   5 PWRGD_P3V3_STBY    IO5 @BASEBOARD_FAB2_LIB.BASEBOARD_FAB2(SCH_1):PWRGD_P3V3_STBY
   6 JTAG_TMS_R    IO6 @BASEBOARD_FAB2_LIB.BASEBOARD_FAB2(SCH_1):JTAG_TMS_R
   7    GND    IO7 @BASEBOARD_FAB2_LIB.BASEBOARD_FAB2(SCH_1):GND
   8 JTAG_TCK_R    IO8 @BASEBOARD_FAB2_LIB.BASEBOARD_FAB2(SCH_1):JTAG_TCK_R

DIODE_SMLF-1N5819HW,IC,D55839-A  I49  CR3U1
   1 P3V3_STBY_PLD_D      C @BASEBOARD_FAB2_LIB.BASEBOARD_FAB2(SCH_1):P3V3_STBY_PLD_D
   2 P3V3_STBY      A @BASEBOARD_FAB2_LIB.BASEBOARD_FAB2(SCH_1):P3V3_STBY

RES_0402-10.0K,1%,1/16W,CHIP,GA  I50  R8G20
   1 P3V3_STBY      A @BASEBOARD_FAB2_LIB.BASEBOARD_FAB2(SCH_1):P3V3_STBY
   2 JTAG_TMS_R      B @BASEBOARD_FAB2_LIB.BASEBOARD_FAB2(SCH_1):JTAG_TMS_R

RES_0402-10.0K,1%,1/16W,CHIP,GA  I51  R7G23
   1 P3V3_STBY      A @BASEBOARD_FAB2_LIB.BASEBOARD_FAB2(SCH_1):P3V3_STBY
   2 JTAG_TDI_R      B @BASEBOARD_FAB2_LIB.BASEBOARD_FAB2(SCH_1):JTAG_TDI_R

RES_0402-10.0K,1%,1/16W,CHIP,GA  I53  R7G22
   1 P3V3_STBY      A @BASEBOARD_FAB2_LIB.BASEBOARD_FAB2(SCH_1):P3V3_STBY
   2 JTAG_TDO_R      B @BASEBOARD_FAB2_LIB.BASEBOARD_FAB2(SCH_1):JTAG_TDO_R

RES_0402-4.75K,1%,1/16W,CHIP,GA  I56  R8G23
   1 JTAG_TCK_R      A @BASEBOARD_FAB2_LIB.BASEBOARD_FAB2(SCH_1):JTAG_TCK_R
   2    GND      B @BASEBOARD_FAB2_LIB.BASEBOARD_FAB2(SCH_1):GND

RES_0402-0.0,5%,1/16W,CHIP,G21A  I63  R7G21
   1 JTAG_TDO      A @BASEBOARD_FAB2_LIB.BASEBOARD_FAB2(SCH_1):JTAG_TDO
   2 JTAG_TDO_R      B @BASEBOARD_FAB2_LIB.BASEBOARD_FAB2(SCH_1):JTAG_TDO_R

RES_0402-0.0,5%,1/16W,CHIP,G21A  I64  R8G19
   1 JTAG_TDI      A @BASEBOARD_FAB2_LIB.BASEBOARD_FAB2(SCH_1):JTAG_TDI
   2 JTAG_TDI_R      B @BASEBOARD_FAB2_LIB.BASEBOARD_FAB2(SCH_1):JTAG_TDI_R

RES_0402-0.0,5%,1/16W,CHIP,G21A  I65  R8G21
   1 JTAG_TMS      A @BASEBOARD_FAB2_LIB.BASEBOARD_FAB2(SCH_1):JTAG_TMS
   2 JTAG_TMS_R      B @BASEBOARD_FAB2_LIB.BASEBOARD_FAB2(SCH_1):JTAG_TMS_R

RES_0402-0.0,5%,1/16W,CHIP,G21A  I66  R8G22
   1 JTAG_TCK      A @BASEBOARD_FAB2_LIB.BASEBOARD_FAB2(SCH_1):JTAG_TCK
   2 JTAG_TCK_R      B @BASEBOARD_FAB2_LIB.BASEBOARD_FAB2(SCH_1):JTAG_TCK_R

TTL3126_QFNLF-74CBTLV3126,IC,DB  I67  SIZE=4  Summary of common pins:

  Section:  I67(3) U1L10
   1 BMC_JTAG_SEL_N_MUX  OE<3> @BASEBOARD_FAB2_LIB.BASEBOARD_FAB2(SCH_1):BMC_JTAG_SEL_N_MUX
   2 JTAG_PLD_TDO_MUX   A<3> @BASEBOARD_FAB2_LIB.BASEBOARD_FAB2(SCH_1):JTAG_PLD_TDO_MUX
   3 JTAG_TDO   B<3> @BASEBOARD_FAB2_LIB.BASEBOARD_FAB2(SCH_1):JTAG_TDO

  Section:  I67(2) U1L10
   4 BMC_JTAG_SEL_N_MUX  OE<2> @BASEBOARD_FAB2_LIB.BASEBOARD_FAB2(SCH_1):BMC_JTAG_SEL_N_MUX
   5 JTAG_PLD_TCK_MUX   A<2> @BASEBOARD_FAB2_LIB.BASEBOARD_FAB2(SCH_1):JTAG_PLD_TCK_MUX
   6 JTAG_TCK   B<2> @BASEBOARD_FAB2_LIB.BASEBOARD_FAB2(SCH_1):JTAG_TCK

  Section:  I67(1) U1L10
  10 BMC_JTAG_SEL_N_MUX  OE<1> @BASEBOARD_FAB2_LIB.BASEBOARD_FAB2(SCH_1):BMC_JTAG_SEL_N_MUX
   9 JTAG_PLD_TMS_MUX   A<1> @BASEBOARD_FAB2_LIB.BASEBOARD_FAB2(SCH_1):JTAG_PLD_TMS_MUX
   8 JTAG_TMS   B<1> @BASEBOARD_FAB2_LIB.BASEBOARD_FAB2(SCH_1):JTAG_TMS

  Section:  I67 U1L10
  13 BMC_JTAG_SEL_N_MUX  OE<0> @BASEBOARD_FAB2_LIB.BASEBOARD_FAB2(SCH_1):BMC_JTAG_SEL_N_MUX
  12 JTAG_PLD_TDI_MUX   A<0> @BASEBOARD_FAB2_LIB.BASEBOARD_FAB2(SCH_1):JTAG_PLD_TDI_MUX
  11 JTAG_TDI   B<0> @BASEBOARD_FAB2_LIB.BASEBOARD_FAB2(SCH_1):JTAG_TDI

CAP_0402-1.0UF,16V,10%,X6S,D97A  I69  C1L119
   1 P3V3_STBY      A @BASEBOARD_FAB2_LIB.BASEBOARD_FAB2(SCH_1):P3V3_STBY
   2    GND      B @BASEBOARD_FAB2_LIB.BASEBOARD_FAB2(SCH_1):GND

RES_0402-0.0,5%,1/16W,CHIP,G21A  I76  R7G114
   1 BMC_JTAG_SEL_N      A @BASEBOARD_FAB2_LIB.BASEBOARD_FAB2(SCH_1):BMC_JTAG_SEL_N
   2 BMC_JTAG_SEL_N_MUX      B @BASEBOARD_FAB2_LIB.BASEBOARD_FAB2(SCH_1):BMC_JTAG_SEL_N_MUX

RES_0402-0.0,5%,1/16W,CHIP,G21A  I77  R25W186
   1 BMC_JTAG_SEL_N      A @BASEBOARD_FAB2_LIB.BASEBOARD_FAB2(SCH_1):BMC_JTAG_SEL_N
   2 FM_JTAG_PLD_EN_DEBUG      B @BASEBOARD_FAB2_LIB.BASEBOARD_FAB2(SCH_1):FM_JTAG_PLD_EN_DEBUG


DRAWING: @BASEBOARD_FAB2_LIB.BASEBOARD_FAB2(SCH_1):PAGE190 

RES_0402-0.0,5%,1/16W,CHIP,G21A  I116  R3P34
   1 RST_CPU0_LVC3_R1_N      A @BASEBOARD_FAB2_LIB.BASEBOARD_FAB2(SCH_1):RST_CPU0_LVC3_R1_N
   2 RST_CPU0_LVC3_N      B @BASEBOARD_FAB2_LIB.BASEBOARD_FAB2(SCH_1):RST_CPU0_LVC3_N

RES_0402-0.0,5%,1/16W,CHIP,G21A  I117  R3P35
   1 RST_CPU1_LVC3_R1_N      A @BASEBOARD_FAB2_LIB.BASEBOARD_FAB2(SCH_1):RST_CPU1_LVC3_R1_N
   2 RST_CPU1_LVC3_N      B @BASEBOARD_FAB2_LIB.BASEBOARD_FAB2(SCH_1):RST_CPU1_LVC3_N

LCMXO2_A_256BGA-IC,H63395-001  I179  U8D7
  P4 FM_CPU1_RC_EN   PB3A @BASEBOARD_FAB2_LIB.BASEBOARD_FAB2(SCH_1):FM_CPU1_RC_EN
  T4 PWRGD_PVSA_CPU1   PB3B @BASEBOARD_FAB2_LIB.BASEBOARD_FAB2(SCH_1):PWRGD_PVSA_CPU1
  T2 FM_ADR_MODE_SEL   PB3C @BASEBOARD_FAB2_LIB.BASEBOARD_FAB2(SCH_1):FM_ADR_MODE_SEL
  R3 FM_CPU0_RC_EN   PB3D @BASEBOARD_FAB2_LIB.BASEBOARD_FAB2(SCH_1):FM_CPU0_RC_EN
  R5 TP_CPLD1_PB5A_CSSPIN PB5A_CSSPIN @BASEBOARD_FAB2_LIB.BASEBOARD_FAB2(SCH_1):TP_CPLD1_PB5A_CSSPIN
  P5 PWRGD_PVCCMCP_CPU0   PB5B @BASEBOARD_FAB2_LIB.BASEBOARD_FAB2(SCH_1):PWRGD_PVCCMCP_CPU0
  T5 PWRGD_PVCCIOMCP_CPU1   PB6A @BASEBOARD_FAB2_LIB.BASEBOARD_FAB2(SCH_1):PWRGD_PVCCIOMCP_CPU1
  R6 RST_PCIE_M2_DEV_N   PB6B @BASEBOARD_FAB2_LIB.BASEBOARD_FAB2(SCH_1):RST_PCIE_M2_DEV_N
  T3 FM_DIS_ADR_DLY   PB6C @BASEBOARD_FAB2_LIB.BASEBOARD_FAB2(SCH_1):FM_DIS_ADR_DLY
  R4 FM_BMC_CPLD_MP_RST_N   PB6D @BASEBOARD_FAB2_LIB.BASEBOARD_FAB2(SCH_1):FM_BMC_CPLD_MP_RST_N
  P6 TP_CPLD1_PB8A_MCLK_CCLK PB8A_MCLK_CCLK @BASEBOARD_FAB2_LIB.BASEBOARD_FAB2(SCH_1):TP_CPLD1_PB8A_MCLK_CCLK
  T6 TP_CPLD1_PB8B_SO_SPISO PB8B_SO_SPISO @BASEBOARD_FAB2_LIB.BASEBOARD_FAB2(SCH_1):TP_CPLD1_PB8B_SO_SPISO
  N6 PWRGD_PVCCIOMCP_CPU0   PB8C @BASEBOARD_FAB2_LIB.BASEBOARD_FAB2(SCH_1):PWRGD_PVCCIOMCP_CPU0
  L7 FM_OC0_USB_N   PB8D @BASEBOARD_FAB2_LIB.BASEBOARD_FAB2(SCH_1):FM_OC0_USB_N
  R7 PWRGD_PVTT_CPU1   PB9A @BASEBOARD_FAB2_LIB.BASEBOARD_FAB2(SCH_1):PWRGD_PVTT_CPU1
  P7 FM_PVCCIOMCP_CPU1_EN   PB9B @BASEBOARD_FAB2_LIB.BASEBOARD_FAB2(SCH_1):FM_PVCCIOMCP_CPU1_EN
  M7 FM_PVCCIO_CPU0_EN   PB9C @BASEBOARD_FAB2_LIB.BASEBOARD_FAB2(SCH_1):FM_PVCCIO_CPU0_EN
  N7 PWRGD_PVPP_ABC   PB9D @BASEBOARD_FAB2_LIB.BASEBOARD_FAB2(SCH_1):PWRGD_PVPP_ABC
  T7 FM_PVCCIO_CPU1_EN PB11A_PCLKT2_0 @BASEBOARD_FAB2_LIB.BASEBOARD_FAB2(SCH_1):FM_PVCCIO_CPU1_EN
  R8 FM_CPLD_USB_P0_EN_N PB11B_PCLKC2_0 @BASEBOARD_FAB2_LIB.BASEBOARD_FAB2(SCH_1):FM_CPLD_USB_P0_EN_N
  M6 PWRGD_PVPP_DEF  PB11C @BASEBOARD_FAB2_LIB.BASEBOARD_FAB2(SCH_1):PWRGD_PVPP_DEF
  L8 PWRGD_PVCCIO_CPU0  PB11D @BASEBOARD_FAB2_LIB.BASEBOARD_FAB2(SCH_1):PWRGD_PVCCIO_CPU0
  P8 PWRGD_PVNN_P1V05_PCH  PB12A @BASEBOARD_FAB2_LIB.BASEBOARD_FAB2(SCH_1):PWRGD_PVNN_P1V05_PCH
  T8 FM_CPLD_DBG_PWR_EN_N  PB12B @BASEBOARD_FAB2_LIB.BASEBOARD_FAB2(SCH_1):FM_CPLD_DBG_PWR_EN_N
  N8 FM_156M_CPU1_BRD_OSC_EN  PB12C @BASEBOARD_FAB2_LIB.BASEBOARD_FAB2(SCH_1):FM_156M_CPU1_BRD_OSC_EN
  L9 FM_IE_DISABLE_N  PB12D @BASEBOARD_FAB2_LIB.BASEBOARD_FAB2(SCH_1):FM_IE_DISABLE_N
  T9 TP_CPLD1_PB16A_PCLKT2_1 PB16A_PCLKT2_1 @BASEBOARD_FAB2_LIB.BASEBOARD_FAB2(SCH_1):TP_CPLD1_PB16A_PCLKT2_1
  P9 TP_CPLD1_PB16B_PCLKC2_1 PB16B_PCLKC2_1 @BASEBOARD_FAB2_LIB.BASEBOARD_FAB2(SCH_1):TP_CPLD1_PB16B_PCLKC2_1
  M8 FM_PVCCMCP_CPU1_EN  PB16C @BASEBOARD_FAB2_LIB.BASEBOARD_FAB2(SCH_1):FM_PVCCMCP_CPU1_EN
  N9 FM_CPLD_BMC_PWRDN_N  PB16D @BASEBOARD_FAB2_LIB.BASEBOARD_FAB2(SCH_1):FM_CPLD_BMC_PWRDN_N
  R9 FM_UARTSW_LSB_N  PB18A @BASEBOARD_FAB2_LIB.BASEBOARD_FAB2(SCH_1):FM_UARTSW_LSB_N
 T10 FM_156M_CPU0_BRD_OSC_EN  PB18B @BASEBOARD_FAB2_LIB.BASEBOARD_FAB2(SCH_1):FM_156M_CPU0_BRD_OSC_EN
  M9 FM_CPLD_UART_CH_LOCK_N  PB18C @BASEBOARD_FAB2_LIB.BASEBOARD_FAB2(SCH_1):FM_CPLD_UART_CH_LOCK_N
 L10 FM_SOL_UART_CH_SEL  PB18D @BASEBOARD_FAB2_LIB.BASEBOARD_FAB2(SCH_1):FM_SOL_UART_CH_SEL
 P10 RST_CD_CPU1_POR_N  PB19A @BASEBOARD_FAB2_LIB.BASEBOARD_FAB2(SCH_1):RST_CD_CPU1_POR_N
 R10 RST_CPU0_LVC3_R1_N  PB19B @BASEBOARD_FAB2_LIB.BASEBOARD_FAB2(SCH_1):RST_CPU0_LVC3_R1_N
 N10 RST_CPU1_LVC3_R1_N  PB19C @BASEBOARD_FAB2_LIB.BASEBOARD_FAB2(SCH_1):RST_CPU1_LVC3_R1_N
 M11 XDP_PWRGD_RST_N  PB19D @BASEBOARD_FAB2_LIB.BASEBOARD_FAB2(SCH_1):XDP_PWRGD_RST_N
 T11 FM_CPU1_PKGID2  PB21A @BASEBOARD_FAB2_LIB.BASEBOARD_FAB2(SCH_1):FM_CPU1_PKGID2
 P11 FM_UARTSW_MSB_N  PB21B @BASEBOARD_FAB2_LIB.BASEBOARD_FAB2(SCH_1):FM_UARTSW_MSB_N
 M10 PWRGD_CPU1_LVC3  PB21C @BASEBOARD_FAB2_LIB.BASEBOARD_FAB2(SCH_1):PWRGD_CPU1_LVC3
 N11 XDP_SYSPWROK  PB21D @BASEBOARD_FAB2_LIB.BASEBOARD_FAB2(SCH_1):XDP_SYSPWROK
 R11 FM_DB1200ZL_BCLKS_EN_N  PB22A @BASEBOARD_FAB2_LIB.BASEBOARD_FAB2(SCH_1):FM_DB1200ZL_BCLKS_EN_N
 T12 FM_CPU1_SKTOCC_LVT3_N  PB22B @BASEBOARD_FAB2_LIB.BASEBOARD_FAB2(SCH_1):FM_CPU1_SKTOCC_LVT3_N
 R13 FM_CPU0_VRM_OSC_EN  PB22C @BASEBOARD_FAB2_LIB.BASEBOARD_FAB2(SCH_1):FM_CPU0_VRM_OSC_EN
 T14 FM_CPU0_SKTOCC_LVT3_N  PB22D @BASEBOARD_FAB2_LIB.BASEBOARD_FAB2(SCH_1):FM_CPU0_SKTOCC_LVT3_N
 P12 FM_CPU1_PKGID1  PB24A @BASEBOARD_FAB2_LIB.BASEBOARD_FAB2(SCH_1):FM_CPU1_PKGID1
 T13 FM_CPU_MSMI_LVT3_N  PB24B @BASEBOARD_FAB2_LIB.BASEBOARD_FAB2(SCH_1):FM_CPU_MSMI_LVT3_N
 R12 FM_CPU1_PKGID0 PB25A_SN @BASEBOARD_FAB2_LIB.BASEBOARD_FAB2(SCH_1):FM_CPU1_PKGID0
 P13 TP_CPLD1_PB25B_SI_SISPI PB25B_SI_SISPI @BASEBOARD_FAB2_LIB.BASEBOARD_FAB2(SCH_1):TP_CPLD1_PB25B_SI_SISPI
 T15 PWRGD_DRAMPWRGD  PB25C @BASEBOARD_FAB2_LIB.BASEBOARD_FAB2(SCH_1):PWRGD_DRAMPWRGD
 R14 FM_CPU_CATERR_LVT3_N  PB25D @BASEBOARD_FAB2_LIB.BASEBOARD_FAB2(SCH_1):FM_CPU_CATERR_LVT3_N
  D3 TP_CPLD1_PL1A_L_GPLLT_FB PL1A_L_GPLLT_FB @BASEBOARD_FAB2_LIB.BASEBOARD_FAB2(SCH_1):TP_CPLD1_PL1A_L_GPLLT_FB
  D1 TP_CPLD1_PL1B_L_GPLLC_FB PL1B_L_GPLLC_FB @BASEBOARD_FAB2_LIB.BASEBOARD_FAB2(SCH_1):TP_CPLD1_PL1B_L_GPLLC_FB
  B1 RST_PCIE_PCH_PERST_N   PL1C @BASEBOARD_FAB2_LIB.BASEBOARD_FAB2(SCH_1):RST_PCIE_PCH_PERST_N
  C2 FM_PCH_PLD_DATA   PL1D @BASEBOARD_FAB2_LIB.BASEBOARD_FAB2(SCH_1):FM_PCH_PLD_DATA
  E2 FM_CPU_CATERR_DLY_LVT3_N PL2A_L_GPLLT_IN @BASEBOARD_FAB2_LIB.BASEBOARD_FAB2(SCH_1):FM_CPU_CATERR_DLY_LVT3_N
  E3 TP_CPLD1_PL2B_L_GPLLC_IN PL2B_L_GPLLC_IN @BASEBOARD_FAB2_LIB.BASEBOARD_FAB2(SCH_1):TP_CPLD1_PL2B_L_GPLLC_IN
  C1 RST_PCIE_CPU_DEV1_N   PL2C @BASEBOARD_FAB2_LIB.BASEBOARD_FAB2(SCH_1):RST_PCIE_CPU_DEV1_N
  D2 FM_MEM_EVENT_FUNC   PL2D @BASEBOARD_FAB2_LIB.BASEBOARD_FAB2(SCH_1):FM_MEM_EVENT_FUNC
  E1 CLK_32K_SUSCLK_PLD PL3A_PCLKT5_0 @BASEBOARD_FAB2_LIB.BASEBOARD_FAB2(SCH_1):CLK_32K_SUSCLK_PLD
  F2 FM_CPU0_PKGID0 PL3B_PCLKC5_0 @BASEBOARD_FAB2_LIB.BASEBOARD_FAB2(SCH_1):FM_CPU0_PKGID0
  F4 PU_RST_PERST_BIT0   PL3C @BASEBOARD_FAB2_LIB.BASEBOARD_FAB2(SCH_1):PU_RST_PERST_BIT0
  G6 FM_PWR_BTN_R2_N   PL3D @BASEBOARD_FAB2_LIB.BASEBOARD_FAB2(SCH_1):FM_PWR_BTN_R2_N
  F3 FM_CPU0_PROC_ID1   PL4A @BASEBOARD_FAB2_LIB.BASEBOARD_FAB2(SCH_1):FM_CPU0_PROC_ID1
  F1 FM_CPU0_PROC_ID0   PL4B @BASEBOARD_FAB2_LIB.BASEBOARD_FAB2(SCH_1):FM_CPU0_PROC_ID0
  G5 FM_DEBUG_RST_BTN_N   PL4C @BASEBOARD_FAB2_LIB.BASEBOARD_FAB2(SCH_1):FM_DEBUG_RST_BTN_N
  G4 RST_RSMRST_R_N   PL4D @BASEBOARD_FAB2_LIB.BASEBOARD_FAB2(SCH_1):RST_RSMRST_R_N
  G2 FM_CPU0_PKGID2   PL5A @BASEBOARD_FAB2_LIB.BASEBOARD_FAB2(SCH_1):FM_CPU0_PKGID2
  G3 FM_CPU0_PKGID1   PL5B @BASEBOARD_FAB2_LIB.BASEBOARD_FAB2(SCH_1):FM_CPU0_PKGID1
  F5 FM_CPU0_FIVR_FAULT_LVT3_N   PL5C @BASEBOARD_FAB2_LIB.BASEBOARD_FAB2(SCH_1):FM_CPU0_FIVR_FAULT_LVT3_N
  H6 PWRGD_P3V3   PL5D @BASEBOARD_FAB2_LIB.BASEBOARD_FAB2(SCH_1):PWRGD_P3V3
  G1 FM_SLPS3_N   PL6A @BASEBOARD_FAB2_LIB.BASEBOARD_FAB2(SCH_1):FM_SLPS3_N
  H2 FM_PVCCMCP_CPU0_EN   PL6B @BASEBOARD_FAB2_LIB.BASEBOARD_FAB2(SCH_1):FM_PVCCMCP_CPU0_EN
  H4 FM_MP_PS_FAIL_N   PL6C @BASEBOARD_FAB2_LIB.BASEBOARD_FAB2(SCH_1):FM_MP_PS_FAIL_N
  J6 PWRGD_P5V   PL6D @BASEBOARD_FAB2_LIB.BASEBOARD_FAB2(SCH_1):PWRGD_P5V
  H3 RST_PCIE_CPU_DEV2_N   PL7A @BASEBOARD_FAB2_LIB.BASEBOARD_FAB2(SCH_1):RST_PCIE_CPU_DEV2_N
  H1 RST_PCIE_CPU_DEV3_N   PL7B @BASEBOARD_FAB2_LIB.BASEBOARD_FAB2(SCH_1):RST_PCIE_CPU_DEV3_N
  J1 SGPIO_BMC_CLK PL7C_PCLKT4_0 @BASEBOARD_FAB2_LIB.BASEBOARD_FAB2(SCH_1):SGPIO_BMC_CLK
  J3 TP_CPLD1_PL7D_PCLKT4_0 PL7D_PCLKC4_0 @BASEBOARD_FAB2_LIB.BASEBOARD_FAB2(SCH_1):TP_CPLD1_PL7D_PCLKT4_0
  J2 SGPIO_BMC_DOUT   PL9A @BASEBOARD_FAB2_LIB.BASEBOARD_FAB2(SCH_1):SGPIO_BMC_DOUT
  K1 FM_PVCCIOMCP_CPU0_EN   PL9B @BASEBOARD_FAB2_LIB.BASEBOARD_FAB2(SCH_1):FM_PVCCIOMCP_CPU0_EN
  H5     NC   PL9C     NC
  J4     NC   PL9D     NC
  K3 SP1_BMC_HOST_UART_RX  PL10A @BASEBOARD_FAB2_LIB.BASEBOARD_FAB2(SCH_1):SP1_BMC_HOST_UART_RX
  K2 SP1_BMC_HOST_UART_TX  PL10B @BASEBOARD_FAB2_LIB.BASEBOARD_FAB2(SCH_1):SP1_BMC_HOST_UART_TX
  J5 UART_BMC_RXD5  PL10C @BASEBOARD_FAB2_LIB.BASEBOARD_FAB2(SCH_1):UART_BMC_RXD5
  K6 UART_BMC_TXD5  PL10D @BASEBOARD_FAB2_LIB.BASEBOARD_FAB2(SCH_1):UART_BMC_TXD5
  L1 PWRGD_PVSA_CPU0  PL11A @BASEBOARD_FAB2_LIB.BASEBOARD_FAB2(SCH_1):PWRGD_PVSA_CPU0
  L3 TP_CPLD1_PL11A  PL11B @BASEBOARD_FAB2_LIB.BASEBOARD_FAB2(SCH_1):TP_CPLD1_PL11A
  K4 SGPIO_BMC_LD_N  PL11C @BASEBOARD_FAB2_LIB.BASEBOARD_FAB2(SCH_1):SGPIO_BMC_LD_N
  L5 PWRGD_CPU0_LVC3  PL11D @BASEBOARD_FAB2_LIB.BASEBOARD_FAB2(SCH_1):PWRGD_CPU0_LVC3
  L2 CLK_25M_CPLD PL12A_PCLKT3_0 @BASEBOARD_FAB2_LIB.BASEBOARD_FAB2(SCH_1):CLK_25M_CPLD
  M1 RST_RSMRST_DLY PL12B_PCLKC3_0 @BASEBOARD_FAB2_LIB.BASEBOARD_FAB2(SCH_1):RST_RSMRST_DLY
  K5 PWRGD_PVCCIN_CPU0  PL12C @BASEBOARD_FAB2_LIB.BASEBOARD_FAB2(SCH_1):PWRGD_PVCCIN_CPU0
  L4 PWRGD_PVCCMCP_CPU1  PL12D @BASEBOARD_FAB2_LIB.BASEBOARD_FAB2(SCH_1):PWRGD_PVCCMCP_CPU1
  M3 RST_PCIE_RISER1_PERST_N  PL13A @BASEBOARD_FAB2_LIB.BASEBOARD_FAB2(SCH_1):RST_PCIE_RISER1_PERST_N
  N1 PWRGD_PVCCIN_CPU1  PL13B @BASEBOARD_FAB2_LIB.BASEBOARD_FAB2(SCH_1):PWRGD_PVCCIN_CPU1
  N2 PWRGD_PVPP_KLM  PL13C @BASEBOARD_FAB2_LIB.BASEBOARD_FAB2(SCH_1):PWRGD_PVPP_KLM
  P1 FM_GLOBAL_RST_WARN_N  PL13D @BASEBOARD_FAB2_LIB.BASEBOARD_FAB2(SCH_1):FM_GLOBAL_RST_WARN_N
  M2 PWRGD_PVPP_GHJ  PL14A @BASEBOARD_FAB2_LIB.BASEBOARD_FAB2(SCH_1):PWRGD_PVPP_GHJ
  N3 RST_CD_CPU0_POR_N  PL14B @BASEBOARD_FAB2_LIB.BASEBOARD_FAB2(SCH_1):RST_CD_CPU0_POR_N
  R1 FM_BMC_CPLD_GPO  PL14C @BASEBOARD_FAB2_LIB.BASEBOARD_FAB2(SCH_1):FM_BMC_CPLD_GPO
  P2 FM_UART_ALERT_N  PL14D @BASEBOARD_FAB2_LIB.BASEBOARD_FAB2(SCH_1):FM_UART_ALERT_N

RES_0402-33.2,1%,1/16W,CHIP,G2A  I338  R2R2
   1 RST_RSMRST_R_N      A @BASEBOARD_FAB2_LIB.BASEBOARD_FAB2(SCH_1):RST_RSMRST_R_N
   2 RST_RSMRST_N      B @BASEBOARD_FAB2_LIB.BASEBOARD_FAB2(SCH_1):RST_RSMRST_N

RES_0402-10.0K,1%,1/16W,EMPTY,A  I349  R1W26
   1 RST_RSMRST_R_N      A @BASEBOARD_FAB2_LIB.BASEBOARD_FAB2(SCH_1):RST_RSMRST_R_N
   2    GND      B @BASEBOARD_FAB2_LIB.BASEBOARD_FAB2(SCH_1):GND

RES_0402-0.0,5%,1/16W,CHIP,G21A  I351  R1W27
   1 FM_PWR_BTN_N      A @BASEBOARD_FAB2_LIB.BASEBOARD_FAB2(SCH_1):FM_PWR_BTN_N
   2 FM_PWR_BTN_R2_N      B @BASEBOARD_FAB2_LIB.BASEBOARD_FAB2(SCH_1):FM_PWR_BTN_R2_N


DRAWING: @BASEBOARD_FAB2_LIB.BASEBOARD_FAB2(SCH_1):PAGE191 

LCMXO2_A_256BGA-IC,H63395-001  I59  U8D7
 D14 PWRGD_SYS_PWROK   PR1A @BASEBOARD_FAB2_LIB.BASEBOARD_FAB2(SCH_1):PWRGD_SYS_PWROK
 E15 RST_PLTRST_N   PR1B @BASEBOARD_FAB2_LIB.BASEBOARD_FAB2(SCH_1):RST_PLTRST_N
 C15 FM_DB1200_PWRGD   PR1C @BASEBOARD_FAB2_LIB.BASEBOARD_FAB2(SCH_1):FM_DB1200_PWRGD
 B16 FM_ADR_COMPLETE_DLY   PR1D @BASEBOARD_FAB2_LIB.BASEBOARD_FAB2(SCH_1):FM_ADR_COMPLETE_DLY
 D16 PWRGD_P1V8MCP_CPU1   PR2A @BASEBOARD_FAB2_LIB.BASEBOARD_FAB2(SCH_1):PWRGD_P1V8MCP_CPU1
 E14 FM_CPLD_ADR_TRIGGER_N   PR2B @BASEBOARD_FAB2_LIB.BASEBOARD_FAB2(SCH_1):FM_CPLD_ADR_TRIGGER_N
 C16 PWRGD_PCH_PWROK   PR2C @BASEBOARD_FAB2_LIB.BASEBOARD_FAB2(SCH_1):PWRGD_PCH_PWROK
 D15 PWRGD_P1V8MCP_CPU0   PR2D @BASEBOARD_FAB2_LIB.BASEBOARD_FAB2(SCH_1):PWRGD_P1V8MCP_CPU0
 E16 FM_P1V8MCP_CPU0_EN   PR3A @BASEBOARD_FAB2_LIB.BASEBOARD_FAB2(SCH_1):FM_P1V8MCP_CPU0_EN
 F15 FM_CPU0_MCP_CLK_EN_N   PR3B @BASEBOARD_FAB2_LIB.BASEBOARD_FAB2(SCH_1):FM_CPU0_MCP_CLK_EN_N
 F13 PWRGD_CPUPWRGD   PR3C @BASEBOARD_FAB2_LIB.BASEBOARD_FAB2(SCH_1):PWRGD_CPUPWRGD
 G12 FM_CPU0_THERMTRIP_LATCH_LVT3_N   PR3D @BASEBOARD_FAB2_LIB.BASEBOARD_FAB2(SCH_1):FM_CPU0_THERMTRIP_LATCH_LVT3_N
 F14 RST_BMC_SYSRST_BTN_OUT_B_R1_N   PR4A @BASEBOARD_FAB2_LIB.BASEBOARD_FAB2(SCH_1):RST_BMC_SYSRST_BTN_OUT_B_R1_N
 F16 FM_CPU1_MCP_CLK_EN_N   PR4B @BASEBOARD_FAB2_LIB.BASEBOARD_FAB2(SCH_1):FM_CPU1_MCP_CLK_EN_N
 F12 FM_P1V8MCP_CPU1_EN   PR4C @BASEBOARD_FAB2_LIB.BASEBOARD_FAB2(SCH_1):FM_P1V8MCP_CPU1_EN
 G13 FM_CPU1_FIVR_FAULT_LVT3   PR4D @BASEBOARD_FAB2_LIB.BASEBOARD_FAB2(SCH_1):FM_CPU1_FIVR_FAULT_LVT3
 G15 FM_UV_ADR_TRIGGER_N   PR5A @BASEBOARD_FAB2_LIB.BASEBOARD_FAB2(SCH_1):FM_UV_ADR_TRIGGER_N
 G14 FM_CPU1_THERMTRIP_LVT3_N   PR5B @BASEBOARD_FAB2_LIB.BASEBOARD_FAB2(SCH_1):FM_CPU1_THERMTRIP_LVT3_N
 G11 FM_WBG_PRSNT_N   PR5C @BASEBOARD_FAB2_LIB.BASEBOARD_FAB2(SCH_1):FM_WBG_PRSNT_N
 H12 FM_UV_ADR_TRIGGER_EN   PR5D @BASEBOARD_FAB2_LIB.BASEBOARD_FAB2(SCH_1):FM_UV_ADR_TRIGGER_EN
 G16 FM_FAST_PROCHOT_THROTTLE_IN_N   PR6A @BASEBOARD_FAB2_LIB.BASEBOARD_FAB2(SCH_1):FM_FAST_PROCHOT_THROTTLE_IN_N
 H15 FM_PVDDQ_KLM_EN   PR6B @BASEBOARD_FAB2_LIB.BASEBOARD_FAB2(SCH_1):FM_PVDDQ_KLM_EN
 H13 FM_PVDDQ_GHJ_EN   PR6C @BASEBOARD_FAB2_LIB.BASEBOARD_FAB2(SCH_1):FM_PVDDQ_GHJ_EN
 J12 FM_FAST_PROCHOT_THROTTLE_DLY_N   PR6D @BASEBOARD_FAB2_LIB.BASEBOARD_FAB2(SCH_1):FM_FAST_PROCHOT_THROTTLE_DLY_N
 H14 TP_CPLD1_PR7A_PCLKT1_0 PR7A_PCLKT1_0 @BASEBOARD_FAB2_LIB.BASEBOARD_FAB2(SCH_1):TP_CPLD1_PR7A_PCLKT1_0
 H16 TP_CPLD1_PR7B_PCLKC1_0 PR7B_PCLKC1_0 @BASEBOARD_FAB2_LIB.BASEBOARD_FAB2(SCH_1):TP_CPLD1_PR7B_PCLKC1_0
 J16 TP_CPLD1_PR7C   PR7C @BASEBOARD_FAB2_LIB.BASEBOARD_FAB2(SCH_1):TP_CPLD1_PR7C
 J14 TP_CPLD1_PR7D   PR7D @BASEBOARD_FAB2_LIB.BASEBOARD_FAB2(SCH_1):TP_CPLD1_PR7D
 J15 TP_CPLD1_PR9A   PR9A @BASEBOARD_FAB2_LIB.BASEBOARD_FAB2(SCH_1):TP_CPLD1_PR9A
 K16 PU_FAB2_MARKER_CPLD   PR9B @BASEBOARD_FAB2_LIB.BASEBOARD_FAB2(SCH_1):PU_FAB2_MARKER_CPLD
 H11 TP_CPLD1_PR9C   PR9C @BASEBOARD_FAB2_LIB.BASEBOARD_FAB2(SCH_1):TP_CPLD1_PR9C
 J13 TP_CPLD1_PR9D   PR9D @BASEBOARD_FAB2_LIB.BASEBOARD_FAB2(SCH_1):TP_CPLD1_PR9D
 K14 FM_PVDDQ_ABC_EN  PR10A @BASEBOARD_FAB2_LIB.BASEBOARD_FAB2(SCH_1):FM_PVDDQ_ABC_EN
 K15 FM_PVDDQ_DEF_EN  PR10B @BASEBOARD_FAB2_LIB.BASEBOARD_FAB2(SCH_1):FM_PVDDQ_DEF_EN
 J11 TP_CPLD1_PR10C  PR10C @BASEBOARD_FAB2_LIB.BASEBOARD_FAB2(SCH_1):TP_CPLD1_PR10C
 L12 PWRGD_P3V3_STBY  PR10D @BASEBOARD_FAB2_LIB.BASEBOARD_FAB2(SCH_1):PWRGD_P3V3_STBY
 L16 PWRGD_PVCCIO_CPU1  PR11A @BASEBOARD_FAB2_LIB.BASEBOARD_FAB2(SCH_1):PWRGD_PVCCIO_CPU1
 L14 TP_CPLD1_PR11B  PR11B @BASEBOARD_FAB2_LIB.BASEBOARD_FAB2(SCH_1):TP_CPLD1_PR11B
 K13 FM_MEM_THERM_EVENT_LVT3_N  PR11C @BASEBOARD_FAB2_LIB.BASEBOARD_FAB2(SCH_1):FM_MEM_THERM_EVENT_LVT3_N
 K12 FM_MEM_THERM_EVENT_PCH_N  PR11D @BASEBOARD_FAB2_LIB.BASEBOARD_FAB2(SCH_1):FM_MEM_THERM_EVENT_PCH_N
 L15 FM_THERMTRIP_DLY  PR12A @BASEBOARD_FAB2_LIB.BASEBOARD_FAB2(SCH_1):FM_THERMTRIP_DLY
 M16 FM_CPU0_FIVR_FAULT_LVT3  PR12B @BASEBOARD_FAB2_LIB.BASEBOARD_FAB2(SCH_1):FM_CPU0_FIVR_FAULT_LVT3
 K11 RST_PLTRST_BUF_N  PR12C @BASEBOARD_FAB2_LIB.BASEBOARD_FAB2(SCH_1):RST_PLTRST_BUF_N
 L13 TP_CPLD1_PR12D  PR12D @BASEBOARD_FAB2_LIB.BASEBOARD_FAB2(SCH_1):TP_CPLD1_PR12D
 M14 FM_CPU1_PROC_ID1  PR13A @BASEBOARD_FAB2_LIB.BASEBOARD_FAB2(SCH_1):FM_CPU1_PROC_ID1
 M15 FM_CPU1_PROC_ID0  PR13B @BASEBOARD_FAB2_LIB.BASEBOARD_FAB2(SCH_1):FM_CPU1_PROC_ID0
 N15 FM_CPU0_THERMTRIP_LVT3_N  PR13C @BASEBOARD_FAB2_LIB.BASEBOARD_FAB2(SCH_1):FM_CPU0_THERMTRIP_LVT3_N
 P16 FM_PVPP_CPU1_EN  PR13D @BASEBOARD_FAB2_LIB.BASEBOARD_FAB2(SCH_1):FM_PVPP_CPU1_EN
 N16 FM_PVCCIN_PVCCSA_CPU1_EN_LVC1  PR14A @BASEBOARD_FAB2_LIB.BASEBOARD_FAB2(SCH_1):FM_PVCCIN_PVCCSA_CPU1_EN_LVC1
 N14 FM_CPU1_VRM_OSC_EN  PR14B @BASEBOARD_FAB2_LIB.BASEBOARD_FAB2(SCH_1):FM_CPU1_VRM_OSC_EN
 P15 FM_PVPP_CPU0_EN  PR14C @BASEBOARD_FAB2_LIB.BASEBOARD_FAB2(SCH_1):FM_PVPP_CPU0_EN
 R16 FM_P12V_MAIN_SW_EN  PR14D @BASEBOARD_FAB2_LIB.BASEBOARD_FAB2(SCH_1):FM_P12V_MAIN_SW_EN
  C4 FM_ADR_SMI_GPIO_R_N   PT9A @BASEBOARD_FAB2_LIB.BASEBOARD_FAB2(SCH_1):FM_ADR_SMI_GPIO_R_N
  B5 PWRGD_P12V_MAIN   PT9B @BASEBOARD_FAB2_LIB.BASEBOARD_FAB2(SCH_1):PWRGD_P12V_MAIN
  B3 FM_CTNR_PS_ON   PT9C @BASEBOARD_FAB2_LIB.BASEBOARD_FAB2(SCH_1):FM_CTNR_PS_ON
  A4 FM_P3V3_CPLD_EN  PT10A @BASEBOARD_FAB2_LIB.BASEBOARD_FAB2(SCH_1):FM_P3V3_CPLD_EN
  C5 FM_CPU1_THERMTRIP_LATCH_LVT3_N  PT10B @BASEBOARD_FAB2_LIB.BASEBOARD_FAB2(SCH_1):FM_CPU1_THERMTRIP_LATCH_LVT3_N
  A5 TP_CPLD1_PT11A  PT11A @BASEBOARD_FAB2_LIB.BASEBOARD_FAB2(SCH_1):TP_CPLD1_PT11A
  B6 TP_CPLD1_PT11B  PT11B @BASEBOARD_FAB2_LIB.BASEBOARD_FAB2(SCH_1):TP_CPLD1_PT11B
  A3 FM_PCH_PRSNT_N  PT11C @BASEBOARD_FAB2_LIB.BASEBOARD_FAB2(SCH_1):FM_PCH_PRSNT_N
  B4 PWRGD_PVTT_CPU0  PT11D @BASEBOARD_FAB2_LIB.BASEBOARD_FAB2(SCH_1):PWRGD_PVTT_CPU0
  D6 RST_PCIE_CPU_DEV0_N  PT12A @BASEBOARD_FAB2_LIB.BASEBOARD_FAB2(SCH_1):RST_PCIE_CPU_DEV0_N
  E7 PWRGD_P1V15_BMC_STBY  PT12B @BASEBOARD_FAB2_LIB.BASEBOARD_FAB2(SCH_1):PWRGD_P1V15_BMC_STBY
  C6 JTAG_PLD_TDO PT12C_TDO @BASEBOARD_FAB2_LIB.BASEBOARD_FAB2(SCH_1):JTAG_PLD_TDO
  A6 JTAG_PLD_TDI PT12D_TDI @BASEBOARD_FAB2_LIB.BASEBOARD_FAB2(SCH_1):JTAG_PLD_TDI
  B7 TP_CPLD1_PT13A  PT13A @BASEBOARD_FAB2_LIB.BASEBOARD_FAB2(SCH_1):TP_CPLD1_PT13A
  C7 FM_BMC_ONCTL_N  PT13B @BASEBOARD_FAB2_LIB.BASEBOARD_FAB2(SCH_1):FM_BMC_ONCTL_N
  E6 FM_CPU1_FIVR_FAULT_LVT3_N  PT13C @BASEBOARD_FAB2_LIB.BASEBOARD_FAB2(SCH_1):FM_CPU1_FIVR_FAULT_LVT3_N
  D7 FM_FORCE_ADR_N  PT13D @BASEBOARD_FAB2_LIB.BASEBOARD_FAB2(SCH_1):FM_FORCE_ADR_N
  F7 FM_PLD_DEBUG_MODE_N  PT16A @BASEBOARD_FAB2_LIB.BASEBOARD_FAB2(SCH_1):FM_PLD_DEBUG_MODE_N
  E8 TP_CPLD1_PT16B  PT16B @BASEBOARD_FAB2_LIB.BASEBOARD_FAB2(SCH_1):TP_CPLD1_PT16B
  A7 JTAG_PLD_TCK PT16C_TCK @BASEBOARD_FAB2_LIB.BASEBOARD_FAB2(SCH_1):JTAG_PLD_TCK
  B8 JTAG_PLD_TMS PT16D_TMS @BASEBOARD_FAB2_LIB.BASEBOARD_FAB2(SCH_1):JTAG_PLD_TMS
  C8 FM_ADR_COMPLETE PT17A_PCLKT0_1 @BASEBOARD_FAB2_LIB.BASEBOARD_FAB2(SCH_1):FM_ADR_COMPLETE
  A8 TP_CPLD1_PT17B_PCLKC0_1 PT17B_PCLKC0_1 @BASEBOARD_FAB2_LIB.BASEBOARD_FAB2(SCH_1):TP_CPLD1_PT17B_PCLKC0_1
  D8 TP_CPLD1_PT17C  PT17C @BASEBOARD_FAB2_LIB.BASEBOARD_FAB2(SCH_1):TP_CPLD1_PT17C
  E9 FM_SLP_SUS_N  PT17D @BASEBOARD_FAB2_LIB.BASEBOARD_FAB2(SCH_1):FM_SLP_SUS_N
  F8 SGPIO_BMC_DIN_R  PT18A @BASEBOARD_FAB2_LIB.BASEBOARD_FAB2(SCH_1):SGPIO_BMC_DIN_R
  D9 RST_PCIE_MIDPLANE_N  PT18B @BASEBOARD_FAB2_LIB.BASEBOARD_FAB2(SCH_1):RST_PCIE_MIDPLANE_N
  A9 SMB_SENSOR_STBY_LVC3_SCL PT18C_SCL_PCLKT0_0 @BASEBOARD_FAB2_LIB.BASEBOARD_FAB2(SCH_1):SMB_SENSOR_STBY_LVC3_SCL
  C9 SMB_SENSOR_STBY_LVC3_SDA PT18D_SDA_PCLKC0_0 @BASEBOARD_FAB2_LIB.BASEBOARD_FAB2(SCH_1):SMB_SENSOR_STBY_LVC3_SDA
  B9 PU_RST_PERST_BIT1  PT19A @BASEBOARD_FAB2_LIB.BASEBOARD_FAB2(SCH_1):PU_RST_PERST_BIT1
 A10 FM_PVCCIN_PVCCSA_CPU0_EN_LVC1  PT19B @BASEBOARD_FAB2_LIB.BASEBOARD_FAB2(SCH_1):FM_PVCCIN_PVCCSA_CPU0_EN_LVC1
  F9 FM_PS_EN  PT19C @BASEBOARD_FAB2_LIB.BASEBOARD_FAB2(SCH_1):FM_PS_EN
 E11 TP_CPLD1_PT19D  PT19D @BASEBOARD_FAB2_LIB.BASEBOARD_FAB2(SCH_1):TP_CPLD1_PT19D
 D10 TP_CPLD1_PT20A  PT20A @BASEBOARD_FAB2_LIB.BASEBOARD_FAB2(SCH_1):TP_CPLD1_PT20A
 E10 TP_CPLD1_PT20B  PT20B @BASEBOARD_FAB2_LIB.BASEBOARD_FAB2(SCH_1):TP_CPLD1_PT20B
 C10 FM_JTAG_PLD_EN_DEBUG PT20C_JTAGENB @BASEBOARD_FAB2_LIB.BASEBOARD_FAB2(SCH_1):FM_JTAG_PLD_EN_DEBUG
 B10 PU_CPLD1_PT20D_PROGRAMN PT20D_PROGRAMN @BASEBOARD_FAB2_LIB.BASEBOARD_FAB2(SCH_1):PU_CPLD1_PT20D_PROGRAMN
 A11 FM_CPU0_OR_CPU1_MCP_PRES  PT21A @BASEBOARD_FAB2_LIB.BASEBOARD_FAB2(SCH_1):FM_CPU0_OR_CPU1_MCP_PRES
 C11 FM_CPU0_CD_PRES  PT21B @BASEBOARD_FAB2_LIB.BASEBOARD_FAB2(SCH_1):FM_CPU0_CD_PRES
 F10 FM_CPU1_CD_PRES_N  PT21C @BASEBOARD_FAB2_LIB.BASEBOARD_FAB2(SCH_1):FM_CPU1_CD_PRES_N
 D11 FM_CPU0_AND_CPU1_MCP_PRES  PT21D @BASEBOARD_FAB2_LIB.BASEBOARD_FAB2(SCH_1):FM_CPU0_AND_CPU1_MCP_PRES
 B11 PWRGD_DSW_PWROK  PT22A @BASEBOARD_FAB2_LIB.BASEBOARD_FAB2(SCH_1):PWRGD_DSW_PWROK
 A12 PU_THERMTRIP_FORCE_N  PT22B @BASEBOARD_FAB2_LIB.BASEBOARD_FAB2(SCH_1):PU_THERMTRIP_FORCE_N
 B13 TP_CPLD1_PT22C  PT22C @BASEBOARD_FAB2_LIB.BASEBOARD_FAB2(SCH_1):TP_CPLD1_PT22C
 A14 TP_CPLD1_PT22D  PT22D @BASEBOARD_FAB2_LIB.BASEBOARD_FAB2(SCH_1):TP_CPLD1_PT22D
 C12 FM_SLPS4_N  PT23A @BASEBOARD_FAB2_LIB.BASEBOARD_FAB2(SCH_1):FM_SLPS4_N
 B12 FM_PCH_PWRBTN_R1_N  PT23B @BASEBOARD_FAB2_LIB.BASEBOARD_FAB2(SCH_1):FM_PCH_PWRBTN_R1_N
 B14 FM_SINT_PRSNT_N  PT24A @BASEBOARD_FAB2_LIB.BASEBOARD_FAB2(SCH_1):FM_SINT_PRSNT_N
 A15 TP_CPLD1_PT24B  PT24B @BASEBOARD_FAB2_LIB.BASEBOARD_FAB2(SCH_1):TP_CPLD1_PT24B
 A13 TP_CPLD1_PT24C_INITN PT24C_INITN @BASEBOARD_FAB2_LIB.BASEBOARD_FAB2(SCH_1):TP_CPLD1_PT24C_INITN
 C13 TP_CPLD1_PT24D_DONE PT24D_DONE @BASEBOARD_FAB2_LIB.BASEBOARD_FAB2(SCH_1):TP_CPLD1_PT24D_DONE

RES_0402-51,5.0%,1/16W,CHIP,G2A  I166  R2R6
   1 SGPIO_BMC_DIN_R      A @BASEBOARD_FAB2_LIB.BASEBOARD_FAB2(SCH_1):SGPIO_BMC_DIN_R
   2 SGPIO_BMC_DIN      B @BASEBOARD_FAB2_LIB.BASEBOARD_FAB2(SCH_1):SGPIO_BMC_DIN

RES_0402-4.75K,1%,1/16W,CHIP,GA  I172  R2R7
   1 P3V3_STBY      A @BASEBOARD_FAB2_LIB.BASEBOARD_FAB2(SCH_1):P3V3_STBY
   2 FM_FORCE_ADR_N      B @BASEBOARD_FAB2_LIB.BASEBOARD_FAB2(SCH_1):FM_FORCE_ADR_N

RES_0402-0.0,5%,1/16W,CHIP,G21A  I184  R2R4
   1 FM_ADR_SMI_GPIO_R_N      A @BASEBOARD_FAB2_LIB.BASEBOARD_FAB2(SCH_1):FM_ADR_SMI_GPIO_R_N
   2 FM_ADR_SMI_GPIO_N      B @BASEBOARD_FAB2_LIB.BASEBOARD_FAB2(SCH_1):FM_ADR_SMI_GPIO_N

RES_0402-4.75K,1%,1/16W,CHIP,GA  I193  R7D42
   1 P3V3_STBY      A @BASEBOARD_FAB2_LIB.BASEBOARD_FAB2(SCH_1):P3V3_STBY
   2 PU_FAB2_MARKER_CPLD      B @BASEBOARD_FAB2_LIB.BASEBOARD_FAB2(SCH_1):PU_FAB2_MARKER_CPLD

RES_0402-4.75K,1%,1/16W,CHIP,GA  I195  R4W1
   1 P3V3_STBY      A @BASEBOARD_FAB2_LIB.BASEBOARD_FAB2(SCH_1):P3V3_STBY
   2 PU_CPLD1_PT20D_PROGRAMN      B @BASEBOARD_FAB2_LIB.BASEBOARD_FAB2(SCH_1):PU_CPLD1_PT20D_PROGRAMN

RES_0402-0.0,5%,1/16W,CHIP,G21A  I197  R1W28
   1 FM_PCH_PWRBTN_R1_N      A @BASEBOARD_FAB2_LIB.BASEBOARD_FAB2(SCH_1):FM_PCH_PWRBTN_R1_N
   2 FM_PCH_PWRBTN_N      B @BASEBOARD_FAB2_LIB.BASEBOARD_FAB2(SCH_1):FM_PCH_PWRBTN_N

RES_0402-0.0,5%,1/16W,CHIP,G21A  I198  R1W29
   1 RST_BMC_SYSRST_BTN_OUT_B_N      A @BASEBOARD_FAB2_LIB.BASEBOARD_FAB2(SCH_1):RST_BMC_SYSRST_BTN_OUT_B_N
   2 RST_BMC_SYSRST_BTN_OUT_B_R1_N      B @BASEBOARD_FAB2_LIB.BASEBOARD_FAB2(SCH_1):RST_BMC_SYSRST_BTN_OUT_B_R1_N


DRAWING: @BASEBOARD_FAB2_LIB.BASEBOARD_FAB2(SCH_1):PAGE192 

CAP_A_0402V-0.01UF,25V,10%,X7RA  I1  C2P8
   1 P3V3_STBY      A @BASEBOARD_FAB2_LIB.BASEBOARD_FAB2(SCH_1):P3V3_STBY
   2    GND      B @BASEBOARD_FAB2_LIB.BASEBOARD_FAB2(SCH_1):GND

CAP_A_0402V-0.1UF,16V,10%,X7R,A  I3  C2P5
   1 P3V3_STBY      A @BASEBOARD_FAB2_LIB.BASEBOARD_FAB2(SCH_1):P3V3_STBY
   2    GND      B @BASEBOARD_FAB2_LIB.BASEBOARD_FAB2(SCH_1):GND

CAP_A_0402V-0.1UF,16V,10%,X7R,A  I4  C3R1
   1 P3V3_STBY      A @BASEBOARD_FAB2_LIB.BASEBOARD_FAB2(SCH_1):P3V3_STBY
   2    GND      B @BASEBOARD_FAB2_LIB.BASEBOARD_FAB2(SCH_1):GND

CAP_A_0402V-0.1UF,16V,10%,X7R,A  I6  C3P43
   1 P3V3_STBY      A @BASEBOARD_FAB2_LIB.BASEBOARD_FAB2(SCH_1):P3V3_STBY
   2    GND      B @BASEBOARD_FAB2_LIB.BASEBOARD_FAB2(SCH_1):GND

CAP_A_0402V-0.1UF,16V,10%,X7R,A  I7  C3R3
   1 P3V3_STBY      A @BASEBOARD_FAB2_LIB.BASEBOARD_FAB2(SCH_1):P3V3_STBY
   2    GND      B @BASEBOARD_FAB2_LIB.BASEBOARD_FAB2(SCH_1):GND

CAP_A_0402V-0.1UF,16V,10%,X7R,A  I8  C2R1
   1 P3V3_STBY      A @BASEBOARD_FAB2_LIB.BASEBOARD_FAB2(SCH_1):P3V3_STBY
   2    GND      B @BASEBOARD_FAB2_LIB.BASEBOARD_FAB2(SCH_1):GND

CAP_A_0402V-0.1UF,16V,10%,X7R,A  I9  C2P2
   1 P3V3_STBY      A @BASEBOARD_FAB2_LIB.BASEBOARD_FAB2(SCH_1):P3V3_STBY
   2    GND      B @BASEBOARD_FAB2_LIB.BASEBOARD_FAB2(SCH_1):GND

CAP_A_0402V-0.1UF,16V,10%,X7R,A  I10  C3R2
   1 P3V3_STBY      A @BASEBOARD_FAB2_LIB.BASEBOARD_FAB2(SCH_1):P3V3_STBY
   2    GND      B @BASEBOARD_FAB2_LIB.BASEBOARD_FAB2(SCH_1):GND

CAP_A_0402V-0.1UF,16V,10%,X7R,A  I11  C3P51
   1 P3V3_STBY      A @BASEBOARD_FAB2_LIB.BASEBOARD_FAB2(SCH_1):P3V3_STBY
   2    GND      B @BASEBOARD_FAB2_LIB.BASEBOARD_FAB2(SCH_1):GND

CAP_A_0402V-0.1UF,16V,10%,X7R,A  I12  C3P47
   1 P3V3_STBY      A @BASEBOARD_FAB2_LIB.BASEBOARD_FAB2(SCH_1):P3V3_STBY
   2    GND      B @BASEBOARD_FAB2_LIB.BASEBOARD_FAB2(SCH_1):GND

LCMXO2_A_256BGA-IC,H63395-001  I14  U8D7
  B2    GND GND<0> @BASEBOARD_FAB2_LIB.BASEBOARD_FAB2(SCH_1):GND
 B15    GND GND<1> @BASEBOARD_FAB2_LIB.BASEBOARD_FAB2(SCH_1):GND
  C3    GND GND<2> @BASEBOARD_FAB2_LIB.BASEBOARD_FAB2(SCH_1):GND
 C14    GND GND<3> @BASEBOARD_FAB2_LIB.BASEBOARD_FAB2(SCH_1):GND
  D4    GND GND<4> @BASEBOARD_FAB2_LIB.BASEBOARD_FAB2(SCH_1):GND
 D13    GND GND<5> @BASEBOARD_FAB2_LIB.BASEBOARD_FAB2(SCH_1):GND
  E5    GND GND<6> @BASEBOARD_FAB2_LIB.BASEBOARD_FAB2(SCH_1):GND
 E12    GND GND<7> @BASEBOARD_FAB2_LIB.BASEBOARD_FAB2(SCH_1):GND
  F6    GND GND<8> @BASEBOARD_FAB2_LIB.BASEBOARD_FAB2(SCH_1):GND
 F11    GND GND<9> @BASEBOARD_FAB2_LIB.BASEBOARD_FAB2(SCH_1):GND
  H8    GND GND<10> @BASEBOARD_FAB2_LIB.BASEBOARD_FAB2(SCH_1):GND
  H9    GND GND<11> @BASEBOARD_FAB2_LIB.BASEBOARD_FAB2(SCH_1):GND
  J8    GND GND<12> @BASEBOARD_FAB2_LIB.BASEBOARD_FAB2(SCH_1):GND
  J9    GND GND<13> @BASEBOARD_FAB2_LIB.BASEBOARD_FAB2(SCH_1):GND
  L6    GND GND<14> @BASEBOARD_FAB2_LIB.BASEBOARD_FAB2(SCH_1):GND
 L11    GND GND<15> @BASEBOARD_FAB2_LIB.BASEBOARD_FAB2(SCH_1):GND
  M5    GND GND<16> @BASEBOARD_FAB2_LIB.BASEBOARD_FAB2(SCH_1):GND
 M12    GND GND<17> @BASEBOARD_FAB2_LIB.BASEBOARD_FAB2(SCH_1):GND
  N4    GND GND<18> @BASEBOARD_FAB2_LIB.BASEBOARD_FAB2(SCH_1):GND
 N13    GND GND<19> @BASEBOARD_FAB2_LIB.BASEBOARD_FAB2(SCH_1):GND
  P3    GND GND<20> @BASEBOARD_FAB2_LIB.BASEBOARD_FAB2(SCH_1):GND
 P14    GND GND<21> @BASEBOARD_FAB2_LIB.BASEBOARD_FAB2(SCH_1):GND
  R2    GND GND<22> @BASEBOARD_FAB2_LIB.BASEBOARD_FAB2(SCH_1):GND
 R15    GND GND<23> @BASEBOARD_FAB2_LIB.BASEBOARD_FAB2(SCH_1):GND
  A1 P3V3_STBY VCC<0> @BASEBOARD_FAB2_LIB.BASEBOARD_FAB2(SCH_1):P3V3_STBY
 A16 P3V3_STBY VCC<1> @BASEBOARD_FAB2_LIB.BASEBOARD_FAB2(SCH_1):P3V3_STBY
  T1 P3V3_STBY VCC<2> @BASEBOARD_FAB2_LIB.BASEBOARD_FAB2(SCH_1):P3V3_STBY
 T16 P3V3_STBY VCC<3> @BASEBOARD_FAB2_LIB.BASEBOARD_FAB2(SCH_1):P3V3_STBY
  G7 P3V3_STBY VCC<4> @BASEBOARD_FAB2_LIB.BASEBOARD_FAB2(SCH_1):P3V3_STBY
 G10 P3V3_STBY VCC<5> @BASEBOARD_FAB2_LIB.BASEBOARD_FAB2(SCH_1):P3V3_STBY
  K7 P3V3_STBY VCC<6> @BASEBOARD_FAB2_LIB.BASEBOARD_FAB2(SCH_1):P3V3_STBY
 K10 P3V3_STBY VCC<7> @BASEBOARD_FAB2_LIB.BASEBOARD_FAB2(SCH_1):P3V3_STBY
  G8 P3V3_STBY VCCIO0<0> @BASEBOARD_FAB2_LIB.BASEBOARD_FAB2(SCH_1):P3V3_STBY
 D12 P3V3_STBY VCCIO0<1> @BASEBOARD_FAB2_LIB.BASEBOARD_FAB2(SCH_1):P3V3_STBY
  G9 P3V3_STBY VCCIO0<2> @BASEBOARD_FAB2_LIB.BASEBOARD_FAB2(SCH_1):P3V3_STBY
 E13 P3V3_STBY VCCIO1<0> @BASEBOARD_FAB2_LIB.BASEBOARD_FAB2(SCH_1):P3V3_STBY
 H10 P3V3_STBY VCCIO1<1> @BASEBOARD_FAB2_LIB.BASEBOARD_FAB2(SCH_1):P3V3_STBY
 J10 P3V3_STBY VCCIO1<2> @BASEBOARD_FAB2_LIB.BASEBOARD_FAB2(SCH_1):P3V3_STBY
 M13 P3V3_STBY VCCIO1<3> @BASEBOARD_FAB2_LIB.BASEBOARD_FAB2(SCH_1):P3V3_STBY
  K9 P3V3_STBY VCCIO2<0> @BASEBOARD_FAB2_LIB.BASEBOARD_FAB2(SCH_1):P3V3_STBY
 N12 P3V3_STBY VCCIO2<1> @BASEBOARD_FAB2_LIB.BASEBOARD_FAB2(SCH_1):P3V3_STBY
  K8 P3V3_STBY VCCIO2<2> @BASEBOARD_FAB2_LIB.BASEBOARD_FAB2(SCH_1):P3V3_STBY
  N5 P3V3_STBY VCCIO2<3> @BASEBOARD_FAB2_LIB.BASEBOARD_FAB2(SCH_1):P3V3_STBY
  J7 P3V3_STBY VCCIO4<0> @BASEBOARD_FAB2_LIB.BASEBOARD_FAB2(SCH_1):P3V3_STBY
  H7 P3V3_STBY VCCIO4<1> @BASEBOARD_FAB2_LIB.BASEBOARD_FAB2(SCH_1):P3V3_STBY
  E4 P3V3_STBY VCCIO5<0> @BASEBOARD_FAB2_LIB.BASEBOARD_FAB2(SCH_1):P3V3_STBY
  D5 P3V3_STBY VCCIO0<3> @BASEBOARD_FAB2_LIB.BASEBOARD_FAB2(SCH_1):P3V3_STBY
  A2     NC  NC<0>     NC
  M4 P3V3_STBY VCCIO3<0> @BASEBOARD_FAB2_LIB.BASEBOARD_FAB2(SCH_1):P3V3_STBY

CAP_A_0402V-0.1UF,16V,10%,X7R,A  I15  C2R5
   1 P3V3_STBY      A @BASEBOARD_FAB2_LIB.BASEBOARD_FAB2(SCH_1):P3V3_STBY
   2    GND      B @BASEBOARD_FAB2_LIB.BASEBOARD_FAB2(SCH_1):GND

CAP_A_0402V-0.1UF,16V,10%,X7R,A  I16  C2P4
   1 P3V3_STBY      A @BASEBOARD_FAB2_LIB.BASEBOARD_FAB2(SCH_1):P3V3_STBY
   2    GND      B @BASEBOARD_FAB2_LIB.BASEBOARD_FAB2(SCH_1):GND

CAP_A_0402V-0.1UF,16V,10%,X7R,A  I17  C3P52
   1 P3V3_STBY      A @BASEBOARD_FAB2_LIB.BASEBOARD_FAB2(SCH_1):P3V3_STBY
   2    GND      B @BASEBOARD_FAB2_LIB.BASEBOARD_FAB2(SCH_1):GND

CAP_A_0402V-0.1UF,16V,10%,X7R,A  I18  C2P6
   1 P3V3_STBY      A @BASEBOARD_FAB2_LIB.BASEBOARD_FAB2(SCH_1):P3V3_STBY
   2    GND      B @BASEBOARD_FAB2_LIB.BASEBOARD_FAB2(SCH_1):GND

CAP_A_0402V-0.1UF,16V,10%,X7R,A  I19  C2R3
   1 P3V3_STBY      A @BASEBOARD_FAB2_LIB.BASEBOARD_FAB2(SCH_1):P3V3_STBY
   2    GND      B @BASEBOARD_FAB2_LIB.BASEBOARD_FAB2(SCH_1):GND

CAP_A_0402V-0.1UF,16V,10%,X7R,A  I20  C2P7
   1 P3V3_STBY      A @BASEBOARD_FAB2_LIB.BASEBOARD_FAB2(SCH_1):P3V3_STBY
   2    GND      B @BASEBOARD_FAB2_LIB.BASEBOARD_FAB2(SCH_1):GND

CAP_A_0402V-0.1UF,16V,10%,X7R,A  I21  C2R4
   1 P3V3_STBY      A @BASEBOARD_FAB2_LIB.BASEBOARD_FAB2(SCH_1):P3V3_STBY
   2    GND      B @BASEBOARD_FAB2_LIB.BASEBOARD_FAB2(SCH_1):GND

CAP_A_0402V-0.1UF,16V,10%,X7R,A  I22  C2P3
   1 P3V3_STBY      A @BASEBOARD_FAB2_LIB.BASEBOARD_FAB2(SCH_1):P3V3_STBY
   2    GND      B @BASEBOARD_FAB2_LIB.BASEBOARD_FAB2(SCH_1):GND

CAP_A_0402V-0.1UF,16V,10%,X7R,A  I23  C3P44
   1 P3V3_STBY      A @BASEBOARD_FAB2_LIB.BASEBOARD_FAB2(SCH_1):P3V3_STBY
   2    GND      B @BASEBOARD_FAB2_LIB.BASEBOARD_FAB2(SCH_1):GND

CAP_A_0402V-0.1UF,16V,10%,X7R,A  I25  C3P48
   1 P3V3_STBY      A @BASEBOARD_FAB2_LIB.BASEBOARD_FAB2(SCH_1):P3V3_STBY
   2    GND      B @BASEBOARD_FAB2_LIB.BASEBOARD_FAB2(SCH_1):GND

CAP_A_0402V-0.1UF,16V,10%,X7R,A  I28  C2R2
   1 P3V3_STBY      A @BASEBOARD_FAB2_LIB.BASEBOARD_FAB2(SCH_1):P3V3_STBY
   2    GND      B @BASEBOARD_FAB2_LIB.BASEBOARD_FAB2(SCH_1):GND

RES_0402-10.0K,1%,1/16W,CHIP,GA  I33  R7E6
   1 P3V3_STBY      A @BASEBOARD_FAB2_LIB.BASEBOARD_FAB2(SCH_1):P3V3_STBY
   2 PU_RST_PERST_BIT1      B @BASEBOARD_FAB2_LIB.BASEBOARD_FAB2(SCH_1):PU_RST_PERST_BIT1

RES_0402-10.0K,1%,1/16W,CHIP,GA  I34  R2R1
   1 P3V3_STBY      A @BASEBOARD_FAB2_LIB.BASEBOARD_FAB2(SCH_1):P3V3_STBY
   2 PU_RST_PERST_BIT0      B @BASEBOARD_FAB2_LIB.BASEBOARD_FAB2(SCH_1):PU_RST_PERST_BIT0

RES_0402-10.0K,1%,1/16W,CHIP,GA  I38  R7E5
   1 P3V3_STBY      A @BASEBOARD_FAB2_LIB.BASEBOARD_FAB2(SCH_1):P3V3_STBY
   2 PU_THERMTRIP_FORCE_N      B @BASEBOARD_FAB2_LIB.BASEBOARD_FAB2(SCH_1):PU_THERMTRIP_FORCE_N

RES_0402-10.0K,1%,1/16W,CHIP,GA  I41  R2R3
   1 P3V3_STBY      A @BASEBOARD_FAB2_LIB.BASEBOARD_FAB2(SCH_1):P3V3_STBY
   2 FM_PLD_DEBUG_MODE_N      B @BASEBOARD_FAB2_LIB.BASEBOARD_FAB2(SCH_1):FM_PLD_DEBUG_MODE_N

RES_0402-4.75K,1%,1/16W,CHIP,GA  I48  R3R16
   1 PVPP_ABC      A @BASEBOARD_FAB2_LIB.BASEBOARD_FAB2(SCH_1):PVPP_ABC
   2 RST_CD_CPU0_POR_N      B @BASEBOARD_FAB2_LIB.BASEBOARD_FAB2(SCH_1):RST_CD_CPU0_POR_N

RES_0402-4.75K,1%,1/16W,CHIP,GA  I49  R6M9
   1 PVPP_KLM      A @BASEBOARD_FAB2_LIB.BASEBOARD_FAB2(SCH_1):PVPP_KLM
   2 RST_CD_CPU1_POR_N      B @BASEBOARD_FAB2_LIB.BASEBOARD_FAB2(SCH_1):RST_CD_CPU1_POR_N

RES_0402-4.75K,1%,1/16W,CHIP,GA  I55  R7E18
   1 P3V3_STBY      A @BASEBOARD_FAB2_LIB.BASEBOARD_FAB2(SCH_1):P3V3_STBY
   2 RST_RSMRST_N      B @BASEBOARD_FAB2_LIB.BASEBOARD_FAB2(SCH_1):RST_RSMRST_N

RES_0402-1.00K,1%,1/16W,EMPTY,A  I57  R7E19
   1 P3V3_STBY      A @BASEBOARD_FAB2_LIB.BASEBOARD_FAB2(SCH_1):P3V3_STBY
   2 FM_MEM_EVENT_FUNC      B @BASEBOARD_FAB2_LIB.BASEBOARD_FAB2(SCH_1):FM_MEM_EVENT_FUNC

RES_0402-1.00K,1%,1/16W,CHIP,GA  I59  R7E20
   1 FM_MEM_EVENT_FUNC      A @BASEBOARD_FAB2_LIB.BASEBOARD_FAB2(SCH_1):FM_MEM_EVENT_FUNC
   2    GND      B @BASEBOARD_FAB2_LIB.BASEBOARD_FAB2(SCH_1):GND


DRAWING: @BASEBOARD_FAB2_LIB.BASEBOARD_FAB2(SCH_1):PAGE193 

CAPP_3018-470UF,2.5V,20%,ALUM,A  I29  C4C1
   1 PVCCIOMCP_CPU1      A @BASEBOARD_FAB2_LIB.BASEBOARD_FAB2(SCH_1):PVCCIOMCP_CPU1
   2    GND      B @BASEBOARD_FAB2_LIB.BASEBOARD_FAB2(SCH_1):GND

CAP_A_0402V-1.0UF,6.3V,10%,X6SA  I31  C3C2
   1 PVCCIOMCP_CPU1      A @BASEBOARD_FAB2_LIB.BASEBOARD_FAB2(SCH_1):PVCCIOMCP_CPU1
   2    GND      B @BASEBOARD_FAB2_LIB.BASEBOARD_FAB2(SCH_1):GND

CAP_A_0402V-1.0UF,6.3V,10%,X6SA  I38  C3C1
   1 PVCCIOMCP_CPU1      A @BASEBOARD_FAB2_LIB.BASEBOARD_FAB2(SCH_1):PVCCIOMCP_CPU1
   2    GND      B @BASEBOARD_FAB2_LIB.BASEBOARD_FAB2(SCH_1):GND

SCONN120_H61426002_SM-CONN,H61A  I45  J4E1
  A1 PVCCMCP_CPU1   IOA1 @BASEBOARD_FAB2_LIB.BASEBOARD_FAB2(SCH_1):PVCCMCP_CPU1
 A10 PVCCMCP_CPU1  IOA10 @BASEBOARD_FAB2_LIB.BASEBOARD_FAB2(SCH_1):PVCCMCP_CPU1
 A11 PVCCMCP_CPU1  IOA11 @BASEBOARD_FAB2_LIB.BASEBOARD_FAB2(SCH_1):PVCCMCP_CPU1
 A12 PVCCMCP_CPU1  IOA12 @BASEBOARD_FAB2_LIB.BASEBOARD_FAB2(SCH_1):PVCCMCP_CPU1
 A13 PVCCMCP_CPU1  IOA13 @BASEBOARD_FAB2_LIB.BASEBOARD_FAB2(SCH_1):PVCCMCP_CPU1
 A14 PVCCMCP_CPU1  IOA14 @BASEBOARD_FAB2_LIB.BASEBOARD_FAB2(SCH_1):PVCCMCP_CPU1
 A15 PVCCMCP_CPU1  IOA15 @BASEBOARD_FAB2_LIB.BASEBOARD_FAB2(SCH_1):PVCCMCP_CPU1
 A16 PVCCMCP_CPU1  IOA16 @BASEBOARD_FAB2_LIB.BASEBOARD_FAB2(SCH_1):PVCCMCP_CPU1
 A17 PVCCMCP_CPU1  IOA17 @BASEBOARD_FAB2_LIB.BASEBOARD_FAB2(SCH_1):PVCCMCP_CPU1
 A18 PVCCMCP_CPU1  IOA18 @BASEBOARD_FAB2_LIB.BASEBOARD_FAB2(SCH_1):PVCCMCP_CPU1
 A19    GND  IOA19 @BASEBOARD_FAB2_LIB.BASEBOARD_FAB2(SCH_1):GND
  A2 PVCCMCP_CPU1   IOA2 @BASEBOARD_FAB2_LIB.BASEBOARD_FAB2(SCH_1):PVCCMCP_CPU1
 A20    GND  IOA20 @BASEBOARD_FAB2_LIB.BASEBOARD_FAB2(SCH_1):GND
  A3 PVCCMCP_CPU1   IOA3 @BASEBOARD_FAB2_LIB.BASEBOARD_FAB2(SCH_1):PVCCMCP_CPU1
  A4 VSENSE_PVCCMCP_CPU1_SKT_VSEN   IOA4 @BASEBOARD_FAB2_LIB.BASEBOARD_FAB2(SCH_1):VSENSE_PVCCMCP_CPU1_SKT_VSEN
  A5 PVCCMCP_CPU1   IOA5 @BASEBOARD_FAB2_LIB.BASEBOARD_FAB2(SCH_1):PVCCMCP_CPU1
  A6 PVCCMCP_CPU1   IOA6 @BASEBOARD_FAB2_LIB.BASEBOARD_FAB2(SCH_1):PVCCMCP_CPU1
  A7 PVCCMCP_CPU1   IOA7 @BASEBOARD_FAB2_LIB.BASEBOARD_FAB2(SCH_1):PVCCMCP_CPU1
  A8 PVCCMCP_CPU1   IOA8 @BASEBOARD_FAB2_LIB.BASEBOARD_FAB2(SCH_1):PVCCMCP_CPU1
  A9 PVCCMCP_CPU1   IOA9 @BASEBOARD_FAB2_LIB.BASEBOARD_FAB2(SCH_1):PVCCMCP_CPU1
  B1 PVCCMCP_CPU1   IOB1 @BASEBOARD_FAB2_LIB.BASEBOARD_FAB2(SCH_1):PVCCMCP_CPU1
 B10 PVCCMCP_CPU1  IOB10 @BASEBOARD_FAB2_LIB.BASEBOARD_FAB2(SCH_1):PVCCMCP_CPU1
 B11 PVCCMCP_CPU1  IOB11 @BASEBOARD_FAB2_LIB.BASEBOARD_FAB2(SCH_1):PVCCMCP_CPU1
 B12 PVCCMCP_CPU1  IOB12 @BASEBOARD_FAB2_LIB.BASEBOARD_FAB2(SCH_1):PVCCMCP_CPU1
 B13 PVCCMCP_CPU1  IOB13 @BASEBOARD_FAB2_LIB.BASEBOARD_FAB2(SCH_1):PVCCMCP_CPU1
 B14 PVCCMCP_CPU1  IOB14 @BASEBOARD_FAB2_LIB.BASEBOARD_FAB2(SCH_1):PVCCMCP_CPU1
 B15 PVCCMCP_CPU1  IOB15 @BASEBOARD_FAB2_LIB.BASEBOARD_FAB2(SCH_1):PVCCMCP_CPU1
 B16 PVCCMCP_CPU1  IOB16 @BASEBOARD_FAB2_LIB.BASEBOARD_FAB2(SCH_1):PVCCMCP_CPU1
 B17 PVCCMCP_CPU1  IOB17 @BASEBOARD_FAB2_LIB.BASEBOARD_FAB2(SCH_1):PVCCMCP_CPU1
 B18 PVCCMCP_CPU1  IOB18 @BASEBOARD_FAB2_LIB.BASEBOARD_FAB2(SCH_1):PVCCMCP_CPU1
 B19    GND  IOB19 @BASEBOARD_FAB2_LIB.BASEBOARD_FAB2(SCH_1):GND
  B2 PVCCMCP_CPU1   IOB2 @BASEBOARD_FAB2_LIB.BASEBOARD_FAB2(SCH_1):PVCCMCP_CPU1
 B20    GND  IOB20 @BASEBOARD_FAB2_LIB.BASEBOARD_FAB2(SCH_1):GND
  B3 PVCCMCP_CPU1   IOB3 @BASEBOARD_FAB2_LIB.BASEBOARD_FAB2(SCH_1):PVCCMCP_CPU1
  B4 VSENSE_PVCCMCP_CPU1_SKT_VRTN   IOB4 @BASEBOARD_FAB2_LIB.BASEBOARD_FAB2(SCH_1):VSENSE_PVCCMCP_CPU1_SKT_VRTN
  B5 PVCCMCP_CPU1   IOB5 @BASEBOARD_FAB2_LIB.BASEBOARD_FAB2(SCH_1):PVCCMCP_CPU1
  B6 PVCCMCP_CPU1   IOB6 @BASEBOARD_FAB2_LIB.BASEBOARD_FAB2(SCH_1):PVCCMCP_CPU1
  B7 PVCCMCP_CPU1   IOB7 @BASEBOARD_FAB2_LIB.BASEBOARD_FAB2(SCH_1):PVCCMCP_CPU1
  B8 PVCCMCP_CPU1   IOB8 @BASEBOARD_FAB2_LIB.BASEBOARD_FAB2(SCH_1):PVCCMCP_CPU1
  B9 PVCCMCP_CPU1   IOB9 @BASEBOARD_FAB2_LIB.BASEBOARD_FAB2(SCH_1):PVCCMCP_CPU1
  C1 PVCCMCP_CPU1   IOC1 @BASEBOARD_FAB2_LIB.BASEBOARD_FAB2(SCH_1):PVCCMCP_CPU1
 C10 PVCCMCP_CPU1  IOC10 @BASEBOARD_FAB2_LIB.BASEBOARD_FAB2(SCH_1):PVCCMCP_CPU1
 C11 PVCCMCP_CPU1  IOC11 @BASEBOARD_FAB2_LIB.BASEBOARD_FAB2(SCH_1):PVCCMCP_CPU1
 C12 PVCCMCP_CPU1  IOC12 @BASEBOARD_FAB2_LIB.BASEBOARD_FAB2(SCH_1):PVCCMCP_CPU1
 C13 PVCCMCP_CPU1  IOC13 @BASEBOARD_FAB2_LIB.BASEBOARD_FAB2(SCH_1):PVCCMCP_CPU1
 C14 PVCCMCP_CPU1  IOC14 @BASEBOARD_FAB2_LIB.BASEBOARD_FAB2(SCH_1):PVCCMCP_CPU1
 C15 PVCCMCP_CPU1  IOC15 @BASEBOARD_FAB2_LIB.BASEBOARD_FAB2(SCH_1):PVCCMCP_CPU1
 C16 PVCCMCP_CPU1  IOC16 @BASEBOARD_FAB2_LIB.BASEBOARD_FAB2(SCH_1):PVCCMCP_CPU1
 C17 PVCCMCP_CPU1  IOC17 @BASEBOARD_FAB2_LIB.BASEBOARD_FAB2(SCH_1):PVCCMCP_CPU1
 C18 PVCCMCP_CPU1  IOC18 @BASEBOARD_FAB2_LIB.BASEBOARD_FAB2(SCH_1):PVCCMCP_CPU1
 C19    GND  IOC19 @BASEBOARD_FAB2_LIB.BASEBOARD_FAB2(SCH_1):GND
  C2 PVCCMCP_CPU1   IOC2 @BASEBOARD_FAB2_LIB.BASEBOARD_FAB2(SCH_1):PVCCMCP_CPU1
 C20    GND  IOC20 @BASEBOARD_FAB2_LIB.BASEBOARD_FAB2(SCH_1):GND
  C3 PVCCMCP_CPU1   IOC3 @BASEBOARD_FAB2_LIB.BASEBOARD_FAB2(SCH_1):PVCCMCP_CPU1
  C4 PVCCMCP_CPU1   IOC4 @BASEBOARD_FAB2_LIB.BASEBOARD_FAB2(SCH_1):PVCCMCP_CPU1
  C5 PVCCMCP_CPU1   IOC5 @BASEBOARD_FAB2_LIB.BASEBOARD_FAB2(SCH_1):PVCCMCP_CPU1
  C6 PVCCMCP_CPU1   IOC6 @BASEBOARD_FAB2_LIB.BASEBOARD_FAB2(SCH_1):PVCCMCP_CPU1
  C7 PVCCMCP_CPU1   IOC7 @BASEBOARD_FAB2_LIB.BASEBOARD_FAB2(SCH_1):PVCCMCP_CPU1
  C8 PVCCMCP_CPU1   IOC8 @BASEBOARD_FAB2_LIB.BASEBOARD_FAB2(SCH_1):PVCCMCP_CPU1
  C9 PVCCMCP_CPU1   IOC9 @BASEBOARD_FAB2_LIB.BASEBOARD_FAB2(SCH_1):PVCCMCP_CPU1
  D1 VSENSE_P1V8MCP_CPU1_SKT_VSEN   IOD1 @BASEBOARD_FAB2_LIB.BASEBOARD_FAB2(SCH_1):VSENSE_P1V8MCP_CPU1_SKT_VSEN
 D10    GND  IOD10 @BASEBOARD_FAB2_LIB.BASEBOARD_FAB2(SCH_1):GND
 D11    GND  IOD11 @BASEBOARD_FAB2_LIB.BASEBOARD_FAB2(SCH_1):GND
 D12    GND  IOD12 @BASEBOARD_FAB2_LIB.BASEBOARD_FAB2(SCH_1):GND
 D13    GND  IOD13 @BASEBOARD_FAB2_LIB.BASEBOARD_FAB2(SCH_1):GND
 D14    GND  IOD14 @BASEBOARD_FAB2_LIB.BASEBOARD_FAB2(SCH_1):GND
 D15    GND  IOD15 @BASEBOARD_FAB2_LIB.BASEBOARD_FAB2(SCH_1):GND
 D16    GND  IOD16 @BASEBOARD_FAB2_LIB.BASEBOARD_FAB2(SCH_1):GND
 D17    GND  IOD17 @BASEBOARD_FAB2_LIB.BASEBOARD_FAB2(SCH_1):GND
 D18    GND  IOD18 @BASEBOARD_FAB2_LIB.BASEBOARD_FAB2(SCH_1):GND
 D19    GND  IOD19 @BASEBOARD_FAB2_LIB.BASEBOARD_FAB2(SCH_1):GND
  D2 VSENSE_P1V8MCP_CPU1_SKT_VRTN   IOD2 @BASEBOARD_FAB2_LIB.BASEBOARD_FAB2(SCH_1):VSENSE_P1V8MCP_CPU1_SKT_VRTN
 D20    GND  IOD20 @BASEBOARD_FAB2_LIB.BASEBOARD_FAB2(SCH_1):GND
  D3 P1V8_MCP_CPU1   IOD3 @BASEBOARD_FAB2_LIB.BASEBOARD_FAB2(SCH_1):P1V8_MCP_CPU1
  D4    GND   IOD4 @BASEBOARD_FAB2_LIB.BASEBOARD_FAB2(SCH_1):GND
  D5    GND   IOD5 @BASEBOARD_FAB2_LIB.BASEBOARD_FAB2(SCH_1):GND
  D6    GND   IOD6 @BASEBOARD_FAB2_LIB.BASEBOARD_FAB2(SCH_1):GND
  D7    GND   IOD7 @BASEBOARD_FAB2_LIB.BASEBOARD_FAB2(SCH_1):GND
  D8    GND   IOD8 @BASEBOARD_FAB2_LIB.BASEBOARD_FAB2(SCH_1):GND
  D9    GND   IOD9 @BASEBOARD_FAB2_LIB.BASEBOARD_FAB2(SCH_1):GND
  E1 P1V8_MCP_CPU1   IOE1 @BASEBOARD_FAB2_LIB.BASEBOARD_FAB2(SCH_1):P1V8_MCP_CPU1
 E10    GND  IOE10 @BASEBOARD_FAB2_LIB.BASEBOARD_FAB2(SCH_1):GND
 E11    GND  IOE11 @BASEBOARD_FAB2_LIB.BASEBOARD_FAB2(SCH_1):GND
 E12    GND  IOE12 @BASEBOARD_FAB2_LIB.BASEBOARD_FAB2(SCH_1):GND
 E13    GND  IOE13 @BASEBOARD_FAB2_LIB.BASEBOARD_FAB2(SCH_1):GND
 E14    GND  IOE14 @BASEBOARD_FAB2_LIB.BASEBOARD_FAB2(SCH_1):GND
 E15    GND  IOE15 @BASEBOARD_FAB2_LIB.BASEBOARD_FAB2(SCH_1):GND
 E16    GND  IOE16 @BASEBOARD_FAB2_LIB.BASEBOARD_FAB2(SCH_1):GND
 E17    GND  IOE17 @BASEBOARD_FAB2_LIB.BASEBOARD_FAB2(SCH_1):GND
 E18    GND  IOE18 @BASEBOARD_FAB2_LIB.BASEBOARD_FAB2(SCH_1):GND
 E19    GND  IOE19 @BASEBOARD_FAB2_LIB.BASEBOARD_FAB2(SCH_1):GND
  E2 P1V8_MCP_CPU1   IOE2 @BASEBOARD_FAB2_LIB.BASEBOARD_FAB2(SCH_1):P1V8_MCP_CPU1
 E20    GND  IOE20 @BASEBOARD_FAB2_LIB.BASEBOARD_FAB2(SCH_1):GND
  E3 P1V8_MCP_CPU1   IOE3 @BASEBOARD_FAB2_LIB.BASEBOARD_FAB2(SCH_1):P1V8_MCP_CPU1
  E4    GND   IOE4 @BASEBOARD_FAB2_LIB.BASEBOARD_FAB2(SCH_1):GND
  E5 CLK_322M_156M_CPU1_OSC_VRM_DP   IOE5 @BASEBOARD_FAB2_LIB.BASEBOARD_FAB2(SCH_1):CLK_322M_156M_CPU1_OSC_VRM_DP
  E6    GND   IOE6 @BASEBOARD_FAB2_LIB.BASEBOARD_FAB2(SCH_1):GND
  E7    GND   IOE7 @BASEBOARD_FAB2_LIB.BASEBOARD_FAB2(SCH_1):GND
  E8    GND   IOE8 @BASEBOARD_FAB2_LIB.BASEBOARD_FAB2(SCH_1):GND
  E9    GND   IOE9 @BASEBOARD_FAB2_LIB.BASEBOARD_FAB2(SCH_1):GND
  F1 P1V8_MCP_CPU1   IOF1 @BASEBOARD_FAB2_LIB.BASEBOARD_FAB2(SCH_1):P1V8_MCP_CPU1
 F10    GND  IOF10 @BASEBOARD_FAB2_LIB.BASEBOARD_FAB2(SCH_1):GND
 F11    GND  IOF11 @BASEBOARD_FAB2_LIB.BASEBOARD_FAB2(SCH_1):GND
 F12    GND  IOF12 @BASEBOARD_FAB2_LIB.BASEBOARD_FAB2(SCH_1):GND
 F13    GND  IOF13 @BASEBOARD_FAB2_LIB.BASEBOARD_FAB2(SCH_1):GND
 F14    GND  IOF14 @BASEBOARD_FAB2_LIB.BASEBOARD_FAB2(SCH_1):GND
 F15    GND  IOF15 @BASEBOARD_FAB2_LIB.BASEBOARD_FAB2(SCH_1):GND
 F16    GND  IOF16 @BASEBOARD_FAB2_LIB.BASEBOARD_FAB2(SCH_1):GND
 F17    GND  IOF17 @BASEBOARD_FAB2_LIB.BASEBOARD_FAB2(SCH_1):GND
 F18    GND  IOF18 @BASEBOARD_FAB2_LIB.BASEBOARD_FAB2(SCH_1):GND
 F19    GND  IOF19 @BASEBOARD_FAB2_LIB.BASEBOARD_FAB2(SCH_1):GND
  F2 P1V8_MCP_CPU1   IOF2 @BASEBOARD_FAB2_LIB.BASEBOARD_FAB2(SCH_1):P1V8_MCP_CPU1
 F20    GND  IOF20 @BASEBOARD_FAB2_LIB.BASEBOARD_FAB2(SCH_1):GND
  F3 P1V8_MCP_CPU1   IOF3 @BASEBOARD_FAB2_LIB.BASEBOARD_FAB2(SCH_1):P1V8_MCP_CPU1
  F4    GND   IOF4 @BASEBOARD_FAB2_LIB.BASEBOARD_FAB2(SCH_1):GND
  F5 CLK_322M_156M_CPU1_OSC_VRM_DN   IOF5 @BASEBOARD_FAB2_LIB.BASEBOARD_FAB2(SCH_1):CLK_322M_156M_CPU1_OSC_VRM_DN
  F6    GND   IOF6 @BASEBOARD_FAB2_LIB.BASEBOARD_FAB2(SCH_1):GND
  F7    GND   IOF7 @BASEBOARD_FAB2_LIB.BASEBOARD_FAB2(SCH_1):GND
  F8    GND   IOF8 @BASEBOARD_FAB2_LIB.BASEBOARD_FAB2(SCH_1):GND
  F9    GND   IOF9 @BASEBOARD_FAB2_LIB.BASEBOARD_FAB2(SCH_1):GND

SCONN120_H61426002_SM-CONN,H61A  I46  J4B2
  A1 P12V_STBY   IOA1 @BASEBOARD_FAB2_LIB.BASEBOARD_FAB2(SCH_1):P12V_STBY
 A10    GND  IOA10 @BASEBOARD_FAB2_LIB.BASEBOARD_FAB2(SCH_1):GND
 A11 P3V3_STBY  IOA11 @BASEBOARD_FAB2_LIB.BASEBOARD_FAB2(SCH_1):P3V3_STBY
 A12    GND  IOA12 @BASEBOARD_FAB2_LIB.BASEBOARD_FAB2(SCH_1):GND
 A13 P5V_STBY  IOA13 @BASEBOARD_FAB2_LIB.BASEBOARD_FAB2(SCH_1):P5V_STBY
 A14    GND  IOA14 @BASEBOARD_FAB2_LIB.BASEBOARD_FAB2(SCH_1):GND
 A15 FM_P1V8MCP_CPU1_EN  IOA15 @BASEBOARD_FAB2_LIB.BASEBOARD_FAB2(SCH_1):FM_P1V8MCP_CPU1_EN
 A16 FM_PVCCIOMCP_CPU1_EN  IOA16 @BASEBOARD_FAB2_LIB.BASEBOARD_FAB2(SCH_1):FM_PVCCIOMCP_CPU1_EN
 A17    GND  IOA17 @BASEBOARD_FAB2_LIB.BASEBOARD_FAB2(SCH_1):GND
 A18 SMB_VR_STBY_LVC3_SCL  IOA18 @BASEBOARD_FAB2_LIB.BASEBOARD_FAB2(SCH_1):SMB_VR_STBY_LVC3_SCL
 A19 SVID_ALERT0_CPU1_R_N  IOA19 @BASEBOARD_FAB2_LIB.BASEBOARD_FAB2(SCH_1):SVID_ALERT0_CPU1_R_N
  A2 P12V_STBY   IOA2 @BASEBOARD_FAB2_LIB.BASEBOARD_FAB2(SCH_1):P12V_STBY
 A20 SVID_CLK0_CPU1_R  IOA20 @BASEBOARD_FAB2_LIB.BASEBOARD_FAB2(SCH_1):SVID_CLK0_CPU1_R
  A3 P12V_STBY   IOA3 @BASEBOARD_FAB2_LIB.BASEBOARD_FAB2(SCH_1):P12V_STBY
  A4 P12V_STBY   IOA4 @BASEBOARD_FAB2_LIB.BASEBOARD_FAB2(SCH_1):P12V_STBY
  A5 P12V_STBY   IOA5 @BASEBOARD_FAB2_LIB.BASEBOARD_FAB2(SCH_1):P12V_STBY
  A6 P12V_STBY   IOA6 @BASEBOARD_FAB2_LIB.BASEBOARD_FAB2(SCH_1):P12V_STBY
  A7 P12V_STBY   IOA7 @BASEBOARD_FAB2_LIB.BASEBOARD_FAB2(SCH_1):P12V_STBY
  A8 P12V_STBY   IOA8 @BASEBOARD_FAB2_LIB.BASEBOARD_FAB2(SCH_1):P12V_STBY
  A9    GND   IOA9 @BASEBOARD_FAB2_LIB.BASEBOARD_FAB2(SCH_1):GND
  B1 P12V_STBY   IOB1 @BASEBOARD_FAB2_LIB.BASEBOARD_FAB2(SCH_1):P12V_STBY
 B10    GND  IOB10 @BASEBOARD_FAB2_LIB.BASEBOARD_FAB2(SCH_1):GND
 B11 P3V3_STBY  IOB11 @BASEBOARD_FAB2_LIB.BASEBOARD_FAB2(SCH_1):P3V3_STBY
 B12    GND  IOB12 @BASEBOARD_FAB2_LIB.BASEBOARD_FAB2(SCH_1):GND
 B13 P5V_STBY  IOB13 @BASEBOARD_FAB2_LIB.BASEBOARD_FAB2(SCH_1):P5V_STBY
 B14    GND  IOB14 @BASEBOARD_FAB2_LIB.BASEBOARD_FAB2(SCH_1):GND
 B15 PWRGD_P1V8MCP_CPU1  IOB15 @BASEBOARD_FAB2_LIB.BASEBOARD_FAB2(SCH_1):PWRGD_P1V8MCP_CPU1
 B16 PWRGD_PVCCIOMCP_CPU1  IOB16 @BASEBOARD_FAB2_LIB.BASEBOARD_FAB2(SCH_1):PWRGD_PVCCIOMCP_CPU1
 B17    GND  IOB17 @BASEBOARD_FAB2_LIB.BASEBOARD_FAB2(SCH_1):GND
 B18 SMB_VR_STBY_LVC3_SDA  IOB18 @BASEBOARD_FAB2_LIB.BASEBOARD_FAB2(SCH_1):SMB_VR_STBY_LVC3_SDA
 B19 SVID_ALERT1_CPU1_R_N  IOB19 @BASEBOARD_FAB2_LIB.BASEBOARD_FAB2(SCH_1):SVID_ALERT1_CPU1_R_N
  B2 P12V_STBY   IOB2 @BASEBOARD_FAB2_LIB.BASEBOARD_FAB2(SCH_1):P12V_STBY
 B20 SVID_DIO0_CPU1_R  IOB20 @BASEBOARD_FAB2_LIB.BASEBOARD_FAB2(SCH_1):SVID_DIO0_CPU1_R
  B3 P12V_STBY   IOB3 @BASEBOARD_FAB2_LIB.BASEBOARD_FAB2(SCH_1):P12V_STBY
  B4 P12V_STBY   IOB4 @BASEBOARD_FAB2_LIB.BASEBOARD_FAB2(SCH_1):P12V_STBY
  B5 P12V_STBY   IOB5 @BASEBOARD_FAB2_LIB.BASEBOARD_FAB2(SCH_1):P12V_STBY
  B6 P12V_STBY   IOB6 @BASEBOARD_FAB2_LIB.BASEBOARD_FAB2(SCH_1):P12V_STBY
  B7 P12V_STBY   IOB7 @BASEBOARD_FAB2_LIB.BASEBOARD_FAB2(SCH_1):P12V_STBY
  B8 P12V_STBY   IOB8 @BASEBOARD_FAB2_LIB.BASEBOARD_FAB2(SCH_1):P12V_STBY
  B9    GND   IOB9 @BASEBOARD_FAB2_LIB.BASEBOARD_FAB2(SCH_1):GND
  C1    GND   IOC1 @BASEBOARD_FAB2_LIB.BASEBOARD_FAB2(SCH_1):GND
 C10    GND  IOC10 @BASEBOARD_FAB2_LIB.BASEBOARD_FAB2(SCH_1):GND
 C11 P3V3_STBY  IOC11 @BASEBOARD_FAB2_LIB.BASEBOARD_FAB2(SCH_1):P3V3_STBY
 C12    GND  IOC12 @BASEBOARD_FAB2_LIB.BASEBOARD_FAB2(SCH_1):GND
 C13 P5V_STBY  IOC13 @BASEBOARD_FAB2_LIB.BASEBOARD_FAB2(SCH_1):P5V_STBY
 C14    GND  IOC14 @BASEBOARD_FAB2_LIB.BASEBOARD_FAB2(SCH_1):GND
 C15    GND  IOC15 @BASEBOARD_FAB2_LIB.BASEBOARD_FAB2(SCH_1):GND
 C16    GND  IOC16 @BASEBOARD_FAB2_LIB.BASEBOARD_FAB2(SCH_1):GND
 C17 PVCCIOMCP_CPU1  IOC17 @BASEBOARD_FAB2_LIB.BASEBOARD_FAB2(SCH_1):PVCCIOMCP_CPU1
 C18 PVCCIOMCP_CPU1  IOC18 @BASEBOARD_FAB2_LIB.BASEBOARD_FAB2(SCH_1):PVCCIOMCP_CPU1
 C19 PVCCIOMCP_CPU1  IOC19 @BASEBOARD_FAB2_LIB.BASEBOARD_FAB2(SCH_1):PVCCIOMCP_CPU1
  C2    GND   IOC2 @BASEBOARD_FAB2_LIB.BASEBOARD_FAB2(SCH_1):GND
 C20 FM_PVCCMCP_CPU1_EN  IOC20 @BASEBOARD_FAB2_LIB.BASEBOARD_FAB2(SCH_1):FM_PVCCMCP_CPU1_EN
  C3    GND   IOC3 @BASEBOARD_FAB2_LIB.BASEBOARD_FAB2(SCH_1):GND
  C4    GND   IOC4 @BASEBOARD_FAB2_LIB.BASEBOARD_FAB2(SCH_1):GND
  C5    GND   IOC5 @BASEBOARD_FAB2_LIB.BASEBOARD_FAB2(SCH_1):GND
  C6    GND   IOC6 @BASEBOARD_FAB2_LIB.BASEBOARD_FAB2(SCH_1):GND
  C7    GND   IOC7 @BASEBOARD_FAB2_LIB.BASEBOARD_FAB2(SCH_1):GND
  C8    GND   IOC8 @BASEBOARD_FAB2_LIB.BASEBOARD_FAB2(SCH_1):GND
  C9    GND   IOC9 @BASEBOARD_FAB2_LIB.BASEBOARD_FAB2(SCH_1):GND
  D1   P3V3   IOD1 @BASEBOARD_FAB2_LIB.BASEBOARD_FAB2(SCH_1):P3V3
 D10    GND  IOD10 @BASEBOARD_FAB2_LIB.BASEBOARD_FAB2(SCH_1):GND
 D11    GND  IOD11 @BASEBOARD_FAB2_LIB.BASEBOARD_FAB2(SCH_1):GND
 D12    GND  IOD12 @BASEBOARD_FAB2_LIB.BASEBOARD_FAB2(SCH_1):GND
 D13    GND  IOD13 @BASEBOARD_FAB2_LIB.BASEBOARD_FAB2(SCH_1):GND
 D14    GND  IOD14 @BASEBOARD_FAB2_LIB.BASEBOARD_FAB2(SCH_1):GND
 D15    GND  IOD15 @BASEBOARD_FAB2_LIB.BASEBOARD_FAB2(SCH_1):GND
 D16    GND  IOD16 @BASEBOARD_FAB2_LIB.BASEBOARD_FAB2(SCH_1):GND
 D17 PVCCIOMCP_CPU1  IOD17 @BASEBOARD_FAB2_LIB.BASEBOARD_FAB2(SCH_1):PVCCIOMCP_CPU1
 D18 PVCCIOMCP_CPU1  IOD18 @BASEBOARD_FAB2_LIB.BASEBOARD_FAB2(SCH_1):PVCCIOMCP_CPU1
 D19 PVCCIOMCP_CPU1  IOD19 @BASEBOARD_FAB2_LIB.BASEBOARD_FAB2(SCH_1):PVCCIOMCP_CPU1
  D2    GND   IOD2 @BASEBOARD_FAB2_LIB.BASEBOARD_FAB2(SCH_1):GND
 D20 PWRGD_PVCCMCP_CPU1  IOD20 @BASEBOARD_FAB2_LIB.BASEBOARD_FAB2(SCH_1):PWRGD_PVCCMCP_CPU1
  D3    GND   IOD3 @BASEBOARD_FAB2_LIB.BASEBOARD_FAB2(SCH_1):GND
  D4    GND   IOD4 @BASEBOARD_FAB2_LIB.BASEBOARD_FAB2(SCH_1):GND
  D5    GND   IOD5 @BASEBOARD_FAB2_LIB.BASEBOARD_FAB2(SCH_1):GND
  D6    GND   IOD6 @BASEBOARD_FAB2_LIB.BASEBOARD_FAB2(SCH_1):GND
  D7    GND   IOD7 @BASEBOARD_FAB2_LIB.BASEBOARD_FAB2(SCH_1):GND
  D8    GND   IOD8 @BASEBOARD_FAB2_LIB.BASEBOARD_FAB2(SCH_1):GND
  D9    GND   IOD9 @BASEBOARD_FAB2_LIB.BASEBOARD_FAB2(SCH_1):GND
  E1 FM_CPU1_VRM_322M_156M_OSC_EN   IOE1 @BASEBOARD_FAB2_LIB.BASEBOARD_FAB2(SCH_1):FM_CPU1_VRM_322M_156M_OSC_EN
 E10 VR_PVCCIOMCP_CPU1_XADDR1  IOE10 @BASEBOARD_FAB2_LIB.BASEBOARD_FAB2(SCH_1):VR_PVCCIOMCP_CPU1_XADDR1
 E11    GND  IOE11 @BASEBOARD_FAB2_LIB.BASEBOARD_FAB2(SCH_1):GND
 E12    GND  IOE12 @BASEBOARD_FAB2_LIB.BASEBOARD_FAB2(SCH_1):GND
 E13    GND  IOE13 @BASEBOARD_FAB2_LIB.BASEBOARD_FAB2(SCH_1):GND
 E14    GND  IOE14 @BASEBOARD_FAB2_LIB.BASEBOARD_FAB2(SCH_1):GND
 E15 PVCCIOMCP_CPU1  IOE15 @BASEBOARD_FAB2_LIB.BASEBOARD_FAB2(SCH_1):PVCCIOMCP_CPU1
 E16 PVCCIOMCP_CPU1  IOE16 @BASEBOARD_FAB2_LIB.BASEBOARD_FAB2(SCH_1):PVCCIOMCP_CPU1
 E17 PVCCIOMCP_CPU1  IOE17 @BASEBOARD_FAB2_LIB.BASEBOARD_FAB2(SCH_1):PVCCIOMCP_CPU1
 E18 PVCCIOMCP_CPU1  IOE18 @BASEBOARD_FAB2_LIB.BASEBOARD_FAB2(SCH_1):PVCCIOMCP_CPU1
 E19 PVCCIOMCP_CPU1  IOE19 @BASEBOARD_FAB2_LIB.BASEBOARD_FAB2(SCH_1):PVCCIOMCP_CPU1
  E2    GND   IOE2 @BASEBOARD_FAB2_LIB.BASEBOARD_FAB2(SCH_1):GND
 E20 SVID_CLK1_CPU1_R  IOE20 @BASEBOARD_FAB2_LIB.BASEBOARD_FAB2(SCH_1):SVID_CLK1_CPU1_R
  E3    GND   IOE3 @BASEBOARD_FAB2_LIB.BASEBOARD_FAB2(SCH_1):GND
  E4    GND   IOE4 @BASEBOARD_FAB2_LIB.BASEBOARD_FAB2(SCH_1):GND
  E5    GND   IOE5 @BASEBOARD_FAB2_LIB.BASEBOARD_FAB2(SCH_1):GND
  E6    GND   IOE6 @BASEBOARD_FAB2_LIB.BASEBOARD_FAB2(SCH_1):GND
  E7    GND   IOE7 @BASEBOARD_FAB2_LIB.BASEBOARD_FAB2(SCH_1):GND
  E8 VSENSE_PVCCIOMCP_CPU1_SKT_VSEN   IOE8 @BASEBOARD_FAB2_LIB.BASEBOARD_FAB2(SCH_1):VSENSE_PVCCIOMCP_CPU1_SKT_VSEN
  E9    GND   IOE9 @BASEBOARD_FAB2_LIB.BASEBOARD_FAB2(SCH_1):GND
  F1 PVCCIO_CPU1   IOF1 @BASEBOARD_FAB2_LIB.BASEBOARD_FAB2(SCH_1):PVCCIO_CPU1
 F10 VR_PVCCMCP_CPU1_XADDR2  IOF10 @BASEBOARD_FAB2_LIB.BASEBOARD_FAB2(SCH_1):VR_PVCCMCP_CPU1_XADDR2
 F11    GND  IOF11 @BASEBOARD_FAB2_LIB.BASEBOARD_FAB2(SCH_1):GND
 F12    GND  IOF12 @BASEBOARD_FAB2_LIB.BASEBOARD_FAB2(SCH_1):GND
 F13    GND  IOF13 @BASEBOARD_FAB2_LIB.BASEBOARD_FAB2(SCH_1):GND
 F14    GND  IOF14 @BASEBOARD_FAB2_LIB.BASEBOARD_FAB2(SCH_1):GND
 F15 PVCCIOMCP_CPU1  IOF15 @BASEBOARD_FAB2_LIB.BASEBOARD_FAB2(SCH_1):PVCCIOMCP_CPU1
 F16 PVCCIOMCP_CPU1  IOF16 @BASEBOARD_FAB2_LIB.BASEBOARD_FAB2(SCH_1):PVCCIOMCP_CPU1
 F17 PVCCIOMCP_CPU1  IOF17 @BASEBOARD_FAB2_LIB.BASEBOARD_FAB2(SCH_1):PVCCIOMCP_CPU1
 F18 PVCCIOMCP_CPU1  IOF18 @BASEBOARD_FAB2_LIB.BASEBOARD_FAB2(SCH_1):PVCCIOMCP_CPU1
 F19 PVCCIOMCP_CPU1  IOF19 @BASEBOARD_FAB2_LIB.BASEBOARD_FAB2(SCH_1):PVCCIOMCP_CPU1
  F2    GND   IOF2 @BASEBOARD_FAB2_LIB.BASEBOARD_FAB2(SCH_1):GND
 F20 SVID_DIO1_CPU1_R  IOF20 @BASEBOARD_FAB2_LIB.BASEBOARD_FAB2(SCH_1):SVID_DIO1_CPU1_R
  F3    GND   IOF3 @BASEBOARD_FAB2_LIB.BASEBOARD_FAB2(SCH_1):GND
  F4    GND   IOF4 @BASEBOARD_FAB2_LIB.BASEBOARD_FAB2(SCH_1):GND
  F5    GND   IOF5 @BASEBOARD_FAB2_LIB.BASEBOARD_FAB2(SCH_1):GND
  F6    GND   IOF6 @BASEBOARD_FAB2_LIB.BASEBOARD_FAB2(SCH_1):GND
  F7    GND   IOF7 @BASEBOARD_FAB2_LIB.BASEBOARD_FAB2(SCH_1):GND
  F8 VSENSE_PVCCIOMCP_CPU1_SKT_VRTN   IOF8 @BASEBOARD_FAB2_LIB.BASEBOARD_FAB2(SCH_1):VSENSE_PVCCIOMCP_CPU1_SKT_VRTN
  F9    GND   IOF9 @BASEBOARD_FAB2_LIB.BASEBOARD_FAB2(SCH_1):GND

CAPP_3018-470UF,2.5V,20%,ALUM,A  I61  C4E24
   1 PVCCMCP_CPU1      A @BASEBOARD_FAB2_LIB.BASEBOARD_FAB2(SCH_1):PVCCMCP_CPU1
   2    GND      B @BASEBOARD_FAB2_LIB.BASEBOARD_FAB2(SCH_1):GND

CAPP_3018-470UF,2.5V,20%,ALUM,A  I62  C6R16
   1 PVCCMCP_CPU1      A @BASEBOARD_FAB2_LIB.BASEBOARD_FAB2(SCH_1):PVCCMCP_CPU1
   2    GND      B @BASEBOARD_FAB2_LIB.BASEBOARD_FAB2(SCH_1):GND

CAP_A_0402V-1.0UF,6.3V,10%,X6SA  I68  C4F1
   1 P1V8_MCP_CPU1      A @BASEBOARD_FAB2_LIB.BASEBOARD_FAB2(SCH_1):P1V8_MCP_CPU1
   2    GND      B @BASEBOARD_FAB2_LIB.BASEBOARD_FAB2(SCH_1):GND

CAP_A_0402V-1.0UF,6.3V,10%,X6SA  I70  C4F3
   1 P1V8_MCP_CPU1      A @BASEBOARD_FAB2_LIB.BASEBOARD_FAB2(SCH_1):P1V8_MCP_CPU1
   2    GND      B @BASEBOARD_FAB2_LIB.BASEBOARD_FAB2(SCH_1):GND

CAP_A_0603V-47UF,4V,20%,X5R,60A  I140  C3F1
   1 P1V8_MCP_CPU1      A @BASEBOARD_FAB2_LIB.BASEBOARD_FAB2(SCH_1):P1V8_MCP_CPU1
   2    GND      B @BASEBOARD_FAB2_LIB.BASEBOARD_FAB2(SCH_1):GND

CAP_A_0603V-47UF,4V,20%,X5R,60A  I141  C4F2
   1 P1V8_MCP_CPU1      A @BASEBOARD_FAB2_LIB.BASEBOARD_FAB2(SCH_1):P1V8_MCP_CPU1
   2    GND      B @BASEBOARD_FAB2_LIB.BASEBOARD_FAB2(SCH_1):GND

RES_0402-8.06K,1%,1/16W,CHIP,GA  I169  R4C12
   1 VR_PVCCIOMCP_CPU1_XADDR1      A @BASEBOARD_FAB2_LIB.BASEBOARD_FAB2(SCH_1):VR_PVCCIOMCP_CPU1_XADDR1
   2    GND      B @BASEBOARD_FAB2_LIB.BASEBOARD_FAB2(SCH_1):GND

RES_0402-3.16K,1%,1/16W,CHIP,GA  I170  R4C11
   1 VR_PVCCMCP_CPU1_XADDR2      A @BASEBOARD_FAB2_LIB.BASEBOARD_FAB2(SCH_1):VR_PVCCMCP_CPU1_XADDR2
   2    GND      B @BASEBOARD_FAB2_LIB.BASEBOARD_FAB2(SCH_1):GND

CAPP_3018-470UF,2.5V,20%,ALUM,A  I175  C4E29
   1 PVCCMCP_CPU1      A @BASEBOARD_FAB2_LIB.BASEBOARD_FAB2(SCH_1):PVCCMCP_CPU1
   2    GND      B @BASEBOARD_FAB2_LIB.BASEBOARD_FAB2(SCH_1):GND


DRAWING: @BASEBOARD_FAB2_LIB.BASEBOARD_FAB2(SCH_1):PAGE194 

CAP_A_0402V-1.0UF,6.3V,10%,X6SA  I9  C4T2
   1 P1V8_MCP_CPU0      A @BASEBOARD_FAB2_LIB.BASEBOARD_FAB2(SCH_1):P1V8_MCP_CPU0
   2    GND      B @BASEBOARD_FAB2_LIB.BASEBOARD_FAB2(SCH_1):GND

CAP_A_0402V-1.0UF,6.3V,10%,X6SA  I16  C4T1
   1 P1V8_MCP_CPU0      A @BASEBOARD_FAB2_LIB.BASEBOARD_FAB2(SCH_1):P1V8_MCP_CPU0
   2    GND      B @BASEBOARD_FAB2_LIB.BASEBOARD_FAB2(SCH_1):GND

CAPP_3018-470UF,2.5V,20%,ALUM,A  I29  C4R1
   1 PVCCMCP_CPU0      A @BASEBOARD_FAB2_LIB.BASEBOARD_FAB2(SCH_1):PVCCMCP_CPU0
   2    GND      B @BASEBOARD_FAB2_LIB.BASEBOARD_FAB2(SCH_1):GND

CAPP_3018-470UF,2.5V,20%,ALUM,A  I31  C3R4
   1 PVCCMCP_CPU0      A @BASEBOARD_FAB2_LIB.BASEBOARD_FAB2(SCH_1):PVCCMCP_CPU0
   2    GND      B @BASEBOARD_FAB2_LIB.BASEBOARD_FAB2(SCH_1):GND

SCONN120_H61426002_SM-CONN,H61A  I55  J6E1
  A1 PVCCMCP_CPU0   IOA1 @BASEBOARD_FAB2_LIB.BASEBOARD_FAB2(SCH_1):PVCCMCP_CPU0
 A10 PVCCMCP_CPU0  IOA10 @BASEBOARD_FAB2_LIB.BASEBOARD_FAB2(SCH_1):PVCCMCP_CPU0
 A11 PVCCMCP_CPU0  IOA11 @BASEBOARD_FAB2_LIB.BASEBOARD_FAB2(SCH_1):PVCCMCP_CPU0
 A12 PVCCMCP_CPU0  IOA12 @BASEBOARD_FAB2_LIB.BASEBOARD_FAB2(SCH_1):PVCCMCP_CPU0
 A13 PVCCMCP_CPU0  IOA13 @BASEBOARD_FAB2_LIB.BASEBOARD_FAB2(SCH_1):PVCCMCP_CPU0
 A14 PVCCMCP_CPU0  IOA14 @BASEBOARD_FAB2_LIB.BASEBOARD_FAB2(SCH_1):PVCCMCP_CPU0
 A15 PVCCMCP_CPU0  IOA15 @BASEBOARD_FAB2_LIB.BASEBOARD_FAB2(SCH_1):PVCCMCP_CPU0
 A16 PVCCMCP_CPU0  IOA16 @BASEBOARD_FAB2_LIB.BASEBOARD_FAB2(SCH_1):PVCCMCP_CPU0
 A17 PVCCMCP_CPU0  IOA17 @BASEBOARD_FAB2_LIB.BASEBOARD_FAB2(SCH_1):PVCCMCP_CPU0
 A18 PVCCMCP_CPU0  IOA18 @BASEBOARD_FAB2_LIB.BASEBOARD_FAB2(SCH_1):PVCCMCP_CPU0
 A19    GND  IOA19 @BASEBOARD_FAB2_LIB.BASEBOARD_FAB2(SCH_1):GND
  A2 PVCCMCP_CPU0   IOA2 @BASEBOARD_FAB2_LIB.BASEBOARD_FAB2(SCH_1):PVCCMCP_CPU0
 A20    GND  IOA20 @BASEBOARD_FAB2_LIB.BASEBOARD_FAB2(SCH_1):GND
  A3 PVCCMCP_CPU0   IOA3 @BASEBOARD_FAB2_LIB.BASEBOARD_FAB2(SCH_1):PVCCMCP_CPU0
  A4 VSENSE_PVCCMCP_CPU0_SKT_VSEN   IOA4 @BASEBOARD_FAB2_LIB.BASEBOARD_FAB2(SCH_1):VSENSE_PVCCMCP_CPU0_SKT_VSEN
  A5 PVCCMCP_CPU0   IOA5 @BASEBOARD_FAB2_LIB.BASEBOARD_FAB2(SCH_1):PVCCMCP_CPU0
  A6 PVCCMCP_CPU0   IOA6 @BASEBOARD_FAB2_LIB.BASEBOARD_FAB2(SCH_1):PVCCMCP_CPU0
  A7 PVCCMCP_CPU0   IOA7 @BASEBOARD_FAB2_LIB.BASEBOARD_FAB2(SCH_1):PVCCMCP_CPU0
  A8 PVCCMCP_CPU0   IOA8 @BASEBOARD_FAB2_LIB.BASEBOARD_FAB2(SCH_1):PVCCMCP_CPU0
  A9 PVCCMCP_CPU0   IOA9 @BASEBOARD_FAB2_LIB.BASEBOARD_FAB2(SCH_1):PVCCMCP_CPU0
  B1 PVCCMCP_CPU0   IOB1 @BASEBOARD_FAB2_LIB.BASEBOARD_FAB2(SCH_1):PVCCMCP_CPU0
 B10 PVCCMCP_CPU0  IOB10 @BASEBOARD_FAB2_LIB.BASEBOARD_FAB2(SCH_1):PVCCMCP_CPU0
 B11 PVCCMCP_CPU0  IOB11 @BASEBOARD_FAB2_LIB.BASEBOARD_FAB2(SCH_1):PVCCMCP_CPU0
 B12 PVCCMCP_CPU0  IOB12 @BASEBOARD_FAB2_LIB.BASEBOARD_FAB2(SCH_1):PVCCMCP_CPU0
 B13 PVCCMCP_CPU0  IOB13 @BASEBOARD_FAB2_LIB.BASEBOARD_FAB2(SCH_1):PVCCMCP_CPU0
 B14 PVCCMCP_CPU0  IOB14 @BASEBOARD_FAB2_LIB.BASEBOARD_FAB2(SCH_1):PVCCMCP_CPU0
 B15 PVCCMCP_CPU0  IOB15 @BASEBOARD_FAB2_LIB.BASEBOARD_FAB2(SCH_1):PVCCMCP_CPU0
 B16 PVCCMCP_CPU0  IOB16 @BASEBOARD_FAB2_LIB.BASEBOARD_FAB2(SCH_1):PVCCMCP_CPU0
 B17 PVCCMCP_CPU0  IOB17 @BASEBOARD_FAB2_LIB.BASEBOARD_FAB2(SCH_1):PVCCMCP_CPU0
 B18 PVCCMCP_CPU0  IOB18 @BASEBOARD_FAB2_LIB.BASEBOARD_FAB2(SCH_1):PVCCMCP_CPU0
 B19    GND  IOB19 @BASEBOARD_FAB2_LIB.BASEBOARD_FAB2(SCH_1):GND
  B2 PVCCMCP_CPU0   IOB2 @BASEBOARD_FAB2_LIB.BASEBOARD_FAB2(SCH_1):PVCCMCP_CPU0
 B20    GND  IOB20 @BASEBOARD_FAB2_LIB.BASEBOARD_FAB2(SCH_1):GND
  B3 PVCCMCP_CPU0   IOB3 @BASEBOARD_FAB2_LIB.BASEBOARD_FAB2(SCH_1):PVCCMCP_CPU0
  B4 VSENSE_PVCCMCP_CPU0_SKT_VRTN   IOB4 @BASEBOARD_FAB2_LIB.BASEBOARD_FAB2(SCH_1):VSENSE_PVCCMCP_CPU0_SKT_VRTN
  B5 PVCCMCP_CPU0   IOB5 @BASEBOARD_FAB2_LIB.BASEBOARD_FAB2(SCH_1):PVCCMCP_CPU0
  B6 PVCCMCP_CPU0   IOB6 @BASEBOARD_FAB2_LIB.BASEBOARD_FAB2(SCH_1):PVCCMCP_CPU0
  B7 PVCCMCP_CPU0   IOB7 @BASEBOARD_FAB2_LIB.BASEBOARD_FAB2(SCH_1):PVCCMCP_CPU0
  B8 PVCCMCP_CPU0   IOB8 @BASEBOARD_FAB2_LIB.BASEBOARD_FAB2(SCH_1):PVCCMCP_CPU0
  B9 PVCCMCP_CPU0   IOB9 @BASEBOARD_FAB2_LIB.BASEBOARD_FAB2(SCH_1):PVCCMCP_CPU0
  C1 PVCCMCP_CPU0   IOC1 @BASEBOARD_FAB2_LIB.BASEBOARD_FAB2(SCH_1):PVCCMCP_CPU0
 C10 PVCCMCP_CPU0  IOC10 @BASEBOARD_FAB2_LIB.BASEBOARD_FAB2(SCH_1):PVCCMCP_CPU0
 C11 PVCCMCP_CPU0  IOC11 @BASEBOARD_FAB2_LIB.BASEBOARD_FAB2(SCH_1):PVCCMCP_CPU0
 C12 PVCCMCP_CPU0  IOC12 @BASEBOARD_FAB2_LIB.BASEBOARD_FAB2(SCH_1):PVCCMCP_CPU0
 C13 PVCCMCP_CPU0  IOC13 @BASEBOARD_FAB2_LIB.BASEBOARD_FAB2(SCH_1):PVCCMCP_CPU0
 C14 PVCCMCP_CPU0  IOC14 @BASEBOARD_FAB2_LIB.BASEBOARD_FAB2(SCH_1):PVCCMCP_CPU0
 C15 PVCCMCP_CPU0  IOC15 @BASEBOARD_FAB2_LIB.BASEBOARD_FAB2(SCH_1):PVCCMCP_CPU0
 C16 PVCCMCP_CPU0  IOC16 @BASEBOARD_FAB2_LIB.BASEBOARD_FAB2(SCH_1):PVCCMCP_CPU0
 C17 PVCCMCP_CPU0  IOC17 @BASEBOARD_FAB2_LIB.BASEBOARD_FAB2(SCH_1):PVCCMCP_CPU0
 C18 PVCCMCP_CPU0  IOC18 @BASEBOARD_FAB2_LIB.BASEBOARD_FAB2(SCH_1):PVCCMCP_CPU0
 C19    GND  IOC19 @BASEBOARD_FAB2_LIB.BASEBOARD_FAB2(SCH_1):GND
  C2 PVCCMCP_CPU0   IOC2 @BASEBOARD_FAB2_LIB.BASEBOARD_FAB2(SCH_1):PVCCMCP_CPU0
 C20    GND  IOC20 @BASEBOARD_FAB2_LIB.BASEBOARD_FAB2(SCH_1):GND
  C3 PVCCMCP_CPU0   IOC3 @BASEBOARD_FAB2_LIB.BASEBOARD_FAB2(SCH_1):PVCCMCP_CPU0
  C4 PVCCMCP_CPU0   IOC4 @BASEBOARD_FAB2_LIB.BASEBOARD_FAB2(SCH_1):PVCCMCP_CPU0
  C5 PVCCMCP_CPU0   IOC5 @BASEBOARD_FAB2_LIB.BASEBOARD_FAB2(SCH_1):PVCCMCP_CPU0
  C6 PVCCMCP_CPU0   IOC6 @BASEBOARD_FAB2_LIB.BASEBOARD_FAB2(SCH_1):PVCCMCP_CPU0
  C7 PVCCMCP_CPU0   IOC7 @BASEBOARD_FAB2_LIB.BASEBOARD_FAB2(SCH_1):PVCCMCP_CPU0
  C8 PVCCMCP_CPU0   IOC8 @BASEBOARD_FAB2_LIB.BASEBOARD_FAB2(SCH_1):PVCCMCP_CPU0
  C9 PVCCMCP_CPU0   IOC9 @BASEBOARD_FAB2_LIB.BASEBOARD_FAB2(SCH_1):PVCCMCP_CPU0
  D1 VSENSE_P1V8MCP_CPU0_SKT_VSEN   IOD1 @BASEBOARD_FAB2_LIB.BASEBOARD_FAB2(SCH_1):VSENSE_P1V8MCP_CPU0_SKT_VSEN
 D10    GND  IOD10 @BASEBOARD_FAB2_LIB.BASEBOARD_FAB2(SCH_1):GND
 D11    GND  IOD11 @BASEBOARD_FAB2_LIB.BASEBOARD_FAB2(SCH_1):GND
 D12    GND  IOD12 @BASEBOARD_FAB2_LIB.BASEBOARD_FAB2(SCH_1):GND
 D13    GND  IOD13 @BASEBOARD_FAB2_LIB.BASEBOARD_FAB2(SCH_1):GND
 D14    GND  IOD14 @BASEBOARD_FAB2_LIB.BASEBOARD_FAB2(SCH_1):GND
 D15    GND  IOD15 @BASEBOARD_FAB2_LIB.BASEBOARD_FAB2(SCH_1):GND
 D16    GND  IOD16 @BASEBOARD_FAB2_LIB.BASEBOARD_FAB2(SCH_1):GND
 D17    GND  IOD17 @BASEBOARD_FAB2_LIB.BASEBOARD_FAB2(SCH_1):GND
 D18    GND  IOD18 @BASEBOARD_FAB2_LIB.BASEBOARD_FAB2(SCH_1):GND
 D19    GND  IOD19 @BASEBOARD_FAB2_LIB.BASEBOARD_FAB2(SCH_1):GND
  D2 VSENSE_P1V8MCP_CPU0_SKT_VRTN   IOD2 @BASEBOARD_FAB2_LIB.BASEBOARD_FAB2(SCH_1):VSENSE_P1V8MCP_CPU0_SKT_VRTN
 D20    GND  IOD20 @BASEBOARD_FAB2_LIB.BASEBOARD_FAB2(SCH_1):GND
  D3 P1V8_MCP_CPU0   IOD3 @BASEBOARD_FAB2_LIB.BASEBOARD_FAB2(SCH_1):P1V8_MCP_CPU0
  D4    GND   IOD4 @BASEBOARD_FAB2_LIB.BASEBOARD_FAB2(SCH_1):GND
  D5    GND   IOD5 @BASEBOARD_FAB2_LIB.BASEBOARD_FAB2(SCH_1):GND
  D6    GND   IOD6 @BASEBOARD_FAB2_LIB.BASEBOARD_FAB2(SCH_1):GND
  D7    GND   IOD7 @BASEBOARD_FAB2_LIB.BASEBOARD_FAB2(SCH_1):GND
  D8    GND   IOD8 @BASEBOARD_FAB2_LIB.BASEBOARD_FAB2(SCH_1):GND
  D9    GND   IOD9 @BASEBOARD_FAB2_LIB.BASEBOARD_FAB2(SCH_1):GND
  E1 P1V8_MCP_CPU0   IOE1 @BASEBOARD_FAB2_LIB.BASEBOARD_FAB2(SCH_1):P1V8_MCP_CPU0
 E10    GND  IOE10 @BASEBOARD_FAB2_LIB.BASEBOARD_FAB2(SCH_1):GND
 E11    GND  IOE11 @BASEBOARD_FAB2_LIB.BASEBOARD_FAB2(SCH_1):GND
 E12    GND  IOE12 @BASEBOARD_FAB2_LIB.BASEBOARD_FAB2(SCH_1):GND
 E13    GND  IOE13 @BASEBOARD_FAB2_LIB.BASEBOARD_FAB2(SCH_1):GND
 E14    GND  IOE14 @BASEBOARD_FAB2_LIB.BASEBOARD_FAB2(SCH_1):GND
 E15    GND  IOE15 @BASEBOARD_FAB2_LIB.BASEBOARD_FAB2(SCH_1):GND
 E16    GND  IOE16 @BASEBOARD_FAB2_LIB.BASEBOARD_FAB2(SCH_1):GND
 E17    GND  IOE17 @BASEBOARD_FAB2_LIB.BASEBOARD_FAB2(SCH_1):GND
 E18    GND  IOE18 @BASEBOARD_FAB2_LIB.BASEBOARD_FAB2(SCH_1):GND
 E19    GND  IOE19 @BASEBOARD_FAB2_LIB.BASEBOARD_FAB2(SCH_1):GND
  E2 P1V8_MCP_CPU0   IOE2 @BASEBOARD_FAB2_LIB.BASEBOARD_FAB2(SCH_1):P1V8_MCP_CPU0
 E20    GND  IOE20 @BASEBOARD_FAB2_LIB.BASEBOARD_FAB2(SCH_1):GND
  E3 P1V8_MCP_CPU0   IOE3 @BASEBOARD_FAB2_LIB.BASEBOARD_FAB2(SCH_1):P1V8_MCP_CPU0
  E4    GND   IOE4 @BASEBOARD_FAB2_LIB.BASEBOARD_FAB2(SCH_1):GND
  E5 CLK_322M_156M_CPU0_OSC_VRM_DP   IOE5 @BASEBOARD_FAB2_LIB.BASEBOARD_FAB2(SCH_1):CLK_322M_156M_CPU0_OSC_VRM_DP
  E6    GND   IOE6 @BASEBOARD_FAB2_LIB.BASEBOARD_FAB2(SCH_1):GND
  E7    GND   IOE7 @BASEBOARD_FAB2_LIB.BASEBOARD_FAB2(SCH_1):GND
  E8    GND   IOE8 @BASEBOARD_FAB2_LIB.BASEBOARD_FAB2(SCH_1):GND
  E9    GND   IOE9 @BASEBOARD_FAB2_LIB.BASEBOARD_FAB2(SCH_1):GND
  F1 P1V8_MCP_CPU0   IOF1 @BASEBOARD_FAB2_LIB.BASEBOARD_FAB2(SCH_1):P1V8_MCP_CPU0
 F10    GND  IOF10 @BASEBOARD_FAB2_LIB.BASEBOARD_FAB2(SCH_1):GND
 F11    GND  IOF11 @BASEBOARD_FAB2_LIB.BASEBOARD_FAB2(SCH_1):GND
 F12    GND  IOF12 @BASEBOARD_FAB2_LIB.BASEBOARD_FAB2(SCH_1):GND
 F13    GND  IOF13 @BASEBOARD_FAB2_LIB.BASEBOARD_FAB2(SCH_1):GND
 F14    GND  IOF14 @BASEBOARD_FAB2_LIB.BASEBOARD_FAB2(SCH_1):GND
 F15    GND  IOF15 @BASEBOARD_FAB2_LIB.BASEBOARD_FAB2(SCH_1):GND
 F16    GND  IOF16 @BASEBOARD_FAB2_LIB.BASEBOARD_FAB2(SCH_1):GND
 F17    GND  IOF17 @BASEBOARD_FAB2_LIB.BASEBOARD_FAB2(SCH_1):GND
 F18    GND  IOF18 @BASEBOARD_FAB2_LIB.BASEBOARD_FAB2(SCH_1):GND
 F19    GND  IOF19 @BASEBOARD_FAB2_LIB.BASEBOARD_FAB2(SCH_1):GND
  F2 P1V8_MCP_CPU0   IOF2 @BASEBOARD_FAB2_LIB.BASEBOARD_FAB2(SCH_1):P1V8_MCP_CPU0
 F20    GND  IOF20 @BASEBOARD_FAB2_LIB.BASEBOARD_FAB2(SCH_1):GND
  F3 P1V8_MCP_CPU0   IOF3 @BASEBOARD_FAB2_LIB.BASEBOARD_FAB2(SCH_1):P1V8_MCP_CPU0
  F4    GND   IOF4 @BASEBOARD_FAB2_LIB.BASEBOARD_FAB2(SCH_1):GND
  F5 CLK_322M_156M_CPU0_OSC_VRM_DN   IOF5 @BASEBOARD_FAB2_LIB.BASEBOARD_FAB2(SCH_1):CLK_322M_156M_CPU0_OSC_VRM_DN
  F6    GND   IOF6 @BASEBOARD_FAB2_LIB.BASEBOARD_FAB2(SCH_1):GND
  F7    GND   IOF7 @BASEBOARD_FAB2_LIB.BASEBOARD_FAB2(SCH_1):GND
  F8    GND   IOF8 @BASEBOARD_FAB2_LIB.BASEBOARD_FAB2(SCH_1):GND
  F9    GND   IOF9 @BASEBOARD_FAB2_LIB.BASEBOARD_FAB2(SCH_1):GND

SCONN120_H61426002_SM-CONN,H61A  I56  J6B1
  A1 P12V_STBY   IOA1 @BASEBOARD_FAB2_LIB.BASEBOARD_FAB2(SCH_1):P12V_STBY
 A10    GND  IOA10 @BASEBOARD_FAB2_LIB.BASEBOARD_FAB2(SCH_1):GND
 A11 P3V3_STBY  IOA11 @BASEBOARD_FAB2_LIB.BASEBOARD_FAB2(SCH_1):P3V3_STBY
 A12    GND  IOA12 @BASEBOARD_FAB2_LIB.BASEBOARD_FAB2(SCH_1):GND
 A13 P5V_STBY  IOA13 @BASEBOARD_FAB2_LIB.BASEBOARD_FAB2(SCH_1):P5V_STBY
 A14    GND  IOA14 @BASEBOARD_FAB2_LIB.BASEBOARD_FAB2(SCH_1):GND
 A15 FM_P1V8MCP_CPU0_EN  IOA15 @BASEBOARD_FAB2_LIB.BASEBOARD_FAB2(SCH_1):FM_P1V8MCP_CPU0_EN
 A16 FM_PVCCIOMCP_CPU0_EN  IOA16 @BASEBOARD_FAB2_LIB.BASEBOARD_FAB2(SCH_1):FM_PVCCIOMCP_CPU0_EN
 A17    GND  IOA17 @BASEBOARD_FAB2_LIB.BASEBOARD_FAB2(SCH_1):GND
 A18 SMB_VR_STBY_LVC3_SCL  IOA18 @BASEBOARD_FAB2_LIB.BASEBOARD_FAB2(SCH_1):SMB_VR_STBY_LVC3_SCL
 A19 SVID_ALERT0_CPU0_R_N  IOA19 @BASEBOARD_FAB2_LIB.BASEBOARD_FAB2(SCH_1):SVID_ALERT0_CPU0_R_N
  A2 P12V_STBY   IOA2 @BASEBOARD_FAB2_LIB.BASEBOARD_FAB2(SCH_1):P12V_STBY
 A20 SVID_CLK0_CPU0_R  IOA20 @BASEBOARD_FAB2_LIB.BASEBOARD_FAB2(SCH_1):SVID_CLK0_CPU0_R
  A3 P12V_STBY   IOA3 @BASEBOARD_FAB2_LIB.BASEBOARD_FAB2(SCH_1):P12V_STBY
  A4 P12V_STBY   IOA4 @BASEBOARD_FAB2_LIB.BASEBOARD_FAB2(SCH_1):P12V_STBY
  A5 P12V_STBY   IOA5 @BASEBOARD_FAB2_LIB.BASEBOARD_FAB2(SCH_1):P12V_STBY
  A6 P12V_STBY   IOA6 @BASEBOARD_FAB2_LIB.BASEBOARD_FAB2(SCH_1):P12V_STBY
  A7 P12V_STBY   IOA7 @BASEBOARD_FAB2_LIB.BASEBOARD_FAB2(SCH_1):P12V_STBY
  A8 P12V_STBY   IOA8 @BASEBOARD_FAB2_LIB.BASEBOARD_FAB2(SCH_1):P12V_STBY
  A9    GND   IOA9 @BASEBOARD_FAB2_LIB.BASEBOARD_FAB2(SCH_1):GND
  B1 P12V_STBY   IOB1 @BASEBOARD_FAB2_LIB.BASEBOARD_FAB2(SCH_1):P12V_STBY
 B10    GND  IOB10 @BASEBOARD_FAB2_LIB.BASEBOARD_FAB2(SCH_1):GND
 B11 P3V3_STBY  IOB11 @BASEBOARD_FAB2_LIB.BASEBOARD_FAB2(SCH_1):P3V3_STBY
 B12    GND  IOB12 @BASEBOARD_FAB2_LIB.BASEBOARD_FAB2(SCH_1):GND
 B13 P5V_STBY  IOB13 @BASEBOARD_FAB2_LIB.BASEBOARD_FAB2(SCH_1):P5V_STBY
 B14    GND  IOB14 @BASEBOARD_FAB2_LIB.BASEBOARD_FAB2(SCH_1):GND
 B15 PWRGD_P1V8MCP_CPU0  IOB15 @BASEBOARD_FAB2_LIB.BASEBOARD_FAB2(SCH_1):PWRGD_P1V8MCP_CPU0
 B16 PWRGD_PVCCIOMCP_CPU0  IOB16 @BASEBOARD_FAB2_LIB.BASEBOARD_FAB2(SCH_1):PWRGD_PVCCIOMCP_CPU0
 B17    GND  IOB17 @BASEBOARD_FAB2_LIB.BASEBOARD_FAB2(SCH_1):GND
 B18 SMB_VR_STBY_LVC3_SDA  IOB18 @BASEBOARD_FAB2_LIB.BASEBOARD_FAB2(SCH_1):SMB_VR_STBY_LVC3_SDA
 B19 SVID_ALERT1_CPU0_R_N  IOB19 @BASEBOARD_FAB2_LIB.BASEBOARD_FAB2(SCH_1):SVID_ALERT1_CPU0_R_N
  B2 P12V_STBY   IOB2 @BASEBOARD_FAB2_LIB.BASEBOARD_FAB2(SCH_1):P12V_STBY
 B20 SVID_DIO0_CPU0_R  IOB20 @BASEBOARD_FAB2_LIB.BASEBOARD_FAB2(SCH_1):SVID_DIO0_CPU0_R
  B3 P12V_STBY   IOB3 @BASEBOARD_FAB2_LIB.BASEBOARD_FAB2(SCH_1):P12V_STBY
  B4 P12V_STBY   IOB4 @BASEBOARD_FAB2_LIB.BASEBOARD_FAB2(SCH_1):P12V_STBY
  B5 P12V_STBY   IOB5 @BASEBOARD_FAB2_LIB.BASEBOARD_FAB2(SCH_1):P12V_STBY
  B6 P12V_STBY   IOB6 @BASEBOARD_FAB2_LIB.BASEBOARD_FAB2(SCH_1):P12V_STBY
  B7 P12V_STBY   IOB7 @BASEBOARD_FAB2_LIB.BASEBOARD_FAB2(SCH_1):P12V_STBY
  B8 P12V_STBY   IOB8 @BASEBOARD_FAB2_LIB.BASEBOARD_FAB2(SCH_1):P12V_STBY
  B9    GND   IOB9 @BASEBOARD_FAB2_LIB.BASEBOARD_FAB2(SCH_1):GND
  C1    GND   IOC1 @BASEBOARD_FAB2_LIB.BASEBOARD_FAB2(SCH_1):GND
 C10    GND  IOC10 @BASEBOARD_FAB2_LIB.BASEBOARD_FAB2(SCH_1):GND
 C11 P3V3_STBY  IOC11 @BASEBOARD_FAB2_LIB.BASEBOARD_FAB2(SCH_1):P3V3_STBY
 C12    GND  IOC12 @BASEBOARD_FAB2_LIB.BASEBOARD_FAB2(SCH_1):GND
 C13 P5V_STBY  IOC13 @BASEBOARD_FAB2_LIB.BASEBOARD_FAB2(SCH_1):P5V_STBY
 C14    GND  IOC14 @BASEBOARD_FAB2_LIB.BASEBOARD_FAB2(SCH_1):GND
 C15    GND  IOC15 @BASEBOARD_FAB2_LIB.BASEBOARD_FAB2(SCH_1):GND
 C16    GND  IOC16 @BASEBOARD_FAB2_LIB.BASEBOARD_FAB2(SCH_1):GND
 C17 PVCCIOMCP_CPU0  IOC17 @BASEBOARD_FAB2_LIB.BASEBOARD_FAB2(SCH_1):PVCCIOMCP_CPU0
 C18 PVCCIOMCP_CPU0  IOC18 @BASEBOARD_FAB2_LIB.BASEBOARD_FAB2(SCH_1):PVCCIOMCP_CPU0
 C19 PVCCIOMCP_CPU0  IOC19 @BASEBOARD_FAB2_LIB.BASEBOARD_FAB2(SCH_1):PVCCIOMCP_CPU0
  C2    GND   IOC2 @BASEBOARD_FAB2_LIB.BASEBOARD_FAB2(SCH_1):GND
 C20 FM_PVCCMCP_CPU0_EN  IOC20 @BASEBOARD_FAB2_LIB.BASEBOARD_FAB2(SCH_1):FM_PVCCMCP_CPU0_EN
  C3    GND   IOC3 @BASEBOARD_FAB2_LIB.BASEBOARD_FAB2(SCH_1):GND
  C4    GND   IOC4 @BASEBOARD_FAB2_LIB.BASEBOARD_FAB2(SCH_1):GND
  C5    GND   IOC5 @BASEBOARD_FAB2_LIB.BASEBOARD_FAB2(SCH_1):GND
  C6    GND   IOC6 @BASEBOARD_FAB2_LIB.BASEBOARD_FAB2(SCH_1):GND
  C7    GND   IOC7 @BASEBOARD_FAB2_LIB.BASEBOARD_FAB2(SCH_1):GND
  C8    GND   IOC8 @BASEBOARD_FAB2_LIB.BASEBOARD_FAB2(SCH_1):GND
  C9    GND   IOC9 @BASEBOARD_FAB2_LIB.BASEBOARD_FAB2(SCH_1):GND
  D1   P3V3   IOD1 @BASEBOARD_FAB2_LIB.BASEBOARD_FAB2(SCH_1):P3V3
 D10    GND  IOD10 @BASEBOARD_FAB2_LIB.BASEBOARD_FAB2(SCH_1):GND
 D11    GND  IOD11 @BASEBOARD_FAB2_LIB.BASEBOARD_FAB2(SCH_1):GND
 D12    GND  IOD12 @BASEBOARD_FAB2_LIB.BASEBOARD_FAB2(SCH_1):GND
 D13    GND  IOD13 @BASEBOARD_FAB2_LIB.BASEBOARD_FAB2(SCH_1):GND
 D14    GND  IOD14 @BASEBOARD_FAB2_LIB.BASEBOARD_FAB2(SCH_1):GND
 D15    GND  IOD15 @BASEBOARD_FAB2_LIB.BASEBOARD_FAB2(SCH_1):GND
 D16    GND  IOD16 @BASEBOARD_FAB2_LIB.BASEBOARD_FAB2(SCH_1):GND
 D17 PVCCIOMCP_CPU0  IOD17 @BASEBOARD_FAB2_LIB.BASEBOARD_FAB2(SCH_1):PVCCIOMCP_CPU0
 D18 PVCCIOMCP_CPU0  IOD18 @BASEBOARD_FAB2_LIB.BASEBOARD_FAB2(SCH_1):PVCCIOMCP_CPU0
 D19 PVCCIOMCP_CPU0  IOD19 @BASEBOARD_FAB2_LIB.BASEBOARD_FAB2(SCH_1):PVCCIOMCP_CPU0
  D2    GND   IOD2 @BASEBOARD_FAB2_LIB.BASEBOARD_FAB2(SCH_1):GND
 D20 PWRGD_PVCCMCP_CPU0  IOD20 @BASEBOARD_FAB2_LIB.BASEBOARD_FAB2(SCH_1):PWRGD_PVCCMCP_CPU0
  D3    GND   IOD3 @BASEBOARD_FAB2_LIB.BASEBOARD_FAB2(SCH_1):GND
  D4    GND   IOD4 @BASEBOARD_FAB2_LIB.BASEBOARD_FAB2(SCH_1):GND
  D5    GND   IOD5 @BASEBOARD_FAB2_LIB.BASEBOARD_FAB2(SCH_1):GND
  D6    GND   IOD6 @BASEBOARD_FAB2_LIB.BASEBOARD_FAB2(SCH_1):GND
  D7    GND   IOD7 @BASEBOARD_FAB2_LIB.BASEBOARD_FAB2(SCH_1):GND
  D8    GND   IOD8 @BASEBOARD_FAB2_LIB.BASEBOARD_FAB2(SCH_1):GND
  D9    GND   IOD9 @BASEBOARD_FAB2_LIB.BASEBOARD_FAB2(SCH_1):GND
  E1 FM_CPU0_VRM_322M_156M_OSC_EN   IOE1 @BASEBOARD_FAB2_LIB.BASEBOARD_FAB2(SCH_1):FM_CPU0_VRM_322M_156M_OSC_EN
 E10 VR_PVCCIOMCP_CPU0_XADDR1  IOE10 @BASEBOARD_FAB2_LIB.BASEBOARD_FAB2(SCH_1):VR_PVCCIOMCP_CPU0_XADDR1
 E11    GND  IOE11 @BASEBOARD_FAB2_LIB.BASEBOARD_FAB2(SCH_1):GND
 E12    GND  IOE12 @BASEBOARD_FAB2_LIB.BASEBOARD_FAB2(SCH_1):GND
 E13    GND  IOE13 @BASEBOARD_FAB2_LIB.BASEBOARD_FAB2(SCH_1):GND
 E14    GND  IOE14 @BASEBOARD_FAB2_LIB.BASEBOARD_FAB2(SCH_1):GND
 E15 PVCCIOMCP_CPU0  IOE15 @BASEBOARD_FAB2_LIB.BASEBOARD_FAB2(SCH_1):PVCCIOMCP_CPU0
 E16 PVCCIOMCP_CPU0  IOE16 @BASEBOARD_FAB2_LIB.BASEBOARD_FAB2(SCH_1):PVCCIOMCP_CPU0
 E17 PVCCIOMCP_CPU0  IOE17 @BASEBOARD_FAB2_LIB.BASEBOARD_FAB2(SCH_1):PVCCIOMCP_CPU0
 E18 PVCCIOMCP_CPU0  IOE18 @BASEBOARD_FAB2_LIB.BASEBOARD_FAB2(SCH_1):PVCCIOMCP_CPU0
 E19 PVCCIOMCP_CPU0  IOE19 @BASEBOARD_FAB2_LIB.BASEBOARD_FAB2(SCH_1):PVCCIOMCP_CPU0
  E2    GND   IOE2 @BASEBOARD_FAB2_LIB.BASEBOARD_FAB2(SCH_1):GND
 E20 SVID_CLK1_CPU0_R  IOE20 @BASEBOARD_FAB2_LIB.BASEBOARD_FAB2(SCH_1):SVID_CLK1_CPU0_R
  E3    GND   IOE3 @BASEBOARD_FAB2_LIB.BASEBOARD_FAB2(SCH_1):GND
  E4    GND   IOE4 @BASEBOARD_FAB2_LIB.BASEBOARD_FAB2(SCH_1):GND
  E5    GND   IOE5 @BASEBOARD_FAB2_LIB.BASEBOARD_FAB2(SCH_1):GND
  E6    GND   IOE6 @BASEBOARD_FAB2_LIB.BASEBOARD_FAB2(SCH_1):GND
  E7    GND   IOE7 @BASEBOARD_FAB2_LIB.BASEBOARD_FAB2(SCH_1):GND
  E8 VSENSE_PVCCIOMCP_CPU0_SKT_VSEN   IOE8 @BASEBOARD_FAB2_LIB.BASEBOARD_FAB2(SCH_1):VSENSE_PVCCIOMCP_CPU0_SKT_VSEN
  E9    GND   IOE9 @BASEBOARD_FAB2_LIB.BASEBOARD_FAB2(SCH_1):GND
  F1 PVCCIO_CPU0   IOF1 @BASEBOARD_FAB2_LIB.BASEBOARD_FAB2(SCH_1):PVCCIO_CPU0
 F10 VR_PVCCMCP_CPU0_XADDR2  IOF10 @BASEBOARD_FAB2_LIB.BASEBOARD_FAB2(SCH_1):VR_PVCCMCP_CPU0_XADDR2
 F11    GND  IOF11 @BASEBOARD_FAB2_LIB.BASEBOARD_FAB2(SCH_1):GND
 F12    GND  IOF12 @BASEBOARD_FAB2_LIB.BASEBOARD_FAB2(SCH_1):GND
 F13    GND  IOF13 @BASEBOARD_FAB2_LIB.BASEBOARD_FAB2(SCH_1):GND
 F14    GND  IOF14 @BASEBOARD_FAB2_LIB.BASEBOARD_FAB2(SCH_1):GND
 F15 PVCCIOMCP_CPU0  IOF15 @BASEBOARD_FAB2_LIB.BASEBOARD_FAB2(SCH_1):PVCCIOMCP_CPU0
 F16 PVCCIOMCP_CPU0  IOF16 @BASEBOARD_FAB2_LIB.BASEBOARD_FAB2(SCH_1):PVCCIOMCP_CPU0
 F17 PVCCIOMCP_CPU0  IOF17 @BASEBOARD_FAB2_LIB.BASEBOARD_FAB2(SCH_1):PVCCIOMCP_CPU0
 F18 PVCCIOMCP_CPU0  IOF18 @BASEBOARD_FAB2_LIB.BASEBOARD_FAB2(SCH_1):PVCCIOMCP_CPU0
 F19 PVCCIOMCP_CPU0  IOF19 @BASEBOARD_FAB2_LIB.BASEBOARD_FAB2(SCH_1):PVCCIOMCP_CPU0
  F2    GND   IOF2 @BASEBOARD_FAB2_LIB.BASEBOARD_FAB2(SCH_1):GND
 F20 SVID_DIO1_CPU0_R  IOF20 @BASEBOARD_FAB2_LIB.BASEBOARD_FAB2(SCH_1):SVID_DIO1_CPU0_R
  F3    GND   IOF3 @BASEBOARD_FAB2_LIB.BASEBOARD_FAB2(SCH_1):GND
  F4    GND   IOF4 @BASEBOARD_FAB2_LIB.BASEBOARD_FAB2(SCH_1):GND
  F5    GND   IOF5 @BASEBOARD_FAB2_LIB.BASEBOARD_FAB2(SCH_1):GND
  F6    GND   IOF6 @BASEBOARD_FAB2_LIB.BASEBOARD_FAB2(SCH_1):GND
  F7    GND   IOF7 @BASEBOARD_FAB2_LIB.BASEBOARD_FAB2(SCH_1):GND
  F8 VSENSE_PVCCIOMCP_CPU0_SKT_VRTN   IOF8 @BASEBOARD_FAB2_LIB.BASEBOARD_FAB2(SCH_1):VSENSE_PVCCIOMCP_CPU0_SKT_VRTN
  F9    GND   IOF9 @BASEBOARD_FAB2_LIB.BASEBOARD_FAB2(SCH_1):GND

CAP_A_0402V-1.0UF,6.3V,10%,X6SA  I86  C3N40
   1 PVCCIOMCP_CPU0      A @BASEBOARD_FAB2_LIB.BASEBOARD_FAB2(SCH_1):PVCCIOMCP_CPU0
   2    GND      B @BASEBOARD_FAB2_LIB.BASEBOARD_FAB2(SCH_1):GND

CAP_A_0402V-1.0UF,6.3V,10%,X6SA  I99  C3M46
   1 PVCCIOMCP_CPU0      A @BASEBOARD_FAB2_LIB.BASEBOARD_FAB2(SCH_1):PVCCIOMCP_CPU0
   2    GND      B @BASEBOARD_FAB2_LIB.BASEBOARD_FAB2(SCH_1):GND

CAPP_3018-470UF,2.5V,20%,ALUM,A  I101  C3N14
   1 PVCCIOMCP_CPU0      A @BASEBOARD_FAB2_LIB.BASEBOARD_FAB2(SCH_1):PVCCIOMCP_CPU0
   2    GND      B @BASEBOARD_FAB2_LIB.BASEBOARD_FAB2(SCH_1):GND

CAP_A_0603V-47UF,4V,20%,X5R,60A  I149  C3T1
   1 P1V8_MCP_CPU0      A @BASEBOARD_FAB2_LIB.BASEBOARD_FAB2(SCH_1):P1V8_MCP_CPU0
   2    GND      B @BASEBOARD_FAB2_LIB.BASEBOARD_FAB2(SCH_1):GND

CAP_A_0603V-47UF,4V,20%,X5R,60A  I150  C3T2
   1 P1V8_MCP_CPU0      A @BASEBOARD_FAB2_LIB.BASEBOARD_FAB2(SCH_1):P1V8_MCP_CPU0
   2    GND      B @BASEBOARD_FAB2_LIB.BASEBOARD_FAB2(SCH_1):GND

RES_0402-4.02K,1%,1/16W,CHIP,GA  I155  R7C24
   1 VR_PVCCMCP_CPU0_XADDR2      A @BASEBOARD_FAB2_LIB.BASEBOARD_FAB2(SCH_1):VR_PVCCMCP_CPU0_XADDR2
   2    GND      B @BASEBOARD_FAB2_LIB.BASEBOARD_FAB2(SCH_1):GND

RES_0402-16K,1.0%,1/16W,CHIP,GA  I156  R3N29
   1 VR_PVCCIOMCP_CPU0_XADDR1      A @BASEBOARD_FAB2_LIB.BASEBOARD_FAB2(SCH_1):VR_PVCCIOMCP_CPU0_XADDR1
   2    GND      B @BASEBOARD_FAB2_LIB.BASEBOARD_FAB2(SCH_1):GND


DRAWING: @BASEBOARD_FAB2_LIB.BASEBOARD_FAB2(SCH_1):PAGE195 

CONN3_G98259001_PIP-CONN,G9825A  I26  RM1E1
   1    GND    IO1 @BASEBOARD_FAB2_LIB.BASEBOARD_FAB2(SCH_1):GND
   2    GND    IO2 @BASEBOARD_FAB2_LIB.BASEBOARD_FAB2(SCH_1):GND
   3    GND    IO3 @BASEBOARD_FAB2_LIB.BASEBOARD_FAB2(SCH_1):GND

CAP_0805-10UF,16V,10%,X6S,C953A  I31  C9R5
   1 P12V_PSU      A @BASEBOARD_FAB2_LIB.BASEBOARD_FAB2(SCH_1):P12V_PSU
   2    GND      B @BASEBOARD_FAB2_LIB.BASEBOARD_FAB2(SCH_1):GND

CAP_0805-10UF,16V,10%,X6S,C953A  I32  C1E12
   1 P12V_PSU      A @BASEBOARD_FAB2_LIB.BASEBOARD_FAB2(SCH_1):P12V_PSU
   2    GND      B @BASEBOARD_FAB2_LIB.BASEBOARD_FAB2(SCH_1):GND

CAP_0805-10UF,16V,10%,X6S,C953A  I35  C1E15
   1 P12V_PSU      A @BASEBOARD_FAB2_LIB.BASEBOARD_FAB2(SCH_1):P12V_PSU
   2    GND      B @BASEBOARD_FAB2_LIB.BASEBOARD_FAB2(SCH_1):GND

CAP_A_0402V-0.1UF,16V,10%,X7R,A  I36  C9R12
   1 P12V_PSU      A @BASEBOARD_FAB2_LIB.BASEBOARD_FAB2(SCH_1):P12V_PSU
   2    GND      B @BASEBOARD_FAB2_LIB.BASEBOARD_FAB2(SCH_1):GND

CAP_A_0402V-0.1UF,16V,10%,X7R,A  I37  C9R6
   1 P12V_PSU      A @BASEBOARD_FAB2_LIB.BASEBOARD_FAB2(SCH_1):P12V_PSU
   2    GND      B @BASEBOARD_FAB2_LIB.BASEBOARD_FAB2(SCH_1):GND

CAP_A_0402V-0.1UF,16V,10%,X7R,A  I38  C1E17
   1 P12V_PSU      A @BASEBOARD_FAB2_LIB.BASEBOARD_FAB2(SCH_1):P12V_PSU
   2    GND      B @BASEBOARD_FAB2_LIB.BASEBOARD_FAB2(SCH_1):GND

CAP_A_0402V-0.1UF,16V,10%,X7R,A  I39  C1E16
   1 P12V_PSU      A @BASEBOARD_FAB2_LIB.BASEBOARD_FAB2(SCH_1):P12V_PSU
   2    GND      B @BASEBOARD_FAB2_LIB.BASEBOARD_FAB2(SCH_1):GND

MTG_KEYHOLE_TH-EMPTY,NA  I49  TH4G1
   1    GND      1 @BASEBOARD_FAB2_LIB.BASEBOARD_FAB2(SCH_1):GND

MTG_KEYHOLE_TH-EMPTY,NA  I52  TH9G1
   1    GND      1 @BASEBOARD_FAB2_LIB.BASEBOARD_FAB2(SCH_1):GND

MTG_KEYHOLE_TH-EMPTY,NA  I54  TH9A1
   1    GND      1 @BASEBOARD_FAB2_LIB.BASEBOARD_FAB2(SCH_1):GND

MTG_KEYHOLE_TH-EMPTY,NA  I56  TH1A1
   1    GND      1 @BASEBOARD_FAB2_LIB.BASEBOARD_FAB2(SCH_1):GND

MTG_KEYHOLE_TH-EMPTY,NA  I62  TH4A1
   1    GND      1 @BASEBOARD_FAB2_LIB.BASEBOARD_FAB2(SCH_1):GND

MTG_KEYHOLE_TH-EMPTY,NA  I65  TH7A1
   1    GND      1 @BASEBOARD_FAB2_LIB.BASEBOARD_FAB2(SCH_1):GND

MTG_KEYHOLE_TH-EMPTY,NA  I67  TH7G1
   1    GND      1 @BASEBOARD_FAB2_LIB.BASEBOARD_FAB2(SCH_1):GND

CAPP_4040LF-470UF,16V,20%,ALUMA  I82  C4F6
   1 P12V_STBY      A @BASEBOARD_FAB2_LIB.BASEBOARD_FAB2(SCH_1):P12V_STBY
   2    GND      B @BASEBOARD_FAB2_LIB.BASEBOARD_FAB2(SCH_1):GND

CAPP_4040LF-470UF,16V,20%,ALUMA  I83  C4B13
   1 P12V_STBY      A @BASEBOARD_FAB2_LIB.BASEBOARD_FAB2(SCH_1):P12V_STBY
   2    GND      B @BASEBOARD_FAB2_LIB.BASEBOARD_FAB2(SCH_1):GND

CAPP_4040LF-470UF,16V,20%,ALUMA  I84  C1B14
   1 P12V_STBY      A @BASEBOARD_FAB2_LIB.BASEBOARD_FAB2(SCH_1):P12V_STBY
   2    GND      B @BASEBOARD_FAB2_LIB.BASEBOARD_FAB2(SCH_1):GND

CAPP_4040LF-470UF,16V,20%,ALUMA  I85  C1F7
   1 P12V_STBY      A @BASEBOARD_FAB2_LIB.BASEBOARD_FAB2(SCH_1):P12V_STBY
   2    GND      B @BASEBOARD_FAB2_LIB.BASEBOARD_FAB2(SCH_1):GND

CAPP_3018-68UF,16V,20%,TANT,72A  I96  C4F5
   1 P12V_STBY      A @BASEBOARD_FAB2_LIB.BASEBOARD_FAB2(SCH_1):P12V_STBY
   2    GND      B @BASEBOARD_FAB2_LIB.BASEBOARD_FAB2(SCH_1):GND

CAPP_3018-68UF,16V,20%,TANT,72A  I97  C4B14
   1 P12V_STBY      A @BASEBOARD_FAB2_LIB.BASEBOARD_FAB2(SCH_1):P12V_STBY
   2    GND      B @BASEBOARD_FAB2_LIB.BASEBOARD_FAB2(SCH_1):GND

CAPP_3018-68UF,16V,20%,TANT,72A  I98  C3T6
   1 P12V_STBY      A @BASEBOARD_FAB2_LIB.BASEBOARD_FAB2(SCH_1):P12V_STBY
   2    GND      B @BASEBOARD_FAB2_LIB.BASEBOARD_FAB2(SCH_1):GND

CAPP_3018-68UF,16V,20%,TANT,72A  I99  C9M3
   1 P12V_STBY      A @BASEBOARD_FAB2_LIB.BASEBOARD_FAB2(SCH_1):P12V_STBY
   2    GND      B @BASEBOARD_FAB2_LIB.BASEBOARD_FAB2(SCH_1):GND

CAPP_3018-68UF,16V,20%,TANT,72A  I100  C3B6
   1 P12V_STBY      A @BASEBOARD_FAB2_LIB.BASEBOARD_FAB2(SCH_1):P12V_STBY
   2    GND      B @BASEBOARD_FAB2_LIB.BASEBOARD_FAB2(SCH_1):GND

CAPP_3018-68UF,16V,20%,TANT,72A  I101  C1R23
   1 P12V_STBY      A @BASEBOARD_FAB2_LIB.BASEBOARD_FAB2(SCH_1):P12V_STBY
   2    GND      B @BASEBOARD_FAB2_LIB.BASEBOARD_FAB2(SCH_1):GND

CAPP_3018-68UF,16V,20%,TANT,72A  I102  C4M6
   1 P12V_STBY      A @BASEBOARD_FAB2_LIB.BASEBOARD_FAB2(SCH_1):P12V_STBY
   2    GND      B @BASEBOARD_FAB2_LIB.BASEBOARD_FAB2(SCH_1):GND

CAPP_3018-68UF,16V,20%,TANT,72A  I103  C1M5
   1 P12V_STBY      A @BASEBOARD_FAB2_LIB.BASEBOARD_FAB2(SCH_1):P12V_STBY
   2    GND      B @BASEBOARD_FAB2_LIB.BASEBOARD_FAB2(SCH_1):GND

CAPP_3018-68UF,16V,20%,TANT,72A  I104  C3T13
   1 P12V_STBY      A @BASEBOARD_FAB2_LIB.BASEBOARD_FAB2(SCH_1):P12V_STBY
   2    GND      B @BASEBOARD_FAB2_LIB.BASEBOARD_FAB2(SCH_1):GND

CAPP_3018-68UF,16V,20%,TANT,72A  I105  C4M7
   1 P12V_STBY      A @BASEBOARD_FAB2_LIB.BASEBOARD_FAB2(SCH_1):P12V_STBY
   2    GND      B @BASEBOARD_FAB2_LIB.BASEBOARD_FAB2(SCH_1):GND

CAPP_3018-68UF,16V,20%,TANT,72A  I106  C3T15
   1 P12V_STBY      A @BASEBOARD_FAB2_LIB.BASEBOARD_FAB2(SCH_1):P12V_STBY
   2    GND      B @BASEBOARD_FAB2_LIB.BASEBOARD_FAB2(SCH_1):GND

CAPP_3018-68UF,16V,20%,TANT,72A  I108  C7M6
   1 P12V_STBY      A @BASEBOARD_FAB2_LIB.BASEBOARD_FAB2(SCH_1):P12V_STBY
   2    GND      B @BASEBOARD_FAB2_LIB.BASEBOARD_FAB2(SCH_1):GND

CAPP_3018-68UF,16V,20%,TANT,72A  I109  C6N5
   1 P12V_STBY      A @BASEBOARD_FAB2_LIB.BASEBOARD_FAB2(SCH_1):P12V_STBY
   2    GND      B @BASEBOARD_FAB2_LIB.BASEBOARD_FAB2(SCH_1):GND

CAPP_3018-68UF,16V,20%,TANT,72A  I111  C9T3
   1 P12V_STBY      A @BASEBOARD_FAB2_LIB.BASEBOARD_FAB2(SCH_1):P12V_STBY
   2    GND      B @BASEBOARD_FAB2_LIB.BASEBOARD_FAB2(SCH_1):GND

CAPP_3018-68UF,16V,20%,TANT,72A  I112  C4F4
   1 P12V_STBY      A @BASEBOARD_FAB2_LIB.BASEBOARD_FAB2(SCH_1):P12V_STBY
   2    GND      B @BASEBOARD_FAB2_LIB.BASEBOARD_FAB2(SCH_1):GND

CAPP_3018-68UF,16V,20%,TANT,72A  I113  C3T3
   1 P12V_STBY      A @BASEBOARD_FAB2_LIB.BASEBOARD_FAB2(SCH_1):P12V_STBY
   2    GND      B @BASEBOARD_FAB2_LIB.BASEBOARD_FAB2(SCH_1):GND

FCI-CONN12-2R-GP_CONN-G5-FCI-CA  I114  J1E1
 2_1 P12V_PSU    2_1 @BASEBOARD_FAB2_LIB.BASEBOARD_FAB2(SCH_1):P12V_PSU
 2_2 P12V_PSU    2_2 @BASEBOARD_FAB2_LIB.BASEBOARD_FAB2(SCH_1):P12V_PSU
 2_3 P12V_PSU    2_3 @BASEBOARD_FAB2_LIB.BASEBOARD_FAB2(SCH_1):P12V_PSU
 3_1    GND    3_1 @BASEBOARD_FAB2_LIB.BASEBOARD_FAB2(SCH_1):GND
 3_2    GND    3_2 @BASEBOARD_FAB2_LIB.BASEBOARD_FAB2(SCH_1):GND
 3_3    GND    3_3 @BASEBOARD_FAB2_LIB.BASEBOARD_FAB2(SCH_1):GND
 NP1     NC    NP1     NC
 1_1 P12V_PSU    1_1 @BASEBOARD_FAB2_LIB.BASEBOARD_FAB2(SCH_1):P12V_PSU
 1_2 P12V_PSU    1_2 @BASEBOARD_FAB2_LIB.BASEBOARD_FAB2(SCH_1):P12V_PSU
 1_3 P12V_PSU    1_3 @BASEBOARD_FAB2_LIB.BASEBOARD_FAB2(SCH_1):P12V_PSU
 4_1    GND    4_1 @BASEBOARD_FAB2_LIB.BASEBOARD_FAB2(SCH_1):GND
 4_2    GND    4_2 @BASEBOARD_FAB2_LIB.BASEBOARD_FAB2(SCH_1):GND
 4_3    GND    4_3 @BASEBOARD_FAB2_LIB.BASEBOARD_FAB2(SCH_1):GND

FCI-CONN12-2R-GP_CONN-G5-FCI-CA  I115  J1D1
 2_1 P12V_PSU    2_1 @BASEBOARD_FAB2_LIB.BASEBOARD_FAB2(SCH_1):P12V_PSU
 2_2 P12V_PSU    2_2 @BASEBOARD_FAB2_LIB.BASEBOARD_FAB2(SCH_1):P12V_PSU
 2_3 P12V_PSU    2_3 @BASEBOARD_FAB2_LIB.BASEBOARD_FAB2(SCH_1):P12V_PSU
 3_1    GND    3_1 @BASEBOARD_FAB2_LIB.BASEBOARD_FAB2(SCH_1):GND
 3_2    GND    3_2 @BASEBOARD_FAB2_LIB.BASEBOARD_FAB2(SCH_1):GND
 3_3    GND    3_3 @BASEBOARD_FAB2_LIB.BASEBOARD_FAB2(SCH_1):GND
 NP1     NC    NP1     NC
 1_1 P12V_PSU    1_1 @BASEBOARD_FAB2_LIB.BASEBOARD_FAB2(SCH_1):P12V_PSU
 1_2 P12V_PSU    1_2 @BASEBOARD_FAB2_LIB.BASEBOARD_FAB2(SCH_1):P12V_PSU
 1_3 P12V_PSU    1_3 @BASEBOARD_FAB2_LIB.BASEBOARD_FAB2(SCH_1):P12V_PSU
 4_1    GND    4_1 @BASEBOARD_FAB2_LIB.BASEBOARD_FAB2(SCH_1):GND
 4_2    GND    4_2 @BASEBOARD_FAB2_LIB.BASEBOARD_FAB2(SCH_1):GND
 4_3    GND    4_3 @BASEBOARD_FAB2_LIB.BASEBOARD_FAB2(SCH_1):GND

STFT363B238R224H453-GP_DISCRETA  I117  RM1G1
   1    GND      1 @BASEBOARD_FAB2_LIB.BASEBOARD_FAB2(SCH_1):GND


DRAWING: @BASEBOARD_FAB2_LIB.BASEBOARD_FAB2(SCH_1):PAGE196 

RES_0402-1.00K,1%,1/16W,CHIP,GA  I46  R2U43
   1 P3V_BAT_SOURCE      A @BASEBOARD_FAB2_LIB.BASEBOARD_FAB2(SCH_1):P3V_BAT_SOURCE
   2 A_P3V_BAT_R      B @BASEBOARD_FAB2_LIB.BASEBOARD_FAB2(SCH_1):A_P3V_BAT_R

BATTERY_PLCLF-202168-001  I47  BT8G1
VERT_BATT_3PIN_PIP-3PVERT,C686A  I51  XBT8G1
   3    GND      N @BASEBOARD_FAB2_LIB.BASEBOARD_FAB2(SCH_1):GND
   1 P3V_BAT_SOURCE     P1 @BASEBOARD_FAB2_LIB.BASEBOARD_FAB2(SCH_1):P3V_BAT_SOURCE
   2 P3V_BAT_SOURCE     P2 @BASEBOARD_FAB2_LIB.BASEBOARD_FAB2(SCH_1):P3V_BAT_SOURCE

DIODE2A_DUAL_SMLF-BAS70-05,DIOA  I53  CR2U1
   3 P3V3_RTC_STBY      C @BASEBOARD_FAB2_LIB.BASEBOARD_FAB2(SCH_1):P3V3_RTC_STBY
   1 P3V3_STBY     A1 @BASEBOARD_FAB2_LIB.BASEBOARD_FAB2(SCH_1):P3V3_STBY
   2 A_P3V_BAT_R     A2 @BASEBOARD_FAB2_LIB.BASEBOARD_FAB2(SCH_1):A_P3V_BAT_R

RES_0402-4.75K,1%,1/16W,CHIP,GA  I59  R3P44
   1 P3V3_STBY      A @BASEBOARD_FAB2_LIB.BASEBOARD_FAB2(SCH_1):P3V3_STBY
   2 PWRGD_DSW_PWROK      B @BASEBOARD_FAB2_LIB.BASEBOARD_FAB2(SCH_1):PWRGD_DSW_PWROK

CAP_0402-0.047UF,25V,10%,X7R,AA  I60  C3P45
   1 A_ADM1085_CEXT      A @BASEBOARD_FAB2_LIB.BASEBOARD_FAB2(SCH_1):A_ADM1085_CEXT
   2    GND      B @BASEBOARD_FAB2_LIB.BASEBOARD_FAB2(SCH_1):GND

RES_0402-100.0,1%,1/16W,CHIP,GA  I65  R2P20
   1 PWRGD_P5V_R      A @BASEBOARD_FAB2_LIB.BASEBOARD_FAB2(SCH_1):PWRGD_P5V_R
   2 PWRGD_P5V      B @BASEBOARD_FAB2_LIB.BASEBOARD_FAB2(SCH_1):PWRGD_P5V

RES_0402-49.9,1%,1/16W,CHIP,G2A  I68  R1L16
   1 PWRGD_P3V3_R1      A @BASEBOARD_FAB2_LIB.BASEBOARD_FAB2(SCH_1):PWRGD_P3V3_R1
   2 PWRGD_P3V3      B @BASEBOARD_FAB2_LIB.BASEBOARD_FAB2(SCH_1):PWRGD_P3V3

ADM1085_SMT-IC,H46130-001  I70  U7D3
   5 A_ADM1085_CEXT   CEXT @BASEBOARD_FAB2_LIB.BASEBOARD_FAB2(SCH_1):A_ADM1085_CEXT
   1 PWRGD_P3V3_STBY   ENIN @BASEBOARD_FAB2_LIB.BASEBOARD_FAB2(SCH_1):PWRGD_P3V3_STBY
   4 PWRGD_DSW_PWROK  ENOUT @BASEBOARD_FAB2_LIB.BASEBOARD_FAB2(SCH_1):PWRGD_DSW_PWROK
   2    GND    GND @BASEBOARD_FAB2_LIB.BASEBOARD_FAB2(SCH_1):GND
   6 P3V3_STBY    VCC @BASEBOARD_FAB2_LIB.BASEBOARD_FAB2(SCH_1):P3V3_STBY
   3 VSENSE_P12V_ADM1085    VIN @BASEBOARD_FAB2_LIB.BASEBOARD_FAB2(SCH_1):VSENSE_P12V_ADM1085

RES_0402-10.0K,1%,1/16W,EMPTY,A  I71  R3P50
   1 P3V3_STBY      A @BASEBOARD_FAB2_LIB.BASEBOARD_FAB2(SCH_1):P3V3_STBY
   2 PWRGD_P3V3_STBY      B @BASEBOARD_FAB2_LIB.BASEBOARD_FAB2(SCH_1):PWRGD_P3V3_STBY

CAP_A_0402V-0.1UF,16V,10%,X7R,A  I72  C3P46
   1 P3V3_STBY      A @BASEBOARD_FAB2_LIB.BASEBOARD_FAB2(SCH_1):P3V3_STBY
   2    GND      B @BASEBOARD_FAB2_LIB.BASEBOARD_FAB2(SCH_1):GND

RES_0402-90.9K,1%,1/16W,CHIP,GA  I74  R3P48
   1 P12V_STBY      A @BASEBOARD_FAB2_LIB.BASEBOARD_FAB2(SCH_1):P12V_STBY
   2 VSENSE_P12V_ADM1085      B @BASEBOARD_FAB2_LIB.BASEBOARD_FAB2(SCH_1):VSENSE_P12V_ADM1085

RES_0402-6.34K,1%,1/16W,CHIP,GA  I75  R3P51
   1 VSENSE_P12V_ADM1085      A @BASEBOARD_FAB2_LIB.BASEBOARD_FAB2(SCH_1):VSENSE_P12V_ADM1085
   2    GND      B @BASEBOARD_FAB2_LIB.BASEBOARD_FAB2(SCH_1):GND

ADM809_SMLF-IC,D23047-001-GND=A  I80  U1L3
   3   P3V3    VCC @BASEBOARD_FAB2_LIB.BASEBOARD_FAB2(SCH_1):P3V3
   2 PWRGD_P3V3_R1 RESET_N @BASEBOARD_FAB2_LIB.BASEBOARD_FAB2(SCH_1):PWRGD_P3V3_R1

CAP_A_0402V-0.1UF,16V,10%,X7R,A  I81  C1L16
   1   P3V3      A @BASEBOARD_FAB2_LIB.BASEBOARD_FAB2(SCH_1):P3V3
   2    GND      B @BASEBOARD_FAB2_LIB.BASEBOARD_FAB2(SCH_1):GND

ADM809_SMLF-IC,D23047-001-GND=A  I89  U8E2
   3 PWRGD_P12V_HSC    VCC @BASEBOARD_FAB2_LIB.BASEBOARD_FAB2(SCH_1):PWRGD_P12V_HSC
   2 PWRGD_P12V_HSC_DLY_R RESET_N @BASEBOARD_FAB2_LIB.BASEBOARD_FAB2(SCH_1):PWRGD_P12V_HSC_DLY_R

RES_0402-22.1,1.0%,1/16W,CHIP,A  I90  R8E7
   1 PWRGD_P12V_HSC_DLY_R      A @BASEBOARD_FAB2_LIB.BASEBOARD_FAB2(SCH_1):PWRGD_P12V_HSC_DLY_R
   2 PWRGD_P12V_HSC_DLY      B @BASEBOARD_FAB2_LIB.BASEBOARD_FAB2(SCH_1):PWRGD_P12V_HSC_DLY

CAP_A_0402V-0.1UF,16V,10%,X7R,A  I94  C8E3
   1 PWRGD_P12V_HSC      A @BASEBOARD_FAB2_LIB.BASEBOARD_FAB2(SCH_1):PWRGD_P12V_HSC
   2    GND      B @BASEBOARD_FAB2_LIB.BASEBOARD_FAB2(SCH_1):GND

CAP_A_0402V-1.0UF,6.3V,10%,X6SA  I102  C2U26
   1 P3V3_RTC_STBY      A @BASEBOARD_FAB2_LIB.BASEBOARD_FAB2(SCH_1):P3V3_RTC_STBY
   2    GND      B @BASEBOARD_FAB2_LIB.BASEBOARD_FAB2(SCH_1):GND

DIODE_SMLF-BAT54WS,IC,C73510-0A  I103  CR7E1
   1 PWRGD_P3V3_STBY      C @BASEBOARD_FAB2_LIB.BASEBOARD_FAB2(SCH_1):PWRGD_P3V3_STBY
   2 PWRGD_DSW_PWROK      A @BASEBOARD_FAB2_LIB.BASEBOARD_FAB2(SCH_1):PWRGD_DSW_PWROK

TPS3700_SM-IC,H69492-001  I104  U8D8
   5    GND    GND @BASEBOARD_FAB2_LIB.BASEBOARD_FAB2(SCH_1):GND
   4 A_PG_P12V_MAIN   INAP @BASEBOARD_FAB2_LIB.BASEBOARD_FAB2(SCH_1):A_PG_P12V_MAIN
   3 A_PG_P5V   INBN @BASEBOARD_FAB2_LIB.BASEBOARD_FAB2(SCH_1):A_PG_P5V
   6 PWRGD_P12V_MAIN_R   OUTA @BASEBOARD_FAB2_LIB.BASEBOARD_FAB2(SCH_1):PWRGD_P12V_MAIN_R
   1 PWRGD_P5V_N   OUTB @BASEBOARD_FAB2_LIB.BASEBOARD_FAB2(SCH_1):PWRGD_P5V_N
   2 P3V3_STBY    VDD @BASEBOARD_FAB2_LIB.BASEBOARD_FAB2(SCH_1):P3V3_STBY

CAP_A_0402V-0.1UF,16V,10%,X7R,A  I105  C8D4
   1 P3V3_STBY      A @BASEBOARD_FAB2_LIB.BASEBOARD_FAB2(SCH_1):P3V3_STBY
   2    GND      B @BASEBOARD_FAB2_LIB.BASEBOARD_FAB2(SCH_1):GND

RES_0402-100.0,1%,1/16W,CHIP,GA  I106  R8D42
   1 PWRGD_P12V_MAIN_R      A @BASEBOARD_FAB2_LIB.BASEBOARD_FAB2(SCH_1):PWRGD_P12V_MAIN_R
   2 PWRGD_P12V_MAIN      B @BASEBOARD_FAB2_LIB.BASEBOARD_FAB2(SCH_1):PWRGD_P12V_MAIN

RES_0402-100.0K,1%,1/16W,CHIP,A  I112  R8D38
   1   P12V      A @BASEBOARD_FAB2_LIB.BASEBOARD_FAB2(SCH_1):P12V
   2 A_PG_P12V_MAIN      B @BASEBOARD_FAB2_LIB.BASEBOARD_FAB2(SCH_1):A_PG_P12V_MAIN

RES_0402-49.9K,1%,1/16W,CHIP,GA  I114  R8D39
   1    P5V      A @BASEBOARD_FAB2_LIB.BASEBOARD_FAB2(SCH_1):P5V
   2 A_PG_P5V      B @BASEBOARD_FAB2_LIB.BASEBOARD_FAB2(SCH_1):A_PG_P5V

RES_0402-4.75K,1%,1/16W,CHIP,GA  I115  R8D37
   1 A_PG_P5V      A @BASEBOARD_FAB2_LIB.BASEBOARD_FAB2(SCH_1):A_PG_P5V
   2    GND      B @BASEBOARD_FAB2_LIB.BASEBOARD_FAB2(SCH_1):GND

RES_0402-10.0K,1%,1/16W,CHIP,GA  I120  R8D41
   1 P3V3_STBY      A @BASEBOARD_FAB2_LIB.BASEBOARD_FAB2(SCH_1):P3V3_STBY
   2 PWRGD_P12V_MAIN_R      B @BASEBOARD_FAB2_LIB.BASEBOARD_FAB2(SCH_1):PWRGD_P12V_MAIN_R

RES_0402-10.0K,1%,1/16W,CHIP,GA  I121  R2P18
   1 P3V3_STBY      A @BASEBOARD_FAB2_LIB.BASEBOARD_FAB2(SCH_1):P3V3_STBY
   2 PWRGD_P5V_N      B @BASEBOARD_FAB2_LIB.BASEBOARD_FAB2(SCH_1):PWRGD_P5V_N

RES_0402-10.0K,1%,1/16W,CHIP,GA  I122  R2P21
   1 P3V3_STBY      A @BASEBOARD_FAB2_LIB.BASEBOARD_FAB2(SCH_1):P3V3_STBY
   2 PWRGD_P5V_R      B @BASEBOARD_FAB2_LIB.BASEBOARD_FAB2(SCH_1):PWRGD_P5V_R

DIODE_SMLF-BAT54WS,IC,C73510-0A  I128  CR8E1
   1 PWRGD_P12V_HSC      C @BASEBOARD_FAB2_LIB.BASEBOARD_FAB2(SCH_1):PWRGD_P12V_HSC
   2 PWRGD_P12V_HSC_DLY      A @BASEBOARD_FAB2_LIB.BASEBOARD_FAB2(SCH_1):PWRGD_P12V_HSC_DLY

FET_N_SOT23LF-2N7002,FET,C7925A  I129  Q1P2
   1 PWRGD_P5V_N   GATE @BASEBOARD_FAB2_LIB.BASEBOARD_FAB2(SCH_1):PWRGD_P5V_N
   2    GND    SRC @BASEBOARD_FAB2_LIB.BASEBOARD_FAB2(SCH_1):GND
   3 PWRGD_P5V_R    DRN @BASEBOARD_FAB2_LIB.BASEBOARD_FAB2(SCH_1):PWRGD_P5V_R

RES_0402-20.0K,1%,1/16W,CHIP,GA  I130  R8D40
   1 A_PG_P12V_MAIN      A @BASEBOARD_FAB2_LIB.BASEBOARD_FAB2(SCH_1):A_PG_P12V_MAIN
   2    GND      B @BASEBOARD_FAB2_LIB.BASEBOARD_FAB2(SCH_1):GND


DRAWING: @BASEBOARD_FAB2_LIB.BASEBOARD_FAB2(SCH_1):PAGE198 

SLG55021_SM-IC,G56246-001  I1  EU2T1
   4    GND    GND @BASEBOARD_FAB2_LIB.BASEBOARD_FAB2(SCH_1):GND
   9    GND  THPAD @BASEBOARD_FAB2_LIB.BASEBOARD_FAB2(SCH_1):GND
   1 P5V_STBY    VCC @BASEBOARD_FAB2_LIB.BASEBOARD_FAB2(SCH_1):P5V_STBY
   2 FM_P3V3_CPLD_EN     ON @BASEBOARD_FAB2_LIB.BASEBOARD_FAB2(SCH_1):FM_P3V3_CPLD_EN
   3 P5V_STBY SHDN_N @BASEBOARD_FAB2_LIB.BASEBOARD_FAB2(SCH_1):P5V_STBY
   5 P3V3_STBY      D @BASEBOARD_FAB2_LIB.BASEBOARD_FAB2(SCH_1):P3V3_STBY
   6   P3V3      S @BASEBOARD_FAB2_LIB.BASEBOARD_FAB2(SCH_1):P3V3
   7 P3V3_SWITCH_G      G @BASEBOARD_FAB2_LIB.BASEBOARD_FAB2(SCH_1):P3V3_SWITCH_G
   8 TP_SLG55021_P3V3_8     PG @BASEBOARD_FAB2_LIB.BASEBOARD_FAB2(SCH_1):TP_SLG55021_P3V3_8

SLG55021_SM-IC,G56246-001  I13  EU8B1
   4    GND    GND @BASEBOARD_FAB2_LIB.BASEBOARD_FAB2(SCH_1):GND
   9    GND  THPAD @BASEBOARD_FAB2_LIB.BASEBOARD_FAB2(SCH_1):GND
   1 P5V_STBY    VCC @BASEBOARD_FAB2_LIB.BASEBOARD_FAB2(SCH_1):P5V_STBY
   2 FM_CTNR_PS_ON     ON @BASEBOARD_FAB2_LIB.BASEBOARD_FAB2(SCH_1):FM_CTNR_PS_ON
   3 P5V_STBY SHDN_N @BASEBOARD_FAB2_LIB.BASEBOARD_FAB2(SCH_1):P5V_STBY
   5 P5V_STBY      D @BASEBOARD_FAB2_LIB.BASEBOARD_FAB2(SCH_1):P5V_STBY
   6    P5V      S @BASEBOARD_FAB2_LIB.BASEBOARD_FAB2(SCH_1):P5V
   7 P5V_SWITCH_G      G @BASEBOARD_FAB2_LIB.BASEBOARD_FAB2(SCH_1):P5V_SWITCH_G
   8 TP_SLG55021_P5V_8     PG @BASEBOARD_FAB2_LIB.BASEBOARD_FAB2(SCH_1):TP_SLG55021_P5V_8

SLG55021_SM-IC,G56246-001  I19  EU7E1
   4    GND    GND @BASEBOARD_FAB2_LIB.BASEBOARD_FAB2(SCH_1):GND
   9    GND  THPAD @BASEBOARD_FAB2_LIB.BASEBOARD_FAB2(SCH_1):GND
   1 P5V_STBY    VCC @BASEBOARD_FAB2_LIB.BASEBOARD_FAB2(SCH_1):P5V_STBY
   2 FM_P12V_MAIN_SW_EN     ON @BASEBOARD_FAB2_LIB.BASEBOARD_FAB2(SCH_1):FM_P12V_MAIN_SW_EN
   3 P5V_STBY SHDN_N @BASEBOARD_FAB2_LIB.BASEBOARD_FAB2(SCH_1):P5V_STBY
   5 P12V_STBY      D @BASEBOARD_FAB2_LIB.BASEBOARD_FAB2(SCH_1):P12V_STBY
   6   P12V      S @BASEBOARD_FAB2_LIB.BASEBOARD_FAB2(SCH_1):P12V
   7 P12V_SWITCH_G      G @BASEBOARD_FAB2_LIB.BASEBOARD_FAB2(SCH_1):P12V_SWITCH_G
   8 TP_SLG55021_P12V_MAIN_8     PG @BASEBOARD_FAB2_LIB.BASEBOARD_FAB2(SCH_1):TP_SLG55021_P12V_MAIN_8

CAP_A_0402V-0.1UF,16V,10%,X7R,A  I24  C8F17
   1 P5V_STBY      A @BASEBOARD_FAB2_LIB.BASEBOARD_FAB2(SCH_1):P5V_STBY
   2    GND      B @BASEBOARD_FAB2_LIB.BASEBOARD_FAB2(SCH_1):GND

CAP_A_0402V-0.1UF,16V,10%,X7R,A  I26  C8B8
   1 P5V_STBY      A @BASEBOARD_FAB2_LIB.BASEBOARD_FAB2(SCH_1):P5V_STBY
   2    GND      B @BASEBOARD_FAB2_LIB.BASEBOARD_FAB2(SCH_1):GND

CAP_A_0402V-0.1UF,16V,10%,X7R,A  I28  C8E19
   1 P5V_STBY      A @BASEBOARD_FAB2_LIB.BASEBOARD_FAB2(SCH_1):P5V_STBY
   2    GND      B @BASEBOARD_FAB2_LIB.BASEBOARD_FAB2(SCH_1):GND

CAP_A_0402V-0.1UF,16V,10%,X7R,A  I37  C8B5
   1 P5V_STBY      A @BASEBOARD_FAB2_LIB.BASEBOARD_FAB2(SCH_1):P5V_STBY
   2    GND      B @BASEBOARD_FAB2_LIB.BASEBOARD_FAB2(SCH_1):GND

CAP_0805-10UF,16V,10%,X6S,C953A  I38  C8B12
   1 P5V_STBY      A @BASEBOARD_FAB2_LIB.BASEBOARD_FAB2(SCH_1):P5V_STBY
   2    GND      B @BASEBOARD_FAB2_LIB.BASEBOARD_FAB2(SCH_1):GND

CAP_0805-10UF,16V,10%,X6S,C953A  I40  C8B6
   1    P5V      A @BASEBOARD_FAB2_LIB.BASEBOARD_FAB2(SCH_1):P5V
   2    GND      B @BASEBOARD_FAB2_LIB.BASEBOARD_FAB2(SCH_1):GND

CAP_A_0402V-0.1UF,16V,10%,X7R,A  I41  C8B7
   1    P5V      A @BASEBOARD_FAB2_LIB.BASEBOARD_FAB2(SCH_1):P5V
   2    GND      B @BASEBOARD_FAB2_LIB.BASEBOARD_FAB2(SCH_1):GND

CAP_A_0402V-0.1UF,16V,10%,X7R,A  I43  C2T36
   1 P3V3_STBY      A @BASEBOARD_FAB2_LIB.BASEBOARD_FAB2(SCH_1):P3V3_STBY
   2    GND      B @BASEBOARD_FAB2_LIB.BASEBOARD_FAB2(SCH_1):GND

CAP_0805-10UF,16V,10%,X6S,C953A  I44  C2U1
   1 P3V3_STBY      A @BASEBOARD_FAB2_LIB.BASEBOARD_FAB2(SCH_1):P3V3_STBY
   2    GND      B @BASEBOARD_FAB2_LIB.BASEBOARD_FAB2(SCH_1):GND

CAP_A_0402V-0.1UF,16V,10%,X7R,A  I46  C2U19
   1   P3V3      A @BASEBOARD_FAB2_LIB.BASEBOARD_FAB2(SCH_1):P3V3
   2    GND      B @BASEBOARD_FAB2_LIB.BASEBOARD_FAB2(SCH_1):GND

CAP_0805-10UF,16V,10%,X6S,C953A  I47  C2U2
   1   P3V3      A @BASEBOARD_FAB2_LIB.BASEBOARD_FAB2(SCH_1):P3V3
   2    GND      B @BASEBOARD_FAB2_LIB.BASEBOARD_FAB2(SCH_1):GND

CAP_A_0402V-0.1UF,16V,10%,X7R,A  I49  C7E9
   1   P12V      A @BASEBOARD_FAB2_LIB.BASEBOARD_FAB2(SCH_1):P12V
   2    GND      B @BASEBOARD_FAB2_LIB.BASEBOARD_FAB2(SCH_1):GND

CAP_0805-10UF,16V,10%,X6S,C953A  I50  C7E8
   1   P12V      A @BASEBOARD_FAB2_LIB.BASEBOARD_FAB2(SCH_1):P12V
   2    GND      B @BASEBOARD_FAB2_LIB.BASEBOARD_FAB2(SCH_1):GND

CAP_A_0402V-0.1UF,16V,10%,X7R,A  I52  C7E5
   1 P12V_STBY      A @BASEBOARD_FAB2_LIB.BASEBOARD_FAB2(SCH_1):P12V_STBY
   2    GND      B @BASEBOARD_FAB2_LIB.BASEBOARD_FAB2(SCH_1):GND

CAP_0805-10UF,16V,10%,X6S,C953A  I53  C7E6
   1 P12V_STBY      A @BASEBOARD_FAB2_LIB.BASEBOARD_FAB2(SCH_1):P12V_STBY
   2    GND      B @BASEBOARD_FAB2_LIB.BASEBOARD_FAB2(SCH_1):GND

CAP_0805-10UF,16V,10%,X6S,C953A  I61  C1B18
   1 P12V_FAN      A @BASEBOARD_FAB2_LIB.BASEBOARD_FAB2(SCH_1):P12V_FAN
   2    GND      B @BASEBOARD_FAB2_LIB.BASEBOARD_FAB2(SCH_1):GND

CAP_A_0402V-0.1UF,16V,10%,X7R,A  I64  C1B19
   1 P12V_FAN      A @BASEBOARD_FAB2_LIB.BASEBOARD_FAB2(SCH_1):P12V_FAN
   2    GND      B @BASEBOARD_FAB2_LIB.BASEBOARD_FAB2(SCH_1):GND

CAP_A_0402V-0.1UF,16V,10%,X7R,A  I67  C9M6
   1 P5V_STBY      A @BASEBOARD_FAB2_LIB.BASEBOARD_FAB2(SCH_1):P5V_STBY
   2    GND      B @BASEBOARD_FAB2_LIB.BASEBOARD_FAB2(SCH_1):GND

SLG55021_SM-IC,G56246-001  I69  EU9M1
   4    GND    GND @BASEBOARD_FAB2_LIB.BASEBOARD_FAB2(SCH_1):GND
   9    GND  THPAD @BASEBOARD_FAB2_LIB.BASEBOARD_FAB2(SCH_1):GND
   1 P5V_STBY    VCC @BASEBOARD_FAB2_LIB.BASEBOARD_FAB2(SCH_1):P5V_STBY
   2 FM_ENABLE_FAN_POWER     ON @BASEBOARD_FAB2_LIB.BASEBOARD_FAB2(SCH_1):FM_ENABLE_FAN_POWER
   3 P5V_STBY SHDN_N @BASEBOARD_FAB2_LIB.BASEBOARD_FAB2(SCH_1):P5V_STBY
   5 P12V_STBY      D @BASEBOARD_FAB2_LIB.BASEBOARD_FAB2(SCH_1):P12V_STBY
   6 P12V_FAN      S @BASEBOARD_FAB2_LIB.BASEBOARD_FAB2(SCH_1):P12V_FAN
   7 P12V_FAN_SWITCH_G      G @BASEBOARD_FAB2_LIB.BASEBOARD_FAB2(SCH_1):P12V_FAN_SWITCH_G
   8 TP_SLG55021_P12V_FAN_8     PG @BASEBOARD_FAB2_LIB.BASEBOARD_FAB2(SCH_1):TP_SLG55021_P12V_FAN_8

CAP_0805-10UF,16V,10%,X6S,C953A  I74  C9M10
   1 P12V_STBY      A @BASEBOARD_FAB2_LIB.BASEBOARD_FAB2(SCH_1):P12V_STBY
   2    GND      B @BASEBOARD_FAB2_LIB.BASEBOARD_FAB2(SCH_1):GND

CAP_A_0402V-0.1UF,16V,10%,X7R,A  I76  C9M9
   1 P12V_STBY      A @BASEBOARD_FAB2_LIB.BASEBOARD_FAB2(SCH_1):P12V_STBY
   2    GND      B @BASEBOARD_FAB2_LIB.BASEBOARD_FAB2(SCH_1):GND

RES_0402-4.75K,1%,1/16W,EMPTY,A  I78  R8E12
   1 P3V3_STBY      A @BASEBOARD_FAB2_LIB.BASEBOARD_FAB2(SCH_1):P3V3_STBY
   2 FM_CTNR_PS_ON      B @BASEBOARD_FAB2_LIB.BASEBOARD_FAB2(SCH_1):FM_CTNR_PS_ON

RES_0402-100.0K,1%,1/16W,CHIP,A  I83  R8B4
   1 FM_CTNR_PS_ON      A @BASEBOARD_FAB2_LIB.BASEBOARD_FAB2(SCH_1):FM_CTNR_PS_ON
   2    GND      B @BASEBOARD_FAB2_LIB.BASEBOARD_FAB2(SCH_1):GND

MOSFET_N_LCC3-BSZ019N03LS,NFETA  I85  Q8G1
   4 P3V3_SWITCH_G   GATE @BASEBOARD_FAB2_LIB.BASEBOARD_FAB2(SCH_1):P3V3_SWITCH_G
   1   P3V3    SRC @BASEBOARD_FAB2_LIB.BASEBOARD_FAB2(SCH_1):P3V3
   5 P3V3_STBY    DRN @BASEBOARD_FAB2_LIB.BASEBOARD_FAB2(SCH_1):P3V3_STBY

MOSFET_N_LCC3-BSZ019N03LS,NFETA  I86  Q1B1
   4 P12V_FAN_SWITCH_G   GATE @BASEBOARD_FAB2_LIB.BASEBOARD_FAB2(SCH_1):P12V_FAN_SWITCH_G
   1 P12V_FAN    SRC @BASEBOARD_FAB2_LIB.BASEBOARD_FAB2(SCH_1):P12V_FAN
   5 P12V_STBY    DRN @BASEBOARD_FAB2_LIB.BASEBOARD_FAB2(SCH_1):P12V_STBY

MOSFET_N_LCC3-BSZ019N03LS,NFETA  I87  Q8B1
   4 P5V_SWITCH_G   GATE @BASEBOARD_FAB2_LIB.BASEBOARD_FAB2(SCH_1):P5V_SWITCH_G
   1    P5V    SRC @BASEBOARD_FAB2_LIB.BASEBOARD_FAB2(SCH_1):P5V
   5 P5V_STBY    DRN @BASEBOARD_FAB2_LIB.BASEBOARD_FAB2(SCH_1):P5V_STBY

MOSFET_N_LCC3-BSZ019N03LS,NFETA  I88  Q7E7
   4 P12V_SWITCH_G   GATE @BASEBOARD_FAB2_LIB.BASEBOARD_FAB2(SCH_1):P12V_SWITCH_G
   1   P12V    SRC @BASEBOARD_FAB2_LIB.BASEBOARD_FAB2(SCH_1):P12V
   5 P12V_STBY    DRN @BASEBOARD_FAB2_LIB.BASEBOARD_FAB2(SCH_1):P12V_STBY


DRAWING: @BASEBOARD_FAB2_LIB.BASEBOARD_FAB2(SCH_1):PAGE199 

RES_0603-10.0,1%,1/10W,CHIP,G2A  I2  R9P30
   1 P12V_PSU      A @BASEBOARD_FAB2_LIB.BASEBOARD_FAB2(SCH_1):P12V_PSU
   2 P12V_HSC_VCC      B @BASEBOARD_FAB2_LIB.BASEBOARD_FAB2(SCH_1):P12V_HSC_VCC

CAP_0402-1.0UF,16V,10%,X6S,D97A  I3  C1D25
   1 P12V_HSC_VCC      A @BASEBOARD_FAB2_LIB.BASEBOARD_FAB2(SCH_1):P12V_HSC_VCC
   2 AGND_HSC      B @BASEBOARD_FAB2_LIB.BASEBOARD_FAB2(SCH_1):AGND_HSC

CAP_A_0402V-0.1UF,16V,10%,X7R,A  I7  C1D27
   1 A_HSC_OV      A @BASEBOARD_FAB2_LIB.BASEBOARD_FAB2(SCH_1):A_HSC_OV
   2 AGND_HSC      B @BASEBOARD_FAB2_LIB.BASEBOARD_FAB2(SCH_1):AGND_HSC

RES_0402-7.5K,1%,1/16W,CHIP,G2A  I9  R1D43
   1 A_HSC_OV      A @BASEBOARD_FAB2_LIB.BASEBOARD_FAB2(SCH_1):A_HSC_OV
   2 AGND_HSC      B @BASEBOARD_FAB2_LIB.BASEBOARD_FAB2(SCH_1):AGND_HSC

ADM1278_SM-IC,G99251-001  I10  EU1D2
   7 FM_P12V_HSC_ADR1   ADR1 @BASEBOARD_FAB2_LIB.BASEBOARD_FAB2(SCH_1):FM_P12V_HSC_ADR1
   8 FM_P12V_HSC_ADR2   ADR2 @BASEBOARD_FAB2_LIB.BASEBOARD_FAB2(SCH_1):FM_P12V_HSC_ADR2
  19 A_HSC_CSOUT  CSOUT @BASEBOARD_FAB2_LIB.BASEBOARD_FAB2(SCH_1):A_HSC_CSOUT
  12 FM_P12V_HOTSWAP0_EN ENABLE @BASEBOARD_FAB2_LIB.BASEBOARD_FAB2(SCH_1):FM_P12V_HOTSWAP0_EN
  33 AGND_HSC     EP @BASEBOARD_FAB2_LIB.BASEBOARD_FAB2(SCH_1):AGND_HSC
   6 IRQ_HSC_FAULT_R_N FAULT_N @BASEBOARD_FAB2_LIB.BASEBOARD_FAB2(SCH_1):IRQ_HSC_FAULT_R_N
  24 A_HSC_GATE   GATE @BASEBOARD_FAB2_LIB.BASEBOARD_FAB2(SCH_1):A_HSC_GATE
  22 AGND_HSC    GND @BASEBOARD_FAB2_LIB.BASEBOARD_FAB2(SCH_1):AGND_HSC
  13 IRQ_SML1_PMBUS_ALERT_R_N GPO1_ALERT1_N_CONV @BASEBOARD_FAB2_LIB.BASEBOARD_FAB2(SCH_1):IRQ_SML1_PMBUS_ALERT_R_N
  14 TP_HSC_ALERT2_N GPO2_ALERT2_N @BASEBOARD_FAB2_LIB.BASEBOARD_FAB2(SCH_1):TP_HSC_ALERT2_N
  27 A_HSC_HSN    HSN @BASEBOARD_FAB2_LIB.BASEBOARD_FAB2(SCH_1):A_HSC_HSN
  28 A_HSC_HSP    HSP @BASEBOARD_FAB2_LIB.BASEBOARD_FAB2(SCH_1):A_HSC_HSP
   3 A_HSC_ISET   ISET @BASEBOARD_FAB2_LIB.BASEBOARD_FAB2(SCH_1):A_HSC_ISET
   4 A_HSC_ISTART ISTART @BASEBOARD_FAB2_LIB.BASEBOARD_FAB2(SCH_1):A_HSC_ISTART
  10 TP_HSC_MCLK   MCLK @BASEBOARD_FAB2_LIB.BASEBOARD_FAB2(SCH_1):TP_HSC_MCLK
  11 TP_HSC_MDAT   MDAT @BASEBOARD_FAB2_LIB.BASEBOARD_FAB2(SCH_1):TP_HSC_MDAT
  26 A_HSC_MON    MON @BASEBOARD_FAB2_LIB.BASEBOARD_FAB2(SCH_1):A_HSC_MON
  29 A_HSC_MOP    MOP @BASEBOARD_FAB2_LIB.BASEBOARD_FAB2(SCH_1):A_HSC_MOP
  32 A_HSC_OV     OV @BASEBOARD_FAB2_LIB.BASEBOARD_FAB2(SCH_1):A_HSC_OV
  23    GND   PGND @BASEBOARD_FAB2_LIB.BASEBOARD_FAB2(SCH_1):GND
   1 A_HSC_PSET   PSET @BASEBOARD_FAB2_LIB.BASEBOARD_FAB2(SCH_1):A_HSC_PSET
  21 A_HSC_PWGIN  PWGIN @BASEBOARD_FAB2_LIB.BASEBOARD_FAB2(SCH_1):A_HSC_PWGIN
  18 PWRGD_P12V_R  PWRGD @BASEBOARD_FAB2_LIB.BASEBOARD_FAB2(SCH_1):PWRGD_P12V_R
  17 PD_HSC_RETRY_N RETRY_N @BASEBOARD_FAB2_LIB.BASEBOARD_FAB2(SCH_1):PD_HSC_RETRY_N
  16 SMB_3V3SB_HSC_SCL_R    SCL @BASEBOARD_FAB2_LIB.BASEBOARD_FAB2(SCH_1):SMB_3V3SB_HSC_SCL_R
  15 SMB_3V3SB_HSC_SDA_R    SDA @BASEBOARD_FAB2_LIB.BASEBOARD_FAB2(SCH_1):SMB_3V3SB_HSC_SDA_R
   9 TP_HSC_SPISSN SPISS_N @BASEBOARD_FAB2_LIB.BASEBOARD_FAB2(SCH_1):TP_HSC_SPISSN
  25 A_HSC_TEMP   TEMP @BASEBOARD_FAB2_LIB.BASEBOARD_FAB2(SCH_1):A_HSC_TEMP
   5 A_HSC_TIMER  TIMER @BASEBOARD_FAB2_LIB.BASEBOARD_FAB2(SCH_1):A_HSC_TIMER
  31 A_HSC_UV     UV @BASEBOARD_FAB2_LIB.BASEBOARD_FAB2(SCH_1):A_HSC_UV
   2 A_HSC_VCAP   VCAP @BASEBOARD_FAB2_LIB.BASEBOARD_FAB2(SCH_1):A_HSC_VCAP
  30 P12V_HSC_VCC    VCC @BASEBOARD_FAB2_LIB.BASEBOARD_FAB2(SCH_1):P12V_HSC_VCC
  20 A_HSC_VOUT   VOUT @BASEBOARD_FAB2_LIB.BASEBOARD_FAB2(SCH_1):A_HSC_VOUT

RES_0402-100.0K,1%,1/16W,CHIP,A  I12  R9P29
   1 P12V_PSU      A @BASEBOARD_FAB2_LIB.BASEBOARD_FAB2(SCH_1):P12V_PSU
   2 A_HSC_UV      B @BASEBOARD_FAB2_LIB.BASEBOARD_FAB2(SCH_1):A_HSC_UV

RES_0402-11K,1%,1/16W,CHIP,G21A  I13  R1D42
   1 A_HSC_UV      A @BASEBOARD_FAB2_LIB.BASEBOARD_FAB2(SCH_1):A_HSC_UV
   2 AGND_HSC      B @BASEBOARD_FAB2_LIB.BASEBOARD_FAB2(SCH_1):AGND_HSC

RES_0402-100.0K,1%,1/16W,CHIP,A  I15  R1D37
   1 A_HSC_VCAP      A @BASEBOARD_FAB2_LIB.BASEBOARD_FAB2(SCH_1):A_HSC_VCAP
   2 A_HSC_ISET      B @BASEBOARD_FAB2_LIB.BASEBOARD_FAB2(SCH_1):A_HSC_ISET

RES_0402-100.0K,1%,1/16W,CHIP,A  I16  R1D39
   1 A_HSC_VCAP      A @BASEBOARD_FAB2_LIB.BASEBOARD_FAB2(SCH_1):A_HSC_VCAP
   2 A_HSC_PSET      B @BASEBOARD_FAB2_LIB.BASEBOARD_FAB2(SCH_1):A_HSC_PSET

RES_0402-100.0K,1%,1/16W,CHIP,A  I17  R1D32
   1 A_HSC_VCAP      A @BASEBOARD_FAB2_LIB.BASEBOARD_FAB2(SCH_1):A_HSC_VCAP
   2 A_HSC_ISTART      B @BASEBOARD_FAB2_LIB.BASEBOARD_FAB2(SCH_1):A_HSC_ISTART

RES_0805-0.0,5%,1/8W,CHIP,G221A  I19  R1D41
   1    GND      A @BASEBOARD_FAB2_LIB.BASEBOARD_FAB2(SCH_1):GND
   2 AGND_HSC      B @BASEBOARD_FAB2_LIB.BASEBOARD_FAB2(SCH_1):AGND_HSC

CAP_0603LF-0.033UF,50V,10%,X7RA  I24  C9P14
   1 A_HSC_TIMER      A @BASEBOARD_FAB2_LIB.BASEBOARD_FAB2(SCH_1):A_HSC_TIMER
   2 AGND_HSC      B @BASEBOARD_FAB2_LIB.BASEBOARD_FAB2(SCH_1):AGND_HSC

RES_0402-100.0,1%,1/16W,EMPTY,A  I26  R1D28
   1 PD_HSC_RETRY_N      A @BASEBOARD_FAB2_LIB.BASEBOARD_FAB2(SCH_1):PD_HSC_RETRY_N
   2 AGND_HSC      B @BASEBOARD_FAB2_LIB.BASEBOARD_FAB2(SCH_1):AGND_HSC

RES_0402-0.0,5%,1/16W,CHIP,G21A  I27  R1D24
   1 SMB_BMC_PMBUS_STBY_LVC3_SCL      A @BASEBOARD_FAB2_LIB.BASEBOARD_FAB2(SCH_1):SMB_BMC_PMBUS_STBY_LVC3_SCL
   2 SMB_3V3SB_HSC_SCL_R      B @BASEBOARD_FAB2_LIB.BASEBOARD_FAB2(SCH_1):SMB_3V3SB_HSC_SCL_R

RES_0402-0.0,5%,1/16W,CHIP,G21A  I28  R1D25
   1 SMB_BMC_PMBUS_STBY_LVC3_SDA      A @BASEBOARD_FAB2_LIB.BASEBOARD_FAB2(SCH_1):SMB_BMC_PMBUS_STBY_LVC3_SDA
   2 SMB_3V3SB_HSC_SDA_R      B @BASEBOARD_FAB2_LIB.BASEBOARD_FAB2(SCH_1):SMB_3V3SB_HSC_SDA_R

RES_0402-150.0K,1%,1/16W,CHIP,A  I33  R9P17
   1 FM_P12V_HSC_ADR1      A @BASEBOARD_FAB2_LIB.BASEBOARD_FAB2(SCH_1):FM_P12V_HSC_ADR1
   2 AGND_HSC      B @BASEBOARD_FAB2_LIB.BASEBOARD_FAB2(SCH_1):AGND_HSC

RES_0402-0.0,5%,1/16W,CHIP,G21A  I36  R9P16
   1 FM_P12V_HSC_ADR2      A @BASEBOARD_FAB2_LIB.BASEBOARD_FAB2(SCH_1):FM_P12V_HSC_ADR2
   2 AGND_HSC      B @BASEBOARD_FAB2_LIB.BASEBOARD_FAB2(SCH_1):AGND_HSC

RES_0402-4.75K,1%,1/16W,EMPTY,A  I38  R1D27
   1 A_HSC_VCAP      A @BASEBOARD_FAB2_LIB.BASEBOARD_FAB2(SCH_1):A_HSC_VCAP
   2 FM_P12V_HSC_ADR2      B @BASEBOARD_FAB2_LIB.BASEBOARD_FAB2(SCH_1):FM_P12V_HSC_ADR2

RES_0402-15.0K,1%,1/16W,CHIP,GA  I41  R9P18
   1 P12V_STBY      A @BASEBOARD_FAB2_LIB.BASEBOARD_FAB2(SCH_1):P12V_STBY
   2 PWRGD_P12V_R      B @BASEBOARD_FAB2_LIB.BASEBOARD_FAB2(SCH_1):PWRGD_P12V_R

RES_0402-6.19K,1%,1/16W,CHIP,GA  I43  R1D31
   1 PWRGD_P12V_R      A @BASEBOARD_FAB2_LIB.BASEBOARD_FAB2(SCH_1):PWRGD_P12V_R
   2    GND      B @BASEBOARD_FAB2_LIB.BASEBOARD_FAB2(SCH_1):GND

CAP_A_0402V-0.1UF,16V,10%,X7R,A  I53  C1D11
   1 FM_P12V_HOTSWAP0_EN      A @BASEBOARD_FAB2_LIB.BASEBOARD_FAB2(SCH_1):FM_P12V_HOTSWAP0_EN
   2 AGND_HSC      B @BASEBOARD_FAB2_LIB.BASEBOARD_FAB2(SCH_1):AGND_HSC

RES_0402-100.0K,1%,1/16W,CHIP,A  I54  R9P23
   1 P12V_STBY      A @BASEBOARD_FAB2_LIB.BASEBOARD_FAB2(SCH_1):P12V_STBY
   2 A_HSC_PWGIN      B @BASEBOARD_FAB2_LIB.BASEBOARD_FAB2(SCH_1):A_HSC_PWGIN

RES_0402-12.1K,1%,1/16W,CHIP,GA  I55  R9P24
   1 A_HSC_PWGIN      A @BASEBOARD_FAB2_LIB.BASEBOARD_FAB2(SCH_1):A_HSC_PWGIN
   2 AGND_HSC      B @BASEBOARD_FAB2_LIB.BASEBOARD_FAB2(SCH_1):AGND_HSC

NPN_SM-MMBT3904,IC,C52245-001  I58  Q1D3
   1 TEMP_SENSOR_B      B @BASEBOARD_FAB2_LIB.BASEBOARD_FAB2(SCH_1):TEMP_SENSOR_B
   3 TEMP_SENSOR_B      C @BASEBOARD_FAB2_LIB.BASEBOARD_FAB2(SCH_1):TEMP_SENSOR_B
   2 TEMP_SENSOR_E      E @BASEBOARD_FAB2_LIB.BASEBOARD_FAB2(SCH_1):TEMP_SENSOR_E

RES_0402-1.00K,1%,1/16W,CHIP,GA  I65  R1D36
   1 P12V_STBY      A @BASEBOARD_FAB2_LIB.BASEBOARD_FAB2(SCH_1):P12V_STBY
   2 A_HSC_VOUT      B @BASEBOARD_FAB2_LIB.BASEBOARD_FAB2(SCH_1):A_HSC_VOUT

CAP_A_0402V-0.1UF,16V,10%,EMPTA  I67  C9P12
   1 A_HSC_VOUT      A @BASEBOARD_FAB2_LIB.BASEBOARD_FAB2(SCH_1):A_HSC_VOUT
   2 AGND_HSC      B @BASEBOARD_FAB2_LIB.BASEBOARD_FAB2(SCH_1):AGND_HSC

FET_N_DUAL_SMLF-2N7002DW,FET,DA  I82  Q1D1
   5 A_HSC_HIGH_EN GATE<0> @BASEBOARD_FAB2_LIB.BASEBOARD_FAB2(SCH_1):A_HSC_HIGH_EN
   4 AGND_HSC SOURCE<0> @BASEBOARD_FAB2_LIB.BASEBOARD_FAB2(SCH_1):AGND_HSC
   3 A_HSC_ISET_S DRAIN<0> @BASEBOARD_FAB2_LIB.BASEBOARD_FAB2(SCH_1):A_HSC_ISET_S

RES_0402-90.9K,1%,1/16W,CHIP,GA  I84  R1D13
   1 A_HSC_ISET_S      A @BASEBOARD_FAB2_LIB.BASEBOARD_FAB2(SCH_1):A_HSC_ISET_S
   2 A_HSC_ISET      B @BASEBOARD_FAB2_LIB.BASEBOARD_FAB2(SCH_1):A_HSC_ISET

RES_0402-69.8K,1%,1/16W,CHIP,GA  I85  R1D16
   1 A_HSC_ISET      A @BASEBOARD_FAB2_LIB.BASEBOARD_FAB2(SCH_1):A_HSC_ISET
   2 A_HSC_ISET_S2      B @BASEBOARD_FAB2_LIB.BASEBOARD_FAB2(SCH_1):A_HSC_ISET_S2

FET_N_DUAL_SMLF-2N7002DW,FET,DA  I86  Q1D1
   2 A_HSC_LOW_EN GATE<0> @BASEBOARD_FAB2_LIB.BASEBOARD_FAB2(SCH_1):A_HSC_LOW_EN
   1 AGND_HSC SOURCE<0> @BASEBOARD_FAB2_LIB.BASEBOARD_FAB2(SCH_1):AGND_HSC
   6 A_HSC_ISET_S2 DRAIN<0> @BASEBOARD_FAB2_LIB.BASEBOARD_FAB2(SCH_1):A_HSC_ISET_S2

RES_0402-100.0K,1%,1/16W,CHIP,A  I92  R1D15
   1 P12V_PSU      A @BASEBOARD_FAB2_LIB.BASEBOARD_FAB2(SCH_1):P12V_PSU
   2 A_HSC_OCP_SEL      B @BASEBOARD_FAB2_LIB.BASEBOARD_FAB2(SCH_1):A_HSC_OCP_SEL

ZENER_SM-13V,IC,H69095-001  I99  VR1D1
   2    GND      A @BASEBOARD_FAB2_LIB.BASEBOARD_FAB2(SCH_1):GND
   1 P12V_PSU      C @BASEBOARD_FAB2_LIB.BASEBOARD_FAB2(SCH_1):P12V_PSU

RES_0402-40.2K,1%,1/16W,CHIP,GA  I100  R1D40
   1 A_HSC_PSET      A @BASEBOARD_FAB2_LIB.BASEBOARD_FAB2(SCH_1):A_HSC_PSET
   2 AGND_HSC      B @BASEBOARD_FAB2_LIB.BASEBOARD_FAB2(SCH_1):AGND_HSC

RES_0402-16K,1.0%,1/16W,CHIP,GA  I102  R1D34
   1 A_HSC_ISTART      A @BASEBOARD_FAB2_LIB.BASEBOARD_FAB2(SCH_1):A_HSC_ISTART
   2 AGND_HSC      B @BASEBOARD_FAB2_LIB.BASEBOARD_FAB2(SCH_1):AGND_HSC

CAP_A_0402V-0.1UF,16V,10%,X7R,A  I105  C9P15
   1 A_HSC_ISET      A @BASEBOARD_FAB2_LIB.BASEBOARD_FAB2(SCH_1):A_HSC_ISET
   2 AGND_HSC      B @BASEBOARD_FAB2_LIB.BASEBOARD_FAB2(SCH_1):AGND_HSC

CAP_A_0402V-0.1UF,16V,10%,X7R,A  I107  C1D26
   1 A_HSC_UV      A @BASEBOARD_FAB2_LIB.BASEBOARD_FAB2(SCH_1):A_HSC_UV
   2 AGND_HSC      B @BASEBOARD_FAB2_LIB.BASEBOARD_FAB2(SCH_1):AGND_HSC

RES_0402-33.2,1%,1/16W,CHIP,G2A  I108  R1D33
   1 PWRGD_P12V_R      A @BASEBOARD_FAB2_LIB.BASEBOARD_FAB2(SCH_1):PWRGD_P12V_R
   2 PWRGD_P12V_HSC      B @BASEBOARD_FAB2_LIB.BASEBOARD_FAB2(SCH_1):PWRGD_P12V_HSC

RES_0402-33.2,1%,1/16W,CHIP,G2A  I109  R1D26
   1 IRQ_SML1_PMBUS_ALERT_R_N      A @BASEBOARD_FAB2_LIB.BASEBOARD_FAB2(SCH_1):IRQ_SML1_PMBUS_ALERT_R_N
   2 IRQ_SML1_PMBUS_ALERT_N      B @BASEBOARD_FAB2_LIB.BASEBOARD_FAB2(SCH_1):IRQ_SML1_PMBUS_ALERT_N

RES_0402-33.2,1%,1/16W,CHIP,G2A  I110  R1D30
   1 IRQ_HSC_FAULT_R_N      A @BASEBOARD_FAB2_LIB.BASEBOARD_FAB2(SCH_1):IRQ_HSC_FAULT_R_N
   2 IRQ_HSC_FAULT_N      B @BASEBOARD_FAB2_LIB.BASEBOARD_FAB2(SCH_1):IRQ_HSC_FAULT_N

CAP_0402-1.0UF,16V,10%,X6S,D97A  I119  C1D19
   1 A_HSC_VCAP      A @BASEBOARD_FAB2_LIB.BASEBOARD_FAB2(SCH_1):A_HSC_VCAP
   2 AGND_HSC      B @BASEBOARD_FAB2_LIB.BASEBOARD_FAB2(SCH_1):AGND_HSC

CAP_A_0402V-0.1UF,16V,10%,X7R,A  I121  C1D21
   1 A_HSC_PSET      A @BASEBOARD_FAB2_LIB.BASEBOARD_FAB2(SCH_1):A_HSC_PSET
   2 AGND_HSC      B @BASEBOARD_FAB2_LIB.BASEBOARD_FAB2(SCH_1):AGND_HSC

RES_0402-100.0K,1%,1/16W,CHIP,A  I87  R1D18
   1 A_HSC_HIGH_EN      A @BASEBOARD_FAB2_LIB.BASEBOARD_FAB2(SCH_1):A_HSC_HIGH_EN
   2 AGND_HSC      B @BASEBOARD_FAB2_LIB.BASEBOARD_FAB2(SCH_1):AGND_HSC

RES_0402-100.0K,1%,1/16W,CHIP,A  I88  R1D11
   1 A_HSC_LOW_EN      A @BASEBOARD_FAB2_LIB.BASEBOARD_FAB2(SCH_1):A_HSC_LOW_EN
   2 AGND_HSC      B @BASEBOARD_FAB2_LIB.BASEBOARD_FAB2(SCH_1):AGND_HSC

FET_N_SOT23LF-2N7002,FET,C7925A  I130  Q1W5
   1 A_HSC_HIGH_EN   GATE @BASEBOARD_FAB2_LIB.BASEBOARD_FAB2(SCH_1):A_HSC_HIGH_EN
   2    GND    SRC @BASEBOARD_FAB2_LIB.BASEBOARD_FAB2(SCH_1):GND
   3 A_HSC_LOW_GATE    DRN @BASEBOARD_FAB2_LIB.BASEBOARD_FAB2(SCH_1):A_HSC_LOW_GATE

CLX-CONN3A-1-GP_CONN-G3-CLX-COA  I131  J1B4
   1 A_HSC_HIGH_EN      1 @BASEBOARD_FAB2_LIB.BASEBOARD_FAB2(SCH_1):A_HSC_HIGH_EN
   2 A_HSC_OCP_SEL      2 @BASEBOARD_FAB2_LIB.BASEBOARD_FAB2(SCH_1):A_HSC_OCP_SEL
   3 A_HSC_LOW_EN      3 @BASEBOARD_FAB2_LIB.BASEBOARD_FAB2(SCH_1):A_HSC_LOW_EN

CAP_0402LF-1000PF,50V,10%,X7R,A  I132  C1W16
   1 A_HSC_TEMP      A @BASEBOARD_FAB2_LIB.BASEBOARD_FAB2(SCH_1):A_HSC_TEMP
   2    GND      B @BASEBOARD_FAB2_LIB.BASEBOARD_FAB2(SCH_1):GND

RES_0402-0.0,5%,1/16W,CHIP,G21A  I134  R1W20
   1 A_HSC_TEMP      A @BASEBOARD_FAB2_LIB.BASEBOARD_FAB2(SCH_1):A_HSC_TEMP
   2 TEMP_SENSOR_B      B @BASEBOARD_FAB2_LIB.BASEBOARD_FAB2(SCH_1):TEMP_SENSOR_B

RES_0402-0.0,5%,1/16W,CHIP,G21A  I135  R1W21
   1    GND      A @BASEBOARD_FAB2_LIB.BASEBOARD_FAB2(SCH_1):GND
   2 TEMP_SENSOR_E      B @BASEBOARD_FAB2_LIB.BASEBOARD_FAB2(SCH_1):TEMP_SENSOR_E

RES_0402-4.75K,1%,1/16W,CHIP,GA  I137  R1D29
   1 A_HSC_VCAP      A @BASEBOARD_FAB2_LIB.BASEBOARD_FAB2(SCH_1):A_HSC_VCAP
   2 FM_P12V_HSC_ADR1      B @BASEBOARD_FAB2_LIB.BASEBOARD_FAB2(SCH_1):FM_P12V_HSC_ADR1

RES_0402-100.0K,1%,1/16W,CHIP,A  I138  R9P28
   1 P12V_PSU      A @BASEBOARD_FAB2_LIB.BASEBOARD_FAB2(SCH_1):P12V_PSU
   2 A_HSC_OV      B @BASEBOARD_FAB2_LIB.BASEBOARD_FAB2(SCH_1):A_HSC_OV


DRAWING: @BASEBOARD_FAB2_LIB.BASEBOARD_FAB2(SCH_1):PAGE200 

CAP_A_0402V-0.1UF,16V,10%,EMPTA  I36  C9P17
   1 A_HSC_MON      A @BASEBOARD_FAB2_LIB.BASEBOARD_FAB2(SCH_1):A_HSC_MON
   2 AGND_HSC      B @BASEBOARD_FAB2_LIB.BASEBOARD_FAB2(SCH_1):AGND_HSC

CAP_A_0402V-0.1UF,16V,10%,EMPTA  I40  C9P16
   1 A_HSC_MOP      A @BASEBOARD_FAB2_LIB.BASEBOARD_FAB2(SCH_1):A_HSC_MOP
   2 AGND_HSC      B @BASEBOARD_FAB2_LIB.BASEBOARD_FAB2(SCH_1):AGND_HSC

CAP_A_0402V-0.1UF,16V,10%,EMPTA  I42  C1D22
   1 A_HSC_MON      A @BASEBOARD_FAB2_LIB.BASEBOARD_FAB2(SCH_1):A_HSC_MON
   2 A_HSC_MOP      B @BASEBOARD_FAB2_LIB.BASEBOARD_FAB2(SCH_1):A_HSC_MOP

RES_0402-0.0,5%,1/16W,CHIP,G21A  I43  R1D45
   1 A_HSC_MON      A @BASEBOARD_FAB2_LIB.BASEBOARD_FAB2(SCH_1):A_HSC_MON
   2 A_HSC_HSN      B @BASEBOARD_FAB2_LIB.BASEBOARD_FAB2(SCH_1):A_HSC_HSN

RES_0402-0.0,5%,1/16W,CHIP,G21A  I44  R1D44
   1 A_HSC_MOP      A @BASEBOARD_FAB2_LIB.BASEBOARD_FAB2(SCH_1):A_HSC_MOP
   2 A_HSC_HSP      B @BASEBOARD_FAB2_LIB.BASEBOARD_FAB2(SCH_1):A_HSC_HSP

RES_0402-10.0,1%,1/16W,CHIP,G2A  I47  R9P27
   1 P12V_HSC_SENP1      A @BASEBOARD_FAB2_LIB.BASEBOARD_FAB2(SCH_1):P12V_HSC_SENP1
   2 A_HSC_HSP      B @BASEBOARD_FAB2_LIB.BASEBOARD_FAB2(SCH_1):A_HSC_HSP

RES_0402-10.0,1%,1/16W,CHIP,G2A  I48  R1D46
   1 P12V_HSC_SENP0      A @BASEBOARD_FAB2_LIB.BASEBOARD_FAB2(SCH_1):P12V_HSC_SENP0
   2 A_HSC_HSP      B @BASEBOARD_FAB2_LIB.BASEBOARD_FAB2(SCH_1):A_HSC_HSP

RES_PWR_6PAD-0.001,1%,3W,CHIP,A  I49  R9R1
   1 P12V_PSU      1 @BASEBOARD_FAB2_LIB.BASEBOARD_FAB2(SCH_1):P12V_PSU
   2 P12V_MB0_SW      2 @BASEBOARD_FAB2_LIB.BASEBOARD_FAB2(SCH_1):P12V_MB0_SW
   3 P12V_HSC_SENP1      3 @BASEBOARD_FAB2_LIB.BASEBOARD_FAB2(SCH_1):P12V_HSC_SENP1
   4 P12V_HSC_SENN1      4 @BASEBOARD_FAB2_LIB.BASEBOARD_FAB2(SCH_1):P12V_HSC_SENN1
   5 P12V_PSU      5 @BASEBOARD_FAB2_LIB.BASEBOARD_FAB2(SCH_1):P12V_PSU
   6 P12V_MB0_SW      6 @BASEBOARD_FAB2_LIB.BASEBOARD_FAB2(SCH_1):P12V_MB0_SW

RES_PWR_6PAD-0.001,1%,3W,CHIP,A  I50  R1D49
   1 P12V_PSU      1 @BASEBOARD_FAB2_LIB.BASEBOARD_FAB2(SCH_1):P12V_PSU
   2 P12V_MB0_SW      2 @BASEBOARD_FAB2_LIB.BASEBOARD_FAB2(SCH_1):P12V_MB0_SW
   3 P12V_HSC_SENP0      3 @BASEBOARD_FAB2_LIB.BASEBOARD_FAB2(SCH_1):P12V_HSC_SENP0
   4 P12V_HSC_SENN0      4 @BASEBOARD_FAB2_LIB.BASEBOARD_FAB2(SCH_1):P12V_HSC_SENN0
   5 P12V_PSU      5 @BASEBOARD_FAB2_LIB.BASEBOARD_FAB2(SCH_1):P12V_PSU
   6 P12V_MB0_SW      6 @BASEBOARD_FAB2_LIB.BASEBOARD_FAB2(SCH_1):P12V_MB0_SW

RES_0402-10.0,1%,1/16W,CHIP,G2A  I51  R9P26
   1 P12V_HSC_SENN1      A @BASEBOARD_FAB2_LIB.BASEBOARD_FAB2(SCH_1):P12V_HSC_SENN1
   2 A_HSC_HSN      B @BASEBOARD_FAB2_LIB.BASEBOARD_FAB2(SCH_1):A_HSC_HSN

RES_0402-10.0,1%,1/16W,CHIP,G2A  I52  R1D47
   1 P12V_HSC_SENN0      A @BASEBOARD_FAB2_LIB.BASEBOARD_FAB2(SCH_1):P12V_HSC_SENN0
   2 A_HSC_HSN      B @BASEBOARD_FAB2_LIB.BASEBOARD_FAB2(SCH_1):A_HSC_HSN

MOSFETN_1D3S_SOT5-IC,G68777-001  I54  EU1E3
   1 P12V_STBY     S1 @BASEBOARD_FAB2_LIB.BASEBOARD_FAB2(SCH_1):P12V_STBY
   2 P12V_STBY     S2 @BASEBOARD_FAB2_LIB.BASEBOARD_FAB2(SCH_1):P12V_STBY
   3 P12V_STBY     S3 @BASEBOARD_FAB2_LIB.BASEBOARD_FAB2(SCH_1):P12V_STBY
   5 P12V_MB0_SW      D @BASEBOARD_FAB2_LIB.BASEBOARD_FAB2(SCH_1):P12V_MB0_SW
   4 A_HSC_GATE1_R      G @BASEBOARD_FAB2_LIB.BASEBOARD_FAB2(SCH_1):A_HSC_GATE1_R

RES_0402-10.0,1%,1/16W,CHIP,G2A  I56  R1E1
   1 A_HSC_GATE      A @BASEBOARD_FAB2_LIB.BASEBOARD_FAB2(SCH_1):A_HSC_GATE
   2 A_HSC_GATE1_R      B @BASEBOARD_FAB2_LIB.BASEBOARD_FAB2(SCH_1):A_HSC_GATE1_R

MOSFETN_1D3S_SOT5-IC,G68777-001  I57  EU9R1
   1 P12V_STBY     S1 @BASEBOARD_FAB2_LIB.BASEBOARD_FAB2(SCH_1):P12V_STBY
   2 P12V_STBY     S2 @BASEBOARD_FAB2_LIB.BASEBOARD_FAB2(SCH_1):P12V_STBY
   3 P12V_STBY     S3 @BASEBOARD_FAB2_LIB.BASEBOARD_FAB2(SCH_1):P12V_STBY
   5 P12V_MB0_SW      D @BASEBOARD_FAB2_LIB.BASEBOARD_FAB2(SCH_1):P12V_MB0_SW
   4 A_HSC_GATE2_R      G @BASEBOARD_FAB2_LIB.BASEBOARD_FAB2(SCH_1):A_HSC_GATE2_R

RES_0402-10.0,1%,1/16W,CHIP,G2A  I58  R9R4
   1 A_HSC_GATE      A @BASEBOARD_FAB2_LIB.BASEBOARD_FAB2(SCH_1):A_HSC_GATE
   2 A_HSC_GATE2_R      B @BASEBOARD_FAB2_LIB.BASEBOARD_FAB2(SCH_1):A_HSC_GATE2_R

MOSFETN_1D3S_SOT5-IC,G68777-001  I59  EU1E1
   1 P12V_STBY     S1 @BASEBOARD_FAB2_LIB.BASEBOARD_FAB2(SCH_1):P12V_STBY
   2 P12V_STBY     S2 @BASEBOARD_FAB2_LIB.BASEBOARD_FAB2(SCH_1):P12V_STBY
   3 P12V_STBY     S3 @BASEBOARD_FAB2_LIB.BASEBOARD_FAB2(SCH_1):P12V_STBY
   5 P12V_MB0_SW      D @BASEBOARD_FAB2_LIB.BASEBOARD_FAB2(SCH_1):P12V_MB0_SW
   4 A_HSC_GATE3_R      G @BASEBOARD_FAB2_LIB.BASEBOARD_FAB2(SCH_1):A_HSC_GATE3_R

RES_0402-10.0,1%,1/16W,CHIP,G2A  I60  R1D48
   1 A_HSC_GATE      A @BASEBOARD_FAB2_LIB.BASEBOARD_FAB2(SCH_1):A_HSC_GATE
   2 A_HSC_GATE3_R      B @BASEBOARD_FAB2_LIB.BASEBOARD_FAB2(SCH_1):A_HSC_GATE3_R

RES_0402-10.0K,1%,1/16W,EMPTY,A  I70  R9P19
   1 A_HSC_TIMER_R      A @BASEBOARD_FAB2_LIB.BASEBOARD_FAB2(SCH_1):A_HSC_TIMER_R
   2 AGND_HSC      B @BASEBOARD_FAB2_LIB.BASEBOARD_FAB2(SCH_1):AGND_HSC

RES_0402-0.0,5%,1/16W,CHIP,G21A  I71  R9P21
   1 A_HSC_TIMER      A @BASEBOARD_FAB2_LIB.BASEBOARD_FAB2(SCH_1):A_HSC_TIMER
   2 A_HSC_TIMER_R      B @BASEBOARD_FAB2_LIB.BASEBOARD_FAB2(SCH_1):A_HSC_TIMER_R

RES_0402-2.7K,1%,1/16W,CHIP,G2A  I86  R9P20
   1 P3V3_STBY      A @BASEBOARD_FAB2_LIB.BASEBOARD_FAB2(SCH_1):P3V3_STBY
   2 FM_HSC_TIMER_EXP_N      B @BASEBOARD_FAB2_LIB.BASEBOARD_FAB2(SCH_1):FM_HSC_TIMER_EXP_N

TTL1G126_A_SOT-74HC1G126,IC,A7B  I103  U1D1
   1 FM_OC_DETECT_EN     OE @BASEBOARD_FAB2_LIB.BASEBOARD_FAB2(SCH_1):FM_OC_DETECT_EN
   2 IRQ_OC_DETECT_N      A @BASEBOARD_FAB2_LIB.BASEBOARD_FAB2(SCH_1):IRQ_OC_DETECT_N
   4 FM_OC_DETECT_N      Y @BASEBOARD_FAB2_LIB.BASEBOARD_FAB2(SCH_1):FM_OC_DETECT_N

RES_0402-10.0K,1%,1/16W,CHIP,GA  I108  R9P11
   1 A_P12V_STBY_FP_TRIGGER      A @BASEBOARD_FAB2_LIB.BASEBOARD_FAB2(SCH_1):A_P12V_STBY_FP_TRIGGER
   2 AGND_HSC      B @BASEBOARD_FAB2_LIB.BASEBOARD_FAB2(SCH_1):AGND_HSC

RES_0402-10.0K,1%,1/16W,CHIP,GA  I149  R9P6
   1 P3V3_STBY      A @BASEBOARD_FAB2_LIB.BASEBOARD_FAB2(SCH_1):P3V3_STBY
   2 FM_UV_ADR_TRIGGER_N      B @BASEBOARD_FAB2_LIB.BASEBOARD_FAB2(SCH_1):FM_UV_ADR_TRIGGER_N

RES_0402-10.0,1%,1/16W,CHIP,G2A  I154  R1D51
   1 A_HSC_C      A @BASEBOARD_FAB2_LIB.BASEBOARD_FAB2(SCH_1):A_HSC_C
   2 A_HSC_GATE      B @BASEBOARD_FAB2_LIB.BASEBOARD_FAB2(SCH_1):A_HSC_GATE

CAP_1206-0.068UF,50V,20%,X7R,1A  I155  C1E2
   1 A_HSC_C      A @BASEBOARD_FAB2_LIB.BASEBOARD_FAB2(SCH_1):A_HSC_C
   2    GND      B @BASEBOARD_FAB2_LIB.BASEBOARD_FAB2(SCH_1):GND

RES_0402-10.0K,1%,1/16W,CHIP,GA  I158  R1D22
   1 P3V3_STBY      A @BASEBOARD_FAB2_LIB.BASEBOARD_FAB2(SCH_1):P3V3_STBY
   2 FM_OC_DETECT_N      B @BASEBOARD_FAB2_LIB.BASEBOARD_FAB2(SCH_1):FM_OC_DETECT_N

TPS3700_SM-IC,H69492-001  I163  U9P1
   5    GND    GND @BASEBOARD_FAB2_LIB.BASEBOARD_FAB2(SCH_1):GND
   4 A_P12V_STBY_ADR_TRIGGER   INAP @BASEBOARD_FAB2_LIB.BASEBOARD_FAB2(SCH_1):A_P12V_STBY_ADR_TRIGGER
   3 A_P12V_STBY_FP_TRIGGER   INBN @BASEBOARD_FAB2_LIB.BASEBOARD_FAB2(SCH_1):A_P12V_STBY_FP_TRIGGER
   6 FM_UV_ADR_TRIGGER_N   OUTA @BASEBOARD_FAB2_LIB.BASEBOARD_FAB2(SCH_1):FM_UV_ADR_TRIGGER_N
   1 A_P12V_STBY_FPH_GATE   OUTB @BASEBOARD_FAB2_LIB.BASEBOARD_FAB2(SCH_1):A_P12V_STBY_FPH_GATE
   2 P12V_STBY    VDD @BASEBOARD_FAB2_LIB.BASEBOARD_FAB2(SCH_1):P12V_STBY

TPS3700_SM-IC,H69492-001  I170  U1D2
   5    GND    GND @BASEBOARD_FAB2_LIB.BASEBOARD_FAB2(SCH_1):GND
   4 A_HSC_LOW   INAP @BASEBOARD_FAB2_LIB.BASEBOARD_FAB2(SCH_1):A_HSC_LOW
   3 A_HSC_HIGH   INBN @BASEBOARD_FAB2_LIB.BASEBOARD_FAB2(SCH_1):A_HSC_HIGH
   6 A_HSC_LOW_GATE   OUTA @BASEBOARD_FAB2_LIB.BASEBOARD_FAB2(SCH_1):A_HSC_LOW_GATE
   1 IRQ_OC_DETECT_N   OUTB @BASEBOARD_FAB2_LIB.BASEBOARD_FAB2(SCH_1):IRQ_OC_DETECT_N
   2 P12V_STBY    VDD @BASEBOARD_FAB2_LIB.BASEBOARD_FAB2(SCH_1):P12V_STBY

RES_0402-10.0K,1%,1/16W,CHIP,GA  I174  R1D12
   1 A_HSC_LOW      A @BASEBOARD_FAB2_LIB.BASEBOARD_FAB2(SCH_1):A_HSC_LOW
   2 AGND_HSC      B @BASEBOARD_FAB2_LIB.BASEBOARD_FAB2(SCH_1):AGND_HSC

RES_0402-10.0K,1%,1/16W,CHIP,GA  I175  R1D19
   1 A_HSC_HIGH      A @BASEBOARD_FAB2_LIB.BASEBOARD_FAB2(SCH_1):A_HSC_HIGH
   2 AGND_HSC      B @BASEBOARD_FAB2_LIB.BASEBOARD_FAB2(SCH_1):AGND_HSC

CAP_A_0402V-0.1UF,16V,10%,X7R,A  I185  C9P6
   1 P12V_STBY      A @BASEBOARD_FAB2_LIB.BASEBOARD_FAB2(SCH_1):P12V_STBY
   2 AGND_HSC      B @BASEBOARD_FAB2_LIB.BASEBOARD_FAB2(SCH_1):AGND_HSC

CAP_A_0402V-0.1UF,16V,10%,X7R,A  I187  C1D9
   1 P12V_STBY      A @BASEBOARD_FAB2_LIB.BASEBOARD_FAB2(SCH_1):P12V_STBY
   2 AGND_HSC      B @BASEBOARD_FAB2_LIB.BASEBOARD_FAB2(SCH_1):AGND_HSC

RES_0402-10.0K,1%,1/16W,CHIP,GA  I191  R1D23
   1 P3V3_STBY      A @BASEBOARD_FAB2_LIB.BASEBOARD_FAB2(SCH_1):P3V3_STBY
   2 IRQ_OC_DETECT_N      B @BASEBOARD_FAB2_LIB.BASEBOARD_FAB2(SCH_1):IRQ_OC_DETECT_N

RES_0402-10.0K,1%,1/16W,CHIP,GA  I192  R9P10
   1 P3V3_STBY      A @BASEBOARD_FAB2_LIB.BASEBOARD_FAB2(SCH_1):P3V3_STBY
   2 A_P12V_STBY_FPH_GATE      B @BASEBOARD_FAB2_LIB.BASEBOARD_FAB2(SCH_1):A_P12V_STBY_FPH_GATE

FET_N_DUAL_SMLF-2N7002DW,FET,DA  I196  Q9P1
   2 A_HSC_LOW_GATE GATE<0> @BASEBOARD_FAB2_LIB.BASEBOARD_FAB2(SCH_1):A_HSC_LOW_GATE
   1    GND SOURCE<0> @BASEBOARD_FAB2_LIB.BASEBOARD_FAB2(SCH_1):GND
   6 A_HSC_LOW_DRAIN DRAIN<0> @BASEBOARD_FAB2_LIB.BASEBOARD_FAB2(SCH_1):A_HSC_LOW_DRAIN

FET_N_DUAL_SMLF-2N7002DW,FET,DA  I199  Q9P1
   5 A_P12V_STBY_FPH_GATE GATE<0> @BASEBOARD_FAB2_LIB.BASEBOARD_FAB2(SCH_1):A_P12V_STBY_FPH_GATE
   4    GND SOURCE<0> @BASEBOARD_FAB2_LIB.BASEBOARD_FAB2(SCH_1):GND
   3 IRQ_UV_DETECT_N DRAIN<0> @BASEBOARD_FAB2_LIB.BASEBOARD_FAB2(SCH_1):IRQ_UV_DETECT_N

TPS3700_SM-IC,H69492-001  I200  U9P2
   5    GND    GND @BASEBOARD_FAB2_LIB.BASEBOARD_FAB2(SCH_1):GND
   4 A_HSC_INAP   INAP @BASEBOARD_FAB2_LIB.BASEBOARD_FAB2(SCH_1):A_HSC_INAP
   3 A_HSC_TIMER_R   INBN @BASEBOARD_FAB2_LIB.BASEBOARD_FAB2(SCH_1):A_HSC_TIMER_R
   6 PWRGD_DSW_PWROK   OUTA @BASEBOARD_FAB2_LIB.BASEBOARD_FAB2(SCH_1):PWRGD_DSW_PWROK
   1 FM_HSC_TIMER_EXP_N   OUTB @BASEBOARD_FAB2_LIB.BASEBOARD_FAB2(SCH_1):FM_HSC_TIMER_EXP_N
   2 P3V3_STBY    VDD @BASEBOARD_FAB2_LIB.BASEBOARD_FAB2(SCH_1):P3V3_STBY

CAP_A_0402V-0.1UF,16V,10%,X7R,A  I201  C9P11
   1 P3V3_STBY      A @BASEBOARD_FAB2_LIB.BASEBOARD_FAB2(SCH_1):P3V3_STBY
   2    GND      B @BASEBOARD_FAB2_LIB.BASEBOARD_FAB2(SCH_1):GND

FET_N_SOT23LF-2N7002,FET,C7925A  I203  Q1D2
   1 FM_OC_DETECT_EN_N   GATE @BASEBOARD_FAB2_LIB.BASEBOARD_FAB2(SCH_1):FM_OC_DETECT_EN_N
   2    GND    SRC @BASEBOARD_FAB2_LIB.BASEBOARD_FAB2(SCH_1):GND
   3 FM_OC_DETECT_EN    DRN @BASEBOARD_FAB2_LIB.BASEBOARD_FAB2(SCH_1):FM_OC_DETECT_EN

RES_0402-4.75K,1%,1/16W,CHIP,GA  I204  R1D21
   1 P3V3_STBY      A @BASEBOARD_FAB2_LIB.BASEBOARD_FAB2(SCH_1):P3V3_STBY
   2 FM_OC_DETECT_EN      B @BASEBOARD_FAB2_LIB.BASEBOARD_FAB2(SCH_1):FM_OC_DETECT_EN

RES_0402-2.7K,1%,1/16W,CHIP,G2A  I210  R9P4
   1 P3V3_STBY      A @BASEBOARD_FAB2_LIB.BASEBOARD_FAB2(SCH_1):P3V3_STBY
   2 IRQ_UV_DETECT_N      B @BASEBOARD_FAB2_LIB.BASEBOARD_FAB2(SCH_1):IRQ_UV_DETECT_N

DIODE_SMLF-BAT54WS,IC,C73510-0A  I213  CR9P2
   1 FM_UV_ADR_TRIGGER_N      C @BASEBOARD_FAB2_LIB.BASEBOARD_FAB2(SCH_1):FM_UV_ADR_TRIGGER_N
   2 FM_DISABLE_FAN_N      A @BASEBOARD_FAB2_LIB.BASEBOARD_FAB2(SCH_1):FM_DISABLE_FAN_N

DIODE_SMLF-BAT54WS,IC,C73510-0A  I214  CR9P1
   1 IRQ_UV_DETECT_N      C @BASEBOARD_FAB2_LIB.BASEBOARD_FAB2(SCH_1):IRQ_UV_DETECT_N
   2 FM_DISABLE_FAN_N      A @BASEBOARD_FAB2_LIB.BASEBOARD_FAB2(SCH_1):FM_DISABLE_FAN_N

RES_0402-10.0K,1%,1/16W,CHIP,GA  I215  R9P5
   1 P3V3_STBY      A @BASEBOARD_FAB2_LIB.BASEBOARD_FAB2(SCH_1):P3V3_STBY
   2 FM_DISABLE_FAN_N      B @BASEBOARD_FAB2_LIB.BASEBOARD_FAB2(SCH_1):FM_DISABLE_FAN_N

RES_0402-4.99K,1%,1/16W,CHIP,GA  I218  R9P12
   1 A_HSC_INAP      A @BASEBOARD_FAB2_LIB.BASEBOARD_FAB2(SCH_1):A_HSC_INAP
   2 AGND_HSC      B @BASEBOARD_FAB2_LIB.BASEBOARD_FAB2(SCH_1):AGND_HSC

DIODE_SM-MBRS340T3G,EMPTY,C819A  I220  CR1F5
   1 P12V_STBY      C @BASEBOARD_FAB2_LIB.BASEBOARD_FAB2(SCH_1):P12V_STBY
   2    GND      A @BASEBOARD_FAB2_LIB.BASEBOARD_FAB2(SCH_1):GND

RES_0402-100.0K,1%,1/16W,CHIP,A  I222  R9P33
   1 P12V_STBY      A @BASEBOARD_FAB2_LIB.BASEBOARD_FAB2(SCH_1):P12V_STBY
   2 A_HSC_INAP      B @BASEBOARD_FAB2_LIB.BASEBOARD_FAB2(SCH_1):A_HSC_INAP

FET_N_SOT23LF-2N7002,FET,C7925A  I225  Q6W1
   1 UV_HIGH_SET   GATE @BASEBOARD_FAB2_LIB.BASEBOARD_FAB2(SCH_1):UV_HIGH_SET
   2    GND    SRC @BASEBOARD_FAB2_LIB.BASEBOARD_FAB2(SCH_1):GND
   3 UV_HIGH_SET_N    DRN @BASEBOARD_FAB2_LIB.BASEBOARD_FAB2(SCH_1):UV_HIGH_SET_N

SC22P50V2JN-4GP_SMD-BCG-SC22P5A  I235  C9W1
   1 A_P12V_STBY_FP_TRIGGER      1 @BASEBOARD_FAB2_LIB.BASEBOARD_FAB2(SCH_1):A_P12V_STBY_FP_TRIGGER
   2 AGND_HSC      2 @BASEBOARD_FAB2_LIB.BASEBOARD_FAB2(SCH_1):AGND_HSC

SC22P50V2JN-4GP_SMD-BCG-SC22P5A  I236  C9W2
   1 A_P12V_STBY_ADR_TRIGGER      1 @BASEBOARD_FAB2_LIB.BASEBOARD_FAB2(SCH_1):A_P12V_STBY_ADR_TRIGGER
   2 AGND_HSC      2 @BASEBOARD_FAB2_LIB.BASEBOARD_FAB2(SCH_1):AGND_HSC

RES_0402-0.0,5%,1/16W,CHIP,G21A  I243  R9P15
   1 A_HSC_LOW_DRAIN      A @BASEBOARD_FAB2_LIB.BASEBOARD_FAB2(SCH_1):A_HSC_LOW_DRAIN
   2 IRQ_OC_DETECT_N      B @BASEBOARD_FAB2_LIB.BASEBOARD_FAB2(SCH_1):IRQ_OC_DETECT_N

RES_0402-10.0K,1%,1/16W,CHIP,GA  I244  R1D10
   1 P3V3_STBY      A @BASEBOARD_FAB2_LIB.BASEBOARD_FAB2(SCH_1):P3V3_STBY
   2 A_HSC_LOW_GATE      B @BASEBOARD_FAB2_LIB.BASEBOARD_FAB2(SCH_1):A_HSC_LOW_GATE

RES_0402-105.0K,1%,1/16W,CHIP,A  I246  R1D14
   1 A_HSC_CSOUT      A @BASEBOARD_FAB2_LIB.BASEBOARD_FAB2(SCH_1):A_HSC_CSOUT
   2 A_HSC_LOW      B @BASEBOARD_FAB2_LIB.BASEBOARD_FAB2(SCH_1):A_HSC_LOW

270KR2F-GP_RCL_GP-270KR2F-GP,6A  I249  R9P13
   1 P12V_STBY      1 @BASEBOARD_FAB2_LIB.BASEBOARD_FAB2(SCH_1):P12V_STBY
   2 A_P12V_STBY_FP_TRIGGER      2 @BASEBOARD_FAB2_LIB.BASEBOARD_FAB2(SCH_1):A_P12V_STBY_FP_TRIGGER

232KR2F-2-GP_SMD-RG1-232KR2F-2A  I250  R6W3
   1 UV_HIGH_SET_N      1 @BASEBOARD_FAB2_LIB.BASEBOARD_FAB2(SCH_1):UV_HIGH_SET_N
   2 A_P12V_STBY_FP_TRIGGER      2 @BASEBOARD_FAB2_LIB.BASEBOARD_FAB2(SCH_1):A_P12V_STBY_FP_TRIGGER

RES_0402-3.74K,1%,1/16W,CHIP,GA  I251  R9P9
   1 A_P12V_STBY_ADR_TRIGGER      A @BASEBOARD_FAB2_LIB.BASEBOARD_FAB2(SCH_1):A_P12V_STBY_ADR_TRIGGER
   2 AGND_HSC      B @BASEBOARD_FAB2_LIB.BASEBOARD_FAB2(SCH_1):AGND_HSC

RES_0402-100.0K,1%,1/16W,CHIP,A  I252  R9P7
   1 P12V_STBY      A @BASEBOARD_FAB2_LIB.BASEBOARD_FAB2(SCH_1):P12V_STBY
   2 A_P12V_STBY_ADR_TRIGGER      B @BASEBOARD_FAB2_LIB.BASEBOARD_FAB2(SCH_1):A_P12V_STBY_ADR_TRIGGER

RES_0402-200.0K,1%,1/16W,CHIP,A  I253  R1D20
   1 A_HSC_CSOUT      A @BASEBOARD_FAB2_LIB.BASEBOARD_FAB2(SCH_1):A_HSC_CSOUT
   2 A_HSC_HIGH      B @BASEBOARD_FAB2_LIB.BASEBOARD_FAB2(SCH_1):A_HSC_HIGH


DRAWING: @BASEBOARD_FAB2_LIB.BASEBOARD_FAB2(SCH_1):PAGE201 

RES_0402-2.26K,1.0%,1/16W,EMPTA  I22  R4D31
   1 P3V3_STBY      A @BASEBOARD_FAB2_LIB.BASEBOARD_FAB2(SCH_1):P3V3_STBY
   2 PU_VR_PVCCIN_CPU0_IMON      B @BASEBOARD_FAB2_LIB.BASEBOARD_FAB2(SCH_1):PU_VR_PVCCIN_CPU0_IMON

RES_0402-1.00K,1%,1/16W,CHIP,GA  I25  R4D58
   1 P3V3_STBY      A @BASEBOARD_FAB2_LIB.BASEBOARD_FAB2(SCH_1):P3V3_STBY
   2 VR_VRRDY_PVCCIN_CPU0      B @BASEBOARD_FAB2_LIB.BASEBOARD_FAB2(SCH_1):VR_VRRDY_PVCCIN_CPU0

RES_0402-0.0,5%,1/16W,CHIP,G21A  I26  R4D67
   1 SVID_VALERT_VCCIN_CPU0      A @BASEBOARD_FAB2_LIB.BASEBOARD_FAB2(SCH_1):SVID_VALERT_VCCIN_CPU0
   2 SVID_ALERT0_CPU0_R_N      B @BASEBOARD_FAB2_LIB.BASEBOARD_FAB2(SCH_1):SVID_ALERT0_CPU0_R_N

RES_0402-1.00K,1%,1/16W,CHIP,GA  I27  R4E5
   1 P3V3_STBY      A @BASEBOARD_FAB2_LIB.BASEBOARD_FAB2(SCH_1):P3V3_STBY
   2 PWRGD_PVSA_CPU0_R      B @BASEBOARD_FAB2_LIB.BASEBOARD_FAB2(SCH_1):PWRGD_PVSA_CPU0_R

CAP_A_0402V-1.0UF,6.3V,10%,X6SA  I30  C4D25
   1 VR_PVCCIN_CPU0_VD12      A @BASEBOARD_FAB2_LIB.BASEBOARD_FAB2(SCH_1):VR_PVCCIN_CPU0_VD12
   2    GND      B @BASEBOARD_FAB2_LIB.BASEBOARD_FAB2(SCH_1):GND

CAP_A_0402V-0.1UF,16V,10%,X7R,A  I32  C4D26
   1 VR_PVCCIN_CPU0_VD12      A @BASEBOARD_FAB2_LIB.BASEBOARD_FAB2(SCH_1):VR_PVCCIN_CPU0_VD12
   2    GND      B @BASEBOARD_FAB2_LIB.BASEBOARD_FAB2(SCH_1):GND

CAP_A_0402V-1.0UF,6.3V,10%,X6SA  I37  C4D15
   1 VR_PVCCIN_CPU0_VDD      A @BASEBOARD_FAB2_LIB.BASEBOARD_FAB2(SCH_1):VR_PVCCIN_CPU0_VDD
   2    GND      B @BASEBOARD_FAB2_LIB.BASEBOARD_FAB2(SCH_1):GND

CAP_A_0402V-0.1UF,16V,10%,X7R,A  I39  C4D19
   1 VR_PVCCIN_CPU0_VDD      A @BASEBOARD_FAB2_LIB.BASEBOARD_FAB2(SCH_1):VR_PVCCIN_CPU0_VDD
   2    GND      B @BASEBOARD_FAB2_LIB.BASEBOARD_FAB2(SCH_1):GND

RES_0402-0.0,5%,1/16W,CHIP,G21A  I40  R4D26
   1 P3V3_STBY      A @BASEBOARD_FAB2_LIB.BASEBOARD_FAB2(SCH_1):P3V3_STBY
   2 VR_PVCCIN_CPU0_VDD      B @BASEBOARD_FAB2_LIB.BASEBOARD_FAB2(SCH_1):VR_PVCCIN_CPU0_VDD

RES_0402-100.0K,1%,1/16W,CHIP,B  I54  R4D27
   1 VR_FET_SW_P12V_STBY_PVCCIN_CPU0      A @BASEBOARD_FAB2_LIB.BASEBOARD_FAB2(SCH_1):VR_FET_SW_P12V_STBY_PVCCIN_CPU0
   2 VR_PVCCIN_CPU0_AVINSEN      B @BASEBOARD_FAB2_LIB.BASEBOARD_FAB2(SCH_1):VR_PVCCIN_CPU0_AVINSEN

RES_0402-1.5K,1%,1/16W,CHIP,G2A  I55  R4D32
   1 VR_PVCCIN_CPU0_AVINSEN      A @BASEBOARD_FAB2_LIB.BASEBOARD_FAB2(SCH_1):VR_PVCCIN_CPU0_AVINSEN
   2    GND      B @BASEBOARD_FAB2_LIB.BASEBOARD_FAB2(SCH_1):GND

RES_0402-150.0,1%,1/16W,CHIP,GA  I56  R4E6
   1 SVID_CLK0_CPU0_R      A @BASEBOARD_FAB2_LIB.BASEBOARD_FAB2(SCH_1):SVID_CLK0_CPU0_R
   2 SVID_VCLK_PVCCIN_CPU0      B @BASEBOARD_FAB2_LIB.BASEBOARD_FAB2(SCH_1):SVID_VCLK_PVCCIN_CPU0

CAP_0402LF-220PF,50V,10%,X7R,AA  I64  C4D29
   1 VSENSE_PVSA_CPU0_BVSP      A @BASEBOARD_FAB2_LIB.BASEBOARD_FAB2(SCH_1):VSENSE_PVSA_CPU0_BVSP
   2 VSENSE_PVSA_CPU0_N      B @BASEBOARD_FAB2_LIB.BASEBOARD_FAB2(SCH_1):VSENSE_PVSA_CPU0_N

CAP_0402LF-220PF,50V,10%,X7R,AA  I66  C4D17
   1 A_TSENSE_PVCCIN_CPU0      A @BASEBOARD_FAB2_LIB.BASEBOARD_FAB2(SCH_1):A_TSENSE_PVCCIN_CPU0
   2    GND      B @BASEBOARD_FAB2_LIB.BASEBOARD_FAB2(SCH_1):GND

CAP_0402LF-220PF,50V,10%,X7R,AA  I68  C4D18
   1 A_TSENSE_PVSA_CPU0      A @BASEBOARD_FAB2_LIB.BASEBOARD_FAB2(SCH_1):A_TSENSE_PVSA_CPU0
   2    GND      B @BASEBOARD_FAB2_LIB.BASEBOARD_FAB2(SCH_1):GND

CAP_0402LF-220PF,50V,10%,X7R,AA  I70  C4D45
   1 VSENSE_PVCCIN_CPU0_AVSP      A @BASEBOARD_FAB2_LIB.BASEBOARD_FAB2(SCH_1):VSENSE_PVCCIN_CPU0_AVSP
   2 VSENSE_PVCCIN_CPU0_N      B @BASEBOARD_FAB2_LIB.BASEBOARD_FAB2(SCH_1):VSENSE_PVCCIN_CPU0_N

RES_0402-0.0,5%,1/16W,CHIP,G21A  I98  R4D66
   1 SVID_VDIO_PVCCIN_CPU0      A @BASEBOARD_FAB2_LIB.BASEBOARD_FAB2(SCH_1):SVID_VDIO_PVCCIN_CPU0
   2 SVID_DIO0_CPU0_R      B @BASEBOARD_FAB2_LIB.BASEBOARD_FAB2(SCH_1):SVID_DIO0_CPU0_R

RES_0402-2.0K,1%,1/16W,EMPTY,GA  I102  R6P32
   1 P3V3_STBY      A @BASEBOARD_FAB2_LIB.BASEBOARD_FAB2(SCH_1):P3V3_STBY
   2 SMB_VR_STBY_LVC3_SDA      B @BASEBOARD_FAB2_LIB.BASEBOARD_FAB2(SCH_1):SMB_VR_STBY_LVC3_SDA

RES_0402-2.0K,1%,1/16W,EMPTY,GA  I103  R6P37
   1 P3V3_STBY      A @BASEBOARD_FAB2_LIB.BASEBOARD_FAB2(SCH_1):P3V3_STBY
   2 SMB_VR_STBY_LVC3_SCL      B @BASEBOARD_FAB2_LIB.BASEBOARD_FAB2(SCH_1):SMB_VR_STBY_LVC3_SCL

RES_0402-10.0,1%,1/16W,CHIP,G2A  I109  R4E8
   1 VSENSE_PVCCIN_CPU0_P      A @BASEBOARD_FAB2_LIB.BASEBOARD_FAB2(SCH_1):VSENSE_PVCCIN_CPU0_P
   2 VSENSE_PVCCIN_CPU0_AVSP      B @BASEBOARD_FAB2_LIB.BASEBOARD_FAB2(SCH_1):VSENSE_PVCCIN_CPU0_AVSP

RES_0402-10.0,1%,1/16W,CHIP,G2A  I110  R4D39
   1 VSENSE_PVSA_CPU0_P      A @BASEBOARD_FAB2_LIB.BASEBOARD_FAB2(SCH_1):VSENSE_PVSA_CPU0_P
   2 VSENSE_PVSA_CPU0_BVSP      B @BASEBOARD_FAB2_LIB.BASEBOARD_FAB2(SCH_1):VSENSE_PVSA_CPU0_BVSP

RES_0402-1.00K,1%,1/16W,CHIP,GA  I111  R4E3
   1 P3V3_STBY      A @BASEBOARD_FAB2_LIB.BASEBOARD_FAB2(SCH_1):P3V3_STBY
   2 IRQ_PVCCIN_CPU0_VRHOT_LVC3_R_N      B @BASEBOARD_FAB2_LIB.BASEBOARD_FAB2(SCH_1):IRQ_PVCCIN_CPU0_VRHOT_LVC3_R_N

RES_0402-2.26K,1.0%,1/16W,EMPTA  I116  R4E20
   1 P3V3_STBY      A @BASEBOARD_FAB2_LIB.BASEBOARD_FAB2(SCH_1):P3V3_STBY
   2 PU_VR_PVCCIN_CPU0_FLT1_SMBALT_N      B @BASEBOARD_FAB2_LIB.BASEBOARD_FAB2(SCH_1):PU_VR_PVCCIN_CPU0_FLT1_SMBALT_N_IMON

RES_0402-4.02K,1%,1/16W,CHIP,GA  I120  R6P27
   1 VR_PVCCIN_CPU0_XADDR2      A @BASEBOARD_FAB2_LIB.BASEBOARD_FAB2(SCH_1):VR_PVCCIN_CPU0_XADDR2
   2    GND      B @BASEBOARD_FAB2_LIB.BASEBOARD_FAB2(SCH_1):GND

RES_0402-4.02K,1%,1/16W,CHIP,GA  I121  R6P28
   1 VR_PVCCIN_CPU0_XADDR1      A @BASEBOARD_FAB2_LIB.BASEBOARD_FAB2(SCH_1):VR_PVCCIN_CPU0_XADDR1
   2    GND      B @BASEBOARD_FAB2_LIB.BASEBOARD_FAB2(SCH_1):GND

RES_0402-22.1,1.0%,1/16W,CHIP,A  I124  R4D63
   1 VR_VRRDY_PVCCIN_CPU0      A @BASEBOARD_FAB2_LIB.BASEBOARD_FAB2(SCH_1):VR_VRRDY_PVCCIN_CPU0
   2 PWRGD_PVCCIN_CPU0      B @BASEBOARD_FAB2_LIB.BASEBOARD_FAB2(SCH_1):PWRGD_PVCCIN_CPU0

CAP_0402LF-1000PF,50V,10%,X7R,A  I125  C4D42
   1 VR_VRRDY_PVCCIN_CPU0      A @BASEBOARD_FAB2_LIB.BASEBOARD_FAB2(SCH_1):VR_VRRDY_PVCCIN_CPU0
   2    GND      B @BASEBOARD_FAB2_LIB.BASEBOARD_FAB2(SCH_1):GND

RES_0402-33.2,1%,1/16W,CHIP,G2A  I127  R4D65
   1 PWRGD_PVSA_CPU0_R      A @BASEBOARD_FAB2_LIB.BASEBOARD_FAB2(SCH_1):PWRGD_PVSA_CPU0_R
   2 PWRGD_PVSA_CPU0      B @BASEBOARD_FAB2_LIB.BASEBOARD_FAB2(SCH_1):PWRGD_PVSA_CPU0

RES_0402-33.2,1%,1/16W,CHIP,G2A  I128  R6P45
   1 IRQ_PVCCIN_CPU0_VRHOT_LVC3_R_N      A @BASEBOARD_FAB2_LIB.BASEBOARD_FAB2(SCH_1):IRQ_PVCCIN_CPU0_VRHOT_LVC3_R_N
   2 IRQ_PVCCIN_CPU0_VRHOT_LVC3_N      B @BASEBOARD_FAB2_LIB.BASEBOARD_FAB2(SCH_1):IRQ_PVCCIN_CPU0_VRHOT_LVC3_N

RES_0402-0.0,5%,1/16W,CHIP,G21A  I131  R6P18
   1 FM_PVCCIN_PVCCSA_CPU0_EN_LVC1      A @BASEBOARD_FAB2_LIB.BASEBOARD_FAB2(SCH_1):FM_PVCCIN_PVCCSA_CPU0_EN_LVC1
   2 VR_PVCCIN_CPU0_VREN      B @BASEBOARD_FAB2_LIB.BASEBOARD_FAB2(SCH_1):VR_PVCCIN_CPU0_VREN

RES_0402-1.00K,1%,1/16W,CHIP,GA  I132  R6P16
   1 PVCCIO_CPU0      A @BASEBOARD_FAB2_LIB.BASEBOARD_FAB2(SCH_1):PVCCIO_CPU0
   2 VR_PVCCIN_CPU0_VREN      B @BASEBOARD_FAB2_LIB.BASEBOARD_FAB2(SCH_1):VR_PVCCIN_CPU0_VREN

PXE1610B_QFN-IC,H79206-001  I155  EU4D4
   1 VR_PVSA_CPU0_PWM  BPWM1 @BASEBOARD_FAB2_LIB.BASEBOARD_FAB2(SCH_1):VR_PVSA_CPU0_PWM
   2     NC  APWM6     NC
   3 VR_PVCCIN_CPU0_PWM5  APWM5 @BASEBOARD_FAB2_LIB.BASEBOARD_FAB2(SCH_1):VR_PVCCIN_CPU0_PWM5
   4 VR_PVCCIN_CPU0_PWM4  APWM4 @BASEBOARD_FAB2_LIB.BASEBOARD_FAB2(SCH_1):VR_PVCCIN_CPU0_PWM4
   5 VR_PVCCIN_CPU0_PWM3  APWM3 @BASEBOARD_FAB2_LIB.BASEBOARD_FAB2(SCH_1):VR_PVCCIN_CPU0_PWM3
   6 VR_PVCCIN_CPU0_PWM2  APWM2 @BASEBOARD_FAB2_LIB.BASEBOARD_FAB2(SCH_1):VR_PVCCIN_CPU0_PWM2
   7 VR_PVCCIN_CPU0_PWM1  APWM1 @BASEBOARD_FAB2_LIB.BASEBOARD_FAB2(SCH_1):VR_PVCCIN_CPU0_PWM1
   8 SMB_VR_STBY_LVC3_SDA    SDA @BASEBOARD_FAB2_LIB.BASEBOARD_FAB2(SCH_1):SMB_VR_STBY_LVC3_SDA
   9 SMB_VR_STBY_LVC3_SCL    SCL @BASEBOARD_FAB2_LIB.BASEBOARD_FAB2(SCH_1):SMB_VR_STBY_LVC3_SCL
  10     NC RESET_N     NC
  11 VR_VRRDY_PVCCIN_CPU0 AVRRDY @BASEBOARD_FAB2_LIB.BASEBOARD_FAB2(SCH_1):VR_VRRDY_PVCCIN_CPU0
  12 VR_PVCCIN_CPU0_VREN  AVREN @BASEBOARD_FAB2_LIB.BASEBOARD_FAB2(SCH_1):VR_PVCCIN_CPU0_VREN
  13 IRQ_PVCCIN_CPU0_VRHOT_LVC3_R_N VRHOT_N @BASEBOARD_FAB2_LIB.BASEBOARD_FAB2(SCH_1):IRQ_PVCCIN_CPU0_VRHOT_LVC3_R_N
  14 FM_PVCCIN_CPU0_PWR_IN_ALERT_N PINALRT_N @BASEBOARD_FAB2_LIB.BASEBOARD_FAB2(SCH_1):FM_PVCCIN_CPU0_PWR_IN_ALERT_N
  15 PWRGD_PVSA_CPU0_R    MP0 @BASEBOARD_FAB2_LIB.BASEBOARD_FAB2(SCH_1):PWRGD_PVSA_CPU0_R
  16     NC    MP1     NC
  17 SVID_VCLK_PVCCIN_CPU0   VCLK @BASEBOARD_FAB2_LIB.BASEBOARD_FAB2(SCH_1):SVID_VCLK_PVCCIN_CPU0
  18 SVID_VDIO_PVCCIN_CPU0   VDIO @BASEBOARD_FAB2_LIB.BASEBOARD_FAB2(SCH_1):SVID_VDIO_PVCCIN_CPU0
  19 SVID_VALERT_VCCIN_CPU0 VALRT_N @BASEBOARD_FAB2_LIB.BASEBOARD_FAB2(SCH_1):SVID_VALERT_VCCIN_CPU0
  20 PU_VR_PVCCIN_CPU0_FLT1_SMBALT_N    MP2 @BASEBOARD_FAB2_LIB.BASEBOARD_FAB2(SCH_1):PU_VR_PVCCIN_CPU0_FLT1_SMBALT_N_IMON
  21 VSENSE_PVCCIN_CPU0_AVSP  AVSEN @BASEBOARD_FAB2_LIB.BASEBOARD_FAB2(SCH_1):VSENSE_PVCCIN_CPU0_AVSP
  22 VSENSE_PVCCIN_CPU0_N  AVREF @BASEBOARD_FAB2_LIB.BASEBOARD_FAB2(SCH_1):VSENSE_PVCCIN_CPU0_N
  23 VR_PVCCIN_CPU0_AIREF1 AIREF1 @BASEBOARD_FAB2_LIB.BASEBOARD_FAB2(SCH_1):VR_PVCCIN_CPU0_AIREF1
  24 ISENSE_PVCCIN_CPU0_PH1_IMON AISEN1 @BASEBOARD_FAB2_LIB.BASEBOARD_FAB2(SCH_1):ISENSE_PVCCIN_CPU0_PH1_IMON
  25 VR_PVCCIN_CPU0_AIREF2 AIREF2 @BASEBOARD_FAB2_LIB.BASEBOARD_FAB2(SCH_1):VR_PVCCIN_CPU0_AIREF2
  26 ISENSE_PVCCIN_CPU0_PH2_IMON AISEN2 @BASEBOARD_FAB2_LIB.BASEBOARD_FAB2(SCH_1):ISENSE_PVCCIN_CPU0_PH2_IMON
  27 VR_PVCCIN_CPU0_AIREF3 AIREF3 @BASEBOARD_FAB2_LIB.BASEBOARD_FAB2(SCH_1):VR_PVCCIN_CPU0_AIREF3
  28 ISENSE_PVCCIN_CPU0_PH3_IMON AISEN3 @BASEBOARD_FAB2_LIB.BASEBOARD_FAB2(SCH_1):ISENSE_PVCCIN_CPU0_PH3_IMON
  29 VR_PVCCIN_CPU0_AIREF4 AIREF4 @BASEBOARD_FAB2_LIB.BASEBOARD_FAB2(SCH_1):VR_PVCCIN_CPU0_AIREF4
  30 ISENSE_PVCCIN_CPU0_PH4_IMON AISEN4 @BASEBOARD_FAB2_LIB.BASEBOARD_FAB2(SCH_1):ISENSE_PVCCIN_CPU0_PH4_IMON
  31 VR_PVCCIN_CPU0_AIREF5 AIREF5 @BASEBOARD_FAB2_LIB.BASEBOARD_FAB2(SCH_1):VR_PVCCIN_CPU0_AIREF5
  32 ISENSE_PVCCIN_CPU0_PH5_IMON AISEN5 @BASEBOARD_FAB2_LIB.BASEBOARD_FAB2(SCH_1):ISENSE_PVCCIN_CPU0_PH5_IMON
  33     NC AIREF6     NC
  34     NC AISEN6     NC
  35 VSENSE_PVSA_CPU0_BVSP  BVSEN @BASEBOARD_FAB2_LIB.BASEBOARD_FAB2(SCH_1):VSENSE_PVSA_CPU0_BVSP
  36 VSENSE_PVSA_CPU0_N  BVREF @BASEBOARD_FAB2_LIB.BASEBOARD_FAB2(SCH_1):VSENSE_PVSA_CPU0_N
  37 VR_PVSA_CPU0_BIREF1 BIREF1 @BASEBOARD_FAB2_LIB.BASEBOARD_FAB2(SCH_1):VR_PVSA_CPU0_BIREF1
  38 ISENSE_PVSA_CPU0_IMON BISEN1 @BASEBOARD_FAB2_LIB.BASEBOARD_FAB2(SCH_1):ISENSE_PVSA_CPU0_IMON
  39 PU_VR_PVCCIN_CPU0_IMON    MP3 @BASEBOARD_FAB2_LIB.BASEBOARD_FAB2(SCH_1):PU_VR_PVCCIN_CPU0_IMON
  40     NC    MP4     NC
  41 VR_PVCCIN_CPU0_XADDR2 XADDR2 @BASEBOARD_FAB2_LIB.BASEBOARD_FAB2(SCH_1):VR_PVCCIN_CPU0_XADDR2
  42 A_TSENSE_PVSA_CPU0  BTSEN @BASEBOARD_FAB2_LIB.BASEBOARD_FAB2(SCH_1):A_TSENSE_PVSA_CPU0
  43 A_TSENSE_PVCCIN_CPU0  ATSEN @BASEBOARD_FAB2_LIB.BASEBOARD_FAB2(SCH_1):A_TSENSE_PVCCIN_CPU0
  44 VR_PVCCIN_CPU0_XADDR1 XADDR1 @BASEBOARD_FAB2_LIB.BASEBOARD_FAB2(SCH_1):VR_PVCCIN_CPU0_XADDR1
  45 VR_PVCCIN_CPU0_AVINSEN VINSEN @BASEBOARD_FAB2_LIB.BASEBOARD_FAB2(SCH_1):VR_PVCCIN_CPU0_AVINSEN
  46     NC IINSEN     NC
  47 VR_PVCCIN_CPU0_VDD    VDD @BASEBOARD_FAB2_LIB.BASEBOARD_FAB2(SCH_1):VR_PVCCIN_CPU0_VDD
  48 VR_PVCCIN_CPU0_VD12   VD12 @BASEBOARD_FAB2_LIB.BASEBOARD_FAB2(SCH_1):VR_PVCCIN_CPU0_VD12
  49    GND  THPAD @BASEBOARD_FAB2_LIB.BASEBOARD_FAB2(SCH_1):GND

SC22P50V2JN-4GP_SMD-BCG-SC22P5A  I168  CF1
   1 VR_PVCCIN_CPU0_AIREF1      1 @BASEBOARD_FAB2_LIB.BASEBOARD_FAB2(SCH_1):VR_PVCCIN_CPU0_AIREF1
   2 ISENSE_PVCCIN_CPU0_PH1_IMON      2 @BASEBOARD_FAB2_LIB.BASEBOARD_FAB2(SCH_1):ISENSE_PVCCIN_CPU0_PH1_IMON

SC22P50V2JN-4GP_SMD-BCG-SC22P5A  I169  CF2
   1 VR_PVCCIN_CPU0_AIREF2      1 @BASEBOARD_FAB2_LIB.BASEBOARD_FAB2(SCH_1):VR_PVCCIN_CPU0_AIREF2
   2 ISENSE_PVCCIN_CPU0_PH2_IMON      2 @BASEBOARD_FAB2_LIB.BASEBOARD_FAB2(SCH_1):ISENSE_PVCCIN_CPU0_PH2_IMON

SC22P50V2JN-4GP_SMD-BCG-SC22P5A  I170  CF3
   1 VR_PVCCIN_CPU0_AIREF3      1 @BASEBOARD_FAB2_LIB.BASEBOARD_FAB2(SCH_1):VR_PVCCIN_CPU0_AIREF3
   2 ISENSE_PVCCIN_CPU0_PH3_IMON      2 @BASEBOARD_FAB2_LIB.BASEBOARD_FAB2(SCH_1):ISENSE_PVCCIN_CPU0_PH3_IMON

SC22P50V2JN-4GP_SMD-BCG-SC22P5A  I171  CF4
   1 VR_PVCCIN_CPU0_AIREF4      1 @BASEBOARD_FAB2_LIB.BASEBOARD_FAB2(SCH_1):VR_PVCCIN_CPU0_AIREF4
   2 ISENSE_PVCCIN_CPU0_PH4_IMON      2 @BASEBOARD_FAB2_LIB.BASEBOARD_FAB2(SCH_1):ISENSE_PVCCIN_CPU0_PH4_IMON

SC22P50V2JN-4GP_SMD-BCG-SC22P5A  I172  CF5
   1 VR_PVCCIN_CPU0_AIREF5      1 @BASEBOARD_FAB2_LIB.BASEBOARD_FAB2(SCH_1):VR_PVCCIN_CPU0_AIREF5
   2 ISENSE_PVCCIN_CPU0_PH5_IMON      2 @BASEBOARD_FAB2_LIB.BASEBOARD_FAB2(SCH_1):ISENSE_PVCCIN_CPU0_PH5_IMON

SC22P50V2JN-4GP_SMD-BCG-SC22P5A  I173  CF6
   1 VR_PVSA_CPU0_BIREF1      1 @BASEBOARD_FAB2_LIB.BASEBOARD_FAB2(SCH_1):VR_PVSA_CPU0_BIREF1
   2 ISENSE_PVSA_CPU0_IMON      2 @BASEBOARD_FAB2_LIB.BASEBOARD_FAB2(SCH_1):ISENSE_PVSA_CPU0_IMON

RES_0402-1.0K,0.1%,1/16W,CHIP,A  I180  RF6
   1 VR_PVSA_CPU0_BIREF1      A @BASEBOARD_FAB2_LIB.BASEBOARD_FAB2(SCH_1):VR_PVSA_CPU0_BIREF1
   2 ISENSE_PVSA_CPU0_IMON      B @BASEBOARD_FAB2_LIB.BASEBOARD_FAB2(SCH_1):ISENSE_PVSA_CPU0_IMON

RES_0402-1.0K,0.1%,1/16W,CHIP,A  I182  RF1
   1 VR_PVCCIN_CPU0_AIREF1      A @BASEBOARD_FAB2_LIB.BASEBOARD_FAB2(SCH_1):VR_PVCCIN_CPU0_AIREF1
   2 ISENSE_PVCCIN_CPU0_PH1_IMON      B @BASEBOARD_FAB2_LIB.BASEBOARD_FAB2(SCH_1):ISENSE_PVCCIN_CPU0_PH1_IMON

RES_0402-1.0K,0.1%,1/16W,CHIP,A  I183  RF2
   1 VR_PVCCIN_CPU0_AIREF2      A @BASEBOARD_FAB2_LIB.BASEBOARD_FAB2(SCH_1):VR_PVCCIN_CPU0_AIREF2
   2 ISENSE_PVCCIN_CPU0_PH2_IMON      B @BASEBOARD_FAB2_LIB.BASEBOARD_FAB2(SCH_1):ISENSE_PVCCIN_CPU0_PH2_IMON

RES_0402-1.0K,0.1%,1/16W,CHIP,A  I184  RF3
   1 VR_PVCCIN_CPU0_AIREF3      A @BASEBOARD_FAB2_LIB.BASEBOARD_FAB2(SCH_1):VR_PVCCIN_CPU0_AIREF3
   2 ISENSE_PVCCIN_CPU0_PH3_IMON      B @BASEBOARD_FAB2_LIB.BASEBOARD_FAB2(SCH_1):ISENSE_PVCCIN_CPU0_PH3_IMON

RES_0402-1.0K,0.1%,1/16W,CHIP,A  I185  RF4
   1 VR_PVCCIN_CPU0_AIREF4      A @BASEBOARD_FAB2_LIB.BASEBOARD_FAB2(SCH_1):VR_PVCCIN_CPU0_AIREF4
   2 ISENSE_PVCCIN_CPU0_PH4_IMON      B @BASEBOARD_FAB2_LIB.BASEBOARD_FAB2(SCH_1):ISENSE_PVCCIN_CPU0_PH4_IMON

RES_0402-1.0K,0.1%,1/16W,CHIP,A  I186  RF5
   1 VR_PVCCIN_CPU0_AIREF5      A @BASEBOARD_FAB2_LIB.BASEBOARD_FAB2(SCH_1):VR_PVCCIN_CPU0_AIREF5
   2 ISENSE_PVCCIN_CPU0_PH5_IMON      B @BASEBOARD_FAB2_LIB.BASEBOARD_FAB2(SCH_1):ISENSE_PVCCIN_CPU0_PH5_IMON

RES_0402-1.00K,1%,1/16W,CHIP,GA  I187  R4E4
   1 P3V3_STBY      A @BASEBOARD_FAB2_LIB.BASEBOARD_FAB2(SCH_1):P3V3_STBY
   2 FM_PVCCIN_CPU0_PWR_IN_ALERT_N      B @BASEBOARD_FAB2_LIB.BASEBOARD_FAB2(SCH_1):FM_PVCCIN_CPU0_PWR_IN_ALERT_N

RES_0402-49.9,1%,1/16W,EMPTY,GA  I189  R4E9
   1 PVCCIO_CPU0      A @BASEBOARD_FAB2_LIB.BASEBOARD_FAB2(SCH_1):PVCCIO_CPU0
   2 SVID_CLK0_CPU0_R      B @BASEBOARD_FAB2_LIB.BASEBOARD_FAB2(SCH_1):SVID_CLK0_CPU0_R

RES_0402-100.0,1%,1/16W,EMPTY,A  I190  R4E10
   1 PVCCIO_CPU0      A @BASEBOARD_FAB2_LIB.BASEBOARD_FAB2(SCH_1):PVCCIO_CPU0
   2 SVID_DIO0_CPU0_R      B @BASEBOARD_FAB2_LIB.BASEBOARD_FAB2(SCH_1):SVID_DIO0_CPU0_R

PIN-CON3-27-GP_CONN-G7-PIN-CONA  I191  J8D4
   1 SMB_VR_STBY_LVC3_SDA      1 @BASEBOARD_FAB2_LIB.BASEBOARD_FAB2(SCH_1):SMB_VR_STBY_LVC3_SDA
   2    GND      2 @BASEBOARD_FAB2_LIB.BASEBOARD_FAB2(SCH_1):GND
   3 SMB_VR_STBY_LVC3_SCL      3 @BASEBOARD_FAB2_LIB.BASEBOARD_FAB2(SCH_1):SMB_VR_STBY_LVC3_SCL

CAP_A_0402V-0.1UF,16V,10%,X7R,A  I192  C4D20
   1 VR_PVCCIN_CPU0_AVINSEN      A @BASEBOARD_FAB2_LIB.BASEBOARD_FAB2(SCH_1):VR_PVCCIN_CPU0_AVINSEN
   2    GND      B @BASEBOARD_FAB2_LIB.BASEBOARD_FAB2(SCH_1):GND


DRAWING: @BASEBOARD_FAB2_LIB.BASEBOARD_FAB2(SCH_1):PAGE202 

CAP_A_0603V-22.0UF,4V,20%,X6S,A  I9  C6R7
   1 PVCCIN_CPU0      A @BASEBOARD_FAB2_LIB.BASEBOARD_FAB2(SCH_1):PVCCIN_CPU0
   2    GND      B @BASEBOARD_FAB2_LIB.BASEBOARD_FAB2(SCH_1):GND

CAP_0402-0.22UF,16V,10%,X7R,A3A  I18  C4E5
   1 P5V_STBY      A @BASEBOARD_FAB2_LIB.BASEBOARD_FAB2(SCH_1):P5V_STBY
   2    GND      B @BASEBOARD_FAB2_LIB.BASEBOARD_FAB2(SCH_1):GND

CAP_0402-0.220UF,16V,10%,X7R,AA  I22  C4E17
   1 VR_PVCCIN_CPU0_PH1_BOOT      A @BASEBOARD_FAB2_LIB.BASEBOARD_FAB2(SCH_1):VR_PVCCIN_CPU0_PH1_BOOT
   2 VR_PVCCIN_CPU0_PH1_PHASE      B @BASEBOARD_FAB2_LIB.BASEBOARD_FAB2(SCH_1):VR_PVCCIN_CPU0_PH1_PHASE

CAP_0402-0.22UF,16V,10%,X7R,A3A  I24  C4E27
   1 P5V_STBY      A @BASEBOARD_FAB2_LIB.BASEBOARD_FAB2(SCH_1):P5V_STBY
   2    GND      B @BASEBOARD_FAB2_LIB.BASEBOARD_FAB2(SCH_1):GND

CAP_A_0603V-22.0UF,4V,20%,X6S,A  I27  C4E11
   1 PVCCIN_CPU0      A @BASEBOARD_FAB2_LIB.BASEBOARD_FAB2(SCH_1):PVCCIN_CPU0
   2    GND      B @BASEBOARD_FAB2_LIB.BASEBOARD_FAB2(SCH_1):GND

CAP_0402-0.220UF,16V,10%,X7R,AA  I32  C4D50
   1 VR_PVCCIN_CPU0_PH2_BOOT      A @BASEBOARD_FAB2_LIB.BASEBOARD_FAB2(SCH_1):VR_PVCCIN_CPU0_PH2_BOOT
   2 VR_PVCCIN_CPU0_PH2_PHASE      B @BASEBOARD_FAB2_LIB.BASEBOARD_FAB2(SCH_1):VR_PVCCIN_CPU0_PH2_PHASE

CAP_0402-1.0UF,16V,10%,X6S,D97A  I34  C4E10
   1 VR_PVCCIN_CPU0_PH1_VCIN      A @BASEBOARD_FAB2_LIB.BASEBOARD_FAB2(SCH_1):VR_PVCCIN_CPU0_PH1_VCIN
   2    GND      B @BASEBOARD_FAB2_LIB.BASEBOARD_FAB2(SCH_1):GND

CAP_A_0402V-0.1UF,16V,10%,X7R,A  I35  C4E20
   1 VR_FET_SW_P12V_STBY_PVCCIN_CPU0      A @BASEBOARD_FAB2_LIB.BASEBOARD_FAB2(SCH_1):VR_FET_SW_P12V_STBY_PVCCIN_CPU0
   2    GND      B @BASEBOARD_FAB2_LIB.BASEBOARD_FAB2(SCH_1):GND

CAP_0402-1.0UF,16V,10%,X6S,D97A  I36  C4E19
   1 VR_FET_SW_P12V_STBY_PVCCIN_CPU0      A @BASEBOARD_FAB2_LIB.BASEBOARD_FAB2(SCH_1):VR_FET_SW_P12V_STBY_PVCCIN_CPU0
   2    GND      B @BASEBOARD_FAB2_LIB.BASEBOARD_FAB2(SCH_1):GND

CAP_0805-10UF,16V,10%,X6S,C953A  I37  C6R11
   1 VR_FET_SW_P12V_STBY_PVCCIN_CPU0      A @BASEBOARD_FAB2_LIB.BASEBOARD_FAB2(SCH_1):VR_FET_SW_P12V_STBY_PVCCIN_CPU0
   2    GND      B @BASEBOARD_FAB2_LIB.BASEBOARD_FAB2(SCH_1):GND

CAP_0805-10UF,16V,10%,X6S,C953A  I38  C6P13
   1 VR_FET_SW_P12V_STBY_PVCCIN_CPU0      A @BASEBOARD_FAB2_LIB.BASEBOARD_FAB2(SCH_1):VR_FET_SW_P12V_STBY_PVCCIN_CPU0
   2    GND      B @BASEBOARD_FAB2_LIB.BASEBOARD_FAB2(SCH_1):GND

CAP_0805-10UF,16V,10%,X6S,C953A  I42  C6R13
   1 VR_FET_SW_P12V_STBY_PVCCIN_CPU0      A @BASEBOARD_FAB2_LIB.BASEBOARD_FAB2(SCH_1):VR_FET_SW_P12V_STBY_PVCCIN_CPU0
   2    GND      B @BASEBOARD_FAB2_LIB.BASEBOARD_FAB2(SCH_1):GND

CAP_0402-1.0UF,16V,10%,X6S,D97A  I45  C4E26
   1 VR_PVCCIN_CPU0_PH2_VCIN      A @BASEBOARD_FAB2_LIB.BASEBOARD_FAB2(SCH_1):VR_PVCCIN_CPU0_PH2_VCIN
   2    GND      B @BASEBOARD_FAB2_LIB.BASEBOARD_FAB2(SCH_1):GND

CAP_A_0402V-0.1UF,16V,10%,X7R,A  I46  C4D49
   1 VR_FET_SW_P12V_STBY_PVCCIN_CPU0      A @BASEBOARD_FAB2_LIB.BASEBOARD_FAB2(SCH_1):VR_FET_SW_P12V_STBY_PVCCIN_CPU0
   2    GND      B @BASEBOARD_FAB2_LIB.BASEBOARD_FAB2(SCH_1):GND

CAP_0402-1.0UF,16V,10%,X6S,D97A  I47  C4D48
   1 VR_FET_SW_P12V_STBY_PVCCIN_CPU0      A @BASEBOARD_FAB2_LIB.BASEBOARD_FAB2(SCH_1):VR_FET_SW_P12V_STBY_PVCCIN_CPU0
   2    GND      B @BASEBOARD_FAB2_LIB.BASEBOARD_FAB2(SCH_1):GND

CAP_0805-10UF,16V,10%,X6S,C953A  I48  C6R4
   1 VR_FET_SW_P12V_STBY_PVCCIN_CPU0      A @BASEBOARD_FAB2_LIB.BASEBOARD_FAB2(SCH_1):VR_FET_SW_P12V_STBY_PVCCIN_CPU0
   2    GND      B @BASEBOARD_FAB2_LIB.BASEBOARD_FAB2(SCH_1):GND

CAP_0805-10UF,16V,10%,X6S,C953A  I49  C6P22
   1 VR_FET_SW_P12V_STBY_PVCCIN_CPU0      A @BASEBOARD_FAB2_LIB.BASEBOARD_FAB2(SCH_1):VR_FET_SW_P12V_STBY_PVCCIN_CPU0
   2    GND      B @BASEBOARD_FAB2_LIB.BASEBOARD_FAB2(SCH_1):GND

CAP_0805-10UF,16V,10%,X6S,C953A  I51  C6N8
   1 VR_FET_SW_P12V_STBY_PVCCIN_CPU0      A @BASEBOARD_FAB2_LIB.BASEBOARD_FAB2(SCH_1):VR_FET_SW_P12V_STBY_PVCCIN_CPU0
   2    GND      B @BASEBOARD_FAB2_LIB.BASEBOARD_FAB2(SCH_1):GND

CAP_A_0603V-22.0UF,4V,20%,X6S,A  I61  C4E3
   1 PVCCIN_CPU0      A @BASEBOARD_FAB2_LIB.BASEBOARD_FAB2(SCH_1):PVCCIN_CPU0
   2    GND      B @BASEBOARD_FAB2_LIB.BASEBOARD_FAB2(SCH_1):GND

CAP_A_0603V-22.0UF,4V,20%,X6S,A  I62  C6P16
   1 PVCCIN_CPU0      A @BASEBOARD_FAB2_LIB.BASEBOARD_FAB2(SCH_1):PVCCIN_CPU0
   2    GND      B @BASEBOARD_FAB2_LIB.BASEBOARD_FAB2(SCH_1):GND

IR354XX_SM-IR35411,IC,H73688-0A  I63  EU4E1
  33 VR_PVCCIN_CPU0_PH1_BOOT_R  BOOST @BASEBOARD_FAB2_LIB.BASEBOARD_FAB2(SCH_1):VR_PVCCIN_CPU0_PH1_BOOT_R
  35 P5V_STBY     EN @BASEBOARD_FAB2_LIB.BASEBOARD_FAB2(SCH_1):P5V_STBY
  41 TP_PVCCIN_CPU0_PH1_GL_1  GL<1> @BASEBOARD_FAB2_LIB.BASEBOARD_FAB2(SCH_1):TP_PVCCIN_CPU0_PH1_GL_1
   6 TP_PVCCIN_CPU0_PH1_GL_0  GL<0> @BASEBOARD_FAB2_LIB.BASEBOARD_FAB2(SCH_1):TP_PVCCIN_CPU0_PH1_GL_0
  38 ISENSE_PVCCIN_CPU0_PH1_IMON   IOUT @BASEBOARD_FAB2_LIB.BASEBOARD_FAB2(SCH_1):ISENSE_PVCCIN_CPU0_PH1_IMON
   2    GND   LGND @BASEBOARD_FAB2_LIB.BASEBOARD_FAB2(SCH_1):GND
  31     NC     NC     NC
  37 VR_PVCCIN_CPU0_PH1_OCSET  OCSET @BASEBOARD_FAB2_LIB.BASEBOARD_FAB2(SCH_1):VR_PVCCIN_CPU0_PH1_OCSET
  40    GND PGND<2> @BASEBOARD_FAB2_LIB.BASEBOARD_FAB2(SCH_1):GND
   7    GND PGND<1> @BASEBOARD_FAB2_LIB.BASEBOARD_FAB2(SCH_1):GND
   5    GND PGND<0> @BASEBOARD_FAB2_LIB.BASEBOARD_FAB2(SCH_1):GND
  32 VR_PVCCIN_CPU0_PH1_PHASE  PHASE @BASEBOARD_FAB2_LIB.BASEBOARD_FAB2(SCH_1):VR_PVCCIN_CPU0_PH1_PHASE
  34 VR_PVCCIN_CPU0_PWM1    PWM @BASEBOARD_FAB2_LIB.BASEBOARD_FAB2(SCH_1):VR_PVCCIN_CPU0_PWM1
  39 VR_PVCCIN_CPU0_AIREF1  REFIN @BASEBOARD_FAB2_LIB.BASEBOARD_FAB2(SCH_1):VR_PVCCIN_CPU0_AIREF1
  10 VR_PVCCIN_CPU0_PHASE1     SW @BASEBOARD_FAB2_LIB.BASEBOARD_FAB2(SCH_1):VR_PVCCIN_CPU0_PHASE1
  36 A_TSENSE_PVCCIN_CPU0 TOUT_FLT @BASEBOARD_FAB2_LIB.BASEBOARD_FAB2(SCH_1):A_TSENSE_PVCCIN_CPU0
   3 VR_PVCCIN_CPU0_PH1_VCIN    VCC @BASEBOARD_FAB2_LIB.BASEBOARD_FAB2(SCH_1):VR_PVCCIN_CPU0_PH1_VCIN
   4 P5V_STBY   VDRV @BASEBOARD_FAB2_LIB.BASEBOARD_FAB2(SCH_1):P5V_STBY
  30 VR_FET_SW_P12V_STBY_PVCCIN_CPU0 VIN<1> @BASEBOARD_FAB2_LIB.BASEBOARD_FAB2(SCH_1):VR_FET_SW_P12V_STBY_PVCCIN_CPU0
  25 VR_FET_SW_P12V_STBY_PVCCIN_CPU0 VIN<0> @BASEBOARD_FAB2_LIB.BASEBOARD_FAB2(SCH_1):VR_FET_SW_P12V_STBY_PVCCIN_CPU0
   1 PVCCIN_CPU0    VOS @BASEBOARD_FAB2_LIB.BASEBOARD_FAB2(SCH_1):PVCCIN_CPU0

IR354XX_SM-IR35411,IC,H73688-0A  I64  EU4D6
  33 VR_PVCCIN_CPU0_PH2_BOOT_R  BOOST @BASEBOARD_FAB2_LIB.BASEBOARD_FAB2(SCH_1):VR_PVCCIN_CPU0_PH2_BOOT_R
  35 P5V_STBY     EN @BASEBOARD_FAB2_LIB.BASEBOARD_FAB2(SCH_1):P5V_STBY
  41 TP_PVCCIN_CPU0_PH2_GL_1  GL<1> @BASEBOARD_FAB2_LIB.BASEBOARD_FAB2(SCH_1):TP_PVCCIN_CPU0_PH2_GL_1
   6 TP_PVCCIN_CPU0_PH2_GL_0  GL<0> @BASEBOARD_FAB2_LIB.BASEBOARD_FAB2(SCH_1):TP_PVCCIN_CPU0_PH2_GL_0
  38 ISENSE_PVCCIN_CPU0_PH2_IMON   IOUT @BASEBOARD_FAB2_LIB.BASEBOARD_FAB2(SCH_1):ISENSE_PVCCIN_CPU0_PH2_IMON
   2    GND   LGND @BASEBOARD_FAB2_LIB.BASEBOARD_FAB2(SCH_1):GND
  31     NC     NC     NC
  37 VR_PVCCIN_CPU0_PH2_OCSET  OCSET @BASEBOARD_FAB2_LIB.BASEBOARD_FAB2(SCH_1):VR_PVCCIN_CPU0_PH2_OCSET
  40    GND PGND<2> @BASEBOARD_FAB2_LIB.BASEBOARD_FAB2(SCH_1):GND
   7    GND PGND<1> @BASEBOARD_FAB2_LIB.BASEBOARD_FAB2(SCH_1):GND
   5    GND PGND<0> @BASEBOARD_FAB2_LIB.BASEBOARD_FAB2(SCH_1):GND
  32 VR_PVCCIN_CPU0_PH2_PHASE  PHASE @BASEBOARD_FAB2_LIB.BASEBOARD_FAB2(SCH_1):VR_PVCCIN_CPU0_PH2_PHASE
  34 VR_PVCCIN_CPU0_PWM2    PWM @BASEBOARD_FAB2_LIB.BASEBOARD_FAB2(SCH_1):VR_PVCCIN_CPU0_PWM2
  39 VR_PVCCIN_CPU0_AIREF2  REFIN @BASEBOARD_FAB2_LIB.BASEBOARD_FAB2(SCH_1):VR_PVCCIN_CPU0_AIREF2
  10 VR_PVCCIN_CPU0_PHASE2     SW @BASEBOARD_FAB2_LIB.BASEBOARD_FAB2(SCH_1):VR_PVCCIN_CPU0_PHASE2
  36 A_TSENSE_PVCCIN_CPU0 TOUT_FLT @BASEBOARD_FAB2_LIB.BASEBOARD_FAB2(SCH_1):A_TSENSE_PVCCIN_CPU0
   3 VR_PVCCIN_CPU0_PH2_VCIN    VCC @BASEBOARD_FAB2_LIB.BASEBOARD_FAB2(SCH_1):VR_PVCCIN_CPU0_PH2_VCIN
   4 P5V_STBY   VDRV @BASEBOARD_FAB2_LIB.BASEBOARD_FAB2(SCH_1):P5V_STBY
  30 VR_FET_SW_P12V_STBY_PVCCIN_CPU0 VIN<1> @BASEBOARD_FAB2_LIB.BASEBOARD_FAB2(SCH_1):VR_FET_SW_P12V_STBY_PVCCIN_CPU0
  25 VR_FET_SW_P12V_STBY_PVCCIN_CPU0 VIN<0> @BASEBOARD_FAB2_LIB.BASEBOARD_FAB2(SCH_1):VR_FET_SW_P12V_STBY_PVCCIN_CPU0
   1 PVCCIN_CPU0    VOS @BASEBOARD_FAB2_LIB.BASEBOARD_FAB2(SCH_1):PVCCIN_CPU0

RES_0402-68.1K,1%,1/16W,EMPTY,A  I65  R4E22
   1 VR_PVCCIN_CPU0_PH1_OCSET      A @BASEBOARD_FAB2_LIB.BASEBOARD_FAB2(SCH_1):VR_PVCCIN_CPU0_PH1_OCSET
   2    GND      B @BASEBOARD_FAB2_LIB.BASEBOARD_FAB2(SCH_1):GND

RES_0402-68.1K,1%,1/16W,EMPTY,A  I67  R4E19
   1 VR_PVCCIN_CPU0_PH2_OCSET      A @BASEBOARD_FAB2_LIB.BASEBOARD_FAB2(SCH_1):VR_PVCCIN_CPU0_PH2_OCSET
   2    GND      B @BASEBOARD_FAB2_LIB.BASEBOARD_FAB2(SCH_1):GND

CAP_A_0402V-0.1UF,16V,10%,X7R,A  I70  CT1
   1 VR_PVCCIN_CPU0_AIREF1      A @BASEBOARD_FAB2_LIB.BASEBOARD_FAB2(SCH_1):VR_PVCCIN_CPU0_AIREF1
   2    GND      B @BASEBOARD_FAB2_LIB.BASEBOARD_FAB2(SCH_1):GND

CAP_0402LF-1000PF,50V,10%,X7R,A  I78  CT2
   1 A_TSENSE_PVCCIN_CPU0      A @BASEBOARD_FAB2_LIB.BASEBOARD_FAB2(SCH_1):A_TSENSE_PVCCIN_CPU0
   2    GND      B @BASEBOARD_FAB2_LIB.BASEBOARD_FAB2(SCH_1):GND

CAP_A_0402V-0.1UF,16V,10%,X7R,A  I81  CT6
   1 VR_PVCCIN_CPU0_AIREF2      A @BASEBOARD_FAB2_LIB.BASEBOARD_FAB2(SCH_1):VR_PVCCIN_CPU0_AIREF2
   2    GND      B @BASEBOARD_FAB2_LIB.BASEBOARD_FAB2(SCH_1):GND

CAP_0402LF-1000PF,50V,10%,X7R,A  I87  CT4
   1 A_TSENSE_PVCCIN_CPU0      A @BASEBOARD_FAB2_LIB.BASEBOARD_FAB2(SCH_1):A_TSENSE_PVCCIN_CPU0
   2    GND      B @BASEBOARD_FAB2_LIB.BASEBOARD_FAB2(SCH_1):GND

CAP_0402LF-1000PF,50V,10%,X7R,A  I97  CT3
   1 VR_PVCCIN_CPU0_PHASE1      A @BASEBOARD_FAB2_LIB.BASEBOARD_FAB2(SCH_1):VR_PVCCIN_CPU0_PHASE1
   2 VR_PVCCIN_CPU0_PHASE1_RC      B @BASEBOARD_FAB2_LIB.BASEBOARD_FAB2(SCH_1):VR_PVCCIN_CPU0_PHASE1_RC

CAP_0402LF-1000PF,50V,10%,X7R,A  I98  CT5
   1 VR_PVCCIN_CPU0_PHASE2      A @BASEBOARD_FAB2_LIB.BASEBOARD_FAB2(SCH_1):VR_PVCCIN_CPU0_PHASE2
   2 VR_PVCCIN_CPU0_PHASE2_RC      B @BASEBOARD_FAB2_LIB.BASEBOARD_FAB2(SCH_1):VR_PVCCIN_CPU0_PHASE2_RC

RES_0603-0,5.0%,1/10W,CHIP,G22A  I101  RT1
   1 VR_PVCCIN_CPU0_PH1_BOOT      A @BASEBOARD_FAB2_LIB.BASEBOARD_FAB2(SCH_1):VR_PVCCIN_CPU0_PH1_BOOT
   2 VR_PVCCIN_CPU0_PH1_BOOT_R      B @BASEBOARD_FAB2_LIB.BASEBOARD_FAB2(SCH_1):VR_PVCCIN_CPU0_PH1_BOOT_R

RES_0603-0,5.0%,1/10W,CHIP,G22A  I102  RT3
   1 VR_PVCCIN_CPU0_PH2_BOOT      A @BASEBOARD_FAB2_LIB.BASEBOARD_FAB2(SCH_1):VR_PVCCIN_CPU0_PH2_BOOT
   2 VR_PVCCIN_CPU0_PH2_BOOT_R      B @BASEBOARD_FAB2_LIB.BASEBOARD_FAB2(SCH_1):VR_PVCCIN_CPU0_PH2_BOOT_R

RES_0402-0.0,5%,1/16W,CHIP,G21A  I107  R6R2
   1 VR_PVCCIN_CPU0_PH1_VCIN      A @BASEBOARD_FAB2_LIB.BASEBOARD_FAB2(SCH_1):VR_PVCCIN_CPU0_PH1_VCIN
   2 P5V_STBY      B @BASEBOARD_FAB2_LIB.BASEBOARD_FAB2(SCH_1):P5V_STBY

RES_0402-0.0,5%,1/16W,CHIP,G21A  I108  R6R6
   1 VR_PVCCIN_CPU0_PH2_VCIN      A @BASEBOARD_FAB2_LIB.BASEBOARD_FAB2(SCH_1):VR_PVCCIN_CPU0_PH2_VCIN
   2 P5V_STBY      B @BASEBOARD_FAB2_LIB.BASEBOARD_FAB2(SCH_1):P5V_STBY

IND-120NH-30-GP_DISCRET-GB2-INA  I109  L4E1
   1 VR_PVCCIN_CPU0_PHASE1      S @BASEBOARD_FAB2_LIB.BASEBOARD_FAB2(SCH_1):VR_PVCCIN_CPU0_PHASE1
   2 PVCCIN_CPU0      F @BASEBOARD_FAB2_LIB.BASEBOARD_FAB2(SCH_1):PVCCIN_CPU0

IND-120NH-30-GP_DISCRET-GB2-INA  I110  L4D3
   1 VR_PVCCIN_CPU0_PHASE2      S @BASEBOARD_FAB2_LIB.BASEBOARD_FAB2(SCH_1):VR_PVCCIN_CPU0_PHASE2
   2 PVCCIN_CPU0      F @BASEBOARD_FAB2_LIB.BASEBOARD_FAB2(SCH_1):PVCCIN_CPU0

SC1U10V2KX-4-GP_SMD-BCG6-SC1U1A  I111  C4E25
   1 P5V_STBY      1 @BASEBOARD_FAB2_LIB.BASEBOARD_FAB2(SCH_1):P5V_STBY
   2    GND      2 @BASEBOARD_FAB2_LIB.BASEBOARD_FAB2(SCH_1):GND

SC1U10V2KX-4-GP_SMD-BCG6-SC1U1A  I112  C4E6
   1 P5V_STBY      1 @BASEBOARD_FAB2_LIB.BASEBOARD_FAB2(SCH_1):P5V_STBY
   2    GND      2 @BASEBOARD_FAB2_LIB.BASEBOARD_FAB2(SCH_1):GND

1R3F-GP_RCL_GP-1R3F-GP,64.1R00A  I114  RT2
   1 VR_PVCCIN_CPU0_PHASE1_RC      1 @BASEBOARD_FAB2_LIB.BASEBOARD_FAB2(SCH_1):VR_PVCCIN_CPU0_PHASE1_RC
   2    GND      2 @BASEBOARD_FAB2_LIB.BASEBOARD_FAB2(SCH_1):GND

1R3F-GP_RCL_GP-1R3F-GP,64.1R00A  I115  RT4
   1 VR_PVCCIN_CPU0_PHASE2_RC      1 @BASEBOARD_FAB2_LIB.BASEBOARD_FAB2(SCH_1):VR_PVCCIN_CPU0_PHASE2_RC
   2    GND      2 @BASEBOARD_FAB2_LIB.BASEBOARD_FAB2(SCH_1):GND


DRAWING: @BASEBOARD_FAB2_LIB.BASEBOARD_FAB2(SCH_1):PAGE203 

CAP_0805-10UF,16V,10%,X6S,C953A  I1  C6P24
   1 VR_FET_SW_P12V_STBY_PVCCIN_CPU0      A @BASEBOARD_FAB2_LIB.BASEBOARD_FAB2(SCH_1):VR_FET_SW_P12V_STBY_PVCCIN_CPU0
   2    GND      B @BASEBOARD_FAB2_LIB.BASEBOARD_FAB2(SCH_1):GND

CAP_0805-10UF,16V,10%,X6S,C953A  I2  C6R6
   1 VR_FET_SW_P12V_STBY_PVCCIN_CPU0      A @BASEBOARD_FAB2_LIB.BASEBOARD_FAB2(SCH_1):VR_FET_SW_P12V_STBY_PVCCIN_CPU0
   2    GND      B @BASEBOARD_FAB2_LIB.BASEBOARD_FAB2(SCH_1):GND

CAP_0402-0.220UF,16V,10%,X7R,AA  I3  C4D9
   1 VR_PVCCIN_CPU0_PH4_BOOT      A @BASEBOARD_FAB2_LIB.BASEBOARD_FAB2(SCH_1):VR_PVCCIN_CPU0_PH4_BOOT
   2 VR_PVCCIN_CPU0_PH4_PHASE      B @BASEBOARD_FAB2_LIB.BASEBOARD_FAB2(SCH_1):VR_PVCCIN_CPU0_PH4_PHASE

CAPP_3018-470UF,2.5V,20%,ALUM,A  I16  C6R3
   1 PVCCIN_CPU0      A @BASEBOARD_FAB2_LIB.BASEBOARD_FAB2(SCH_1):PVCCIN_CPU0
   2    GND      B @BASEBOARD_FAB2_LIB.BASEBOARD_FAB2(SCH_1):GND

CAPP_3018-470UF,2.5V,20%,ALUM,A  I18  C6R9
   1 PVCCIN_CPU0      A @BASEBOARD_FAB2_LIB.BASEBOARD_FAB2(SCH_1):PVCCIN_CPU0
   2    GND      B @BASEBOARD_FAB2_LIB.BASEBOARD_FAB2(SCH_1):GND

CAP_A_0603V-22.0UF,4V,20%,X6S,A  I25  C6P3
   1 PVCCIN_CPU0      A @BASEBOARD_FAB2_LIB.BASEBOARD_FAB2(SCH_1):PVCCIN_CPU0
   2    GND      B @BASEBOARD_FAB2_LIB.BASEBOARD_FAB2(SCH_1):GND

CAPP_3018-470UF,2.5V,20%,ALUM,A  I28  C6P23
   1 PVCCIN_CPU0      A @BASEBOARD_FAB2_LIB.BASEBOARD_FAB2(SCH_1):PVCCIN_CPU0
   2    GND      B @BASEBOARD_FAB2_LIB.BASEBOARD_FAB2(SCH_1):GND

CAPP_3018-470UF,2.5V,20%,ALUM,A  I29  C6P14
   1 PVCCIN_CPU0      A @BASEBOARD_FAB2_LIB.BASEBOARD_FAB2(SCH_1):PVCCIN_CPU0
   2    GND      B @BASEBOARD_FAB2_LIB.BASEBOARD_FAB2(SCH_1):GND

CAPP_3018-470UF,2.5V,20%,ALUM,A  I30  C6P18
   1 PVCCIN_CPU0      A @BASEBOARD_FAB2_LIB.BASEBOARD_FAB2(SCH_1):PVCCIN_CPU0
   2    GND      B @BASEBOARD_FAB2_LIB.BASEBOARD_FAB2(SCH_1):GND

CAPP_3018-470UF,2.5V,20%,ALUM,A  I32  C6P8
   1 PVCCIN_CPU0      A @BASEBOARD_FAB2_LIB.BASEBOARD_FAB2(SCH_1):PVCCIN_CPU0
   2    GND      B @BASEBOARD_FAB2_LIB.BASEBOARD_FAB2(SCH_1):GND

CAPP_3018-470UF,2.5V,20%,ALUM,A  I34  C6N9
   1 PVCCIN_CPU0      A @BASEBOARD_FAB2_LIB.BASEBOARD_FAB2(SCH_1):PVCCIN_CPU0
   2    GND      B @BASEBOARD_FAB2_LIB.BASEBOARD_FAB2(SCH_1):GND

CAP_0402-0.22UF,16V,10%,X7R,A3A  I40  C4D13
   1 P5V_STBY      A @BASEBOARD_FAB2_LIB.BASEBOARD_FAB2(SCH_1):P5V_STBY
   2    GND      B @BASEBOARD_FAB2_LIB.BASEBOARD_FAB2(SCH_1):GND

CAP_0402-0.220UF,16V,10%,X7R,AA  I42  C4D28
   1 VR_PVCCIN_CPU0_PH3_BOOT      A @BASEBOARD_FAB2_LIB.BASEBOARD_FAB2(SCH_1):VR_PVCCIN_CPU0_PH3_BOOT
   2 VR_PVCCIN_CPU0_PH3_PHASE      B @BASEBOARD_FAB2_LIB.BASEBOARD_FAB2(SCH_1):VR_PVCCIN_CPU0_PH3_PHASE

CAP_0402-1.0UF,16V,10%,X6S,D97A  I45  C4D16
   1 VR_PVCCIN_CPU0_PH3_VCIN      A @BASEBOARD_FAB2_LIB.BASEBOARD_FAB2(SCH_1):VR_PVCCIN_CPU0_PH3_VCIN
   2    GND      B @BASEBOARD_FAB2_LIB.BASEBOARD_FAB2(SCH_1):GND

CAP_A_0402V-0.1UF,16V,10%,X7R,A  I46  C4D35
   1 VR_FET_SW_P12V_STBY_PVCCIN_CPU0      A @BASEBOARD_FAB2_LIB.BASEBOARD_FAB2(SCH_1):VR_FET_SW_P12V_STBY_PVCCIN_CPU0
   2    GND      B @BASEBOARD_FAB2_LIB.BASEBOARD_FAB2(SCH_1):GND

CAP_0402-1.0UF,16V,10%,X6S,D97A  I47  C4D30
   1 VR_FET_SW_P12V_STBY_PVCCIN_CPU0      A @BASEBOARD_FAB2_LIB.BASEBOARD_FAB2(SCH_1):VR_FET_SW_P12V_STBY_PVCCIN_CPU0
   2    GND      B @BASEBOARD_FAB2_LIB.BASEBOARD_FAB2(SCH_1):GND

CAP_0402-0.22UF,16V,10%,X7R,A3A  I48  C4D5
   1 P5V_STBY      A @BASEBOARD_FAB2_LIB.BASEBOARD_FAB2(SCH_1):P5V_STBY
   2    GND      B @BASEBOARD_FAB2_LIB.BASEBOARD_FAB2(SCH_1):GND

CAP_0402-1.0UF,16V,10%,X6S,D97A  I51  C4D7
   1 VR_PVCCIN_CPU0_PH4_VCIN      A @BASEBOARD_FAB2_LIB.BASEBOARD_FAB2(SCH_1):VR_PVCCIN_CPU0_PH4_VCIN
   2    GND      B @BASEBOARD_FAB2_LIB.BASEBOARD_FAB2(SCH_1):GND

CAP_A_0402V-0.1UF,16V,10%,X7R,A  I52  C4D11
   1 VR_FET_SW_P12V_STBY_PVCCIN_CPU0      A @BASEBOARD_FAB2_LIB.BASEBOARD_FAB2(SCH_1):VR_FET_SW_P12V_STBY_PVCCIN_CPU0
   2    GND      B @BASEBOARD_FAB2_LIB.BASEBOARD_FAB2(SCH_1):GND

CAP_0402-1.0UF,16V,10%,X6S,D97A  I53  C4D10
   1 VR_FET_SW_P12V_STBY_PVCCIN_CPU0      A @BASEBOARD_FAB2_LIB.BASEBOARD_FAB2(SCH_1):VR_FET_SW_P12V_STBY_PVCCIN_CPU0
   2    GND      B @BASEBOARD_FAB2_LIB.BASEBOARD_FAB2(SCH_1):GND

CAP_0805-10UF,16V,10%,X6S,C953A  I54  C6P19
   1 VR_FET_SW_P12V_STBY_PVCCIN_CPU0      A @BASEBOARD_FAB2_LIB.BASEBOARD_FAB2(SCH_1):VR_FET_SW_P12V_STBY_PVCCIN_CPU0
   2    GND      B @BASEBOARD_FAB2_LIB.BASEBOARD_FAB2(SCH_1):GND

CAP_0805-10UF,16V,10%,X6S,C953A  I57  C6P20
   1 VR_FET_SW_P12V_STBY_PVCCIN_CPU0      A @BASEBOARD_FAB2_LIB.BASEBOARD_FAB2(SCH_1):VR_FET_SW_P12V_STBY_PVCCIN_CPU0
   2    GND      B @BASEBOARD_FAB2_LIB.BASEBOARD_FAB2(SCH_1):GND

CAP_0805-10UF,16V,10%,X6S,C953A  I58  C6P15
   1 VR_FET_SW_P12V_STBY_PVCCIN_CPU0      A @BASEBOARD_FAB2_LIB.BASEBOARD_FAB2(SCH_1):VR_FET_SW_P12V_STBY_PVCCIN_CPU0
   2    GND      B @BASEBOARD_FAB2_LIB.BASEBOARD_FAB2(SCH_1):GND

CAP_0805-10UF,16V,10%,X6S,C953A  I59  C6P7
   1 VR_FET_SW_P12V_STBY_PVCCIN_CPU0      A @BASEBOARD_FAB2_LIB.BASEBOARD_FAB2(SCH_1):VR_FET_SW_P12V_STBY_PVCCIN_CPU0
   2    GND      B @BASEBOARD_FAB2_LIB.BASEBOARD_FAB2(SCH_1):GND

CAP_A_0603V-22.0UF,4V,20%,X6S,A  I66  C6P21
   1 PVCCIN_CPU0      A @BASEBOARD_FAB2_LIB.BASEBOARD_FAB2(SCH_1):PVCCIN_CPU0
   2    GND      B @BASEBOARD_FAB2_LIB.BASEBOARD_FAB2(SCH_1):GND

RES_0603-100.0,1%,1/10W,CHIP,GA  I67  R4E13
   1 PVCCIN_CPU0      A @BASEBOARD_FAB2_LIB.BASEBOARD_FAB2(SCH_1):PVCCIN_CPU0
   2    GND      B @BASEBOARD_FAB2_LIB.BASEBOARD_FAB2(SCH_1):GND

CAP_A_0603V-22.0UF,4V,20%,X6S,A  I68  C4D34
   1 PVCCIN_CPU0      A @BASEBOARD_FAB2_LIB.BASEBOARD_FAB2(SCH_1):PVCCIN_CPU0
   2    GND      B @BASEBOARD_FAB2_LIB.BASEBOARD_FAB2(SCH_1):GND

CAP_A_0603V-22.0UF,4V,20%,X6S,A  I69  C4D4
   1 PVCCIN_CPU0      A @BASEBOARD_FAB2_LIB.BASEBOARD_FAB2(SCH_1):PVCCIN_CPU0
   2    GND      B @BASEBOARD_FAB2_LIB.BASEBOARD_FAB2(SCH_1):GND

IR354XX_SM-IR35411,IC,H73688-0A  I70  EU4D3
  33 VR_PVCCIN_CPU0_PH3_BOOT_R  BOOST @BASEBOARD_FAB2_LIB.BASEBOARD_FAB2(SCH_1):VR_PVCCIN_CPU0_PH3_BOOT_R
  35 P5V_STBY     EN @BASEBOARD_FAB2_LIB.BASEBOARD_FAB2(SCH_1):P5V_STBY
  41 TP_PVCCIN_CPU0_PH3_GL_1  GL<1> @BASEBOARD_FAB2_LIB.BASEBOARD_FAB2(SCH_1):TP_PVCCIN_CPU0_PH3_GL_1
   6 TP_PVCCIN_CPU0_PH3_GL_0  GL<0> @BASEBOARD_FAB2_LIB.BASEBOARD_FAB2(SCH_1):TP_PVCCIN_CPU0_PH3_GL_0
  38 ISENSE_PVCCIN_CPU0_PH3_IMON   IOUT @BASEBOARD_FAB2_LIB.BASEBOARD_FAB2(SCH_1):ISENSE_PVCCIN_CPU0_PH3_IMON
   2    GND   LGND @BASEBOARD_FAB2_LIB.BASEBOARD_FAB2(SCH_1):GND
  31     NC     NC     NC
  37 VR_PVCCIN_CPU0_PH3_OCSET  OCSET @BASEBOARD_FAB2_LIB.BASEBOARD_FAB2(SCH_1):VR_PVCCIN_CPU0_PH3_OCSET
  40    GND PGND<2> @BASEBOARD_FAB2_LIB.BASEBOARD_FAB2(SCH_1):GND
   7    GND PGND<1> @BASEBOARD_FAB2_LIB.BASEBOARD_FAB2(SCH_1):GND
   5    GND PGND<0> @BASEBOARD_FAB2_LIB.BASEBOARD_FAB2(SCH_1):GND
  32 VR_PVCCIN_CPU0_PH3_PHASE  PHASE @BASEBOARD_FAB2_LIB.BASEBOARD_FAB2(SCH_1):VR_PVCCIN_CPU0_PH3_PHASE
  34 VR_PVCCIN_CPU0_PWM3    PWM @BASEBOARD_FAB2_LIB.BASEBOARD_FAB2(SCH_1):VR_PVCCIN_CPU0_PWM3
  39 VR_PVCCIN_CPU0_AIREF3  REFIN @BASEBOARD_FAB2_LIB.BASEBOARD_FAB2(SCH_1):VR_PVCCIN_CPU0_AIREF3
  10 VR_PVCCIN_CPU0_PHASE3     SW @BASEBOARD_FAB2_LIB.BASEBOARD_FAB2(SCH_1):VR_PVCCIN_CPU0_PHASE3
  36 A_TSENSE_PVCCIN_CPU0 TOUT_FLT @BASEBOARD_FAB2_LIB.BASEBOARD_FAB2(SCH_1):A_TSENSE_PVCCIN_CPU0
   3 VR_PVCCIN_CPU0_PH3_VCIN    VCC @BASEBOARD_FAB2_LIB.BASEBOARD_FAB2(SCH_1):VR_PVCCIN_CPU0_PH3_VCIN
   4 P5V_STBY   VDRV @BASEBOARD_FAB2_LIB.BASEBOARD_FAB2(SCH_1):P5V_STBY
  30 VR_FET_SW_P12V_STBY_PVCCIN_CPU0 VIN<1> @BASEBOARD_FAB2_LIB.BASEBOARD_FAB2(SCH_1):VR_FET_SW_P12V_STBY_PVCCIN_CPU0
  25 VR_FET_SW_P12V_STBY_PVCCIN_CPU0 VIN<0> @BASEBOARD_FAB2_LIB.BASEBOARD_FAB2(SCH_1):VR_FET_SW_P12V_STBY_PVCCIN_CPU0
   1 PVCCIN_CPU0    VOS @BASEBOARD_FAB2_LIB.BASEBOARD_FAB2(SCH_1):PVCCIN_CPU0

IR354XX_SM-IR35411,IC,H73688-0A  I71  EU4D1
  33 VR_PVCCIN_CPU0_PH4_BOOT_R  BOOST @BASEBOARD_FAB2_LIB.BASEBOARD_FAB2(SCH_1):VR_PVCCIN_CPU0_PH4_BOOT_R
  35 P5V_STBY     EN @BASEBOARD_FAB2_LIB.BASEBOARD_FAB2(SCH_1):P5V_STBY
  41 TP_PVCCIN_CPU0_PH4_GL_1  GL<1> @BASEBOARD_FAB2_LIB.BASEBOARD_FAB2(SCH_1):TP_PVCCIN_CPU0_PH4_GL_1
   6 TP_PVCCIN_CPU0_PH4_GL_0  GL<0> @BASEBOARD_FAB2_LIB.BASEBOARD_FAB2(SCH_1):TP_PVCCIN_CPU0_PH4_GL_0
  38 ISENSE_PVCCIN_CPU0_PH4_IMON   IOUT @BASEBOARD_FAB2_LIB.BASEBOARD_FAB2(SCH_1):ISENSE_PVCCIN_CPU0_PH4_IMON
   2    GND   LGND @BASEBOARD_FAB2_LIB.BASEBOARD_FAB2(SCH_1):GND
  31     NC     NC     NC
  37 VR_PVCCIN_CPU0_PH4_OCSET  OCSET @BASEBOARD_FAB2_LIB.BASEBOARD_FAB2(SCH_1):VR_PVCCIN_CPU0_PH4_OCSET
  40    GND PGND<2> @BASEBOARD_FAB2_LIB.BASEBOARD_FAB2(SCH_1):GND
   7    GND PGND<1> @BASEBOARD_FAB2_LIB.BASEBOARD_FAB2(SCH_1):GND
   5    GND PGND<0> @BASEBOARD_FAB2_LIB.BASEBOARD_FAB2(SCH_1):GND
  32 VR_PVCCIN_CPU0_PH4_PHASE  PHASE @BASEBOARD_FAB2_LIB.BASEBOARD_FAB2(SCH_1):VR_PVCCIN_CPU0_PH4_PHASE
  34 VR_PVCCIN_CPU0_PWM4    PWM @BASEBOARD_FAB2_LIB.BASEBOARD_FAB2(SCH_1):VR_PVCCIN_CPU0_PWM4
  39 VR_PVCCIN_CPU0_AIREF4  REFIN @BASEBOARD_FAB2_LIB.BASEBOARD_FAB2(SCH_1):VR_PVCCIN_CPU0_AIREF4
  10 VR_PVCCIN_CPU0_PHASE4     SW @BASEBOARD_FAB2_LIB.BASEBOARD_FAB2(SCH_1):VR_PVCCIN_CPU0_PHASE4
  36 A_TSENSE_PVCCIN_CPU0 TOUT_FLT @BASEBOARD_FAB2_LIB.BASEBOARD_FAB2(SCH_1):A_TSENSE_PVCCIN_CPU0
   3 VR_PVCCIN_CPU0_PH4_VCIN    VCC @BASEBOARD_FAB2_LIB.BASEBOARD_FAB2(SCH_1):VR_PVCCIN_CPU0_PH4_VCIN
   4 P5V_STBY   VDRV @BASEBOARD_FAB2_LIB.BASEBOARD_FAB2(SCH_1):P5V_STBY
  30 VR_FET_SW_P12V_STBY_PVCCIN_CPU0 VIN<1> @BASEBOARD_FAB2_LIB.BASEBOARD_FAB2(SCH_1):VR_FET_SW_P12V_STBY_PVCCIN_CPU0
  25 VR_FET_SW_P12V_STBY_PVCCIN_CPU0 VIN<0> @BASEBOARD_FAB2_LIB.BASEBOARD_FAB2(SCH_1):VR_FET_SW_P12V_STBY_PVCCIN_CPU0
   1 PVCCIN_CPU0    VOS @BASEBOARD_FAB2_LIB.BASEBOARD_FAB2(SCH_1):PVCCIN_CPU0

RES_0402-68.1K,1%,1/16W,EMPTY,A  I89  R4D72
   1 VR_PVCCIN_CPU0_PH3_OCSET      A @BASEBOARD_FAB2_LIB.BASEBOARD_FAB2(SCH_1):VR_PVCCIN_CPU0_PH3_OCSET
   2    GND      B @BASEBOARD_FAB2_LIB.BASEBOARD_FAB2(SCH_1):GND

RES_0402-68.1K,1%,1/16W,EMPTY,A  I91  R4D71
   1 VR_PVCCIN_CPU0_PH4_OCSET      A @BASEBOARD_FAB2_LIB.BASEBOARD_FAB2(SCH_1):VR_PVCCIN_CPU0_PH4_OCSET
   2    GND      B @BASEBOARD_FAB2_LIB.BASEBOARD_FAB2(SCH_1):GND

CAP_A_0402V-0.1UF,16V,10%,X7R,A  I93  CT40
   1 VR_PVCCIN_CPU0_AIREF4      A @BASEBOARD_FAB2_LIB.BASEBOARD_FAB2(SCH_1):VR_PVCCIN_CPU0_AIREF4
   2    GND      B @BASEBOARD_FAB2_LIB.BASEBOARD_FAB2(SCH_1):GND

CAP_A_0402V-0.1UF,16V,10%,X7R,A  I96  CT39
   1 VR_PVCCIN_CPU0_AIREF3      A @BASEBOARD_FAB2_LIB.BASEBOARD_FAB2(SCH_1):VR_PVCCIN_CPU0_AIREF3
   2    GND      B @BASEBOARD_FAB2_LIB.BASEBOARD_FAB2(SCH_1):GND

CAP_0402LF-1000PF,50V,10%,X7R,A  I99  CT37
   1 A_TSENSE_PVCCIN_CPU0      A @BASEBOARD_FAB2_LIB.BASEBOARD_FAB2(SCH_1):A_TSENSE_PVCCIN_CPU0
   2    GND      B @BASEBOARD_FAB2_LIB.BASEBOARD_FAB2(SCH_1):GND

CAP_0402LF-1000PF,50V,10%,X7R,A  I108  CT42
   1 A_TSENSE_PVCCIN_CPU0      A @BASEBOARD_FAB2_LIB.BASEBOARD_FAB2(SCH_1):A_TSENSE_PVCCIN_CPU0
   2    GND      B @BASEBOARD_FAB2_LIB.BASEBOARD_FAB2(SCH_1):GND

CAP_0402LF-1000PF,50V,10%,X7R,A  I118  CT38
   1 VR_PVCCIN_CPU0_PHASE3      A @BASEBOARD_FAB2_LIB.BASEBOARD_FAB2(SCH_1):VR_PVCCIN_CPU0_PHASE3
   2 VR_PVCCIN_CPU0_PHASE3_RC      B @BASEBOARD_FAB2_LIB.BASEBOARD_FAB2(SCH_1):VR_PVCCIN_CPU0_PHASE3_RC

CAP_0402LF-1000PF,50V,10%,X7R,A  I119  CT41
   1 VR_PVCCIN_CPU0_PHASE4      A @BASEBOARD_FAB2_LIB.BASEBOARD_FAB2(SCH_1):VR_PVCCIN_CPU0_PHASE4
   2 VR_PVCCIN_CPU0_PHASE4_RC      B @BASEBOARD_FAB2_LIB.BASEBOARD_FAB2(SCH_1):VR_PVCCIN_CPU0_PHASE4_RC

RES_0603-0,5.0%,1/10W,CHIP,G22A  I122  RT25
   1 VR_PVCCIN_CPU0_PH3_BOOT      A @BASEBOARD_FAB2_LIB.BASEBOARD_FAB2(SCH_1):VR_PVCCIN_CPU0_PH3_BOOT
   2 VR_PVCCIN_CPU0_PH3_BOOT_R      B @BASEBOARD_FAB2_LIB.BASEBOARD_FAB2(SCH_1):VR_PVCCIN_CPU0_PH3_BOOT_R

RES_0603-0,5.0%,1/10W,CHIP,G22A  I123  RT28
   1 VR_PVCCIN_CPU0_PH4_BOOT      A @BASEBOARD_FAB2_LIB.BASEBOARD_FAB2(SCH_1):VR_PVCCIN_CPU0_PH4_BOOT
   2 VR_PVCCIN_CPU0_PH4_BOOT_R      B @BASEBOARD_FAB2_LIB.BASEBOARD_FAB2(SCH_1):VR_PVCCIN_CPU0_PH4_BOOT_R

RES_0402-0.0,5%,1/16W,CHIP,G21A  I128  R6P19
   1 VR_PVCCIN_CPU0_PH3_VCIN      A @BASEBOARD_FAB2_LIB.BASEBOARD_FAB2(SCH_1):VR_PVCCIN_CPU0_PH3_VCIN
   2 P5V_STBY      B @BASEBOARD_FAB2_LIB.BASEBOARD_FAB2(SCH_1):P5V_STBY

RES_0402-0.0,5%,1/16W,CHIP,G21A  I129  R6P10
   1 VR_PVCCIN_CPU0_PH4_VCIN      A @BASEBOARD_FAB2_LIB.BASEBOARD_FAB2(SCH_1):VR_PVCCIN_CPU0_PH4_VCIN
   2 P5V_STBY      B @BASEBOARD_FAB2_LIB.BASEBOARD_FAB2(SCH_1):P5V_STBY

IND-120NH-30-GP_DISCRET-GB2-INA  I130  L4D2
   1 VR_PVCCIN_CPU0_PHASE3      S @BASEBOARD_FAB2_LIB.BASEBOARD_FAB2(SCH_1):VR_PVCCIN_CPU0_PHASE3
   2 PVCCIN_CPU0      F @BASEBOARD_FAB2_LIB.BASEBOARD_FAB2(SCH_1):PVCCIN_CPU0

IND-120NH-30-GP_DISCRET-GB2-INA  I131  L4D1
   1 VR_PVCCIN_CPU0_PHASE4      S @BASEBOARD_FAB2_LIB.BASEBOARD_FAB2(SCH_1):VR_PVCCIN_CPU0_PHASE4
   2 PVCCIN_CPU0      F @BASEBOARD_FAB2_LIB.BASEBOARD_FAB2(SCH_1):PVCCIN_CPU0

SC1U10V2KX-4-GP_SMD-BCG6-SC1U1A  I132  C4D14
   1 P5V_STBY      1 @BASEBOARD_FAB2_LIB.BASEBOARD_FAB2(SCH_1):P5V_STBY
   2    GND      2 @BASEBOARD_FAB2_LIB.BASEBOARD_FAB2(SCH_1):GND

SC1U10V2KX-4-GP_SMD-BCG6-SC1U1A  I133  C4D6
   1 P5V_STBY      1 @BASEBOARD_FAB2_LIB.BASEBOARD_FAB2(SCH_1):P5V_STBY
   2    GND      2 @BASEBOARD_FAB2_LIB.BASEBOARD_FAB2(SCH_1):GND

1R3F-GP_RCL_GP-1R3F-GP,64.1R00A  I134  RT26
   1 VR_PVCCIN_CPU0_PHASE3_RC      1 @BASEBOARD_FAB2_LIB.BASEBOARD_FAB2(SCH_1):VR_PVCCIN_CPU0_PHASE3_RC
   2    GND      2 @BASEBOARD_FAB2_LIB.BASEBOARD_FAB2(SCH_1):GND

1R3F-GP_RCL_GP-1R3F-GP,64.1R00A  I135  RT27
   1 VR_PVCCIN_CPU0_PHASE4_RC      1 @BASEBOARD_FAB2_LIB.BASEBOARD_FAB2(SCH_1):VR_PVCCIN_CPU0_PHASE4_RC
   2    GND      2 @BASEBOARD_FAB2_LIB.BASEBOARD_FAB2(SCH_1):GND


DRAWING: @BASEBOARD_FAB2_LIB.BASEBOARD_FAB2(SCH_1):PAGE204 

CAP_A_0603V-22.0UF,4V,20%,X6S,A  I9  C4D12
   1 PVCCIN_CPU0      A @BASEBOARD_FAB2_LIB.BASEBOARD_FAB2(SCH_1):PVCCIN_CPU0
   2    GND      B @BASEBOARD_FAB2_LIB.BASEBOARD_FAB2(SCH_1):GND

CAP_0402-0.22UF,16V,10%,X7R,A3A  I18  C4D47
   1 P5V_STBY      A @BASEBOARD_FAB2_LIB.BASEBOARD_FAB2(SCH_1):P5V_STBY
   2    GND      B @BASEBOARD_FAB2_LIB.BASEBOARD_FAB2(SCH_1):GND

CAP_0402-0.220UF,16V,10%,X7R,AA  I22  C4C17
   1 VR_PVCCIN_CPU0_PH5_BOOT      A @BASEBOARD_FAB2_LIB.BASEBOARD_FAB2(SCH_1):VR_PVCCIN_CPU0_PH5_BOOT
   2 VR_PVCCIN_CPU0_PH5_PHASE      B @BASEBOARD_FAB2_LIB.BASEBOARD_FAB2(SCH_1):VR_PVCCIN_CPU0_PH5_PHASE

CAP_0402-1.0UF,16V,10%,X6S,D97A  I34  C4D46
   1 VR_PVCCIN_CPU0_PH5_VCIN      A @BASEBOARD_FAB2_LIB.BASEBOARD_FAB2(SCH_1):VR_PVCCIN_CPU0_PH5_VCIN
   2    GND      B @BASEBOARD_FAB2_LIB.BASEBOARD_FAB2(SCH_1):GND

CAP_A_0402V-0.1UF,16V,10%,X7R,A  I35  C4C19
   1 VR_FET_SW_P12V_STBY_PVCCIN_CPU0      A @BASEBOARD_FAB2_LIB.BASEBOARD_FAB2(SCH_1):VR_FET_SW_P12V_STBY_PVCCIN_CPU0
   2    GND      B @BASEBOARD_FAB2_LIB.BASEBOARD_FAB2(SCH_1):GND

CAP_0402-1.0UF,16V,10%,X6S,D97A  I36  C4C18
   1 VR_FET_SW_P12V_STBY_PVCCIN_CPU0      A @BASEBOARD_FAB2_LIB.BASEBOARD_FAB2(SCH_1):VR_FET_SW_P12V_STBY_PVCCIN_CPU0
   2    GND      B @BASEBOARD_FAB2_LIB.BASEBOARD_FAB2(SCH_1):GND

CAP_0805-10UF,16V,10%,X6S,C953A  I37  C6N10
   1 VR_FET_SW_P12V_STBY_PVCCIN_CPU0      A @BASEBOARD_FAB2_LIB.BASEBOARD_FAB2(SCH_1):VR_FET_SW_P12V_STBY_PVCCIN_CPU0
   2    GND      B @BASEBOARD_FAB2_LIB.BASEBOARD_FAB2(SCH_1):GND

CAP_0805-10UF,16V,10%,X6S,C953A  I38  C6P17
   1 VR_FET_SW_P12V_STBY_PVCCIN_CPU0      A @BASEBOARD_FAB2_LIB.BASEBOARD_FAB2(SCH_1):VR_FET_SW_P12V_STBY_PVCCIN_CPU0
   2    GND      B @BASEBOARD_FAB2_LIB.BASEBOARD_FAB2(SCH_1):GND

CAP_0805-10UF,16V,10%,X6S,C953A  I42  C6N11
   1 VR_FET_SW_P12V_STBY_PVCCIN_CPU0      A @BASEBOARD_FAB2_LIB.BASEBOARD_FAB2(SCH_1):VR_FET_SW_P12V_STBY_PVCCIN_CPU0
   2    GND      B @BASEBOARD_FAB2_LIB.BASEBOARD_FAB2(SCH_1):GND

CAPP_2626-270UF,16V,20%,OSCON,A  I48  C4D2
   1 VR_FET_SW_P12V_STBY_PVCCIN_CPU0      A @BASEBOARD_FAB2_LIB.BASEBOARD_FAB2(SCH_1):VR_FET_SW_P12V_STBY_PVCCIN_CPU0
   2    GND      B @BASEBOARD_FAB2_LIB.BASEBOARD_FAB2(SCH_1):GND

CAPP_2626-270UF,16V,20%,OSCON,A  I50  C4E16
   1 VR_FET_SW_P12V_STBY_PVCCIN_CPU0      A @BASEBOARD_FAB2_LIB.BASEBOARD_FAB2(SCH_1):VR_FET_SW_P12V_STBY_PVCCIN_CPU0
   2    GND      B @BASEBOARD_FAB2_LIB.BASEBOARD_FAB2(SCH_1):GND

RES_0402-100.0,1%,1/16W,CHIP,GA  I60  R4E14
   1 VSENSE_PVCCIN_CPU0_P      A @BASEBOARD_FAB2_LIB.BASEBOARD_FAB2(SCH_1):VSENSE_PVCCIN_CPU0_P
   2 PVCCIN_CPU0      B @BASEBOARD_FAB2_LIB.BASEBOARD_FAB2(SCH_1):PVCCIN_CPU0

RES_0402-0.0,5%,1/16W,CHIP,G21A  I61  R4E16
   1 VSENSE_PVCCIN_CPU0_P      A @BASEBOARD_FAB2_LIB.BASEBOARD_FAB2(SCH_1):VSENSE_PVCCIN_CPU0_P
   2 VSENSE_PVCCIN_CPU0_SKT_VSEN      B @BASEBOARD_FAB2_LIB.BASEBOARD_FAB2(SCH_1):VSENSE_PVCCIN_CPU0_SKT_VSEN

RES_0402-0.0,5%,1/16W,CHIP,G21A  I62  R4E17
   1 VSENSE_PVCCIN_CPU0_N      A @BASEBOARD_FAB2_LIB.BASEBOARD_FAB2(SCH_1):VSENSE_PVCCIN_CPU0_N
   2 VSENSE_PVCCIN_CPU0_SKT_VRTN      B @BASEBOARD_FAB2_LIB.BASEBOARD_FAB2(SCH_1):VSENSE_PVCCIN_CPU0_SKT_VRTN

RES_0402-1.00K,1%,1/16W,EMPTY,A  I63  R4E15
   1 VSENSE_PVCCIN_CPU0_P      A @BASEBOARD_FAB2_LIB.BASEBOARD_FAB2(SCH_1):VSENSE_PVCCIN_CPU0_P
   2 VSENSE_PVCCIN_CPU0_N      B @BASEBOARD_FAB2_LIB.BASEBOARD_FAB2(SCH_1):VSENSE_PVCCIN_CPU0_N

RES_0402-100.0,1%,1/16W,CHIP,GA  I64  R4E18
   1 VSENSE_PVCCIN_CPU0_N      A @BASEBOARD_FAB2_LIB.BASEBOARD_FAB2(SCH_1):VSENSE_PVCCIN_CPU0_N
   2    GND      B @BASEBOARD_FAB2_LIB.BASEBOARD_FAB2(SCH_1):GND

CAPP_2626-270UF,16V,20%,OSCON,A  I67  C4C12
   1 VR_FET_SW_P12V_STBY_PVCCIN_CPU0      A @BASEBOARD_FAB2_LIB.BASEBOARD_FAB2(SCH_1):VR_FET_SW_P12V_STBY_PVCCIN_CPU0
   2    GND      B @BASEBOARD_FAB2_LIB.BASEBOARD_FAB2(SCH_1):GND

CAP_A_0603V-22.0UF,4V,20%,X6S,A  I70  C6R2
   1 PVCCIN_CPU0      A @BASEBOARD_FAB2_LIB.BASEBOARD_FAB2(SCH_1):PVCCIN_CPU0
   2    GND      B @BASEBOARD_FAB2_LIB.BASEBOARD_FAB2(SCH_1):GND

IR354XX_SM-IR35411,IC,H73688-0A  I71  EU4C2
  33 VR_PVCCIN_CPU0_PH5_BOOT_R  BOOST @BASEBOARD_FAB2_LIB.BASEBOARD_FAB2(SCH_1):VR_PVCCIN_CPU0_PH5_BOOT_R
  35 P5V_STBY     EN @BASEBOARD_FAB2_LIB.BASEBOARD_FAB2(SCH_1):P5V_STBY
  41 TP_PVCCIN_CPU0_PH5_GL_1  GL<1> @BASEBOARD_FAB2_LIB.BASEBOARD_FAB2(SCH_1):TP_PVCCIN_CPU0_PH5_GL_1
   6 TP_PVCCIN_CPU0_PH5_GL_0  GL<0> @BASEBOARD_FAB2_LIB.BASEBOARD_FAB2(SCH_1):TP_PVCCIN_CPU0_PH5_GL_0
  38 ISENSE_PVCCIN_CPU0_PH5_IMON   IOUT @BASEBOARD_FAB2_LIB.BASEBOARD_FAB2(SCH_1):ISENSE_PVCCIN_CPU0_PH5_IMON
   2    GND   LGND @BASEBOARD_FAB2_LIB.BASEBOARD_FAB2(SCH_1):GND
  31     NC     NC     NC
  37 VR_PVCCIN_CPU0_PH5_OCSET  OCSET @BASEBOARD_FAB2_LIB.BASEBOARD_FAB2(SCH_1):VR_PVCCIN_CPU0_PH5_OCSET
  40    GND PGND<2> @BASEBOARD_FAB2_LIB.BASEBOARD_FAB2(SCH_1):GND
   7    GND PGND<1> @BASEBOARD_FAB2_LIB.BASEBOARD_FAB2(SCH_1):GND
   5    GND PGND<0> @BASEBOARD_FAB2_LIB.BASEBOARD_FAB2(SCH_1):GND
  32 VR_PVCCIN_CPU0_PH5_PHASE  PHASE @BASEBOARD_FAB2_LIB.BASEBOARD_FAB2(SCH_1):VR_PVCCIN_CPU0_PH5_PHASE
  34 VR_PVCCIN_CPU0_PWM5    PWM @BASEBOARD_FAB2_LIB.BASEBOARD_FAB2(SCH_1):VR_PVCCIN_CPU0_PWM5
  39 VR_PVCCIN_CPU0_AIREF5  REFIN @BASEBOARD_FAB2_LIB.BASEBOARD_FAB2(SCH_1):VR_PVCCIN_CPU0_AIREF5
  10 VR_PVCCIN_CPU0_PHASE5     SW @BASEBOARD_FAB2_LIB.BASEBOARD_FAB2(SCH_1):VR_PVCCIN_CPU0_PHASE5
  36 A_TSENSE_PVCCIN_CPU0 TOUT_FLT @BASEBOARD_FAB2_LIB.BASEBOARD_FAB2(SCH_1):A_TSENSE_PVCCIN_CPU0
   3 VR_PVCCIN_CPU0_PH5_VCIN    VCC @BASEBOARD_FAB2_LIB.BASEBOARD_FAB2(SCH_1):VR_PVCCIN_CPU0_PH5_VCIN
   4 P5V_STBY   VDRV @BASEBOARD_FAB2_LIB.BASEBOARD_FAB2(SCH_1):P5V_STBY
  30 VR_FET_SW_P12V_STBY_PVCCIN_CPU0 VIN<1> @BASEBOARD_FAB2_LIB.BASEBOARD_FAB2(SCH_1):VR_FET_SW_P12V_STBY_PVCCIN_CPU0
  25 VR_FET_SW_P12V_STBY_PVCCIN_CPU0 VIN<0> @BASEBOARD_FAB2_LIB.BASEBOARD_FAB2(SCH_1):VR_FET_SW_P12V_STBY_PVCCIN_CPU0
   1 PVCCIN_CPU0    VOS @BASEBOARD_FAB2_LIB.BASEBOARD_FAB2(SCH_1):PVCCIN_CPU0

RES_0402-68.1K,1%,1/16W,EMPTY,A  I83  R4D68
   1 VR_PVCCIN_CPU0_PH5_OCSET      A @BASEBOARD_FAB2_LIB.BASEBOARD_FAB2(SCH_1):VR_PVCCIN_CPU0_PH5_OCSET
   2    GND      B @BASEBOARD_FAB2_LIB.BASEBOARD_FAB2(SCH_1):GND

CAP_A_0402V-0.1UF,16V,10%,X7R,A  I85  CT36
   1 VR_PVCCIN_CPU0_AIREF5      A @BASEBOARD_FAB2_LIB.BASEBOARD_FAB2(SCH_1):VR_PVCCIN_CPU0_AIREF5
   2    GND      B @BASEBOARD_FAB2_LIB.BASEBOARD_FAB2(SCH_1):GND

CAP_0402LF-1000PF,50V,10%,X7R,A  I88  CT34
   1 A_TSENSE_PVCCIN_CPU0      A @BASEBOARD_FAB2_LIB.BASEBOARD_FAB2(SCH_1):A_TSENSE_PVCCIN_CPU0
   2    GND      B @BASEBOARD_FAB2_LIB.BASEBOARD_FAB2(SCH_1):GND

CAP_0402LF-1000PF,50V,10%,X7R,A  I97  CT35
   1 VR_PVCCIN_CPU0_PHASE5      A @BASEBOARD_FAB2_LIB.BASEBOARD_FAB2(SCH_1):VR_PVCCIN_CPU0_PHASE5
   2 VR_PVCCIN_CPU0_PHASE5_RC      B @BASEBOARD_FAB2_LIB.BASEBOARD_FAB2(SCH_1):VR_PVCCIN_CPU0_PHASE5_RC

RES_0603-0,5.0%,1/10W,CHIP,G22A  I99  RT23
   1 VR_PVCCIN_CPU0_PH5_BOOT      A @BASEBOARD_FAB2_LIB.BASEBOARD_FAB2(SCH_1):VR_PVCCIN_CPU0_PH5_BOOT
   2 VR_PVCCIN_CPU0_PH5_BOOT_R      B @BASEBOARD_FAB2_LIB.BASEBOARD_FAB2(SCH_1):VR_PVCCIN_CPU0_PH5_BOOT_R

RES_0402-0.0,5%,1/16W,CHIP,G21A  I103  R6P47
   1 VR_PVCCIN_CPU0_PH5_VCIN      A @BASEBOARD_FAB2_LIB.BASEBOARD_FAB2(SCH_1):VR_PVCCIN_CPU0_PH5_VCIN
   2 P5V_STBY      B @BASEBOARD_FAB2_LIB.BASEBOARD_FAB2(SCH_1):P5V_STBY

IND-120NH-30-GP_DISCRET-GB2-INA  I104  L4C3
   1 VR_PVCCIN_CPU0_PHASE5      S @BASEBOARD_FAB2_LIB.BASEBOARD_FAB2(SCH_1):VR_PVCCIN_CPU0_PHASE5
   2 PVCCIN_CPU0      F @BASEBOARD_FAB2_LIB.BASEBOARD_FAB2(SCH_1):PVCCIN_CPU0

IND-80NH-1-GP_DISCRET-GC2-IND-A  I105  L4C1
   1 P12V_STBY      S @BASEBOARD_FAB2_LIB.BASEBOARD_FAB2(SCH_1):P12V_STBY
   2 VR_FET_SW_P12V_STBY_PVCCIN_CPU0      F @BASEBOARD_FAB2_LIB.BASEBOARD_FAB2(SCH_1):VR_FET_SW_P12V_STBY_PVCCIN_CPU0

SC1U10V2KX-4-GP_SMD-BCG6-SC1U1A  I113  C4C14
   1 P5V_STBY      1 @BASEBOARD_FAB2_LIB.BASEBOARD_FAB2(SCH_1):P5V_STBY
   2    GND      2 @BASEBOARD_FAB2_LIB.BASEBOARD_FAB2(SCH_1):GND

1R3F-GP_RCL_GP-1R3F-GP,64.1R00A  I114  RT24
   1 VR_PVCCIN_CPU0_PHASE5_RC      1 @BASEBOARD_FAB2_LIB.BASEBOARD_FAB2(SCH_1):VR_PVCCIN_CPU0_PHASE5_RC
   2    GND      2 @BASEBOARD_FAB2_LIB.BASEBOARD_FAB2(SCH_1):GND


DRAWING: @BASEBOARD_FAB2_LIB.BASEBOARD_FAB2(SCH_1):PAGE205 

CAP_A_0603V-22.0UF,4V,20%,X6S,A  I5  C6N7
   1 PVSA_CPU0      A @BASEBOARD_FAB2_LIB.BASEBOARD_FAB2(SCH_1):PVSA_CPU0
   2    GND      B @BASEBOARD_FAB2_LIB.BASEBOARD_FAB2(SCH_1):GND

CAPP_3018-470UF,2.5V,20%,ALUM,A  I12  C6N1
   1 PVSA_CPU0      A @BASEBOARD_FAB2_LIB.BASEBOARD_FAB2(SCH_1):PVSA_CPU0
   2    GND      B @BASEBOARD_FAB2_LIB.BASEBOARD_FAB2(SCH_1):GND

CAPP_3018-470UF,2.5V,20%,ALUM,A  I14  C6N4
   1 PVSA_CPU0      A @BASEBOARD_FAB2_LIB.BASEBOARD_FAB2(SCH_1):PVSA_CPU0
   2    GND      B @BASEBOARD_FAB2_LIB.BASEBOARD_FAB2(SCH_1):GND

CAP_0402-0.22UF,16V,10%,X7R,A3A  I16  C4C5
   1 P5V_STBY      A @BASEBOARD_FAB2_LIB.BASEBOARD_FAB2(SCH_1):P5V_STBY
   2    GND      B @BASEBOARD_FAB2_LIB.BASEBOARD_FAB2(SCH_1):GND

CAP_0402-1.0UF,16V,10%,X6S,D97A  I20  C4C6
   1 VR_PVSA_CPU0_VCIN      A @BASEBOARD_FAB2_LIB.BASEBOARD_FAB2(SCH_1):VR_PVSA_CPU0_VCIN
   2    GND      B @BASEBOARD_FAB2_LIB.BASEBOARD_FAB2(SCH_1):GND

RES_0402-100.0,1%,1/16W,CHIP,GA  I24  R4C5
   1 VSENSE_PVSA_CPU0_P      A @BASEBOARD_FAB2_LIB.BASEBOARD_FAB2(SCH_1):VSENSE_PVSA_CPU0_P
   2 PVSA_CPU0      B @BASEBOARD_FAB2_LIB.BASEBOARD_FAB2(SCH_1):PVSA_CPU0

CAP_0402-0.220UF,16V,10%,X7R,AA  I25  C4C8
   1 VR_PVSA_CPU0_BOOT      A @BASEBOARD_FAB2_LIB.BASEBOARD_FAB2(SCH_1):VR_PVSA_CPU0_BOOT
   2 VR_PVSA_CPU0_PHASE      B @BASEBOARD_FAB2_LIB.BASEBOARD_FAB2(SCH_1):VR_PVSA_CPU0_PHASE

RES_0402-0.0,5%,1/16W,CHIP,G21A  I26  R4C4
   1 VSENSE_PVSA_CPU0_P      A @BASEBOARD_FAB2_LIB.BASEBOARD_FAB2(SCH_1):VSENSE_PVSA_CPU0_P
   2 VSENSE_PVSA_CPU0_SKT_VSEN      B @BASEBOARD_FAB2_LIB.BASEBOARD_FAB2(SCH_1):VSENSE_PVSA_CPU0_SKT_VSEN

RES_0402-100.0,1%,1/16W,CHIP,GA  I29  R4C1
   1 VSENSE_PVSA_CPU0_N      A @BASEBOARD_FAB2_LIB.BASEBOARD_FAB2(SCH_1):VSENSE_PVSA_CPU0_N
   2    GND      B @BASEBOARD_FAB2_LIB.BASEBOARD_FAB2(SCH_1):GND

RES_0402-0.0,5%,1/16W,CHIP,G21A  I30  R4C2
   1 VSENSE_PVSA_CPU0_N      A @BASEBOARD_FAB2_LIB.BASEBOARD_FAB2(SCH_1):VSENSE_PVSA_CPU0_N
   2 VSENSE_PVSA_CPU0_SKT_VRTN      B @BASEBOARD_FAB2_LIB.BASEBOARD_FAB2(SCH_1):VSENSE_PVSA_CPU0_SKT_VRTN

CAP_A_0402V-0.1UF,16V,10%,X7R,A  I31  C4C10
   1 VR_FET_SW_P12V_STBY_PVCCIN_CPU0      A @BASEBOARD_FAB2_LIB.BASEBOARD_FAB2(SCH_1):VR_FET_SW_P12V_STBY_PVCCIN_CPU0
   2    GND      B @BASEBOARD_FAB2_LIB.BASEBOARD_FAB2(SCH_1):GND

CAP_0402-1.0UF,16V,10%,X6S,D97A  I32  C4C9
   1 VR_FET_SW_P12V_STBY_PVCCIN_CPU0      A @BASEBOARD_FAB2_LIB.BASEBOARD_FAB2(SCH_1):VR_FET_SW_P12V_STBY_PVCCIN_CPU0
   2    GND      B @BASEBOARD_FAB2_LIB.BASEBOARD_FAB2(SCH_1):GND

CAP_0805-10UF,16V,10%,X6S,C953A  I33  C6N2
   1 VR_FET_SW_P12V_STBY_PVCCIN_CPU0      A @BASEBOARD_FAB2_LIB.BASEBOARD_FAB2(SCH_1):VR_FET_SW_P12V_STBY_PVCCIN_CPU0
   2    GND      B @BASEBOARD_FAB2_LIB.BASEBOARD_FAB2(SCH_1):GND

CAP_0805-10UF,16V,10%,X6S,C953A  I34  C6N3
   1 VR_FET_SW_P12V_STBY_PVCCIN_CPU0      A @BASEBOARD_FAB2_LIB.BASEBOARD_FAB2(SCH_1):VR_FET_SW_P12V_STBY_PVCCIN_CPU0
   2    GND      B @BASEBOARD_FAB2_LIB.BASEBOARD_FAB2(SCH_1):GND

CAP_0805-10UF,16V,10%,X6S,C953A  I35  C6N6
   1 VR_FET_SW_P12V_STBY_PVCCIN_CPU0      A @BASEBOARD_FAB2_LIB.BASEBOARD_FAB2(SCH_1):VR_FET_SW_P12V_STBY_PVCCIN_CPU0
   2    GND      B @BASEBOARD_FAB2_LIB.BASEBOARD_FAB2(SCH_1):GND

RES_0402-1.00K,1%,1/16W,EMPTY,A  I37  R4C3
   1 VSENSE_PVSA_CPU0_P      A @BASEBOARD_FAB2_LIB.BASEBOARD_FAB2(SCH_1):VSENSE_PVSA_CPU0_P
   2 VSENSE_PVSA_CPU0_N      B @BASEBOARD_FAB2_LIB.BASEBOARD_FAB2(SCH_1):VSENSE_PVSA_CPU0_N

CAP_A_0603V-22.0UF,4V,20%,X6S,A  I43  C4C11
   1 PVSA_CPU0      A @BASEBOARD_FAB2_LIB.BASEBOARD_FAB2(SCH_1):PVSA_CPU0
   2    GND      B @BASEBOARD_FAB2_LIB.BASEBOARD_FAB2(SCH_1):GND

RES_0402-51.1,1.0%,1/16W,CHIP,A  I45  R6N4
   1 PVSA_CPU0      A @BASEBOARD_FAB2_LIB.BASEBOARD_FAB2(SCH_1):PVSA_CPU0
   2    GND      B @BASEBOARD_FAB2_LIB.BASEBOARD_FAB2(SCH_1):GND

IR354XX_SM-IR35412,IC,H73684-0A  I46  EU4C1
  33 VR_PVSA_CPU0_BOOT_R  BOOST @BASEBOARD_FAB2_LIB.BASEBOARD_FAB2(SCH_1):VR_PVSA_CPU0_BOOT_R
  35 P5V_STBY     EN @BASEBOARD_FAB2_LIB.BASEBOARD_FAB2(SCH_1):P5V_STBY
  41 TP_PVSA_CPU0_GL_1  GL<1> @BASEBOARD_FAB2_LIB.BASEBOARD_FAB2(SCH_1):TP_PVSA_CPU0_GL_1
   6 TP_PVSA_CPU0_GL_0  GL<0> @BASEBOARD_FAB2_LIB.BASEBOARD_FAB2(SCH_1):TP_PVSA_CPU0_GL_0
  38 ISENSE_PVSA_CPU0_IMON   IOUT @BASEBOARD_FAB2_LIB.BASEBOARD_FAB2(SCH_1):ISENSE_PVSA_CPU0_IMON
   2    GND   LGND @BASEBOARD_FAB2_LIB.BASEBOARD_FAB2(SCH_1):GND
  31     NC     NC     NC
  37 VR_PVSA_CPU0_OCSET  OCSET @BASEBOARD_FAB2_LIB.BASEBOARD_FAB2(SCH_1):VR_PVSA_CPU0_OCSET
  40    GND PGND<2> @BASEBOARD_FAB2_LIB.BASEBOARD_FAB2(SCH_1):GND
   7    GND PGND<1> @BASEBOARD_FAB2_LIB.BASEBOARD_FAB2(SCH_1):GND
   5    GND PGND<0> @BASEBOARD_FAB2_LIB.BASEBOARD_FAB2(SCH_1):GND
  32 VR_PVSA_CPU0_PHASE  PHASE @BASEBOARD_FAB2_LIB.BASEBOARD_FAB2(SCH_1):VR_PVSA_CPU0_PHASE
  34 VR_PVSA_CPU0_PWM    PWM @BASEBOARD_FAB2_LIB.BASEBOARD_FAB2(SCH_1):VR_PVSA_CPU0_PWM
  39 VR_PVSA_CPU0_BIREF1  REFIN @BASEBOARD_FAB2_LIB.BASEBOARD_FAB2(SCH_1):VR_PVSA_CPU0_BIREF1
  10 VR_PVSA_CPU0_PHASE_SW     SW @BASEBOARD_FAB2_LIB.BASEBOARD_FAB2(SCH_1):VR_PVSA_CPU0_PHASE_SW
  36 A_TSENSE_PVSA_CPU0 TOUT_FLT @BASEBOARD_FAB2_LIB.BASEBOARD_FAB2(SCH_1):A_TSENSE_PVSA_CPU0
   3 VR_PVSA_CPU0_VCIN    VCC @BASEBOARD_FAB2_LIB.BASEBOARD_FAB2(SCH_1):VR_PVSA_CPU0_VCIN
   4 P5V_STBY   VDRV @BASEBOARD_FAB2_LIB.BASEBOARD_FAB2(SCH_1):P5V_STBY
  30 VR_FET_SW_P12V_STBY_PVCCIN_CPU0 VIN<1> @BASEBOARD_FAB2_LIB.BASEBOARD_FAB2(SCH_1):VR_FET_SW_P12V_STBY_PVCCIN_CPU0
  25 VR_FET_SW_P12V_STBY_PVCCIN_CPU0 VIN<0> @BASEBOARD_FAB2_LIB.BASEBOARD_FAB2(SCH_1):VR_FET_SW_P12V_STBY_PVCCIN_CPU0
   1 PVSA_CPU0    VOS @BASEBOARD_FAB2_LIB.BASEBOARD_FAB2(SCH_1):PVSA_CPU0

RES_0402-68.1K,1%,1/16W,EMPTY,A  I62  R4C13
   1 VR_PVSA_CPU0_OCSET      A @BASEBOARD_FAB2_LIB.BASEBOARD_FAB2(SCH_1):VR_PVSA_CPU0_OCSET
   2    GND      B @BASEBOARD_FAB2_LIB.BASEBOARD_FAB2(SCH_1):GND

CAP_0402LF-1000PF,50V,10%,X7R,A  I65  CT58
   1 A_TSENSE_PVSA_CPU0      A @BASEBOARD_FAB2_LIB.BASEBOARD_FAB2(SCH_1):A_TSENSE_PVSA_CPU0
   2    GND      B @BASEBOARD_FAB2_LIB.BASEBOARD_FAB2(SCH_1):GND

CAP_A_0402V-0.1UF,16V,10%,X7R,A  I69  CT60
   1 VR_PVSA_CPU0_BIREF1      A @BASEBOARD_FAB2_LIB.BASEBOARD_FAB2(SCH_1):VR_PVSA_CPU0_BIREF1
   2    GND      B @BASEBOARD_FAB2_LIB.BASEBOARD_FAB2(SCH_1):GND

CAP_0402LF-1000PF,50V,10%,X7R,A  I76  CT59
   1 VR_PVSA_CPU0_PHASE_SW      A @BASEBOARD_FAB2_LIB.BASEBOARD_FAB2(SCH_1):VR_PVSA_CPU0_PHASE_SW
   2 VR_PVSA_CPU0_PHASE_SW_RC      B @BASEBOARD_FAB2_LIB.BASEBOARD_FAB2(SCH_1):VR_PVSA_CPU0_PHASE_SW_RC

RES_0603-0,5.0%,1/10W,CHIP,G22A  I78  RT40
   1 VR_PVSA_CPU0_BOOT      A @BASEBOARD_FAB2_LIB.BASEBOARD_FAB2(SCH_1):VR_PVSA_CPU0_BOOT
   2 VR_PVSA_CPU0_BOOT_R      B @BASEBOARD_FAB2_LIB.BASEBOARD_FAB2(SCH_1):VR_PVSA_CPU0_BOOT_R

RES_0402-0.0,5%,1/16W,CHIP,G21A  I81  R6N3
   1 VR_PVSA_CPU0_VCIN      A @BASEBOARD_FAB2_LIB.BASEBOARD_FAB2(SCH_1):VR_PVSA_CPU0_VCIN
   2 P5V_STBY      B @BASEBOARD_FAB2_LIB.BASEBOARD_FAB2(SCH_1):P5V_STBY

IND-300NH-20-GP_DISCRET-GB1-INA  I82  L4C2
   1 VR_PVSA_CPU0_PHASE_SW      S @BASEBOARD_FAB2_LIB.BASEBOARD_FAB2(SCH_1):VR_PVSA_CPU0_PHASE_SW
   2 PVSA_CPU0      F @BASEBOARD_FAB2_LIB.BASEBOARD_FAB2(SCH_1):PVSA_CPU0

SC1U10V2KX-4-GP_SMD-BCG6-SC1U1A  I83  C4C4
   1 P5V_STBY      1 @BASEBOARD_FAB2_LIB.BASEBOARD_FAB2(SCH_1):P5V_STBY
   2    GND      2 @BASEBOARD_FAB2_LIB.BASEBOARD_FAB2(SCH_1):GND

1R3F-GP_RCL_GP-1R3F-GP,64.1R00A  I84  RT39
   1 VR_PVSA_CPU0_PHASE_SW_RC      1 @BASEBOARD_FAB2_LIB.BASEBOARD_FAB2(SCH_1):VR_PVSA_CPU0_PHASE_SW_RC
   2    GND      2 @BASEBOARD_FAB2_LIB.BASEBOARD_FAB2(SCH_1):GND


DRAWING: @BASEBOARD_FAB2_LIB.BASEBOARD_FAB2(SCH_1):PAGE206 

RES_0402-100.0,1%,1/16W,CHIP,GA  I4  R9P1
   1 PVCCIO_CPU1      A @BASEBOARD_FAB2_LIB.BASEBOARD_FAB2(SCH_1):PVCCIO_CPU1
   2 SVID_DIO0_CPU1_R      B @BASEBOARD_FAB2_LIB.BASEBOARD_FAB2(SCH_1):SVID_DIO0_CPU1_R

RES_0402-1.00K,1%,1/16W,CHIP,GA  I6  R1D6
   1 P3V3_STBY      A @BASEBOARD_FAB2_LIB.BASEBOARD_FAB2(SCH_1):P3V3_STBY
   2 IRQ_PVCCIN_CPU1_VRHOT_LVC3_R_N      B @BASEBOARD_FAB2_LIB.BASEBOARD_FAB2(SCH_1):IRQ_PVCCIN_CPU1_VRHOT_LVC3_R_N

CAP_A_0402V-1.0UF,6.3V,10%,X6SA  I29  C1C13
   1 VR_PVCCIN_CPU1_VD12      A @BASEBOARD_FAB2_LIB.BASEBOARD_FAB2(SCH_1):VR_PVCCIN_CPU1_VD12
   2    GND      B @BASEBOARD_FAB2_LIB.BASEBOARD_FAB2(SCH_1):GND

CAP_A_0402V-0.1UF,16V,10%,X7R,A  I31  C1C14
   1 VR_PVCCIN_CPU1_VD12      A @BASEBOARD_FAB2_LIB.BASEBOARD_FAB2(SCH_1):VR_PVCCIN_CPU1_VD12
   2    GND      B @BASEBOARD_FAB2_LIB.BASEBOARD_FAB2(SCH_1):GND

RES_0402-2.26K,1.0%,1/16W,EMPTA  I33  R1D53
   1 P3V3_STBY      A @BASEBOARD_FAB2_LIB.BASEBOARD_FAB2(SCH_1):P3V3_STBY
   2 PU_VR_PVCCIN_CPU1_FLT1_SMBALT_N      B @BASEBOARD_FAB2_LIB.BASEBOARD_FAB2(SCH_1):PU_VR_PVCCIN_CPU1_FLT1_SMBALT_N_IMON

RES_0402-2.26K,1.0%,1/16W,EMPTA  I34  R1C18
   1 P3V3_STBY      A @BASEBOARD_FAB2_LIB.BASEBOARD_FAB2(SCH_1):P3V3_STBY
   2 PU_VR_PVCCIN_CPU1_IMON      B @BASEBOARD_FAB2_LIB.BASEBOARD_FAB2(SCH_1):PU_VR_PVCCIN_CPU1_IMON

RES_0402-1.00K,1%,1/16W,CHIP,GA  I35  R1C28
   1 P3V3_STBY      A @BASEBOARD_FAB2_LIB.BASEBOARD_FAB2(SCH_1):P3V3_STBY
   2 VR_VRRDY_PVCCIN_CPU1      B @BASEBOARD_FAB2_LIB.BASEBOARD_FAB2(SCH_1):VR_VRRDY_PVCCIN_CPU1

RES_0402-1.00K,1%,1/16W,CHIP,GA  I36  R1D8
   1 P3V3_STBY      A @BASEBOARD_FAB2_LIB.BASEBOARD_FAB2(SCH_1):P3V3_STBY
   2 PWRGD_PVSA_CPU1_R      B @BASEBOARD_FAB2_LIB.BASEBOARD_FAB2(SCH_1):PWRGD_PVSA_CPU1_R

RES_0402-0.0,5%,1/16W,CHIP,G21A  I37  R1D3
   1 SVID_VALERT_VCCIN_CPU1      A @BASEBOARD_FAB2_LIB.BASEBOARD_FAB2(SCH_1):SVID_VALERT_VCCIN_CPU1
   2 SVID_ALERT0_CPU1_R_N      B @BASEBOARD_FAB2_LIB.BASEBOARD_FAB2(SCH_1):SVID_ALERT0_CPU1_R_N

RES_0402-0.0,5%,1/16W,CHIP,G21A  I38  R1D2
   1 SVID_VDIO_PVCCIN_CPU1      A @BASEBOARD_FAB2_LIB.BASEBOARD_FAB2(SCH_1):SVID_VDIO_PVCCIN_CPU1
   2 SVID_DIO0_CPU1_R      B @BASEBOARD_FAB2_LIB.BASEBOARD_FAB2(SCH_1):SVID_DIO0_CPU1_R

CAP_A_0402V-1.0UF,6.3V,10%,X6SA  I41  C1C7
   1 VR_PVCCIN_CPU1_VDD      A @BASEBOARD_FAB2_LIB.BASEBOARD_FAB2(SCH_1):VR_PVCCIN_CPU1_VDD
   2    GND      B @BASEBOARD_FAB2_LIB.BASEBOARD_FAB2(SCH_1):GND

CAP_A_0402V-0.1UF,16V,10%,X7R,A  I42  C1C9
   1 VR_PVCCIN_CPU1_VDD      A @BASEBOARD_FAB2_LIB.BASEBOARD_FAB2(SCH_1):VR_PVCCIN_CPU1_VDD
   2    GND      B @BASEBOARD_FAB2_LIB.BASEBOARD_FAB2(SCH_1):GND

RES_0402-0.0,5%,1/16W,CHIP,G21A  I46  R1C14
   1 P3V3_STBY      A @BASEBOARD_FAB2_LIB.BASEBOARD_FAB2(SCH_1):P3V3_STBY
   2 VR_PVCCIN_CPU1_VDD      B @BASEBOARD_FAB2_LIB.BASEBOARD_FAB2(SCH_1):VR_PVCCIN_CPU1_VDD

RES_0402-100.0K,1%,1/16W,CHIP,B  I49  R1C13
   1 VR_FET_SW_P12V_STBY_PVCCIN_CPU1      A @BASEBOARD_FAB2_LIB.BASEBOARD_FAB2(SCH_1):VR_FET_SW_P12V_STBY_PVCCIN_CPU1
   2 VR_PVCCIN_CPU1_AVINSEN      B @BASEBOARD_FAB2_LIB.BASEBOARD_FAB2(SCH_1):VR_PVCCIN_CPU1_AVINSEN

RES_0402-49.9,1%,1/16W,CHIP,G2A  I53  R9P2
   1 PVCCIO_CPU1      A @BASEBOARD_FAB2_LIB.BASEBOARD_FAB2(SCH_1):PVCCIO_CPU1
   2 SVID_CLK0_CPU1_R      B @BASEBOARD_FAB2_LIB.BASEBOARD_FAB2(SCH_1):SVID_CLK0_CPU1_R

RES_0402-150.0,1%,1/16W,CHIP,GA  I54  R1D9
   1 SVID_CLK0_CPU1_R      A @BASEBOARD_FAB2_LIB.BASEBOARD_FAB2(SCH_1):SVID_CLK0_CPU1_R
   2 SVID_VCLK_PVCCIN_CPU1      B @BASEBOARD_FAB2_LIB.BASEBOARD_FAB2(SCH_1):SVID_VCLK_PVCCIN_CPU1

RES_0402-1.5K,1%,1/16W,CHIP,G2A  I56  R1C16
   1 VR_PVCCIN_CPU1_AVINSEN      A @BASEBOARD_FAB2_LIB.BASEBOARD_FAB2(SCH_1):VR_PVCCIN_CPU1_AVINSEN
   2    GND      B @BASEBOARD_FAB2_LIB.BASEBOARD_FAB2(SCH_1):GND

CAP_0402LF-220PF,50V,10%,X7R,AA  I68  C1C16
   1 VSENSE_PVSA_CPU1_BVSP      A @BASEBOARD_FAB2_LIB.BASEBOARD_FAB2(SCH_1):VSENSE_PVSA_CPU1_BVSP
   2 VSENSE_PVSA_CPU1_N      B @BASEBOARD_FAB2_LIB.BASEBOARD_FAB2(SCH_1):VSENSE_PVSA_CPU1_N

CAP_0402LF-220PF,50V,10%,X7R,AA  I69  C1C10
   1 A_TSENSE_PVCCIN_CPU1      A @BASEBOARD_FAB2_LIB.BASEBOARD_FAB2(SCH_1):A_TSENSE_PVCCIN_CPU1
   2    GND      B @BASEBOARD_FAB2_LIB.BASEBOARD_FAB2(SCH_1):GND

CAP_0402LF-220PF,50V,10%,X7R,AA  I71  C1C11
   1 A_TSENSE_PVSA_CPU1      A @BASEBOARD_FAB2_LIB.BASEBOARD_FAB2(SCH_1):A_TSENSE_PVSA_CPU1
   2    GND      B @BASEBOARD_FAB2_LIB.BASEBOARD_FAB2(SCH_1):GND

RES_0402-10.0,1%,1/16W,CHIP,G2A  I77  R1C21
   1 VSENSE_PVSA_CPU1_P      A @BASEBOARD_FAB2_LIB.BASEBOARD_FAB2(SCH_1):VSENSE_PVSA_CPU1_P
   2 VSENSE_PVSA_CPU1_BVSP      B @BASEBOARD_FAB2_LIB.BASEBOARD_FAB2(SCH_1):VSENSE_PVSA_CPU1_BVSP

CAP_0402LF-220PF,50V,10%,X7R,AA  I78  C1D1
   1 VSENSE_PVCCIN_CPU1_AVSP      A @BASEBOARD_FAB2_LIB.BASEBOARD_FAB2(SCH_1):VSENSE_PVCCIN_CPU1_AVSP
   2 VSENSE_PVCCIN_CPU1_N      B @BASEBOARD_FAB2_LIB.BASEBOARD_FAB2(SCH_1):VSENSE_PVCCIN_CPU1_N

RES_0402-10.0,1%,1/16W,CHIP,G2A  I79  R1D4
   1 VSENSE_PVCCIN_CPU1_P      A @BASEBOARD_FAB2_LIB.BASEBOARD_FAB2(SCH_1):VSENSE_PVCCIN_CPU1_P
   2 VSENSE_PVCCIN_CPU1_AVSP      B @BASEBOARD_FAB2_LIB.BASEBOARD_FAB2(SCH_1):VSENSE_PVCCIN_CPU1_AVSP

RES_0402-3.16K,1%,1/16W,CHIP,GA  I111  R9N7
   1 VR_PVCCIN_CPU1_XADDR2      A @BASEBOARD_FAB2_LIB.BASEBOARD_FAB2(SCH_1):VR_PVCCIN_CPU1_XADDR2
   2    GND      B @BASEBOARD_FAB2_LIB.BASEBOARD_FAB2(SCH_1):GND

RES_0402-4.02K,1%,1/16W,CHIP,GA  I112  R9N8
   1 VR_PVCCIN_CPU1_XADDR1      A @BASEBOARD_FAB2_LIB.BASEBOARD_FAB2(SCH_1):VR_PVCCIN_CPU1_XADDR1
   2    GND      B @BASEBOARD_FAB2_LIB.BASEBOARD_FAB2(SCH_1):GND

RES_0402-22.1,1.0%,1/16W,CHIP,A  I113  R1C30
   1 VR_VRRDY_PVCCIN_CPU1      A @BASEBOARD_FAB2_LIB.BASEBOARD_FAB2(SCH_1):VR_VRRDY_PVCCIN_CPU1
   2 PWRGD_PVCCIN_CPU1      B @BASEBOARD_FAB2_LIB.BASEBOARD_FAB2(SCH_1):PWRGD_PVCCIN_CPU1

CAP_0402LF-1000PF,50V,10%,X7R,A  I114  C1C23
   1 VR_VRRDY_PVCCIN_CPU1      A @BASEBOARD_FAB2_LIB.BASEBOARD_FAB2(SCH_1):VR_VRRDY_PVCCIN_CPU1
   2    GND      B @BASEBOARD_FAB2_LIB.BASEBOARD_FAB2(SCH_1):GND

RES_0402-33.2,1%,1/16W,CHIP,G2A  I116  R1D1
   1 PWRGD_PVSA_CPU1_R      A @BASEBOARD_FAB2_LIB.BASEBOARD_FAB2(SCH_1):PWRGD_PVSA_CPU1_R
   2 PWRGD_PVSA_CPU1      B @BASEBOARD_FAB2_LIB.BASEBOARD_FAB2(SCH_1):PWRGD_PVSA_CPU1

RES_0402-33.2,1%,1/16W,CHIP,G2A  I117  R9P3
   1 IRQ_PVCCIN_CPU1_VRHOT_LVC3_R_N      A @BASEBOARD_FAB2_LIB.BASEBOARD_FAB2(SCH_1):IRQ_PVCCIN_CPU1_VRHOT_LVC3_R_N
   2 IRQ_PVCCIN_CPU1_VRHOT_LVC3_N      B @BASEBOARD_FAB2_LIB.BASEBOARD_FAB2(SCH_1):IRQ_PVCCIN_CPU1_VRHOT_LVC3_N

RES_0402-0.0,5%,1/16W,CHIP,G21A  I119  R9N16
   1 FM_PVCCIN_PVCCSA_CPU1_EN_LVC1      A @BASEBOARD_FAB2_LIB.BASEBOARD_FAB2(SCH_1):FM_PVCCIN_PVCCSA_CPU1_EN_LVC1
   2 VR_PVCCIN_CPU1_VREN      B @BASEBOARD_FAB2_LIB.BASEBOARD_FAB2(SCH_1):VR_PVCCIN_CPU1_VREN

RES_0402-1.00K,1%,1/16W,CHIP,GA  I120  R9N14
   1 PVCCIO_CPU1      A @BASEBOARD_FAB2_LIB.BASEBOARD_FAB2(SCH_1):PVCCIO_CPU1
   2 VR_PVCCIN_CPU1_VREN      B @BASEBOARD_FAB2_LIB.BASEBOARD_FAB2(SCH_1):VR_PVCCIN_CPU1_VREN

PXE1610B_QFN-IC,H79206-001  I130  EU1C2
   1 VR_PVSA_CPU1_PWM  BPWM1 @BASEBOARD_FAB2_LIB.BASEBOARD_FAB2(SCH_1):VR_PVSA_CPU1_PWM
   2     NC  APWM6     NC
   3 VR_PVCCIN_CPU1_PWM5  APWM5 @BASEBOARD_FAB2_LIB.BASEBOARD_FAB2(SCH_1):VR_PVCCIN_CPU1_PWM5
   4 VR_PVCCIN_CPU1_PWM4  APWM4 @BASEBOARD_FAB2_LIB.BASEBOARD_FAB2(SCH_1):VR_PVCCIN_CPU1_PWM4
   5 VR_PVCCIN_CPU1_PWM3  APWM3 @BASEBOARD_FAB2_LIB.BASEBOARD_FAB2(SCH_1):VR_PVCCIN_CPU1_PWM3
   6 VR_PVCCIN_CPU1_PWM2  APWM2 @BASEBOARD_FAB2_LIB.BASEBOARD_FAB2(SCH_1):VR_PVCCIN_CPU1_PWM2
   7 VR_PVCCIN_CPU1_PWM1  APWM1 @BASEBOARD_FAB2_LIB.BASEBOARD_FAB2(SCH_1):VR_PVCCIN_CPU1_PWM1
   8 SMB_VR_STBY_LVC3_SDA    SDA @BASEBOARD_FAB2_LIB.BASEBOARD_FAB2(SCH_1):SMB_VR_STBY_LVC3_SDA
   9 SMB_VR_STBY_LVC3_SCL    SCL @BASEBOARD_FAB2_LIB.BASEBOARD_FAB2(SCH_1):SMB_VR_STBY_LVC3_SCL
  10     NC RESET_N     NC
  11 VR_VRRDY_PVCCIN_CPU1 AVRRDY @BASEBOARD_FAB2_LIB.BASEBOARD_FAB2(SCH_1):VR_VRRDY_PVCCIN_CPU1
  12 VR_PVCCIN_CPU1_VREN  AVREN @BASEBOARD_FAB2_LIB.BASEBOARD_FAB2(SCH_1):VR_PVCCIN_CPU1_VREN
  13 IRQ_PVCCIN_CPU1_VRHOT_LVC3_R_N VRHOT_N @BASEBOARD_FAB2_LIB.BASEBOARD_FAB2(SCH_1):IRQ_PVCCIN_CPU1_VRHOT_LVC3_R_N
  14 FM_PVCCIN_CPU1_PWR_IN_ALERT_N PINALRT_N @BASEBOARD_FAB2_LIB.BASEBOARD_FAB2(SCH_1):FM_PVCCIN_CPU1_PWR_IN_ALERT_N
  15 PWRGD_PVSA_CPU1_R    MP0 @BASEBOARD_FAB2_LIB.BASEBOARD_FAB2(SCH_1):PWRGD_PVSA_CPU1_R
  16     NC    MP1     NC
  17 SVID_VCLK_PVCCIN_CPU1   VCLK @BASEBOARD_FAB2_LIB.BASEBOARD_FAB2(SCH_1):SVID_VCLK_PVCCIN_CPU1
  18 SVID_VDIO_PVCCIN_CPU1   VDIO @BASEBOARD_FAB2_LIB.BASEBOARD_FAB2(SCH_1):SVID_VDIO_PVCCIN_CPU1
  19 SVID_VALERT_VCCIN_CPU1 VALRT_N @BASEBOARD_FAB2_LIB.BASEBOARD_FAB2(SCH_1):SVID_VALERT_VCCIN_CPU1
  20 PU_VR_PVCCIN_CPU1_FLT1_SMBALT_N    MP2 @BASEBOARD_FAB2_LIB.BASEBOARD_FAB2(SCH_1):PU_VR_PVCCIN_CPU1_FLT1_SMBALT_N_IMON
  21 VSENSE_PVCCIN_CPU1_AVSP  AVSEN @BASEBOARD_FAB2_LIB.BASEBOARD_FAB2(SCH_1):VSENSE_PVCCIN_CPU1_AVSP
  22 VSENSE_PVCCIN_CPU1_N  AVREF @BASEBOARD_FAB2_LIB.BASEBOARD_FAB2(SCH_1):VSENSE_PVCCIN_CPU1_N
  23 VR_PVCCIN_CPU1_AIREF1 AIREF1 @BASEBOARD_FAB2_LIB.BASEBOARD_FAB2(SCH_1):VR_PVCCIN_CPU1_AIREF1
  24 ISENSE_PVCCIN_CPU1_PH1_IMON AISEN1 @BASEBOARD_FAB2_LIB.BASEBOARD_FAB2(SCH_1):ISENSE_PVCCIN_CPU1_PH1_IMON
  25 VR_PVCCIN_CPU1_AIREF2 AIREF2 @BASEBOARD_FAB2_LIB.BASEBOARD_FAB2(SCH_1):VR_PVCCIN_CPU1_AIREF2
  26 ISENSE_PVCCIN_CPU1_PH2_IMON AISEN2 @BASEBOARD_FAB2_LIB.BASEBOARD_FAB2(SCH_1):ISENSE_PVCCIN_CPU1_PH2_IMON
  27 VR_PVCCIN_CPU1_AIREF3 AIREF3 @BASEBOARD_FAB2_LIB.BASEBOARD_FAB2(SCH_1):VR_PVCCIN_CPU1_AIREF3
  28 ISENSE_PVCCIN_CPU1_PH3_IMON AISEN3 @BASEBOARD_FAB2_LIB.BASEBOARD_FAB2(SCH_1):ISENSE_PVCCIN_CPU1_PH3_IMON
  29 VR_PVCCIN_CPU1_AIREF4 AIREF4 @BASEBOARD_FAB2_LIB.BASEBOARD_FAB2(SCH_1):VR_PVCCIN_CPU1_AIREF4
  30 ISENSE_PVCCIN_CPU1_PH4_IMON AISEN4 @BASEBOARD_FAB2_LIB.BASEBOARD_FAB2(SCH_1):ISENSE_PVCCIN_CPU1_PH4_IMON
  31 VR_PVCCIN_CPU1_AIREF5 AIREF5 @BASEBOARD_FAB2_LIB.BASEBOARD_FAB2(SCH_1):VR_PVCCIN_CPU1_AIREF5
  32 ISENSE_PVCCIN_CPU1_PH5_IMON AISEN5 @BASEBOARD_FAB2_LIB.BASEBOARD_FAB2(SCH_1):ISENSE_PVCCIN_CPU1_PH5_IMON
  33     NC AIREF6     NC
  34     NC AISEN6     NC
  35 VSENSE_PVSA_CPU1_BVSP  BVSEN @BASEBOARD_FAB2_LIB.BASEBOARD_FAB2(SCH_1):VSENSE_PVSA_CPU1_BVSP
  36 VSENSE_PVSA_CPU1_N  BVREF @BASEBOARD_FAB2_LIB.BASEBOARD_FAB2(SCH_1):VSENSE_PVSA_CPU1_N
  37 VR_PVSA_CPU1_BIREF1 BIREF1 @BASEBOARD_FAB2_LIB.BASEBOARD_FAB2(SCH_1):VR_PVSA_CPU1_BIREF1
  38 ISENSE_PVSA_CPU1_IMON BISEN1 @BASEBOARD_FAB2_LIB.BASEBOARD_FAB2(SCH_1):ISENSE_PVSA_CPU1_IMON
  39 PU_VR_PVCCIN_CPU1_IMON    MP3 @BASEBOARD_FAB2_LIB.BASEBOARD_FAB2(SCH_1):PU_VR_PVCCIN_CPU1_IMON
  40     NC    MP4     NC
  41 VR_PVCCIN_CPU1_XADDR2 XADDR2 @BASEBOARD_FAB2_LIB.BASEBOARD_FAB2(SCH_1):VR_PVCCIN_CPU1_XADDR2
  42 A_TSENSE_PVSA_CPU1  BTSEN @BASEBOARD_FAB2_LIB.BASEBOARD_FAB2(SCH_1):A_TSENSE_PVSA_CPU1
  43 A_TSENSE_PVCCIN_CPU1  ATSEN @BASEBOARD_FAB2_LIB.BASEBOARD_FAB2(SCH_1):A_TSENSE_PVCCIN_CPU1
  44 VR_PVCCIN_CPU1_XADDR1 XADDR1 @BASEBOARD_FAB2_LIB.BASEBOARD_FAB2(SCH_1):VR_PVCCIN_CPU1_XADDR1
  45 VR_PVCCIN_CPU1_AVINSEN VINSEN @BASEBOARD_FAB2_LIB.BASEBOARD_FAB2(SCH_1):VR_PVCCIN_CPU1_AVINSEN
  46     NC IINSEN     NC
  47 VR_PVCCIN_CPU1_VDD    VDD @BASEBOARD_FAB2_LIB.BASEBOARD_FAB2(SCH_1):VR_PVCCIN_CPU1_VDD
  48 VR_PVCCIN_CPU1_VD12   VD12 @BASEBOARD_FAB2_LIB.BASEBOARD_FAB2(SCH_1):VR_PVCCIN_CPU1_VD12
  49    GND  THPAD @BASEBOARD_FAB2_LIB.BASEBOARD_FAB2(SCH_1):GND

SC22P50V2JN-4GP_SMD-BCG-SC22P5A  I137  CF7
   1 VR_PVCCIN_CPU1_AIREF1      1 @BASEBOARD_FAB2_LIB.BASEBOARD_FAB2(SCH_1):VR_PVCCIN_CPU1_AIREF1
   2 ISENSE_PVCCIN_CPU1_PH1_IMON      2 @BASEBOARD_FAB2_LIB.BASEBOARD_FAB2(SCH_1):ISENSE_PVCCIN_CPU1_PH1_IMON

SC22P50V2JN-4GP_SMD-BCG-SC22P5A  I138  CF8
   1 VR_PVCCIN_CPU1_AIREF2      1 @BASEBOARD_FAB2_LIB.BASEBOARD_FAB2(SCH_1):VR_PVCCIN_CPU1_AIREF2
   2 ISENSE_PVCCIN_CPU1_PH2_IMON      2 @BASEBOARD_FAB2_LIB.BASEBOARD_FAB2(SCH_1):ISENSE_PVCCIN_CPU1_PH2_IMON

SC22P50V2JN-4GP_SMD-BCG-SC22P5A  I139  CF9
   1 VR_PVCCIN_CPU1_AIREF3      1 @BASEBOARD_FAB2_LIB.BASEBOARD_FAB2(SCH_1):VR_PVCCIN_CPU1_AIREF3
   2 ISENSE_PVCCIN_CPU1_PH3_IMON      2 @BASEBOARD_FAB2_LIB.BASEBOARD_FAB2(SCH_1):ISENSE_PVCCIN_CPU1_PH3_IMON

SC22P50V2JN-4GP_SMD-BCG-SC22P5A  I140  CF10
   1 VR_PVCCIN_CPU1_AIREF4      1 @BASEBOARD_FAB2_LIB.BASEBOARD_FAB2(SCH_1):VR_PVCCIN_CPU1_AIREF4
   2 ISENSE_PVCCIN_CPU1_PH4_IMON      2 @BASEBOARD_FAB2_LIB.BASEBOARD_FAB2(SCH_1):ISENSE_PVCCIN_CPU1_PH4_IMON

SC22P50V2JN-4GP_SMD-BCG-SC22P5A  I141  CF11
   1 VR_PVCCIN_CPU1_AIREF5      1 @BASEBOARD_FAB2_LIB.BASEBOARD_FAB2(SCH_1):VR_PVCCIN_CPU1_AIREF5
   2 ISENSE_PVCCIN_CPU1_PH5_IMON      2 @BASEBOARD_FAB2_LIB.BASEBOARD_FAB2(SCH_1):ISENSE_PVCCIN_CPU1_PH5_IMON

SC22P50V2JN-4GP_SMD-BCG-SC22P5A  I142  CF12
   1 VR_PVSA_CPU1_BIREF1      1 @BASEBOARD_FAB2_LIB.BASEBOARD_FAB2(SCH_1):VR_PVSA_CPU1_BIREF1
   2 ISENSE_PVSA_CPU1_IMON      2 @BASEBOARD_FAB2_LIB.BASEBOARD_FAB2(SCH_1):ISENSE_PVSA_CPU1_IMON

RES_0402-1.0K,0.1%,1/16W,CHIP,A  I149  RF12
   1 VR_PVSA_CPU1_BIREF1      A @BASEBOARD_FAB2_LIB.BASEBOARD_FAB2(SCH_1):VR_PVSA_CPU1_BIREF1
   2 ISENSE_PVSA_CPU1_IMON      B @BASEBOARD_FAB2_LIB.BASEBOARD_FAB2(SCH_1):ISENSE_PVSA_CPU1_IMON

RES_0402-1.0K,0.1%,1/16W,CHIP,A  I150  RF7
   1 VR_PVCCIN_CPU1_AIREF1      A @BASEBOARD_FAB2_LIB.BASEBOARD_FAB2(SCH_1):VR_PVCCIN_CPU1_AIREF1
   2 ISENSE_PVCCIN_CPU1_PH1_IMON      B @BASEBOARD_FAB2_LIB.BASEBOARD_FAB2(SCH_1):ISENSE_PVCCIN_CPU1_PH1_IMON

RES_0402-1.0K,0.1%,1/16W,CHIP,A  I151  RF8
   1 VR_PVCCIN_CPU1_AIREF2      A @BASEBOARD_FAB2_LIB.BASEBOARD_FAB2(SCH_1):VR_PVCCIN_CPU1_AIREF2
   2 ISENSE_PVCCIN_CPU1_PH2_IMON      B @BASEBOARD_FAB2_LIB.BASEBOARD_FAB2(SCH_1):ISENSE_PVCCIN_CPU1_PH2_IMON

RES_0402-1.0K,0.1%,1/16W,CHIP,A  I152  RF9
   1 VR_PVCCIN_CPU1_AIREF3      A @BASEBOARD_FAB2_LIB.BASEBOARD_FAB2(SCH_1):VR_PVCCIN_CPU1_AIREF3
   2 ISENSE_PVCCIN_CPU1_PH3_IMON      B @BASEBOARD_FAB2_LIB.BASEBOARD_FAB2(SCH_1):ISENSE_PVCCIN_CPU1_PH3_IMON

RES_0402-1.0K,0.1%,1/16W,CHIP,A  I153  RF10
   1 VR_PVCCIN_CPU1_AIREF4      A @BASEBOARD_FAB2_LIB.BASEBOARD_FAB2(SCH_1):VR_PVCCIN_CPU1_AIREF4
   2 ISENSE_PVCCIN_CPU1_PH4_IMON      B @BASEBOARD_FAB2_LIB.BASEBOARD_FAB2(SCH_1):ISENSE_PVCCIN_CPU1_PH4_IMON

RES_0402-1.0K,0.1%,1/16W,CHIP,A  I154  RF11
   1 VR_PVCCIN_CPU1_AIREF5      A @BASEBOARD_FAB2_LIB.BASEBOARD_FAB2(SCH_1):VR_PVCCIN_CPU1_AIREF5
   2 ISENSE_PVCCIN_CPU1_PH5_IMON      B @BASEBOARD_FAB2_LIB.BASEBOARD_FAB2(SCH_1):ISENSE_PVCCIN_CPU1_PH5_IMON

RES_0402-1.00K,1%,1/16W,CHIP,GA  I155  R1D7
   1 P3V3_STBY      A @BASEBOARD_FAB2_LIB.BASEBOARD_FAB2(SCH_1):P3V3_STBY
   2 FM_PVCCIN_CPU1_PWR_IN_ALERT_N      B @BASEBOARD_FAB2_LIB.BASEBOARD_FAB2(SCH_1):FM_PVCCIN_CPU1_PWR_IN_ALERT_N

CAP_A_0402V-0.1UF,16V,10%,X7R,A  I156  C1C8
   1 VR_PVCCIN_CPU1_AVINSEN      A @BASEBOARD_FAB2_LIB.BASEBOARD_FAB2(SCH_1):VR_PVCCIN_CPU1_AVINSEN
   2    GND      B @BASEBOARD_FAB2_LIB.BASEBOARD_FAB2(SCH_1):GND


DRAWING: @BASEBOARD_FAB2_LIB.BASEBOARD_FAB2(SCH_1):PAGE207 

CAP_A_0603V-22.0UF,4V,20%,X6S,A  I8  C9R8
   1 PVCCIN_CPU1      A @BASEBOARD_FAB2_LIB.BASEBOARD_FAB2(SCH_1):PVCCIN_CPU1
   2    GND      B @BASEBOARD_FAB2_LIB.BASEBOARD_FAB2(SCH_1):GND

CAP_A_0603V-22.0UF,4V,20%,X6S,A  I18  C1E3
   1 PVCCIN_CPU1      A @BASEBOARD_FAB2_LIB.BASEBOARD_FAB2(SCH_1):PVCCIN_CPU1
   2    GND      B @BASEBOARD_FAB2_LIB.BASEBOARD_FAB2(SCH_1):GND

IR354XX_SM-IR35411,IC,H73688-0A  I20  EU1E2
  33 VR_PVCCIN_CPU1_PH1_BOOT_R  BOOST @BASEBOARD_FAB2_LIB.BASEBOARD_FAB2(SCH_1):VR_PVCCIN_CPU1_PH1_BOOT_R
  35 P5V_STBY     EN @BASEBOARD_FAB2_LIB.BASEBOARD_FAB2(SCH_1):P5V_STBY
  41 TP_PVCCINC_CPU1_PH1_GL_1  GL<1> @BASEBOARD_FAB2_LIB.BASEBOARD_FAB2(SCH_1):TP_PVCCINC_CPU1_PH1_GL_1
   6 TP_PVCCINC_CPU1_PH1_GL_0  GL<0> @BASEBOARD_FAB2_LIB.BASEBOARD_FAB2(SCH_1):TP_PVCCINC_CPU1_PH1_GL_0
  38 ISENSE_PVCCIN_CPU1_PH1_IMON   IOUT @BASEBOARD_FAB2_LIB.BASEBOARD_FAB2(SCH_1):ISENSE_PVCCIN_CPU1_PH1_IMON
   2    GND   LGND @BASEBOARD_FAB2_LIB.BASEBOARD_FAB2(SCH_1):GND
  31     NC     NC     NC
  37 VR_PVCCIN_CPU1_PH1_OCSET  OCSET @BASEBOARD_FAB2_LIB.BASEBOARD_FAB2(SCH_1):VR_PVCCIN_CPU1_PH1_OCSET
  40    GND PGND<2> @BASEBOARD_FAB2_LIB.BASEBOARD_FAB2(SCH_1):GND
   7    GND PGND<1> @BASEBOARD_FAB2_LIB.BASEBOARD_FAB2(SCH_1):GND
   5    GND PGND<0> @BASEBOARD_FAB2_LIB.BASEBOARD_FAB2(SCH_1):GND
  32 VR_PVCCIN_CPU1_PH1_PHASE  PHASE @BASEBOARD_FAB2_LIB.BASEBOARD_FAB2(SCH_1):VR_PVCCIN_CPU1_PH1_PHASE
  34 VR_PVCCIN_CPU1_PWM1    PWM @BASEBOARD_FAB2_LIB.BASEBOARD_FAB2(SCH_1):VR_PVCCIN_CPU1_PWM1
  39 VR_PVCCIN_CPU1_AIREF1  REFIN @BASEBOARD_FAB2_LIB.BASEBOARD_FAB2(SCH_1):VR_PVCCIN_CPU1_AIREF1
  10 VR_PVCCIN_CPU1_PHASE1     SW @BASEBOARD_FAB2_LIB.BASEBOARD_FAB2(SCH_1):VR_PVCCIN_CPU1_PHASE1
  36 A_TSENSE_PVCCIN_CPU1 TOUT_FLT @BASEBOARD_FAB2_LIB.BASEBOARD_FAB2(SCH_1):A_TSENSE_PVCCIN_CPU1
   3 VR_PVCCIN_CPU1_PH1_VCIN    VCC @BASEBOARD_FAB2_LIB.BASEBOARD_FAB2(SCH_1):VR_PVCCIN_CPU1_PH1_VCIN
   4 P5V_STBY   VDRV @BASEBOARD_FAB2_LIB.BASEBOARD_FAB2(SCH_1):P5V_STBY
  30 VR_FET_SW_P12V_STBY_PVCCIN_CPU1 VIN<1> @BASEBOARD_FAB2_LIB.BASEBOARD_FAB2(SCH_1):VR_FET_SW_P12V_STBY_PVCCIN_CPU1
  25 VR_FET_SW_P12V_STBY_PVCCIN_CPU1 VIN<0> @BASEBOARD_FAB2_LIB.BASEBOARD_FAB2(SCH_1):VR_FET_SW_P12V_STBY_PVCCIN_CPU1
   1 PVCCIN_CPU1    VOS @BASEBOARD_FAB2_LIB.BASEBOARD_FAB2(SCH_1):PVCCIN_CPU1

CAP_0402-0.22UF,16V,10%,X7R,A3A  I28  C1E7
   1 P5V_STBY      A @BASEBOARD_FAB2_LIB.BASEBOARD_FAB2(SCH_1):P5V_STBY
   2    GND      B @BASEBOARD_FAB2_LIB.BASEBOARD_FAB2(SCH_1):GND

CAP_0402-0.220UF,16V,10%,X7R,AA  I30  C1E11
   1 VR_PVCCIN_CPU1_PH1_BOOT      A @BASEBOARD_FAB2_LIB.BASEBOARD_FAB2(SCH_1):VR_PVCCIN_CPU1_PH1_BOOT
   2 VR_PVCCIN_CPU1_PH1_PHASE      B @BASEBOARD_FAB2_LIB.BASEBOARD_FAB2(SCH_1):VR_PVCCIN_CPU1_PH1_PHASE

CAP_0402-1.0UF,16V,10%,X6S,D97A  I32  C1E8
   1 VR_PVCCIN_CPU1_PH1_VCIN      A @BASEBOARD_FAB2_LIB.BASEBOARD_FAB2(SCH_1):VR_PVCCIN_CPU1_PH1_VCIN
   2    GND      B @BASEBOARD_FAB2_LIB.BASEBOARD_FAB2(SCH_1):GND

CAP_A_0402V-0.1UF,16V,10%,X7R,A  I33  C1E14
   1 VR_FET_SW_P12V_STBY_PVCCIN_CPU1      A @BASEBOARD_FAB2_LIB.BASEBOARD_FAB2(SCH_1):VR_FET_SW_P12V_STBY_PVCCIN_CPU1
   2    GND      B @BASEBOARD_FAB2_LIB.BASEBOARD_FAB2(SCH_1):GND

CAP_0402-1.0UF,16V,10%,X6S,D97A  I34  C1E13
   1 VR_FET_SW_P12V_STBY_PVCCIN_CPU1      A @BASEBOARD_FAB2_LIB.BASEBOARD_FAB2(SCH_1):VR_FET_SW_P12V_STBY_PVCCIN_CPU1
   2    GND      B @BASEBOARD_FAB2_LIB.BASEBOARD_FAB2(SCH_1):GND

CAP_0402-0.22UF,16V,10%,X7R,A3A  I36  C1E25
   1 P5V_STBY      A @BASEBOARD_FAB2_LIB.BASEBOARD_FAB2(SCH_1):P5V_STBY
   2    GND      B @BASEBOARD_FAB2_LIB.BASEBOARD_FAB2(SCH_1):GND

CAP_0402-0.220UF,16V,10%,X7R,AA  I38  C1D36
   1 VR_PVCCIN_CPU1_PH2_BOOT      A @BASEBOARD_FAB2_LIB.BASEBOARD_FAB2(SCH_1):VR_PVCCIN_CPU1_PH2_BOOT
   2 VR_PVCCIN_CPU1_PH2_PHASE      B @BASEBOARD_FAB2_LIB.BASEBOARD_FAB2(SCH_1):VR_PVCCIN_CPU1_PH2_PHASE

CAP_0402-1.0UF,16V,10%,X6S,D97A  I40  C1E24
   1 VR_PVCCIN_CPU1_PH2_VCIN      A @BASEBOARD_FAB2_LIB.BASEBOARD_FAB2(SCH_1):VR_PVCCIN_CPU1_PH2_VCIN
   2    GND      B @BASEBOARD_FAB2_LIB.BASEBOARD_FAB2(SCH_1):GND

CAP_A_0402V-0.1UF,16V,10%,X7R,A  I41  C1D34
   1 VR_FET_SW_P12V_STBY_PVCCIN_CPU1      A @BASEBOARD_FAB2_LIB.BASEBOARD_FAB2(SCH_1):VR_FET_SW_P12V_STBY_PVCCIN_CPU1
   2    GND      B @BASEBOARD_FAB2_LIB.BASEBOARD_FAB2(SCH_1):GND

CAP_0402-1.0UF,16V,10%,X6S,D97A  I42  C1D35
   1 VR_FET_SW_P12V_STBY_PVCCIN_CPU1      A @BASEBOARD_FAB2_LIB.BASEBOARD_FAB2(SCH_1):VR_FET_SW_P12V_STBY_PVCCIN_CPU1
   2    GND      B @BASEBOARD_FAB2_LIB.BASEBOARD_FAB2(SCH_1):GND

CAP_0805-10UF,16V,10%,X6S,C953A  I43  C9R7
   1 VR_FET_SW_P12V_STBY_PVCCIN_CPU1      A @BASEBOARD_FAB2_LIB.BASEBOARD_FAB2(SCH_1):VR_FET_SW_P12V_STBY_PVCCIN_CPU1
   2    GND      B @BASEBOARD_FAB2_LIB.BASEBOARD_FAB2(SCH_1):GND

CAP_0805-10UF,16V,10%,X6S,C953A  I44  C9R10
   1 VR_FET_SW_P12V_STBY_PVCCIN_CPU1      A @BASEBOARD_FAB2_LIB.BASEBOARD_FAB2(SCH_1):VR_FET_SW_P12V_STBY_PVCCIN_CPU1
   2    GND      B @BASEBOARD_FAB2_LIB.BASEBOARD_FAB2(SCH_1):GND

CAP_0805-10UF,16V,10%,X6S,C953A  I48  C9R11
   1 VR_FET_SW_P12V_STBY_PVCCIN_CPU1      A @BASEBOARD_FAB2_LIB.BASEBOARD_FAB2(SCH_1):VR_FET_SW_P12V_STBY_PVCCIN_CPU1
   2    GND      B @BASEBOARD_FAB2_LIB.BASEBOARD_FAB2(SCH_1):GND

CAP_0805-10UF,16V,10%,X6S,C953A  I50  C9P22
   1 VR_FET_SW_P12V_STBY_PVCCIN_CPU1      A @BASEBOARD_FAB2_LIB.BASEBOARD_FAB2(SCH_1):VR_FET_SW_P12V_STBY_PVCCIN_CPU1
   2    GND      B @BASEBOARD_FAB2_LIB.BASEBOARD_FAB2(SCH_1):GND

CAP_0805-10UF,16V,10%,X6S,C953A  I51  C9P25
   1 VR_FET_SW_P12V_STBY_PVCCIN_CPU1      A @BASEBOARD_FAB2_LIB.BASEBOARD_FAB2(SCH_1):VR_FET_SW_P12V_STBY_PVCCIN_CPU1
   2    GND      B @BASEBOARD_FAB2_LIB.BASEBOARD_FAB2(SCH_1):GND

CAP_0805-10UF,16V,10%,X6S,C953A  I54  C9P26
   1 VR_FET_SW_P12V_STBY_PVCCIN_CPU1      A @BASEBOARD_FAB2_LIB.BASEBOARD_FAB2(SCH_1):VR_FET_SW_P12V_STBY_PVCCIN_CPU1
   2    GND      B @BASEBOARD_FAB2_LIB.BASEBOARD_FAB2(SCH_1):GND

CAP_A_0603V-22.0UF,4V,20%,X6S,A  I58  C1E9
   1 PVCCIN_CPU1      A @BASEBOARD_FAB2_LIB.BASEBOARD_FAB2(SCH_1):PVCCIN_CPU1
   2    GND      B @BASEBOARD_FAB2_LIB.BASEBOARD_FAB2(SCH_1):GND

CAP_A_0603V-22.0UF,4V,20%,X6S,A  I59  C9P3
   1 PVCCIN_CPU1      A @BASEBOARD_FAB2_LIB.BASEBOARD_FAB2(SCH_1):PVCCIN_CPU1
   2    GND      B @BASEBOARD_FAB2_LIB.BASEBOARD_FAB2(SCH_1):GND

RES_0402-68.1K,1%,1/16W,EMPTY,A  I67  R1E13
   1 VR_PVCCIN_CPU1_PH2_OCSET      A @BASEBOARD_FAB2_LIB.BASEBOARD_FAB2(SCH_1):VR_PVCCIN_CPU1_PH2_OCSET
   2    GND      B @BASEBOARD_FAB2_LIB.BASEBOARD_FAB2(SCH_1):GND

RES_0402-68.1K,1%,1/16W,EMPTY,A  I68  R1E14
   1 VR_PVCCIN_CPU1_PH1_OCSET      A @BASEBOARD_FAB2_LIB.BASEBOARD_FAB2(SCH_1):VR_PVCCIN_CPU1_PH1_OCSET
   2    GND      B @BASEBOARD_FAB2_LIB.BASEBOARD_FAB2(SCH_1):GND

CAP_A_0402V-0.1UF,16V,10%,X7R,A  I71  CT24
   1 VR_PVCCIN_CPU1_AIREF1      A @BASEBOARD_FAB2_LIB.BASEBOARD_FAB2(SCH_1):VR_PVCCIN_CPU1_AIREF1
   2    GND      B @BASEBOARD_FAB2_LIB.BASEBOARD_FAB2(SCH_1):GND

CAP_0402LF-1000PF,50V,10%,X7R,A  I74  CT22
   1 A_TSENSE_PVCCIN_CPU1      A @BASEBOARD_FAB2_LIB.BASEBOARD_FAB2(SCH_1):A_TSENSE_PVCCIN_CPU1
   2    GND      B @BASEBOARD_FAB2_LIB.BASEBOARD_FAB2(SCH_1):GND

CAP_A_0402V-0.1UF,16V,10%,X7R,A  I81  CT25
   1 VR_PVCCIN_CPU1_AIREF2      A @BASEBOARD_FAB2_LIB.BASEBOARD_FAB2(SCH_1):VR_PVCCIN_CPU1_AIREF2
   2    GND      B @BASEBOARD_FAB2_LIB.BASEBOARD_FAB2(SCH_1):GND

CAP_0402LF-1000PF,50V,10%,X7R,A  I82  CT26
   1 A_TSENSE_PVCCIN_CPU1      A @BASEBOARD_FAB2_LIB.BASEBOARD_FAB2(SCH_1):A_TSENSE_PVCCIN_CPU1
   2    GND      B @BASEBOARD_FAB2_LIB.BASEBOARD_FAB2(SCH_1):GND

CAP_0402LF-1000PF,50V,10%,X7R,A  I95  CT23
   1 VR_PVCCIN_CPU1_PHASE1      A @BASEBOARD_FAB2_LIB.BASEBOARD_FAB2(SCH_1):VR_PVCCIN_CPU1_PHASE1
   2 VR_PVCCIN_CPU1_PHASE1_RC      B @BASEBOARD_FAB2_LIB.BASEBOARD_FAB2(SCH_1):VR_PVCCIN_CPU1_PHASE1_RC

CAP_0402LF-1000PF,50V,10%,X7R,A  I96  CT27
   1 VR_PVCCIN_CPU1_PHASE2      A @BASEBOARD_FAB2_LIB.BASEBOARD_FAB2(SCH_1):VR_PVCCIN_CPU1_PHASE2
   2 VR_PVCCIN_CPU1_PHASE2_RC      B @BASEBOARD_FAB2_LIB.BASEBOARD_FAB2(SCH_1):VR_PVCCIN_CPU1_PHASE2_RC

RES_0603-0,5.0%,1/10W,CHIP,G22A  I99  RT15
   1 VR_PVCCIN_CPU1_PH1_BOOT      A @BASEBOARD_FAB2_LIB.BASEBOARD_FAB2(SCH_1):VR_PVCCIN_CPU1_PH1_BOOT
   2 VR_PVCCIN_CPU1_PH1_BOOT_R      B @BASEBOARD_FAB2_LIB.BASEBOARD_FAB2(SCH_1):VR_PVCCIN_CPU1_PH1_BOOT_R

RES_0603-0,5.0%,1/10W,CHIP,G22A  I100  RT17
   1 VR_PVCCIN_CPU1_PH2_BOOT      A @BASEBOARD_FAB2_LIB.BASEBOARD_FAB2(SCH_1):VR_PVCCIN_CPU1_PH2_BOOT
   2 VR_PVCCIN_CPU1_PH2_BOOT_R      B @BASEBOARD_FAB2_LIB.BASEBOARD_FAB2(SCH_1):VR_PVCCIN_CPU1_PH2_BOOT_R

RES_0402-0.0,5%,1/16W,CHIP,G21A  I105  R9R11
   1 VR_PVCCIN_CPU1_PH2_VCIN      A @BASEBOARD_FAB2_LIB.BASEBOARD_FAB2(SCH_1):VR_PVCCIN_CPU1_PH2_VCIN
   2 P5V_STBY      B @BASEBOARD_FAB2_LIB.BASEBOARD_FAB2(SCH_1):P5V_STBY

RES_0402-0.0,5%,1/16W,CHIP,G21A  I106  R9R2
   1 VR_PVCCIN_CPU1_PH1_VCIN      A @BASEBOARD_FAB2_LIB.BASEBOARD_FAB2(SCH_1):VR_PVCCIN_CPU1_PH1_VCIN
   2 P5V_STBY      B @BASEBOARD_FAB2_LIB.BASEBOARD_FAB2(SCH_1):P5V_STBY

IND-120NH-30-GP_DISCRET-GB2-INA  I107  L1E1
   1 VR_PVCCIN_CPU1_PHASE1      S @BASEBOARD_FAB2_LIB.BASEBOARD_FAB2(SCH_1):VR_PVCCIN_CPU1_PHASE1
   2 PVCCIN_CPU1      F @BASEBOARD_FAB2_LIB.BASEBOARD_FAB2(SCH_1):PVCCIN_CPU1

IND-120NH-30-GP_DISCRET-GB2-INA  I108  L1D3
   1 VR_PVCCIN_CPU1_PHASE2      S @BASEBOARD_FAB2_LIB.BASEBOARD_FAB2(SCH_1):VR_PVCCIN_CPU1_PHASE2
   2 PVCCIN_CPU1      F @BASEBOARD_FAB2_LIB.BASEBOARD_FAB2(SCH_1):PVCCIN_CPU1

SC1U10V2KX-4-GP_SMD-BCG6-SC1U1A  I109  C1E23
   1 P5V_STBY      1 @BASEBOARD_FAB2_LIB.BASEBOARD_FAB2(SCH_1):P5V_STBY
   2    GND      2 @BASEBOARD_FAB2_LIB.BASEBOARD_FAB2(SCH_1):GND

SC1U10V2KX-4-GP_SMD-BCG6-SC1U1A  I110  C1E6
   1 P5V_STBY      1 @BASEBOARD_FAB2_LIB.BASEBOARD_FAB2(SCH_1):P5V_STBY
   2    GND      2 @BASEBOARD_FAB2_LIB.BASEBOARD_FAB2(SCH_1):GND

1R3F-GP_RCL_GP-1R3F-GP,64.1R00A  I111  RT16
   1 VR_PVCCIN_CPU1_PHASE1_RC      1 @BASEBOARD_FAB2_LIB.BASEBOARD_FAB2(SCH_1):VR_PVCCIN_CPU1_PHASE1_RC
   2    GND      2 @BASEBOARD_FAB2_LIB.BASEBOARD_FAB2(SCH_1):GND

1R3F-GP_RCL_GP-1R3F-GP,64.1R00A  I112  RT18
   1 VR_PVCCIN_CPU1_PHASE2_RC      1 @BASEBOARD_FAB2_LIB.BASEBOARD_FAB2(SCH_1):VR_PVCCIN_CPU1_PHASE2_RC
   2    GND      2 @BASEBOARD_FAB2_LIB.BASEBOARD_FAB2(SCH_1):GND

IR354XX_SM-IR35411,IC,H73688-0A  I113  EU1D4
  33 VR_PVCCIN_CPU1_PH2_BOOT_R  BOOST @BASEBOARD_FAB2_LIB.BASEBOARD_FAB2(SCH_1):VR_PVCCIN_CPU1_PH2_BOOT_R
  35 P5V_STBY     EN @BASEBOARD_FAB2_LIB.BASEBOARD_FAB2(SCH_1):P5V_STBY
  41 TP_PVCCINC_CPU1_PH2_GL_1  GL<1> @BASEBOARD_FAB2_LIB.BASEBOARD_FAB2(SCH_1):TP_PVCCINC_CPU1_PH2_GL_1
   6 TP_PVCCINC_CPU1_PH2_GL_0  GL<0> @BASEBOARD_FAB2_LIB.BASEBOARD_FAB2(SCH_1):TP_PVCCINC_CPU1_PH2_GL_0
  38 ISENSE_PVCCIN_CPU1_PH2_IMON   IOUT @BASEBOARD_FAB2_LIB.BASEBOARD_FAB2(SCH_1):ISENSE_PVCCIN_CPU1_PH2_IMON
   2    GND   LGND @BASEBOARD_FAB2_LIB.BASEBOARD_FAB2(SCH_1):GND
  31     NC     NC     NC
  37 VR_PVCCIN_CPU1_PH2_OCSET  OCSET @BASEBOARD_FAB2_LIB.BASEBOARD_FAB2(SCH_1):VR_PVCCIN_CPU1_PH2_OCSET
  40    GND PGND<2> @BASEBOARD_FAB2_LIB.BASEBOARD_FAB2(SCH_1):GND
   7    GND PGND<1> @BASEBOARD_FAB2_LIB.BASEBOARD_FAB2(SCH_1):GND
   5    GND PGND<0> @BASEBOARD_FAB2_LIB.BASEBOARD_FAB2(SCH_1):GND
  32 VR_PVCCIN_CPU1_PH2_PHASE  PHASE @BASEBOARD_FAB2_LIB.BASEBOARD_FAB2(SCH_1):VR_PVCCIN_CPU1_PH2_PHASE
  34 VR_PVCCIN_CPU1_PWM2    PWM @BASEBOARD_FAB2_LIB.BASEBOARD_FAB2(SCH_1):VR_PVCCIN_CPU1_PWM2
  39 VR_PVCCIN_CPU1_AIREF2  REFIN @BASEBOARD_FAB2_LIB.BASEBOARD_FAB2(SCH_1):VR_PVCCIN_CPU1_AIREF2
  10 VR_PVCCIN_CPU1_PHASE2     SW @BASEBOARD_FAB2_LIB.BASEBOARD_FAB2(SCH_1):VR_PVCCIN_CPU1_PHASE2
  36 A_TSENSE_PVCCIN_CPU1 TOUT_FLT @BASEBOARD_FAB2_LIB.BASEBOARD_FAB2(SCH_1):A_TSENSE_PVCCIN_CPU1
   3 VR_PVCCIN_CPU1_PH2_VCIN    VCC @BASEBOARD_FAB2_LIB.BASEBOARD_FAB2(SCH_1):VR_PVCCIN_CPU1_PH2_VCIN
   4 P5V_STBY   VDRV @BASEBOARD_FAB2_LIB.BASEBOARD_FAB2(SCH_1):P5V_STBY
  30 VR_FET_SW_P12V_STBY_PVCCIN_CPU1 VIN<1> @BASEBOARD_FAB2_LIB.BASEBOARD_FAB2(SCH_1):VR_FET_SW_P12V_STBY_PVCCIN_CPU1
  25 VR_FET_SW_P12V_STBY_PVCCIN_CPU1 VIN<0> @BASEBOARD_FAB2_LIB.BASEBOARD_FAB2(SCH_1):VR_FET_SW_P12V_STBY_PVCCIN_CPU1
   1 PVCCIN_CPU1    VOS @BASEBOARD_FAB2_LIB.BASEBOARD_FAB2(SCH_1):PVCCIN_CPU1


DRAWING: @BASEBOARD_FAB2_LIB.BASEBOARD_FAB2(SCH_1):PAGE208 

RES_0603-100.0,1%,1/10W,CHIP,GA  I7  R1E3
   1 PVCCIN_CPU1      A @BASEBOARD_FAB2_LIB.BASEBOARD_FAB2(SCH_1):PVCCIN_CPU1
   2    GND      B @BASEBOARD_FAB2_LIB.BASEBOARD_FAB2(SCH_1):GND

CAP_A_0603V-22.0UF,4V,20%,X6S,A  I9  C1D14
   1 PVCCIN_CPU1      A @BASEBOARD_FAB2_LIB.BASEBOARD_FAB2(SCH_1):PVCCIN_CPU1
   2    GND      B @BASEBOARD_FAB2_LIB.BASEBOARD_FAB2(SCH_1):GND

CAPP_3018-470UF,2.5V,20%,ALUM,A  I12  C9P8
   1 PVCCIN_CPU1      A @BASEBOARD_FAB2_LIB.BASEBOARD_FAB2(SCH_1):PVCCIN_CPU1
   2    GND      B @BASEBOARD_FAB2_LIB.BASEBOARD_FAB2(SCH_1):GND

CAPP_3018-470UF,2.5V,20%,ALUM,A  I14  C9P5
   1 PVCCIN_CPU1      A @BASEBOARD_FAB2_LIB.BASEBOARD_FAB2(SCH_1):PVCCIN_CPU1
   2    GND      B @BASEBOARD_FAB2_LIB.BASEBOARD_FAB2(SCH_1):GND

CAP_A_0603V-22.0UF,4V,20%,X6S,A  I22  C1D3
   1 PVCCIN_CPU1      A @BASEBOARD_FAB2_LIB.BASEBOARD_FAB2(SCH_1):PVCCIN_CPU1
   2    GND      B @BASEBOARD_FAB2_LIB.BASEBOARD_FAB2(SCH_1):GND

CAPP_3018-470UF,2.5V,20%,ALUM,A  I24  C9N24
   1 PVCCIN_CPU1      A @BASEBOARD_FAB2_LIB.BASEBOARD_FAB2(SCH_1):PVCCIN_CPU1
   2    GND      B @BASEBOARD_FAB2_LIB.BASEBOARD_FAB2(SCH_1):GND

CAPP_3018-470UF,2.5V,20%,ALUM,A  I25  C9R9
   1 PVCCIN_CPU1      A @BASEBOARD_FAB2_LIB.BASEBOARD_FAB2(SCH_1):PVCCIN_CPU1
   2    GND      B @BASEBOARD_FAB2_LIB.BASEBOARD_FAB2(SCH_1):GND

CAPP_3018-470UF,2.5V,20%,ALUM,A  I26  C9R3
   1 PVCCIN_CPU1      A @BASEBOARD_FAB2_LIB.BASEBOARD_FAB2(SCH_1):PVCCIN_CPU1
   2    GND      B @BASEBOARD_FAB2_LIB.BASEBOARD_FAB2(SCH_1):GND

IR354XX_SM-IR35411,IC,H73688-0A  I27  EU1D3
  33 VR_PVCCIN_CPU1_PH3_BOOT_R  BOOST @BASEBOARD_FAB2_LIB.BASEBOARD_FAB2(SCH_1):VR_PVCCIN_CPU1_PH3_BOOT_R
  35 P5V_STBY     EN @BASEBOARD_FAB2_LIB.BASEBOARD_FAB2(SCH_1):P5V_STBY
  41 TP_PVCCIN_CPU1_PH3_GL_1  GL<1> @BASEBOARD_FAB2_LIB.BASEBOARD_FAB2(SCH_1):TP_PVCCIN_CPU1_PH3_GL_1
   6 TP_PVCCIN_CPU1_PH3_GL_0  GL<0> @BASEBOARD_FAB2_LIB.BASEBOARD_FAB2(SCH_1):TP_PVCCIN_CPU1_PH3_GL_0
  38 ISENSE_PVCCIN_CPU1_PH3_IMON   IOUT @BASEBOARD_FAB2_LIB.BASEBOARD_FAB2(SCH_1):ISENSE_PVCCIN_CPU1_PH3_IMON
   2    GND   LGND @BASEBOARD_FAB2_LIB.BASEBOARD_FAB2(SCH_1):GND
  31     NC     NC     NC
  37 VR_PVCCIN_CPU1_PH3_OCSET  OCSET @BASEBOARD_FAB2_LIB.BASEBOARD_FAB2(SCH_1):VR_PVCCIN_CPU1_PH3_OCSET
  40    GND PGND<2> @BASEBOARD_FAB2_LIB.BASEBOARD_FAB2(SCH_1):GND
   7    GND PGND<1> @BASEBOARD_FAB2_LIB.BASEBOARD_FAB2(SCH_1):GND
   5    GND PGND<0> @BASEBOARD_FAB2_LIB.BASEBOARD_FAB2(SCH_1):GND
  32 VR_PVCCIN_CPU1_PH3_PHASE  PHASE @BASEBOARD_FAB2_LIB.BASEBOARD_FAB2(SCH_1):VR_PVCCIN_CPU1_PH3_PHASE
  34 VR_PVCCIN_CPU1_PWM3    PWM @BASEBOARD_FAB2_LIB.BASEBOARD_FAB2(SCH_1):VR_PVCCIN_CPU1_PWM3
  39 VR_PVCCIN_CPU1_AIREF3  REFIN @BASEBOARD_FAB2_LIB.BASEBOARD_FAB2(SCH_1):VR_PVCCIN_CPU1_AIREF3
  10 VR_PVCCIN_CPU1_PHASE3     SW @BASEBOARD_FAB2_LIB.BASEBOARD_FAB2(SCH_1):VR_PVCCIN_CPU1_PHASE3
  36 A_TSENSE_PVCCIN_CPU1 TOUT_FLT @BASEBOARD_FAB2_LIB.BASEBOARD_FAB2(SCH_1):A_TSENSE_PVCCIN_CPU1
   3 VR_PVCCIN_CPU1_PH3_VCIN    VCC @BASEBOARD_FAB2_LIB.BASEBOARD_FAB2(SCH_1):VR_PVCCIN_CPU1_PH3_VCIN
   4 P5V_STBY   VDRV @BASEBOARD_FAB2_LIB.BASEBOARD_FAB2(SCH_1):P5V_STBY
  30 VR_FET_SW_P12V_STBY_PVCCIN_CPU1 VIN<1> @BASEBOARD_FAB2_LIB.BASEBOARD_FAB2(SCH_1):VR_FET_SW_P12V_STBY_PVCCIN_CPU1
  25 VR_FET_SW_P12V_STBY_PVCCIN_CPU1 VIN<0> @BASEBOARD_FAB2_LIB.BASEBOARD_FAB2(SCH_1):VR_FET_SW_P12V_STBY_PVCCIN_CPU1
   1 PVCCIN_CPU1    VOS @BASEBOARD_FAB2_LIB.BASEBOARD_FAB2(SCH_1):PVCCIN_CPU1

CAPP_3018-470UF,2.5V,20%,ALUM,A  I28  C9P23
   1 PVCCIN_CPU1      A @BASEBOARD_FAB2_LIB.BASEBOARD_FAB2(SCH_1):PVCCIN_CPU1
   2    GND      B @BASEBOARD_FAB2_LIB.BASEBOARD_FAB2(SCH_1):GND

CAPP_3018-470UF,2.5V,20%,ALUM,A  I30  C9P18
   1 PVCCIN_CPU1      A @BASEBOARD_FAB2_LIB.BASEBOARD_FAB2(SCH_1):PVCCIN_CPU1
   2    GND      B @BASEBOARD_FAB2_LIB.BASEBOARD_FAB2(SCH_1):GND

CAP_0402-0.22UF,16V,10%,X7R,A3A  I38  C1D16
   1 P5V_STBY      A @BASEBOARD_FAB2_LIB.BASEBOARD_FAB2(SCH_1):P5V_STBY
   2    GND      B @BASEBOARD_FAB2_LIB.BASEBOARD_FAB2(SCH_1):GND

CAP_0402-0.220UF,16V,10%,X7R,AA  I40  C1D20
   1 VR_PVCCIN_CPU1_PH3_BOOT      A @BASEBOARD_FAB2_LIB.BASEBOARD_FAB2(SCH_1):VR_PVCCIN_CPU1_PH3_BOOT
   2 VR_PVCCIN_CPU1_PH3_PHASE      B @BASEBOARD_FAB2_LIB.BASEBOARD_FAB2(SCH_1):VR_PVCCIN_CPU1_PH3_PHASE

CAP_0402-1.0UF,16V,10%,X6S,D97A  I43  C1D17
   1 VR_PVCCIN_CPU1_PH3_VCIN      A @BASEBOARD_FAB2_LIB.BASEBOARD_FAB2(SCH_1):VR_PVCCIN_CPU1_PH3_VCIN
   2    GND      B @BASEBOARD_FAB2_LIB.BASEBOARD_FAB2(SCH_1):GND

CAP_A_0402V-0.1UF,16V,10%,X7R,A  I44  C1D28
   1 VR_FET_SW_P12V_STBY_PVCCIN_CPU1      A @BASEBOARD_FAB2_LIB.BASEBOARD_FAB2(SCH_1):VR_FET_SW_P12V_STBY_PVCCIN_CPU1
   2    GND      B @BASEBOARD_FAB2_LIB.BASEBOARD_FAB2(SCH_1):GND

CAP_0402-1.0UF,16V,10%,X6S,D97A  I45  C1D23
   1 VR_FET_SW_P12V_STBY_PVCCIN_CPU1      A @BASEBOARD_FAB2_LIB.BASEBOARD_FAB2(SCH_1):VR_FET_SW_P12V_STBY_PVCCIN_CPU1
   2    GND      B @BASEBOARD_FAB2_LIB.BASEBOARD_FAB2(SCH_1):GND

CAP_0402-0.22UF,16V,10%,X7R,A3A  I46  C1D6
   1 P5V_STBY      A @BASEBOARD_FAB2_LIB.BASEBOARD_FAB2(SCH_1):P5V_STBY
   2    GND      B @BASEBOARD_FAB2_LIB.BASEBOARD_FAB2(SCH_1):GND

CAP_0402-0.220UF,16V,10%,X7R,AA  I48  C1D10
   1 VR_PVCCIN_CPU1_PH4_BOOT      A @BASEBOARD_FAB2_LIB.BASEBOARD_FAB2(SCH_1):VR_PVCCIN_CPU1_PH4_BOOT
   2 VR_PVCCIN_CPU1_PH4_PHASE      B @BASEBOARD_FAB2_LIB.BASEBOARD_FAB2(SCH_1):VR_PVCCIN_CPU1_PH4_PHASE

CAP_0402-1.0UF,16V,10%,X6S,D97A  I50  C1D7
   1 VR_PVCCIN_CPU1_PH4_VCIN      A @BASEBOARD_FAB2_LIB.BASEBOARD_FAB2(SCH_1):VR_PVCCIN_CPU1_PH4_VCIN
   2    GND      B @BASEBOARD_FAB2_LIB.BASEBOARD_FAB2(SCH_1):GND

CAP_A_0402V-0.1UF,16V,10%,X7R,A  I51  C1D13
   1 VR_FET_SW_P12V_STBY_PVCCIN_CPU1      A @BASEBOARD_FAB2_LIB.BASEBOARD_FAB2(SCH_1):VR_FET_SW_P12V_STBY_PVCCIN_CPU1
   2    GND      B @BASEBOARD_FAB2_LIB.BASEBOARD_FAB2(SCH_1):GND

CAP_0402-1.0UF,16V,10%,X6S,D97A  I52  C1D12
   1 VR_FET_SW_P12V_STBY_PVCCIN_CPU1      A @BASEBOARD_FAB2_LIB.BASEBOARD_FAB2(SCH_1):VR_FET_SW_P12V_STBY_PVCCIN_CPU1
   2    GND      B @BASEBOARD_FAB2_LIB.BASEBOARD_FAB2(SCH_1):GND

CAP_0805-10UF,16V,10%,X6S,C953A  I53  C9P4
   1 VR_FET_SW_P12V_STBY_PVCCIN_CPU1      A @BASEBOARD_FAB2_LIB.BASEBOARD_FAB2(SCH_1):VR_FET_SW_P12V_STBY_PVCCIN_CPU1
   2    GND      B @BASEBOARD_FAB2_LIB.BASEBOARD_FAB2(SCH_1):GND

CAP_0805-10UF,16V,10%,X6S,C953A  I54  C9P7
   1 VR_FET_SW_P12V_STBY_PVCCIN_CPU1      A @BASEBOARD_FAB2_LIB.BASEBOARD_FAB2(SCH_1):VR_FET_SW_P12V_STBY_PVCCIN_CPU1
   2    GND      B @BASEBOARD_FAB2_LIB.BASEBOARD_FAB2(SCH_1):GND

CAP_0805-10UF,16V,10%,X6S,C953A  I55  C9P9
   1 VR_FET_SW_P12V_STBY_PVCCIN_CPU1      A @BASEBOARD_FAB2_LIB.BASEBOARD_FAB2(SCH_1):VR_FET_SW_P12V_STBY_PVCCIN_CPU1
   2    GND      B @BASEBOARD_FAB2_LIB.BASEBOARD_FAB2(SCH_1):GND

CAP_0805-10UF,16V,10%,X6S,C953A  I58  C9P24
   1 VR_FET_SW_P12V_STBY_PVCCIN_CPU1      A @BASEBOARD_FAB2_LIB.BASEBOARD_FAB2(SCH_1):VR_FET_SW_P12V_STBY_PVCCIN_CPU1
   2    GND      B @BASEBOARD_FAB2_LIB.BASEBOARD_FAB2(SCH_1):GND

CAP_0805-10UF,16V,10%,X6S,C953A  I59  C9P1
   1 VR_FET_SW_P12V_STBY_PVCCIN_CPU1      A @BASEBOARD_FAB2_LIB.BASEBOARD_FAB2(SCH_1):VR_FET_SW_P12V_STBY_PVCCIN_CPU1
   2    GND      B @BASEBOARD_FAB2_LIB.BASEBOARD_FAB2(SCH_1):GND

CAP_0805-10UF,16V,10%,X6S,C953A  I60  C9P2
   1 VR_FET_SW_P12V_STBY_PVCCIN_CPU1      A @BASEBOARD_FAB2_LIB.BASEBOARD_FAB2(SCH_1):VR_FET_SW_P12V_STBY_PVCCIN_CPU1
   2    GND      B @BASEBOARD_FAB2_LIB.BASEBOARD_FAB2(SCH_1):GND

CAP_A_0603V-22.0UF,4V,20%,X6S,A  I66  C9P10
   1 PVCCIN_CPU1      A @BASEBOARD_FAB2_LIB.BASEBOARD_FAB2(SCH_1):PVCCIN_CPU1
   2    GND      B @BASEBOARD_FAB2_LIB.BASEBOARD_FAB2(SCH_1):GND

CAP_A_0603V-22.0UF,4V,20%,X6S,A  I67  C9R2
   1 PVCCIN_CPU1      A @BASEBOARD_FAB2_LIB.BASEBOARD_FAB2(SCH_1):PVCCIN_CPU1
   2    GND      B @BASEBOARD_FAB2_LIB.BASEBOARD_FAB2(SCH_1):GND

IR354XX_SM-IR35411,IC,H73688-0A  I71  EU1D1
  33 VR_PVCCIN_CPU1_PH4_BOOT_R  BOOST @BASEBOARD_FAB2_LIB.BASEBOARD_FAB2(SCH_1):VR_PVCCIN_CPU1_PH4_BOOT_R
  35 P5V_STBY     EN @BASEBOARD_FAB2_LIB.BASEBOARD_FAB2(SCH_1):P5V_STBY
  41 TP_PVCCIN_CPU1_PH4_GL_1  GL<1> @BASEBOARD_FAB2_LIB.BASEBOARD_FAB2(SCH_1):TP_PVCCIN_CPU1_PH4_GL_1
   6 TP_PVCCIN_CPU1_PH4_GL_0  GL<0> @BASEBOARD_FAB2_LIB.BASEBOARD_FAB2(SCH_1):TP_PVCCIN_CPU1_PH4_GL_0
  38 ISENSE_PVCCIN_CPU1_PH4_IMON   IOUT @BASEBOARD_FAB2_LIB.BASEBOARD_FAB2(SCH_1):ISENSE_PVCCIN_CPU1_PH4_IMON
   2    GND   LGND @BASEBOARD_FAB2_LIB.BASEBOARD_FAB2(SCH_1):GND
  31     NC     NC     NC
  37 VR_PVCCIN_CPU1_PH4_OCSET  OCSET @BASEBOARD_FAB2_LIB.BASEBOARD_FAB2(SCH_1):VR_PVCCIN_CPU1_PH4_OCSET
  40    GND PGND<2> @BASEBOARD_FAB2_LIB.BASEBOARD_FAB2(SCH_1):GND
   7    GND PGND<1> @BASEBOARD_FAB2_LIB.BASEBOARD_FAB2(SCH_1):GND
   5    GND PGND<0> @BASEBOARD_FAB2_LIB.BASEBOARD_FAB2(SCH_1):GND
  32 VR_PVCCIN_CPU1_PH4_PHASE  PHASE @BASEBOARD_FAB2_LIB.BASEBOARD_FAB2(SCH_1):VR_PVCCIN_CPU1_PH4_PHASE
  34 VR_PVCCIN_CPU1_PWM4    PWM @BASEBOARD_FAB2_LIB.BASEBOARD_FAB2(SCH_1):VR_PVCCIN_CPU1_PWM4
  39 VR_PVCCIN_CPU1_AIREF4  REFIN @BASEBOARD_FAB2_LIB.BASEBOARD_FAB2(SCH_1):VR_PVCCIN_CPU1_AIREF4
  10 VR_PVCCIN_CPU1_PHASE4     SW @BASEBOARD_FAB2_LIB.BASEBOARD_FAB2(SCH_1):VR_PVCCIN_CPU1_PHASE4
  36 A_TSENSE_PVCCIN_CPU1 TOUT_FLT @BASEBOARD_FAB2_LIB.BASEBOARD_FAB2(SCH_1):A_TSENSE_PVCCIN_CPU1
   3 VR_PVCCIN_CPU1_PH4_VCIN    VCC @BASEBOARD_FAB2_LIB.BASEBOARD_FAB2(SCH_1):VR_PVCCIN_CPU1_PH4_VCIN
   4 P5V_STBY   VDRV @BASEBOARD_FAB2_LIB.BASEBOARD_FAB2(SCH_1):P5V_STBY
  30 VR_FET_SW_P12V_STBY_PVCCIN_CPU1 VIN<1> @BASEBOARD_FAB2_LIB.BASEBOARD_FAB2(SCH_1):VR_FET_SW_P12V_STBY_PVCCIN_CPU1
  25 VR_FET_SW_P12V_STBY_PVCCIN_CPU1 VIN<0> @BASEBOARD_FAB2_LIB.BASEBOARD_FAB2(SCH_1):VR_FET_SW_P12V_STBY_PVCCIN_CPU1
   1 PVCCIN_CPU1    VOS @BASEBOARD_FAB2_LIB.BASEBOARD_FAB2(SCH_1):PVCCIN_CPU1

RES_0402-68.1K,1%,1/16W,EMPTY,A  I75  R1D54
   1 VR_PVCCIN_CPU1_PH4_OCSET      A @BASEBOARD_FAB2_LIB.BASEBOARD_FAB2(SCH_1):VR_PVCCIN_CPU1_PH4_OCSET
   2    GND      B @BASEBOARD_FAB2_LIB.BASEBOARD_FAB2(SCH_1):GND

RES_0402-68.1K,1%,1/16W,EMPTY,A  I76  R1D55
   1 VR_PVCCIN_CPU1_PH3_OCSET      A @BASEBOARD_FAB2_LIB.BASEBOARD_FAB2(SCH_1):VR_PVCCIN_CPU1_PH3_OCSET
   2    GND      B @BASEBOARD_FAB2_LIB.BASEBOARD_FAB2(SCH_1):GND

CAP_A_0402V-0.1UF,16V,10%,X7R,A  I80  CT16
   1 VR_PVCCIN_CPU1_AIREF3      A @BASEBOARD_FAB2_LIB.BASEBOARD_FAB2(SCH_1):VR_PVCCIN_CPU1_AIREF3
   2    GND      B @BASEBOARD_FAB2_LIB.BASEBOARD_FAB2(SCH_1):GND

CAP_0402LF-1000PF,50V,10%,X7R,A  I82  CTI7
   1 A_TSENSE_PVCCIN_CPU1      A @BASEBOARD_FAB2_LIB.BASEBOARD_FAB2(SCH_1):A_TSENSE_PVCCIN_CPU1
   2    GND      B @BASEBOARD_FAB2_LIB.BASEBOARD_FAB2(SCH_1):GND

CAP_A_0402V-0.1UF,16V,10%,X7R,A  I87  CT21
   1 VR_PVCCIN_CPU1_AIREF4      A @BASEBOARD_FAB2_LIB.BASEBOARD_FAB2(SCH_1):VR_PVCCIN_CPU1_AIREF4
   2    GND      B @BASEBOARD_FAB2_LIB.BASEBOARD_FAB2(SCH_1):GND

CAP_0402LF-1000PF,50V,10%,X7R,A  I90  CT19
   1 A_TSENSE_PVCCIN_CPU1      A @BASEBOARD_FAB2_LIB.BASEBOARD_FAB2(SCH_1):A_TSENSE_PVCCIN_CPU1
   2    GND      B @BASEBOARD_FAB2_LIB.BASEBOARD_FAB2(SCH_1):GND

CAP_0402LF-1000PF,50V,10%,X7R,A  I104  CT18
   1 VR_PVCCIN_CPU1_PHASE3      A @BASEBOARD_FAB2_LIB.BASEBOARD_FAB2(SCH_1):VR_PVCCIN_CPU1_PHASE3
   2 VR_PVCCIN_CPU1_PHASE3_RC      B @BASEBOARD_FAB2_LIB.BASEBOARD_FAB2(SCH_1):VR_PVCCIN_CPU1_PHASE3_RC

CAP_0402LF-1000PF,50V,10%,X7R,A  I105  CT20
   1 VR_PVCCIN_CPU1_PHASE4      A @BASEBOARD_FAB2_LIB.BASEBOARD_FAB2(SCH_1):VR_PVCCIN_CPU1_PHASE4
   2 VR_PVCCIN_CPU1_PHASE4_RC      B @BASEBOARD_FAB2_LIB.BASEBOARD_FAB2(SCH_1):VR_PVCCIN_CPU1_PHASE4_RC

RES_0603-0,5.0%,1/10W,CHIP,G22A  I108  RT11
   1 VR_PVCCIN_CPU1_PH3_BOOT      A @BASEBOARD_FAB2_LIB.BASEBOARD_FAB2(SCH_1):VR_PVCCIN_CPU1_PH3_BOOT
   2 VR_PVCCIN_CPU1_PH3_BOOT_R      B @BASEBOARD_FAB2_LIB.BASEBOARD_FAB2(SCH_1):VR_PVCCIN_CPU1_PH3_BOOT_R

RES_0603-0,5.0%,1/10W,CHIP,G22A  I109  RT14
   1 VR_PVCCIN_CPU1_PH4_BOOT      A @BASEBOARD_FAB2_LIB.BASEBOARD_FAB2(SCH_1):VR_PVCCIN_CPU1_PH4_BOOT
   2 VR_PVCCIN_CPU1_PH4_BOOT_R      B @BASEBOARD_FAB2_LIB.BASEBOARD_FAB2(SCH_1):VR_PVCCIN_CPU1_PH4_BOOT_R

RES_0402-0.0,5%,1/16W,CHIP,G21A  I114  R9P22
   1 VR_PVCCIN_CPU1_PH3_VCIN      A @BASEBOARD_FAB2_LIB.BASEBOARD_FAB2(SCH_1):VR_PVCCIN_CPU1_PH3_VCIN
   2 P5V_STBY      B @BASEBOARD_FAB2_LIB.BASEBOARD_FAB2(SCH_1):P5V_STBY

RES_0402-0.0,5%,1/16W,CHIP,G21A  I115  R9P8
   1 VR_PVCCIN_CPU1_PH4_VCIN      A @BASEBOARD_FAB2_LIB.BASEBOARD_FAB2(SCH_1):VR_PVCCIN_CPU1_PH4_VCIN
   2 P5V_STBY      B @BASEBOARD_FAB2_LIB.BASEBOARD_FAB2(SCH_1):P5V_STBY

IND-120NH-30-GP_DISCRET-GB2-INA  I116  L1D2
   1 VR_PVCCIN_CPU1_PHASE3      S @BASEBOARD_FAB2_LIB.BASEBOARD_FAB2(SCH_1):VR_PVCCIN_CPU1_PHASE3
   2 PVCCIN_CPU1      F @BASEBOARD_FAB2_LIB.BASEBOARD_FAB2(SCH_1):PVCCIN_CPU1

IND-120NH-30-GP_DISCRET-GB2-INA  I117  L1D1
   1 VR_PVCCIN_CPU1_PHASE4      S @BASEBOARD_FAB2_LIB.BASEBOARD_FAB2(SCH_1):VR_PVCCIN_CPU1_PHASE4
   2 PVCCIN_CPU1      F @BASEBOARD_FAB2_LIB.BASEBOARD_FAB2(SCH_1):PVCCIN_CPU1

SC1U10V2KX-4-GP_SMD-BCG6-SC1U1A  I118  C1D15
   1 P5V_STBY      1 @BASEBOARD_FAB2_LIB.BASEBOARD_FAB2(SCH_1):P5V_STBY
   2    GND      2 @BASEBOARD_FAB2_LIB.BASEBOARD_FAB2(SCH_1):GND

SC1U10V2KX-4-GP_SMD-BCG6-SC1U1A  I119  C1D5
   1 P5V_STBY      1 @BASEBOARD_FAB2_LIB.BASEBOARD_FAB2(SCH_1):P5V_STBY
   2    GND      2 @BASEBOARD_FAB2_LIB.BASEBOARD_FAB2(SCH_1):GND

1R3F-GP_RCL_GP-1R3F-GP,64.1R00A  I120  RT12
   1 VR_PVCCIN_CPU1_PHASE3_RC      1 @BASEBOARD_FAB2_LIB.BASEBOARD_FAB2(SCH_1):VR_PVCCIN_CPU1_PHASE3_RC
   2    GND      2 @BASEBOARD_FAB2_LIB.BASEBOARD_FAB2(SCH_1):GND

1R3F-GP_RCL_GP-1R3F-GP,64.1R00A  I121  RT13
   1 VR_PVCCIN_CPU1_PHASE4_RC      1 @BASEBOARD_FAB2_LIB.BASEBOARD_FAB2(SCH_1):VR_PVCCIN_CPU1_PHASE4_RC
   2    GND      2 @BASEBOARD_FAB2_LIB.BASEBOARD_FAB2(SCH_1):GND


DRAWING: @BASEBOARD_FAB2_LIB.BASEBOARD_FAB2(SCH_1):PAGE209 

RES_0402-1.00K,1%,1/16W,EMPTY,A  I3  R1E5
   1 VSENSE_PVCCIN_CPU1_P      A @BASEBOARD_FAB2_LIB.BASEBOARD_FAB2(SCH_1):VSENSE_PVCCIN_CPU1_P
   2 VSENSE_PVCCIN_CPU1_N      B @BASEBOARD_FAB2_LIB.BASEBOARD_FAB2(SCH_1):VSENSE_PVCCIN_CPU1_N

CAP_0805-10UF,16V,10%,X6S,C953A  I5  C9N27
   1 VR_FET_SW_P12V_STBY_PVCCIN_CPU1      A @BASEBOARD_FAB2_LIB.BASEBOARD_FAB2(SCH_1):VR_FET_SW_P12V_STBY_PVCCIN_CPU1
   2    GND      B @BASEBOARD_FAB2_LIB.BASEBOARD_FAB2(SCH_1):GND

CAP_0805-10UF,16V,10%,X6S,C953A  I7  C9N26
   1 VR_FET_SW_P12V_STBY_PVCCIN_CPU1      A @BASEBOARD_FAB2_LIB.BASEBOARD_FAB2(SCH_1):VR_FET_SW_P12V_STBY_PVCCIN_CPU1
   2    GND      B @BASEBOARD_FAB2_LIB.BASEBOARD_FAB2(SCH_1):GND

CAP_0805-10UF,16V,10%,X6S,C953A  I8  C9N25
   1 VR_FET_SW_P12V_STBY_PVCCIN_CPU1      A @BASEBOARD_FAB2_LIB.BASEBOARD_FAB2(SCH_1):VR_FET_SW_P12V_STBY_PVCCIN_CPU1
   2    GND      B @BASEBOARD_FAB2_LIB.BASEBOARD_FAB2(SCH_1):GND

RES_0402-100.0,1%,1/16W,CHIP,GA  I9  R1E8
   1 VSENSE_PVCCIN_CPU1_N      A @BASEBOARD_FAB2_LIB.BASEBOARD_FAB2(SCH_1):VSENSE_PVCCIN_CPU1_N
   2    GND      B @BASEBOARD_FAB2_LIB.BASEBOARD_FAB2(SCH_1):GND

RES_0402-0.0,5%,1/16W,CHIP,G21A  I10  R1E7
   1 VSENSE_PVCCIN_CPU1_N      A @BASEBOARD_FAB2_LIB.BASEBOARD_FAB2(SCH_1):VSENSE_PVCCIN_CPU1_N
   2 VSENSE_PVCCIN_CPU1_SKT_VRTN      B @BASEBOARD_FAB2_LIB.BASEBOARD_FAB2(SCH_1):VSENSE_PVCCIN_CPU1_SKT_VRTN

RES_0402-0.0,5%,1/16W,CHIP,G21A  I11  R1E6
   1 VSENSE_PVCCIN_CPU1_P      A @BASEBOARD_FAB2_LIB.BASEBOARD_FAB2(SCH_1):VSENSE_PVCCIN_CPU1_P
   2 VSENSE_PVCCIN_CPU1_SKT_VSEN      B @BASEBOARD_FAB2_LIB.BASEBOARD_FAB2(SCH_1):VSENSE_PVCCIN_CPU1_SKT_VSEN

RES_0402-100.0,1%,1/16W,CHIP,GA  I15  R1E4
   1 VSENSE_PVCCIN_CPU1_P      A @BASEBOARD_FAB2_LIB.BASEBOARD_FAB2(SCH_1):VSENSE_PVCCIN_CPU1_P
   2 PVCCIN_CPU1      B @BASEBOARD_FAB2_LIB.BASEBOARD_FAB2(SCH_1):PVCCIN_CPU1

CAP_0402-1.0UF,16V,10%,X6S,D97A  I16  C1C26
   1 VR_FET_SW_P12V_STBY_PVCCIN_CPU1      A @BASEBOARD_FAB2_LIB.BASEBOARD_FAB2(SCH_1):VR_FET_SW_P12V_STBY_PVCCIN_CPU1
   2    GND      B @BASEBOARD_FAB2_LIB.BASEBOARD_FAB2(SCH_1):GND

CAP_A_0402V-0.1UF,16V,10%,X7R,A  I17  C1C25
   1 VR_FET_SW_P12V_STBY_PVCCIN_CPU1      A @BASEBOARD_FAB2_LIB.BASEBOARD_FAB2(SCH_1):VR_FET_SW_P12V_STBY_PVCCIN_CPU1
   2    GND      B @BASEBOARD_FAB2_LIB.BASEBOARD_FAB2(SCH_1):GND

CAP_0402-1.0UF,16V,10%,X6S,D97A  I18  C1D32
   1 VR_PVCCIN_CPU1_PH5_VCIN      A @BASEBOARD_FAB2_LIB.BASEBOARD_FAB2(SCH_1):VR_PVCCIN_CPU1_PH5_VCIN
   2    GND      B @BASEBOARD_FAB2_LIB.BASEBOARD_FAB2(SCH_1):GND

CAP_0402-0.220UF,16V,10%,X7R,AA  I20  C1C24
   1 VR_PVCCIN_CPU1_PH5_BOOT      A @BASEBOARD_FAB2_LIB.BASEBOARD_FAB2(SCH_1):VR_PVCCIN_CPU1_PH5_BOOT
   2 VR_PVCCIN_CPU1_PH5_PHASE      B @BASEBOARD_FAB2_LIB.BASEBOARD_FAB2(SCH_1):VR_PVCCIN_CPU1_PH5_PHASE

CAP_0402-0.22UF,16V,10%,X7R,A3A  I22  C1D33
   1 P5V_STBY      A @BASEBOARD_FAB2_LIB.BASEBOARD_FAB2(SCH_1):P5V_STBY
   2    GND      B @BASEBOARD_FAB2_LIB.BASEBOARD_FAB2(SCH_1):GND

CAPP_2626-270UF,16V,20%,OSCON,A  I35  C1C1
   1 VR_FET_SW_P12V_STBY_PVCCIN_CPU1      A @BASEBOARD_FAB2_LIB.BASEBOARD_FAB2(SCH_1):VR_FET_SW_P12V_STBY_PVCCIN_CPU1
   2    GND      B @BASEBOARD_FAB2_LIB.BASEBOARD_FAB2(SCH_1):GND

CAPP_2626-270UF,16V,20%,OSCON,A  I37  C1E18
   1 VR_FET_SW_P12V_STBY_PVCCIN_CPU1      A @BASEBOARD_FAB2_LIB.BASEBOARD_FAB2(SCH_1):VR_FET_SW_P12V_STBY_PVCCIN_CPU1
   2    GND      B @BASEBOARD_FAB2_LIB.BASEBOARD_FAB2(SCH_1):GND

CAPP_2626-270UF,16V,20%,OSCON,A  I38  C1C2
   1 VR_FET_SW_P12V_STBY_PVCCIN_CPU1      A @BASEBOARD_FAB2_LIB.BASEBOARD_FAB2(SCH_1):VR_FET_SW_P12V_STBY_PVCCIN_CPU1
   2    GND      B @BASEBOARD_FAB2_LIB.BASEBOARD_FAB2(SCH_1):GND

CAP_A_0603V-22.0UF,4V,20%,X6S,A  I42  C1D24
   1 PVCCIN_CPU1      A @BASEBOARD_FAB2_LIB.BASEBOARD_FAB2(SCH_1):PVCCIN_CPU1
   2    GND      B @BASEBOARD_FAB2_LIB.BASEBOARD_FAB2(SCH_1):GND

CAP_A_0603V-22.0UF,4V,20%,X6S,A  I55  C9P20
   1 PVCCIN_CPU1      A @BASEBOARD_FAB2_LIB.BASEBOARD_FAB2(SCH_1):PVCCIN_CPU1
   2    GND      B @BASEBOARD_FAB2_LIB.BASEBOARD_FAB2(SCH_1):GND

IR354XX_SM-IR35411,IC,H73688-0A  I56  EU1C3
  33 VR_PVCCIN_CPU1_PH5_BOOT_R  BOOST @BASEBOARD_FAB2_LIB.BASEBOARD_FAB2(SCH_1):VR_PVCCIN_CPU1_PH5_BOOT_R
  35 P5V_STBY     EN @BASEBOARD_FAB2_LIB.BASEBOARD_FAB2(SCH_1):P5V_STBY
  41 TP_PVCCIN_CPU1_PH5_GL_1  GL<1> @BASEBOARD_FAB2_LIB.BASEBOARD_FAB2(SCH_1):TP_PVCCIN_CPU1_PH5_GL_1
   6 TP_PVCCIN_CPU1_PH5_GL_0  GL<0> @BASEBOARD_FAB2_LIB.BASEBOARD_FAB2(SCH_1):TP_PVCCIN_CPU1_PH5_GL_0
  38 ISENSE_PVCCIN_CPU1_PH5_IMON   IOUT @BASEBOARD_FAB2_LIB.BASEBOARD_FAB2(SCH_1):ISENSE_PVCCIN_CPU1_PH5_IMON
   2    GND   LGND @BASEBOARD_FAB2_LIB.BASEBOARD_FAB2(SCH_1):GND
  31     NC     NC     NC
  37 VR_PVCCIN_CPU1_PH5_OCSET  OCSET @BASEBOARD_FAB2_LIB.BASEBOARD_FAB2(SCH_1):VR_PVCCIN_CPU1_PH5_OCSET
  40    GND PGND<2> @BASEBOARD_FAB2_LIB.BASEBOARD_FAB2(SCH_1):GND
   7    GND PGND<1> @BASEBOARD_FAB2_LIB.BASEBOARD_FAB2(SCH_1):GND
   5    GND PGND<0> @BASEBOARD_FAB2_LIB.BASEBOARD_FAB2(SCH_1):GND
  32 VR_PVCCIN_CPU1_PH5_PHASE  PHASE @BASEBOARD_FAB2_LIB.BASEBOARD_FAB2(SCH_1):VR_PVCCIN_CPU1_PH5_PHASE
  34 VR_PVCCIN_CPU1_PWM5    PWM @BASEBOARD_FAB2_LIB.BASEBOARD_FAB2(SCH_1):VR_PVCCIN_CPU1_PWM5
  39 VR_PVCCIN_CPU1_AIREF5  REFIN @BASEBOARD_FAB2_LIB.BASEBOARD_FAB2(SCH_1):VR_PVCCIN_CPU1_AIREF5
  10 VR_PVCCIN_CPU1_PHASE5     SW @BASEBOARD_FAB2_LIB.BASEBOARD_FAB2(SCH_1):VR_PVCCIN_CPU1_PHASE5
  36 A_TSENSE_PVCCIN_CPU1 TOUT_FLT @BASEBOARD_FAB2_LIB.BASEBOARD_FAB2(SCH_1):A_TSENSE_PVCCIN_CPU1
   3 VR_PVCCIN_CPU1_PH5_VCIN    VCC @BASEBOARD_FAB2_LIB.BASEBOARD_FAB2(SCH_1):VR_PVCCIN_CPU1_PH5_VCIN
   4 P5V_STBY   VDRV @BASEBOARD_FAB2_LIB.BASEBOARD_FAB2(SCH_1):P5V_STBY
  30 VR_FET_SW_P12V_STBY_PVCCIN_CPU1 VIN<1> @BASEBOARD_FAB2_LIB.BASEBOARD_FAB2(SCH_1):VR_FET_SW_P12V_STBY_PVCCIN_CPU1
  25 VR_FET_SW_P12V_STBY_PVCCIN_CPU1 VIN<0> @BASEBOARD_FAB2_LIB.BASEBOARD_FAB2(SCH_1):VR_FET_SW_P12V_STBY_PVCCIN_CPU1
   1 PVCCIN_CPU1    VOS @BASEBOARD_FAB2_LIB.BASEBOARD_FAB2(SCH_1):PVCCIN_CPU1

RES_0402-68.1K,1%,1/16W,EMPTY,A  I59  R1D52
   1 VR_PVCCIN_CPU1_PH5_OCSET      A @BASEBOARD_FAB2_LIB.BASEBOARD_FAB2(SCH_1):VR_PVCCIN_CPU1_PH5_OCSET
   2    GND      B @BASEBOARD_FAB2_LIB.BASEBOARD_FAB2(SCH_1):GND

CAP_A_0402V-0.1UF,16V,10%,X7R,A  I62  CT13
   1 VR_PVCCIN_CPU1_AIREF5      A @BASEBOARD_FAB2_LIB.BASEBOARD_FAB2(SCH_1):VR_PVCCIN_CPU1_AIREF5
   2    GND      B @BASEBOARD_FAB2_LIB.BASEBOARD_FAB2(SCH_1):GND

CAP_0402LF-1000PF,50V,10%,X7R,A  I67  CT15
   1 A_TSENSE_PVCCIN_CPU1      A @BASEBOARD_FAB2_LIB.BASEBOARD_FAB2(SCH_1):A_TSENSE_PVCCIN_CPU1
   2    GND      B @BASEBOARD_FAB2_LIB.BASEBOARD_FAB2(SCH_1):GND

CAP_0402LF-1000PF,50V,10%,X7R,A  I73  CT14
   1 VR_PVCCIN_CPU1_PHASE5      A @BASEBOARD_FAB2_LIB.BASEBOARD_FAB2(SCH_1):VR_PVCCIN_CPU1_PHASE5
   2 VR_PVCCIN_CPU1_PHASE5_RC      B @BASEBOARD_FAB2_LIB.BASEBOARD_FAB2(SCH_1):VR_PVCCIN_CPU1_PHASE5_RC

RES_0603-0,5.0%,1/10W,CHIP,G22A  I75  RT9
   1 VR_PVCCIN_CPU1_PH5_BOOT      A @BASEBOARD_FAB2_LIB.BASEBOARD_FAB2(SCH_1):VR_PVCCIN_CPU1_PH5_BOOT
   2 VR_PVCCIN_CPU1_PH5_BOOT_R      B @BASEBOARD_FAB2_LIB.BASEBOARD_FAB2(SCH_1):VR_PVCCIN_CPU1_PH5_BOOT_R

RES_0402-0.0,5%,1/16W,CHIP,G21A  I79  R9P32
   1 VR_PVCCIN_CPU1_PH5_VCIN      A @BASEBOARD_FAB2_LIB.BASEBOARD_FAB2(SCH_1):VR_PVCCIN_CPU1_PH5_VCIN
   2 P5V_STBY      B @BASEBOARD_FAB2_LIB.BASEBOARD_FAB2(SCH_1):P5V_STBY

IND-120NH-30-GP_DISCRET-GB2-INA  I80  L1C2
   1 VR_PVCCIN_CPU1_PHASE5      S @BASEBOARD_FAB2_LIB.BASEBOARD_FAB2(SCH_1):VR_PVCCIN_CPU1_PHASE5
   2 PVCCIN_CPU1      F @BASEBOARD_FAB2_LIB.BASEBOARD_FAB2(SCH_1):PVCCIN_CPU1

IND-80NH-1-GP_DISCRET-GC2-IND-A  I81  L1B2
   1 P12V_STBY      S @BASEBOARD_FAB2_LIB.BASEBOARD_FAB2(SCH_1):P12V_STBY
   2 VR_FET_SW_P12V_STBY_PVCCIN_CPU1      F @BASEBOARD_FAB2_LIB.BASEBOARD_FAB2(SCH_1):VR_FET_SW_P12V_STBY_PVCCIN_CPU1

SC1U10V2KX-4-GP_SMD-BCG6-SC1U1A  I89  C1C18
   1 P5V_STBY      1 @BASEBOARD_FAB2_LIB.BASEBOARD_FAB2(SCH_1):P5V_STBY
   2    GND      2 @BASEBOARD_FAB2_LIB.BASEBOARD_FAB2(SCH_1):GND

1R3F-GP_RCL_GP-1R3F-GP,64.1R00A  I90  RT10
   1 VR_PVCCIN_CPU1_PHASE5_RC      1 @BASEBOARD_FAB2_LIB.BASEBOARD_FAB2(SCH_1):VR_PVCCIN_CPU1_PHASE5_RC
   2    GND      2 @BASEBOARD_FAB2_LIB.BASEBOARD_FAB2(SCH_1):GND


DRAWING: @BASEBOARD_FAB2_LIB.BASEBOARD_FAB2(SCH_1):PAGE210 

CAP_A_0603V-22.0UF,4V,20%,X6S,A  I8  C1C19
   1 PVSA_CPU1      A @BASEBOARD_FAB2_LIB.BASEBOARD_FAB2(SCH_1):PVSA_CPU1
   2    GND      B @BASEBOARD_FAB2_LIB.BASEBOARD_FAB2(SCH_1):GND

CAPP_3018-470UF,2.5V,20%,ALUM,A  I12  C9N11
   1 PVSA_CPU1      A @BASEBOARD_FAB2_LIB.BASEBOARD_FAB2(SCH_1):PVSA_CPU1
   2    GND      B @BASEBOARD_FAB2_LIB.BASEBOARD_FAB2(SCH_1):GND

CAPP_3018-470UF,2.5V,20%,ALUM,A  I14  C9N20
   1 PVSA_CPU1      A @BASEBOARD_FAB2_LIB.BASEBOARD_FAB2(SCH_1):PVSA_CPU1
   2    GND      B @BASEBOARD_FAB2_LIB.BASEBOARD_FAB2(SCH_1):GND

CAP_0402-0.22UF,16V,10%,X7R,A3A  I22  C1C4
   1 P5V_STBY      A @BASEBOARD_FAB2_LIB.BASEBOARD_FAB2(SCH_1):P5V_STBY
   2    GND      B @BASEBOARD_FAB2_LIB.BASEBOARD_FAB2(SCH_1):GND

CAP_0402-0.220UF,16V,10%,X7R,AA  I24  C1C12
   1 VR_PVSA_CPU1_BOOT      A @BASEBOARD_FAB2_LIB.BASEBOARD_FAB2(SCH_1):VR_PVSA_CPU1_BOOT
   2 VR_PVSA_CPU1_PHASE      B @BASEBOARD_FAB2_LIB.BASEBOARD_FAB2(SCH_1):VR_PVSA_CPU1_PHASE

CAP_0402-1.0UF,16V,10%,X6S,D97A  I26  C1C5
   1 VR_PVSA_CPU1_VCIN      A @BASEBOARD_FAB2_LIB.BASEBOARD_FAB2(SCH_1):VR_PVSA_CPU1_VCIN
   2    GND      B @BASEBOARD_FAB2_LIB.BASEBOARD_FAB2(SCH_1):GND

CAP_A_0402V-0.1UF,16V,10%,X7R,A  I27  C1C17
   1 VR_FET_SW_P12V_STBY_PVCCIN_CPU1      A @BASEBOARD_FAB2_LIB.BASEBOARD_FAB2(SCH_1):VR_FET_SW_P12V_STBY_PVCCIN_CPU1
   2    GND      B @BASEBOARD_FAB2_LIB.BASEBOARD_FAB2(SCH_1):GND

CAP_0402-1.0UF,16V,10%,X6S,D97A  I28  C1C15
   1 VR_FET_SW_P12V_STBY_PVCCIN_CPU1      A @BASEBOARD_FAB2_LIB.BASEBOARD_FAB2(SCH_1):VR_FET_SW_P12V_STBY_PVCCIN_CPU1
   2    GND      B @BASEBOARD_FAB2_LIB.BASEBOARD_FAB2(SCH_1):GND

RES_0402-100.0,1%,1/16W,CHIP,GA  I29  R1C12
   1 VSENSE_PVSA_CPU1_P      A @BASEBOARD_FAB2_LIB.BASEBOARD_FAB2(SCH_1):VSENSE_PVSA_CPU1_P
   2 PVSA_CPU1      B @BASEBOARD_FAB2_LIB.BASEBOARD_FAB2(SCH_1):PVSA_CPU1

RES_0402-0.0,5%,1/16W,CHIP,G21A  I31  R1C7
   1 VSENSE_PVSA_CPU1_P      A @BASEBOARD_FAB2_LIB.BASEBOARD_FAB2(SCH_1):VSENSE_PVSA_CPU1_P
   2 VSENSE_PVSA_CPU1_SKT_VSEN      B @BASEBOARD_FAB2_LIB.BASEBOARD_FAB2(SCH_1):VSENSE_PVSA_CPU1_SKT_VSEN

RES_0402-0.0,5%,1/16W,CHIP,G21A  I32  R1C5
   1 VSENSE_PVSA_CPU1_N      A @BASEBOARD_FAB2_LIB.BASEBOARD_FAB2(SCH_1):VSENSE_PVSA_CPU1_N
   2 VSENSE_PVSA_CPU1_SKT_VRTN      B @BASEBOARD_FAB2_LIB.BASEBOARD_FAB2(SCH_1):VSENSE_PVSA_CPU1_SKT_VRTN

RES_0402-100.0,1%,1/16W,CHIP,GA  I33  R1C4
   1 VSENSE_PVSA_CPU1_N      A @BASEBOARD_FAB2_LIB.BASEBOARD_FAB2(SCH_1):VSENSE_PVSA_CPU1_N
   2    GND      B @BASEBOARD_FAB2_LIB.BASEBOARD_FAB2(SCH_1):GND

RES_0402-1.00K,1%,1/16W,EMPTY,A  I34  R1C6
   1 VSENSE_PVSA_CPU1_P      A @BASEBOARD_FAB2_LIB.BASEBOARD_FAB2(SCH_1):VSENSE_PVSA_CPU1_P
   2 VSENSE_PVSA_CPU1_N      B @BASEBOARD_FAB2_LIB.BASEBOARD_FAB2(SCH_1):VSENSE_PVSA_CPU1_N

CAP_0805-10UF,16V,10%,X6S,C953A  I35  C9N13
   1 VR_FET_SW_P12V_STBY_PVCCIN_CPU1      A @BASEBOARD_FAB2_LIB.BASEBOARD_FAB2(SCH_1):VR_FET_SW_P12V_STBY_PVCCIN_CPU1
   2    GND      B @BASEBOARD_FAB2_LIB.BASEBOARD_FAB2(SCH_1):GND

CAP_0805-10UF,16V,10%,X6S,C953A  I36  C9N19
   1 VR_FET_SW_P12V_STBY_PVCCIN_CPU1      A @BASEBOARD_FAB2_LIB.BASEBOARD_FAB2(SCH_1):VR_FET_SW_P12V_STBY_PVCCIN_CPU1
   2    GND      B @BASEBOARD_FAB2_LIB.BASEBOARD_FAB2(SCH_1):GND

CAP_0805-10UF,16V,10%,X6S,C953A  I38  C9N21
   1 VR_FET_SW_P12V_STBY_PVCCIN_CPU1      A @BASEBOARD_FAB2_LIB.BASEBOARD_FAB2(SCH_1):VR_FET_SW_P12V_STBY_PVCCIN_CPU1
   2    GND      B @BASEBOARD_FAB2_LIB.BASEBOARD_FAB2(SCH_1):GND

CAP_A_0603V-22.0UF,4V,20%,X6S,A  I44  C9N22
   1 PVSA_CPU1      A @BASEBOARD_FAB2_LIB.BASEBOARD_FAB2(SCH_1):PVSA_CPU1
   2    GND      B @BASEBOARD_FAB2_LIB.BASEBOARD_FAB2(SCH_1):GND

RES_0402-51.1,1.0%,1/16W,CHIP,A  I45  R9N4
   1 PVSA_CPU1      A @BASEBOARD_FAB2_LIB.BASEBOARD_FAB2(SCH_1):PVSA_CPU1
   2    GND      B @BASEBOARD_FAB2_LIB.BASEBOARD_FAB2(SCH_1):GND

IR354XX_SM-IR35412,IC,H73684-0A  I51  EU1C1
  33 VR_PVSA_CPU1_BOOT_R  BOOST @BASEBOARD_FAB2_LIB.BASEBOARD_FAB2(SCH_1):VR_PVSA_CPU1_BOOT_R
  35 P5V_STBY     EN @BASEBOARD_FAB2_LIB.BASEBOARD_FAB2(SCH_1):P5V_STBY
  41 TP_PVSA_CPU1_GL_1  GL<1> @BASEBOARD_FAB2_LIB.BASEBOARD_FAB2(SCH_1):TP_PVSA_CPU1_GL_1
   6 TP_PVSA_CPU1_GL_0  GL<0> @BASEBOARD_FAB2_LIB.BASEBOARD_FAB2(SCH_1):TP_PVSA_CPU1_GL_0
  38 ISENSE_PVSA_CPU1_IMON   IOUT @BASEBOARD_FAB2_LIB.BASEBOARD_FAB2(SCH_1):ISENSE_PVSA_CPU1_IMON
   2    GND   LGND @BASEBOARD_FAB2_LIB.BASEBOARD_FAB2(SCH_1):GND
  31     NC     NC     NC
  37 VR_PVSA_CPU1_OCSET  OCSET @BASEBOARD_FAB2_LIB.BASEBOARD_FAB2(SCH_1):VR_PVSA_CPU1_OCSET
  40    GND PGND<2> @BASEBOARD_FAB2_LIB.BASEBOARD_FAB2(SCH_1):GND
   7    GND PGND<1> @BASEBOARD_FAB2_LIB.BASEBOARD_FAB2(SCH_1):GND
   5    GND PGND<0> @BASEBOARD_FAB2_LIB.BASEBOARD_FAB2(SCH_1):GND
  32 VR_PVSA_CPU1_PHASE  PHASE @BASEBOARD_FAB2_LIB.BASEBOARD_FAB2(SCH_1):VR_PVSA_CPU1_PHASE
  34 VR_PVSA_CPU1_PWM    PWM @BASEBOARD_FAB2_LIB.BASEBOARD_FAB2(SCH_1):VR_PVSA_CPU1_PWM
  39 VR_PVSA_CPU1_BIREF1  REFIN @BASEBOARD_FAB2_LIB.BASEBOARD_FAB2(SCH_1):VR_PVSA_CPU1_BIREF1
  10 VR_PVSA_CPU1_PHASE_SW     SW @BASEBOARD_FAB2_LIB.BASEBOARD_FAB2(SCH_1):VR_PVSA_CPU1_PHASE_SW
  36 A_TSENSE_PVSA_CPU1 TOUT_FLT @BASEBOARD_FAB2_LIB.BASEBOARD_FAB2(SCH_1):A_TSENSE_PVSA_CPU1
   3 VR_PVSA_CPU1_VCIN    VCC @BASEBOARD_FAB2_LIB.BASEBOARD_FAB2(SCH_1):VR_PVSA_CPU1_VCIN
   4 P5V_STBY   VDRV @BASEBOARD_FAB2_LIB.BASEBOARD_FAB2(SCH_1):P5V_STBY
  30 VR_FET_SW_P12V_STBY_PVCCIN_CPU1 VIN<1> @BASEBOARD_FAB2_LIB.BASEBOARD_FAB2(SCH_1):VR_FET_SW_P12V_STBY_PVCCIN_CPU1
  25 VR_FET_SW_P12V_STBY_PVCCIN_CPU1 VIN<0> @BASEBOARD_FAB2_LIB.BASEBOARD_FAB2(SCH_1):VR_FET_SW_P12V_STBY_PVCCIN_CPU1
   1 PVSA_CPU1    VOS @BASEBOARD_FAB2_LIB.BASEBOARD_FAB2(SCH_1):PVSA_CPU1

RES_0402-68.1K,1%,1/16W,EMPTY,A  I52  R1C37
   1 VR_PVSA_CPU1_OCSET      A @BASEBOARD_FAB2_LIB.BASEBOARD_FAB2(SCH_1):VR_PVSA_CPU1_OCSET
   2    GND      B @BASEBOARD_FAB2_LIB.BASEBOARD_FAB2(SCH_1):GND

CAP_A_0402V-0.1UF,16V,10%,X7R,A  I55  CT57
   1 VR_PVSA_CPU1_BIREF1      A @BASEBOARD_FAB2_LIB.BASEBOARD_FAB2(SCH_1):VR_PVSA_CPU1_BIREF1
   2    GND      B @BASEBOARD_FAB2_LIB.BASEBOARD_FAB2(SCH_1):GND

CAP_0402LF-1000PF,50V,10%,X7R,A  I60  CT55
   1 A_TSENSE_PVSA_CPU1      A @BASEBOARD_FAB2_LIB.BASEBOARD_FAB2(SCH_1):A_TSENSE_PVSA_CPU1
   2    GND      B @BASEBOARD_FAB2_LIB.BASEBOARD_FAB2(SCH_1):GND

CAP_0402LF-1000PF,50V,10%,X7R,A  I66  CT56
   1 VR_PVSA_CPU1_PHASE_SW      A @BASEBOARD_FAB2_LIB.BASEBOARD_FAB2(SCH_1):VR_PVSA_CPU1_PHASE_SW
   2 VR_PVSA_CPU1_PHASE_SW_RC      B @BASEBOARD_FAB2_LIB.BASEBOARD_FAB2(SCH_1):VR_PVSA_CPU1_PHASE_SW_RC

RES_0603-0,5.0%,1/10W,CHIP,G22A  I68  RT37
   1 VR_PVSA_CPU1_BOOT      A @BASEBOARD_FAB2_LIB.BASEBOARD_FAB2(SCH_1):VR_PVSA_CPU1_BOOT
   2 VR_PVSA_CPU1_BOOT_R      B @BASEBOARD_FAB2_LIB.BASEBOARD_FAB2(SCH_1):VR_PVSA_CPU1_BOOT_R

RES_0402-0.0,5%,1/16W,CHIP,G21A  I71  R9N3
   1 VR_PVSA_CPU1_VCIN      A @BASEBOARD_FAB2_LIB.BASEBOARD_FAB2(SCH_1):VR_PVSA_CPU1_VCIN
   2 P5V_STBY      B @BASEBOARD_FAB2_LIB.BASEBOARD_FAB2(SCH_1):P5V_STBY

IND-300NH-20-GP_DISCRET-GB1-INA  I72  L1C1
   1 VR_PVSA_CPU1_PHASE_SW      S @BASEBOARD_FAB2_LIB.BASEBOARD_FAB2(SCH_1):VR_PVSA_CPU1_PHASE_SW
   2 PVSA_CPU1      F @BASEBOARD_FAB2_LIB.BASEBOARD_FAB2(SCH_1):PVSA_CPU1

SC1U10V2KX-4-GP_SMD-BCG6-SC1U1A  I73  C1C3
   1 P5V_STBY      1 @BASEBOARD_FAB2_LIB.BASEBOARD_FAB2(SCH_1):P5V_STBY
   2    GND      2 @BASEBOARD_FAB2_LIB.BASEBOARD_FAB2(SCH_1):GND

1R3F-GP_RCL_GP-1R3F-GP,64.1R00A  I74  RT38
   1 VR_PVSA_CPU1_PHASE_SW_RC      1 @BASEBOARD_FAB2_LIB.BASEBOARD_FAB2(SCH_1):VR_PVSA_CPU1_PHASE_SW_RC
   2    GND      2 @BASEBOARD_FAB2_LIB.BASEBOARD_FAB2(SCH_1):GND


DRAWING: @BASEBOARD_FAB2_LIB.BASEBOARD_FAB2(SCH_1):PAGE211 

CAP_A_0402V-1.0UF,6.3V,10%,X6SA  I11  C3P4
   1 VR_PVCCIO_CPU0_VD12      A @BASEBOARD_FAB2_LIB.BASEBOARD_FAB2(SCH_1):VR_PVCCIO_CPU0_VD12
   2    GND      B @BASEBOARD_FAB2_LIB.BASEBOARD_FAB2(SCH_1):GND

CAP_A_0402V-0.1UF,16V,10%,X7R,A  I13  C3P5
   1 VR_PVCCIO_CPU0_VD12      A @BASEBOARD_FAB2_LIB.BASEBOARD_FAB2(SCH_1):VR_PVCCIO_CPU0_VD12
   2    GND      B @BASEBOARD_FAB2_LIB.BASEBOARD_FAB2(SCH_1):GND

RES_0402-0.0,5%,1/16W,CHIP,G21A  I16  R3P11
   1 SVID_DIO0_CPU0_R      A @BASEBOARD_FAB2_LIB.BASEBOARD_FAB2(SCH_1):SVID_DIO0_CPU0_R
   2 SVID_VDIO_PVCCIO_CPU0      B @BASEBOARD_FAB2_LIB.BASEBOARD_FAB2(SCH_1):SVID_VDIO_PVCCIO_CPU0

CAP_A_0402V-1.0UF,6.3V,10%,X6SA  I20  C3P3
   1 VR_PVCCIO_CPU0_VDD      A @BASEBOARD_FAB2_LIB.BASEBOARD_FAB2(SCH_1):VR_PVCCIO_CPU0_VDD
   2    GND      B @BASEBOARD_FAB2_LIB.BASEBOARD_FAB2(SCH_1):GND

CAP_A_0402V-0.1UF,16V,10%,X7R,A  I22  C3P7
   1 VR_PVCCIO_CPU0_VDD      A @BASEBOARD_FAB2_LIB.BASEBOARD_FAB2(SCH_1):VR_PVCCIO_CPU0_VDD
   2    GND      B @BASEBOARD_FAB2_LIB.BASEBOARD_FAB2(SCH_1):GND

RES_0402-0.0,5%,1/16W,CHIP,G21A  I24  R3P22
   1 P3V3_STBY      A @BASEBOARD_FAB2_LIB.BASEBOARD_FAB2(SCH_1):P3V3_STBY
   2 VR_PVCCIO_CPU0_VDD      B @BASEBOARD_FAB2_LIB.BASEBOARD_FAB2(SCH_1):VR_PVCCIO_CPU0_VDD

RES_0402-150.0,1%,1/16W,CHIP,GA  I29  R3P15
   1 SVID_CLK0_CPU0_R      A @BASEBOARD_FAB2_LIB.BASEBOARD_FAB2(SCH_1):SVID_CLK0_CPU0_R
   2 SVID_CLK_PVCCIO_CPU0      B @BASEBOARD_FAB2_LIB.BASEBOARD_FAB2(SCH_1):SVID_CLK_PVCCIO_CPU0

RES_0402-100.0K,1%,1/16W,CHIP,B  I31  R3P12
   1 VR_FET_SW_P12V_STBY_PVCCIO_CPU0      A @BASEBOARD_FAB2_LIB.BASEBOARD_FAB2(SCH_1):VR_FET_SW_P12V_STBY_PVCCIO_CPU0
   2 VR_PVCCIO_CPU0_VINSEN      B @BASEBOARD_FAB2_LIB.BASEBOARD_FAB2(SCH_1):VR_PVCCIO_CPU0_VINSEN

RES_0402-1.5K,1%,1/16W,CHIP,G2A  I32  R3P16
   1 VR_PVCCIO_CPU0_VINSEN      A @BASEBOARD_FAB2_LIB.BASEBOARD_FAB2(SCH_1):VR_PVCCIO_CPU0_VINSEN
   2    GND      B @BASEBOARD_FAB2_LIB.BASEBOARD_FAB2(SCH_1):GND

RES_0402-3.16K,1%,1/16W,CHIP,GA  I52  R3N31
   1 VR_PVCCIO_CPU0_XADDR1      A @BASEBOARD_FAB2_LIB.BASEBOARD_FAB2(SCH_1):VR_PVCCIO_CPU0_XADDR1
   2    GND      B @BASEBOARD_FAB2_LIB.BASEBOARD_FAB2(SCH_1):GND

RES_0402-1.00K,1%,1/16W,CHIP,GA  I56  R3P25
   1 P3V3_STBY      A @BASEBOARD_FAB2_LIB.BASEBOARD_FAB2(SCH_1):P3V3_STBY
   2 PWRGD_PVCCIO_CPU0_R      B @BASEBOARD_FAB2_LIB.BASEBOARD_FAB2(SCH_1):PWRGD_PVCCIO_CPU0_R

RES_0402-22.1,1.0%,1/16W,CHIP,A  I58  R3P20
   1 PWRGD_PVCCIO_CPU0_R      A @BASEBOARD_FAB2_LIB.BASEBOARD_FAB2(SCH_1):PWRGD_PVCCIO_CPU0_R
   2 PWRGD_PVCCIO_CPU0      B @BASEBOARD_FAB2_LIB.BASEBOARD_FAB2(SCH_1):PWRGD_PVCCIO_CPU0

RES_0402-2.26K,1.0%,1/16W,EMPTA  I60  R3N23
   1 P3V3_STBY      A @BASEBOARD_FAB2_LIB.BASEBOARD_FAB2(SCH_1):P3V3_STBY
   2 PU_VR_PVCCIO_CPU0_FAULT1      B @BASEBOARD_FAB2_LIB.BASEBOARD_FAB2(SCH_1):PU_VR_PVCCIO_CPU0_FAULT1

RES_0402-0.0,5%,1/16W,CHIP,G21A  I61  R3P1
   1 SVID_ALERT_PVCCIO_CPU0      A @BASEBOARD_FAB2_LIB.BASEBOARD_FAB2(SCH_1):SVID_ALERT_PVCCIO_CPU0
   2 SVID_ALERT0_CPU0_R_N      B @BASEBOARD_FAB2_LIB.BASEBOARD_FAB2(SCH_1):SVID_ALERT0_CPU0_R_N

RES_0402-1.00K,1%,1/16W,CHIP,GA  I64  R3P18
   1 P3V3_STBY      A @BASEBOARD_FAB2_LIB.BASEBOARD_FAB2(SCH_1):P3V3_STBY
   2 IRQ_PVCCIO_CPU0_VRHOT_N      B @BASEBOARD_FAB2_LIB.BASEBOARD_FAB2(SCH_1):IRQ_PVCCIO_CPU0_VRHOT_N

CAP_0402LF-1000PF,50V,10%,X7R,A  I71  C3P6
   1 PWRGD_PVCCIO_CPU0_R      A @BASEBOARD_FAB2_LIB.BASEBOARD_FAB2(SCH_1):PWRGD_PVCCIO_CPU0_R
   2    GND      B @BASEBOARD_FAB2_LIB.BASEBOARD_FAB2(SCH_1):GND

RES_0402-10.0,1%,1/16W,CHIP,G2A  I81  R3N19
   1 VSENSE_PVCCIO_CPU0_AVSP      A @BASEBOARD_FAB2_LIB.BASEBOARD_FAB2(SCH_1):VSENSE_PVCCIO_CPU0_AVSP
   2 VR_PVCCIO_CPU0_AVSP      B @BASEBOARD_FAB2_LIB.BASEBOARD_FAB2(SCH_1):VR_PVCCIO_CPU0_AVSP

CAP_0402LF-220PF,50V,10%,X7R,AA  I83  C3N39
   1 VR_PVCCIO_CPU0_AVSP      A @BASEBOARD_FAB2_LIB.BASEBOARD_FAB2(SCH_1):VR_PVCCIO_CPU0_AVSP
   2 VSENSE_PVCCIO_CPU0_AVSN      B @BASEBOARD_FAB2_LIB.BASEBOARD_FAB2(SCH_1):VSENSE_PVCCIO_CPU0_AVSN

RES_0402-0.0,5%,1/16W,CHIP,G21A  I87  R3P26
   1 FM_PVCCIO_CPU0_EN      A @BASEBOARD_FAB2_LIB.BASEBOARD_FAB2(SCH_1):FM_PVCCIO_CPU0_EN
   2 VR_PVCCIO_CPU0_EN      B @BASEBOARD_FAB2_LIB.BASEBOARD_FAB2(SCH_1):VR_PVCCIO_CPU0_EN

RES_0402-100.0K,1%,1/16W,EMPTYA  I88  R3P21
   1 P3V3_STBY      A @BASEBOARD_FAB2_LIB.BASEBOARD_FAB2(SCH_1):P3V3_STBY
   2 VR_PVCCIO_CPU0_EN      B @BASEBOARD_FAB2_LIB.BASEBOARD_FAB2(SCH_1):VR_PVCCIO_CPU0_EN

PXE1110B_QFN-IC,H89187-001  I93  EU3P1
   1     NC DNC<0>     NC
   2     NC DNC<1>     NC
   3     NC  BPWM1     NC
   4     NC DNC<2>     NC
   5 VR_PVCCIO_CPU0_PWM1  APWM1 @BASEBOARD_FAB2_LIB.BASEBOARD_FAB2(SCH_1):VR_PVCCIO_CPU0_PWM1
   6 SMB_VR_STBY_LVC3_SDA    SDA @BASEBOARD_FAB2_LIB.BASEBOARD_FAB2(SCH_1):SMB_VR_STBY_LVC3_SDA
   7 SMB_VR_STBY_LVC3_SCL    SCL @BASEBOARD_FAB2_LIB.BASEBOARD_FAB2(SCH_1):SMB_VR_STBY_LVC3_SCL
   8     NC RESET_N     NC
   9 PWRGD_PVCCIO_CPU0_R AVRRDY @BASEBOARD_FAB2_LIB.BASEBOARD_FAB2(SCH_1):PWRGD_PVCCIO_CPU0_R
  10 VR_PVCCIO_CPU0_EN  AVREN @BASEBOARD_FAB2_LIB.BASEBOARD_FAB2(SCH_1):VR_PVCCIO_CPU0_EN
  11 IRQ_PVCCIO_CPU0_VRHOT_N VRHOT_N @BASEBOARD_FAB2_LIB.BASEBOARD_FAB2(SCH_1):IRQ_PVCCIO_CPU0_VRHOT_N
  12     NC PINALRT_N     NC
  13     NC    MP0     NC
  14     NC    MP1     NC
  15 SVID_CLK_PVCCIO_CPU0   VCLK @BASEBOARD_FAB2_LIB.BASEBOARD_FAB2(SCH_1):SVID_CLK_PVCCIO_CPU0
  16 SVID_VDIO_PVCCIO_CPU0   VDIO @BASEBOARD_FAB2_LIB.BASEBOARD_FAB2(SCH_1):SVID_VDIO_PVCCIO_CPU0
  17 SVID_ALERT_PVCCIO_CPU0 VALRT_N @BASEBOARD_FAB2_LIB.BASEBOARD_FAB2(SCH_1):SVID_ALERT_PVCCIO_CPU0
  18     NC    MP2     NC
  19 VR_PVCCIO_CPU0_AVSP  AVSEN @BASEBOARD_FAB2_LIB.BASEBOARD_FAB2(SCH_1):VR_PVCCIO_CPU0_AVSP
  20 VSENSE_PVCCIO_CPU0_AVSN  AVREF @BASEBOARD_FAB2_LIB.BASEBOARD_FAB2(SCH_1):VSENSE_PVCCIO_CPU0_AVSN
  21 VR_PVCCIO_CPU0_AIREF1 AIREF1 @BASEBOARD_FAB2_LIB.BASEBOARD_FAB2(SCH_1):VR_PVCCIO_CPU0_AIREF1
  22 ISENSE_PVCCIO_CPU0_PH1_IMON AISEN1 @BASEBOARD_FAB2_LIB.BASEBOARD_FAB2(SCH_1):ISENSE_PVCCIO_CPU0_PH1_IMON
  23    GND GND<1> @BASEBOARD_FAB2_LIB.BASEBOARD_FAB2(SCH_1):GND
  24     NC DNC<3>     NC
  25     NC BIREF1     NC
  26    GND BISEN1 @BASEBOARD_FAB2_LIB.BASEBOARD_FAB2(SCH_1):GND
  27    GND GND<0> @BASEBOARD_FAB2_LIB.BASEBOARD_FAB2(SCH_1):GND
  28     NC DNC<4>     NC
  29     NC  BVSEN     NC
  30     NC  BVREF     NC
  31     NC    MP3     NC
  32 PU_VR_PVCCIO_CPU0_FAULT1    MP4 @BASEBOARD_FAB2_LIB.BASEBOARD_FAB2(SCH_1):PU_VR_PVCCIO_CPU0_FAULT1
  33 VR_PVCCIO_CPU0_XADDR2 XADDR2 @BASEBOARD_FAB2_LIB.BASEBOARD_FAB2(SCH_1):VR_PVCCIO_CPU0_XADDR2
  34     NC  BTSEN     NC
  35 A_TSENSE_PVCCIO_CPU0  ATSEN @BASEBOARD_FAB2_LIB.BASEBOARD_FAB2(SCH_1):A_TSENSE_PVCCIO_CPU0
  36 VR_PVCCIO_CPU0_XADDR1 XADDR1 @BASEBOARD_FAB2_LIB.BASEBOARD_FAB2(SCH_1):VR_PVCCIO_CPU0_XADDR1
  37 VR_PVCCIO_CPU0_VINSEN VINSEN @BASEBOARD_FAB2_LIB.BASEBOARD_FAB2(SCH_1):VR_PVCCIO_CPU0_VINSEN
  38     NC IINSEN     NC
  39 VR_PVCCIO_CPU0_VDD    VDD @BASEBOARD_FAB2_LIB.BASEBOARD_FAB2(SCH_1):VR_PVCCIO_CPU0_VDD
  40 VR_PVCCIO_CPU0_VD12   VD12 @BASEBOARD_FAB2_LIB.BASEBOARD_FAB2(SCH_1):VR_PVCCIO_CPU0_VD12
  41    GND  THPAD @BASEBOARD_FAB2_LIB.BASEBOARD_FAB2(SCH_1):GND

SC22P50V2JN-4GP_SMD-BCG-SC22P5A  I95  CF13
   1 VR_PVCCIO_CPU0_AIREF1      1 @BASEBOARD_FAB2_LIB.BASEBOARD_FAB2(SCH_1):VR_PVCCIO_CPU0_AIREF1
   2 ISENSE_PVCCIO_CPU0_PH1_IMON      2 @BASEBOARD_FAB2_LIB.BASEBOARD_FAB2(SCH_1):ISENSE_PVCCIO_CPU0_PH1_IMON

RES_0402-1.0K,0.1%,1/16W,CHIP,A  I96  RF13
   1 VR_PVCCIO_CPU0_AIREF1      A @BASEBOARD_FAB2_LIB.BASEBOARD_FAB2(SCH_1):VR_PVCCIO_CPU0_AIREF1
   2 ISENSE_PVCCIO_CPU0_PH1_IMON      B @BASEBOARD_FAB2_LIB.BASEBOARD_FAB2(SCH_1):ISENSE_PVCCIO_CPU0_PH1_IMON

CAP_0402LF-220PF,50V,10%,X7R,AA  I97  C4W1
   1 A_TSENSE_PVCCIO_CPU0      A @BASEBOARD_FAB2_LIB.BASEBOARD_FAB2(SCH_1):A_TSENSE_PVCCIO_CPU0
   2    GND      B @BASEBOARD_FAB2_LIB.BASEBOARD_FAB2(SCH_1):GND

RES_0402-49.9,1%,1/16W,CHIP,G2A  I99  R3P17
   1 PVCCIO_CPU0      A @BASEBOARD_FAB2_LIB.BASEBOARD_FAB2(SCH_1):PVCCIO_CPU0
   2 SVID_CLK0_CPU0_R      B @BASEBOARD_FAB2_LIB.BASEBOARD_FAB2(SCH_1):SVID_CLK0_CPU0_R

RES_0402-100.0,1%,1/16W,CHIP,GA  I100  R3P13
   1 PVCCIO_CPU0      A @BASEBOARD_FAB2_LIB.BASEBOARD_FAB2(SCH_1):PVCCIO_CPU0
   2 SVID_DIO0_CPU0_R      B @BASEBOARD_FAB2_LIB.BASEBOARD_FAB2(SCH_1):SVID_DIO0_CPU0_R

RES_0402-4.02K,1%,1/16W,CHIP,GA  I102  R3N22
   1 VR_PVCCIO_CPU0_XADDR2      A @BASEBOARD_FAB2_LIB.BASEBOARD_FAB2(SCH_1):VR_PVCCIO_CPU0_XADDR2
   2    GND      B @BASEBOARD_FAB2_LIB.BASEBOARD_FAB2(SCH_1):GND

CAP_A_0402V-0.1UF,16V,10%,X7R,A  I103  C3P2
   1 VR_PVCCIO_CPU0_VINSEN      A @BASEBOARD_FAB2_LIB.BASEBOARD_FAB2(SCH_1):VR_PVCCIO_CPU0_VINSEN
   2    GND      B @BASEBOARD_FAB2_LIB.BASEBOARD_FAB2(SCH_1):GND


DRAWING: @BASEBOARD_FAB2_LIB.BASEBOARD_FAB2(SCH_1):PAGE212 

CAPP_3018-470UF,2.5V,20%,ALUM,A  I18  C3N35
   1 PVCCIO_CPU0      A @BASEBOARD_FAB2_LIB.BASEBOARD_FAB2(SCH_1):PVCCIO_CPU0
   2    GND      B @BASEBOARD_FAB2_LIB.BASEBOARD_FAB2(SCH_1):GND

CAP_A_0603V-22.0UF,4V,20%,X6S,A  I23  C7C6
   1 PVCCIO_CPU0      A @BASEBOARD_FAB2_LIB.BASEBOARD_FAB2(SCH_1):PVCCIO_CPU0
   2    GND      B @BASEBOARD_FAB2_LIB.BASEBOARD_FAB2(SCH_1):GND

CAP_0402-0.22UF,16V,10%,X7R,A3A  I33  C7C18
   1 P5V_STBY      A @BASEBOARD_FAB2_LIB.BASEBOARD_FAB2(SCH_1):P5V_STBY
   2    GND      B @BASEBOARD_FAB2_LIB.BASEBOARD_FAB2(SCH_1):GND

CAP_0402-1.0UF,16V,10%,X6S,D97A  I36  C7C17
   1 VR_PVCCIO_CPU0_PH1_VCIN      A @BASEBOARD_FAB2_LIB.BASEBOARD_FAB2(SCH_1):VR_PVCCIO_CPU0_PH1_VCIN
   2    GND      B @BASEBOARD_FAB2_LIB.BASEBOARD_FAB2(SCH_1):GND

CAP_0402-0.220UF,16V,10%,X7R,AA  I37  C7C14
   1 VR_PVCCIO_CPU0_PH1_BOOT      A @BASEBOARD_FAB2_LIB.BASEBOARD_FAB2(SCH_1):VR_PVCCIO_CPU0_PH1_BOOT
   2 VR_PVCCIO_CPU0_PH1_PHASE      B @BASEBOARD_FAB2_LIB.BASEBOARD_FAB2(SCH_1):VR_PVCCIO_CPU0_PH1_PHASE

CAP_A_0402V-0.1UF,16V,10%,X7R,A  I38  C7C11
   1 VR_FET_SW_P12V_STBY_PVCCIO_CPU0      A @BASEBOARD_FAB2_LIB.BASEBOARD_FAB2(SCH_1):VR_FET_SW_P12V_STBY_PVCCIO_CPU0
   2    GND      B @BASEBOARD_FAB2_LIB.BASEBOARD_FAB2(SCH_1):GND

CAP_0402-1.0UF,16V,10%,X6S,D97A  I39  C7C12
   1 VR_FET_SW_P12V_STBY_PVCCIO_CPU0      A @BASEBOARD_FAB2_LIB.BASEBOARD_FAB2(SCH_1):VR_FET_SW_P12V_STBY_PVCCIO_CPU0
   2    GND      B @BASEBOARD_FAB2_LIB.BASEBOARD_FAB2(SCH_1):GND

CAP_0805-10UF,16V,10%,X6S,C953A  I40  C3N36
   1 VR_FET_SW_P12V_STBY_PVCCIO_CPU0      A @BASEBOARD_FAB2_LIB.BASEBOARD_FAB2(SCH_1):VR_FET_SW_P12V_STBY_PVCCIO_CPU0
   2    GND      B @BASEBOARD_FAB2_LIB.BASEBOARD_FAB2(SCH_1):GND

CAP_0805-10UF,16V,10%,X6S,C953A  I41  C3N33
   1 VR_FET_SW_P12V_STBY_PVCCIO_CPU0      A @BASEBOARD_FAB2_LIB.BASEBOARD_FAB2(SCH_1):VR_FET_SW_P12V_STBY_PVCCIO_CPU0
   2    GND      B @BASEBOARD_FAB2_LIB.BASEBOARD_FAB2(SCH_1):GND

CAP_0805-10UF,16V,10%,X6S,C953A  I43  C3N34
   1 VR_FET_SW_P12V_STBY_PVCCIO_CPU0      A @BASEBOARD_FAB2_LIB.BASEBOARD_FAB2(SCH_1):VR_FET_SW_P12V_STBY_PVCCIO_CPU0
   2    GND      B @BASEBOARD_FAB2_LIB.BASEBOARD_FAB2(SCH_1):GND

CAP_A_0402V-0.1UF,16V,10%,EMPTA  I60  C3P1
   1 VSENSE_PVCCIO_CPU0_SKT_VSEN      A @BASEBOARD_FAB2_LIB.BASEBOARD_FAB2(SCH_1):VSENSE_PVCCIO_CPU0_SKT_VSEN
   2 VSENSE_PVCCIO_CPU0_SKT_VRTN      B @BASEBOARD_FAB2_LIB.BASEBOARD_FAB2(SCH_1):VSENSE_PVCCIO_CPU0_SKT_VRTN

RES_0402-100.0,1%,1/16W,CHIP,GA  I68  R3N20
   1 VSENSE_PVCCIO_CPU0_AVSN      A @BASEBOARD_FAB2_LIB.BASEBOARD_FAB2(SCH_1):VSENSE_PVCCIO_CPU0_AVSN
   2    GND      B @BASEBOARD_FAB2_LIB.BASEBOARD_FAB2(SCH_1):GND

RES_0402-100.0,1%,1/16W,CHIP,GA  I74  R3N21
   1 VSENSE_PVCCIO_CPU0_AVSP      A @BASEBOARD_FAB2_LIB.BASEBOARD_FAB2(SCH_1):VSENSE_PVCCIO_CPU0_AVSP
   2 PVCCIO_CPU0      B @BASEBOARD_FAB2_LIB.BASEBOARD_FAB2(SCH_1):PVCCIO_CPU0

CAP_A_0603V-22.0UF,4V,20%,X6S,A  I77  C7C10
   1 PVCCIO_CPU0      A @BASEBOARD_FAB2_LIB.BASEBOARD_FAB2(SCH_1):PVCCIO_CPU0
   2    GND      B @BASEBOARD_FAB2_LIB.BASEBOARD_FAB2(SCH_1):GND

RES_0402-51.1,1.0%,1/16W,CHIP,A  I78  R7C3
   1 PVCCIO_CPU0      A @BASEBOARD_FAB2_LIB.BASEBOARD_FAB2(SCH_1):PVCCIO_CPU0
   2    GND      B @BASEBOARD_FAB2_LIB.BASEBOARD_FAB2(SCH_1):GND

IR354XX_SM-IR35412,IC,H73684-0A  I101  EU7C1
  33 VR_PVCCIO_CPU0_PH1_BOOT_R  BOOST @BASEBOARD_FAB2_LIB.BASEBOARD_FAB2(SCH_1):VR_PVCCIO_CPU0_PH1_BOOT_R
  35 P5V_STBY     EN @BASEBOARD_FAB2_LIB.BASEBOARD_FAB2(SCH_1):P5V_STBY
  41 TP_PVCCIO_CPU0_GL_1  GL<1> @BASEBOARD_FAB2_LIB.BASEBOARD_FAB2(SCH_1):TP_PVCCIO_CPU0_GL_1
   6 TP_PVCCIO_CPU0_GL_0  GL<0> @BASEBOARD_FAB2_LIB.BASEBOARD_FAB2(SCH_1):TP_PVCCIO_CPU0_GL_0
  38 ISENSE_PVCCIO_CPU0_PH1_IMON   IOUT @BASEBOARD_FAB2_LIB.BASEBOARD_FAB2(SCH_1):ISENSE_PVCCIO_CPU0_PH1_IMON
   2    GND   LGND @BASEBOARD_FAB2_LIB.BASEBOARD_FAB2(SCH_1):GND
  31     NC     NC     NC
  37 VR_PVCCIO_CPU0_OCSET  OCSET @BASEBOARD_FAB2_LIB.BASEBOARD_FAB2(SCH_1):VR_PVCCIO_CPU0_OCSET
  40    GND PGND<2> @BASEBOARD_FAB2_LIB.BASEBOARD_FAB2(SCH_1):GND
   7    GND PGND<1> @BASEBOARD_FAB2_LIB.BASEBOARD_FAB2(SCH_1):GND
   5    GND PGND<0> @BASEBOARD_FAB2_LIB.BASEBOARD_FAB2(SCH_1):GND
  32 VR_PVCCIO_CPU0_PH1_PHASE  PHASE @BASEBOARD_FAB2_LIB.BASEBOARD_FAB2(SCH_1):VR_PVCCIO_CPU0_PH1_PHASE
  34 VR_PVCCIO_CPU0_PWM1    PWM @BASEBOARD_FAB2_LIB.BASEBOARD_FAB2(SCH_1):VR_PVCCIO_CPU0_PWM1
  39 VR_PVCCIO_CPU0_AIREF1  REFIN @BASEBOARD_FAB2_LIB.BASEBOARD_FAB2(SCH_1):VR_PVCCIO_CPU0_AIREF1
  10 VR_PVCCIO_CPU0_PH1_SW     SW @BASEBOARD_FAB2_LIB.BASEBOARD_FAB2(SCH_1):VR_PVCCIO_CPU0_PH1_SW
  36 A_TSENSE_PVCCIO_CPU0 TOUT_FLT @BASEBOARD_FAB2_LIB.BASEBOARD_FAB2(SCH_1):A_TSENSE_PVCCIO_CPU0
   3 VR_PVCCIO_CPU0_PH1_VCIN    VCC @BASEBOARD_FAB2_LIB.BASEBOARD_FAB2(SCH_1):VR_PVCCIO_CPU0_PH1_VCIN
   4 P5V_STBY   VDRV @BASEBOARD_FAB2_LIB.BASEBOARD_FAB2(SCH_1):P5V_STBY
  30 VR_FET_SW_P12V_STBY_PVCCIO_CPU0 VIN<1> @BASEBOARD_FAB2_LIB.BASEBOARD_FAB2(SCH_1):VR_FET_SW_P12V_STBY_PVCCIO_CPU0
  25 VR_FET_SW_P12V_STBY_PVCCIO_CPU0 VIN<0> @BASEBOARD_FAB2_LIB.BASEBOARD_FAB2(SCH_1):VR_FET_SW_P12V_STBY_PVCCIO_CPU0
   1 PVCCIO_CPU0    VOS @BASEBOARD_FAB2_LIB.BASEBOARD_FAB2(SCH_1):PVCCIO_CPU0

RES_0402-68.1K,1%,1/16W,EMPTY,A  I103  R7C25
   1 VR_PVCCIO_CPU0_OCSET      A @BASEBOARD_FAB2_LIB.BASEBOARD_FAB2(SCH_1):VR_PVCCIO_CPU0_OCSET
   2    GND      B @BASEBOARD_FAB2_LIB.BASEBOARD_FAB2(SCH_1):GND

SHUNT_SH0201-EMPTY,N_A  I104  SH3P1
   1 VSENSE_PVCCIO_CPU0_SKT_VSEN      A @BASEBOARD_FAB2_LIB.BASEBOARD_FAB2(SCH_1):VSENSE_PVCCIO_CPU0_SKT_VSEN
   2 VSENSE_PVCCIO_CPU0_AVSP      B @BASEBOARD_FAB2_LIB.BASEBOARD_FAB2(SCH_1):VSENSE_PVCCIO_CPU0_AVSP

SHUNT_SH0201-EMPTY,N_A  I105  SH3P2
   1 VSENSE_PVCCIO_CPU0_SKT_VRTN      A @BASEBOARD_FAB2_LIB.BASEBOARD_FAB2(SCH_1):VSENSE_PVCCIO_CPU0_SKT_VRTN
   2 VSENSE_PVCCIO_CPU0_AVSN      B @BASEBOARD_FAB2_LIB.BASEBOARD_FAB2(SCH_1):VSENSE_PVCCIO_CPU0_AVSN

CAP_A_0402V-0.1UF,16V,10%,X7R,A  I106  CT70
   1 VR_PVCCIO_CPU0_AIREF1      A @BASEBOARD_FAB2_LIB.BASEBOARD_FAB2(SCH_1):VR_PVCCIO_CPU0_AIREF1
   2    GND      B @BASEBOARD_FAB2_LIB.BASEBOARD_FAB2(SCH_1):GND

CAP_0402LF-1000PF,50V,10%,X7R,A  I109  CT71
   1 A_TSENSE_PVCCIO_CPU0      A @BASEBOARD_FAB2_LIB.BASEBOARD_FAB2(SCH_1):A_TSENSE_PVCCIO_CPU0
   2    GND      B @BASEBOARD_FAB2_LIB.BASEBOARD_FAB2(SCH_1):GND

CAP_0402LF-1000PF,50V,10%,X7R,A  I118  CT72
   1 VR_PVCCIO_CPU0_PH1_SW      A @BASEBOARD_FAB2_LIB.BASEBOARD_FAB2(SCH_1):VR_PVCCIO_CPU0_PH1_SW
   2 VR_PVCCIO_CPU0_PH1_SW_RC      B @BASEBOARD_FAB2_LIB.BASEBOARD_FAB2(SCH_1):VR_PVCCIO_CPU0_PH1_SW_RC

RES_0603-0,5.0%,1/10W,CHIP,G22A  I120  RT47
   1 VR_PVCCIO_CPU0_PH1_BOOT      A @BASEBOARD_FAB2_LIB.BASEBOARD_FAB2(SCH_1):VR_PVCCIO_CPU0_PH1_BOOT
   2 VR_PVCCIO_CPU0_PH1_BOOT_R      B @BASEBOARD_FAB2_LIB.BASEBOARD_FAB2(SCH_1):VR_PVCCIO_CPU0_PH1_BOOT_R

SC22U16V5MX-4-GP_SMD-BCG5-SC22A  I124  C22W33
   1 VR_FET_SW_P12V_STBY_PVCCIO_CPU0      1 @BASEBOARD_FAB2_LIB.BASEBOARD_FAB2(SCH_1):VR_FET_SW_P12V_STBY_PVCCIO_CPU0
   2    GND      2 @BASEBOARD_FAB2_LIB.BASEBOARD_FAB2(SCH_1):GND

SC22U16V5MX-4-GP_SMD-BCG5-SC22A  I126  C22W32
   1 VR_FET_SW_P12V_STBY_PVCCIO_CPU0      1 @BASEBOARD_FAB2_LIB.BASEBOARD_FAB2(SCH_1):VR_FET_SW_P12V_STBY_PVCCIO_CPU0
   2    GND      2 @BASEBOARD_FAB2_LIB.BASEBOARD_FAB2(SCH_1):GND

SC22U16V5MX-4-GP_SMD-BCG5-SC22A  I129  C22W31
   1 VR_FET_SW_P12V_STBY_PVCCIO_CPU0      1 @BASEBOARD_FAB2_LIB.BASEBOARD_FAB2(SCH_1):VR_FET_SW_P12V_STBY_PVCCIO_CPU0
   2    GND      2 @BASEBOARD_FAB2_LIB.BASEBOARD_FAB2(SCH_1):GND

SC22U16V5MX-4-GP_SMD-BCG5-SC22A  I130  C7C8
   1 VR_FET_SW_P12V_STBY_PVCCIO_CPU0      1 @BASEBOARD_FAB2_LIB.BASEBOARD_FAB2(SCH_1):VR_FET_SW_P12V_STBY_PVCCIO_CPU0
   2    GND      2 @BASEBOARD_FAB2_LIB.BASEBOARD_FAB2(SCH_1):GND

SC22U16V5MX-4-GP_SMD-BCG5-SC22A  I132  C22W30
   1 VR_FET_SW_P12V_STBY_PVCCIO_CPU0      1 @BASEBOARD_FAB2_LIB.BASEBOARD_FAB2(SCH_1):VR_FET_SW_P12V_STBY_PVCCIO_CPU0
   2    GND      2 @BASEBOARD_FAB2_LIB.BASEBOARD_FAB2(SCH_1):GND

SC22U16V5MX-4-GP_SMD-BCG5-SC22A  I134  C22W29
   1 VR_FET_SW_P12V_STBY_PVCCIO_CPU0      1 @BASEBOARD_FAB2_LIB.BASEBOARD_FAB2(SCH_1):VR_FET_SW_P12V_STBY_PVCCIO_CPU0
   2    GND      2 @BASEBOARD_FAB2_LIB.BASEBOARD_FAB2(SCH_1):GND

SC22U16V5MX-4-GP_SMD-BCG5-SC22A  I136  C22W28
   1 VR_FET_SW_P12V_STBY_PVCCIO_CPU0      1 @BASEBOARD_FAB2_LIB.BASEBOARD_FAB2(SCH_1):VR_FET_SW_P12V_STBY_PVCCIO_CPU0
   2    GND      2 @BASEBOARD_FAB2_LIB.BASEBOARD_FAB2(SCH_1):GND

SC22U16V5MX-4-GP_SMD-BCG5-SC22A  I138  C7C7
   1 VR_FET_SW_P12V_STBY_PVCCIO_CPU0      1 @BASEBOARD_FAB2_LIB.BASEBOARD_FAB2(SCH_1):VR_FET_SW_P12V_STBY_PVCCIO_CPU0
   2    GND      2 @BASEBOARD_FAB2_LIB.BASEBOARD_FAB2(SCH_1):GND

RES_0402-0.0,5%,1/16W,CHIP,G21A  I140  R3N7
   1 VR_PVCCIO_CPU0_PH1_VCIN      A @BASEBOARD_FAB2_LIB.BASEBOARD_FAB2(SCH_1):VR_PVCCIO_CPU0_PH1_VCIN
   2 P5V_STBY      B @BASEBOARD_FAB2_LIB.BASEBOARD_FAB2(SCH_1):P5V_STBY

IND-150NH-56-GP_DISCRET-GA1-INA  I141  L7C2
   1 VR_PVCCIO_CPU0_PH1_SW      S @BASEBOARD_FAB2_LIB.BASEBOARD_FAB2(SCH_1):VR_PVCCIO_CPU0_PH1_SW
   2 PVCCIO_CPU0      F @BASEBOARD_FAB2_LIB.BASEBOARD_FAB2(SCH_1):PVCCIO_CPU0

IND-100NH-35-GP_DISCRET-G8-INDA  I142  L7C1
   1 P12V_STBY      S @BASEBOARD_FAB2_LIB.BASEBOARD_FAB2(SCH_1):P12V_STBY
   2 VR_FET_SW_P12V_STBY_PVCCIO_CPU0      F @BASEBOARD_FAB2_LIB.BASEBOARD_FAB2(SCH_1):VR_FET_SW_P12V_STBY_PVCCIO_CPU0

SC1U10V2KX-4-GP_SMD-BCG6-SC1U1A  I143  C7C20
   1 P5V_STBY      1 @BASEBOARD_FAB2_LIB.BASEBOARD_FAB2(SCH_1):P5V_STBY
   2    GND      2 @BASEBOARD_FAB2_LIB.BASEBOARD_FAB2(SCH_1):GND

1R3F-GP_RCL_GP-1R3F-GP,64.1R00A  I144  RT48
   1 VR_PVCCIO_CPU0_PH1_SW_RC      1 @BASEBOARD_FAB2_LIB.BASEBOARD_FAB2(SCH_1):VR_PVCCIO_CPU0_PH1_SW_RC
   2    GND      2 @BASEBOARD_FAB2_LIB.BASEBOARD_FAB2(SCH_1):GND

CAPP_3018-470UF,2.5V,20%,ALUM,A  I145  C3N26
   1 PVCCIO_CPU0      A @BASEBOARD_FAB2_LIB.BASEBOARD_FAB2(SCH_1):PVCCIO_CPU0
   2    GND      B @BASEBOARD_FAB2_LIB.BASEBOARD_FAB2(SCH_1):GND

CAPP_3018-470UF,2.5V,20%,ALUM,A  I146  C3N38
   1 PVCCIO_CPU0      A @BASEBOARD_FAB2_LIB.BASEBOARD_FAB2(SCH_1):PVCCIO_CPU0
   2    GND      B @BASEBOARD_FAB2_LIB.BASEBOARD_FAB2(SCH_1):GND


DRAWING: @BASEBOARD_FAB2_LIB.BASEBOARD_FAB2(SCH_1):PAGE213 

CAP_A_0402V-1.0UF,6.3V,10%,X6SA  I9  C4D31
   1 VR_PVCCIO_CPU1_VD12      A @BASEBOARD_FAB2_LIB.BASEBOARD_FAB2(SCH_1):VR_PVCCIO_CPU1_VD12
   2    GND      B @BASEBOARD_FAB2_LIB.BASEBOARD_FAB2(SCH_1):GND

CAP_A_0402V-0.1UF,16V,10%,X7R,A  I11  C4D32
   1 VR_PVCCIO_CPU1_VD12      A @BASEBOARD_FAB2_LIB.BASEBOARD_FAB2(SCH_1):VR_PVCCIO_CPU1_VD12
   2    GND      B @BASEBOARD_FAB2_LIB.BASEBOARD_FAB2(SCH_1):GND

RES_0402-22.1,1.0%,1/16W,CHIP,A  I13  R4D46
   1 PWRGD_PVCCIO_CPU1_R      A @BASEBOARD_FAB2_LIB.BASEBOARD_FAB2(SCH_1):PWRGD_PVCCIO_CPU1_R
   2 PWRGD_PVCCIO_CPU1      B @BASEBOARD_FAB2_LIB.BASEBOARD_FAB2(SCH_1):PWRGD_PVCCIO_CPU1

RES_0402-2.26K,1.0%,1/16W,EMPTA  I14  R6P49
   1 P3V3_STBY      A @BASEBOARD_FAB2_LIB.BASEBOARD_FAB2(SCH_1):P3V3_STBY
   2 PU_VR_PVCCIO_CPU1_FAULT1      B @BASEBOARD_FAB2_LIB.BASEBOARD_FAB2(SCH_1):PU_VR_PVCCIO_CPU1_FAULT1

RES_0402-1.00K,1%,1/16W,CHIP,GA  I15  R4D42
   1 P3V3_STBY      A @BASEBOARD_FAB2_LIB.BASEBOARD_FAB2(SCH_1):P3V3_STBY
   2 PWRGD_PVCCIO_CPU1_R      B @BASEBOARD_FAB2_LIB.BASEBOARD_FAB2(SCH_1):PWRGD_PVCCIO_CPU1_R

RES_0402-0.0,5%,1/16W,CHIP,G21A  I16  R4D56
   1 SVID_ALERT_PVCCIO_CPU1      A @BASEBOARD_FAB2_LIB.BASEBOARD_FAB2(SCH_1):SVID_ALERT_PVCCIO_CPU1
   2 SVID_ALERT0_CPU1_R_N      B @BASEBOARD_FAB2_LIB.BASEBOARD_FAB2(SCH_1):SVID_ALERT0_CPU1_R_N

CAP_A_0402V-1.0UF,6.3V,10%,X6SA  I17  C4D36
   1 VR_PVCCIO_CPU1_VDD      A @BASEBOARD_FAB2_LIB.BASEBOARD_FAB2(SCH_1):VR_PVCCIO_CPU1_VDD
   2    GND      B @BASEBOARD_FAB2_LIB.BASEBOARD_FAB2(SCH_1):GND

RES_0402-0.0,5%,1/16W,CHIP,G21A  I25  R4D47
   1 P3V3_STBY      A @BASEBOARD_FAB2_LIB.BASEBOARD_FAB2(SCH_1):P3V3_STBY
   2 VR_PVCCIO_CPU1_VDD      B @BASEBOARD_FAB2_LIB.BASEBOARD_FAB2(SCH_1):VR_PVCCIO_CPU1_VDD

RES_0402-100.0,1%,1/16W,EMPTY,A  I27  R6P35
   1 PVCCIO_CPU1      A @BASEBOARD_FAB2_LIB.BASEBOARD_FAB2(SCH_1):PVCCIO_CPU1
   2 SVID_DIO0_CPU1_R      B @BASEBOARD_FAB2_LIB.BASEBOARD_FAB2(SCH_1):SVID_DIO0_CPU1_R

RES_0402-110,1%,1/16W,EMPTY,G2A  I30  R6P33
   1 PVCCIO_CPU1      A @BASEBOARD_FAB2_LIB.BASEBOARD_FAB2(SCH_1):PVCCIO_CPU1
   2 SVID_CLK0_CPU1_R      B @BASEBOARD_FAB2_LIB.BASEBOARD_FAB2(SCH_1):SVID_CLK0_CPU1_R

RES_0402-100.0K,1%,1/16W,CHIP,B  I31  R4D60
   1 VR_FET_SW_P12V_STBY_PVCCIN_CPU0      A @BASEBOARD_FAB2_LIB.BASEBOARD_FAB2(SCH_1):VR_FET_SW_P12V_STBY_PVCCIN_CPU0
   2 VR_PVCCIO_CPU1_VINSEN      B @BASEBOARD_FAB2_LIB.BASEBOARD_FAB2(SCH_1):VR_PVCCIO_CPU1_VINSEN

RES_0402-1.5K,1%,1/16W,CHIP,G2A  I32  R4D57
   1 VR_PVCCIO_CPU1_VINSEN      A @BASEBOARD_FAB2_LIB.BASEBOARD_FAB2(SCH_1):VR_PVCCIO_CPU1_VINSEN
   2    GND      B @BASEBOARD_FAB2_LIB.BASEBOARD_FAB2(SCH_1):GND

CAP_A_0402V-0.1UF,16V,10%,X7R,A  I35  C4D38
   1 VR_PVCCIO_CPU1_VDD      A @BASEBOARD_FAB2_LIB.BASEBOARD_FAB2(SCH_1):VR_PVCCIO_CPU1_VDD
   2    GND      B @BASEBOARD_FAB2_LIB.BASEBOARD_FAB2(SCH_1):GND

RES_0402-0.0,5%,1/16W,CHIP,G21A  I37  R4D54
   1 SVID_DIO0_CPU1_R      A @BASEBOARD_FAB2_LIB.BASEBOARD_FAB2(SCH_1):SVID_DIO0_CPU1_R
   2 SVID_VDIO_PVCCIO_CPU1      B @BASEBOARD_FAB2_LIB.BASEBOARD_FAB2(SCH_1):SVID_VDIO_PVCCIO_CPU1

RES_0402-150.0,1%,1/16W,CHIP,GA  I46  R4D51
   1 SVID_CLK0_CPU1_R      A @BASEBOARD_FAB2_LIB.BASEBOARD_FAB2(SCH_1):SVID_CLK0_CPU1_R
   2 SVID_CLK_PVCCIO_CPU1      B @BASEBOARD_FAB2_LIB.BASEBOARD_FAB2(SCH_1):SVID_CLK_PVCCIO_CPU1

RES_0402-1.00K,1%,1/16W,CHIP,GA  I63  R4D49
   1 P3V3_STBY      A @BASEBOARD_FAB2_LIB.BASEBOARD_FAB2(SCH_1):P3V3_STBY
   2 IRQ_PVCCIO_CPU1_VRHOT_N      B @BASEBOARD_FAB2_LIB.BASEBOARD_FAB2(SCH_1):IRQ_PVCCIO_CPU1_VRHOT_N

CAP_0402LF-1000PF,50V,10%,X7R,A  I73  C4D33
   1 PWRGD_PVCCIO_CPU1_R      A @BASEBOARD_FAB2_LIB.BASEBOARD_FAB2(SCH_1):PWRGD_PVCCIO_CPU1_R
   2    GND      B @BASEBOARD_FAB2_LIB.BASEBOARD_FAB2(SCH_1):GND

CAP_0402LF-220PF,50V,10%,X7R,AA  I83  C4D44
   1 VR_PVCCIO_CPU1_AVSP      A @BASEBOARD_FAB2_LIB.BASEBOARD_FAB2(SCH_1):VR_PVCCIO_CPU1_AVSP
   2 VSENSE_PVCCIO_CPU1_AVSN      B @BASEBOARD_FAB2_LIB.BASEBOARD_FAB2(SCH_1):VSENSE_PVCCIO_CPU1_AVSN

RES_0402-10.0,1%,1/16W,CHIP,G2A  I84  R4E7
   1 VSENSE_PVCCIO_CPU1_AVSP      A @BASEBOARD_FAB2_LIB.BASEBOARD_FAB2(SCH_1):VSENSE_PVCCIO_CPU1_AVSP
   2 VR_PVCCIO_CPU1_AVSP      B @BASEBOARD_FAB2_LIB.BASEBOARD_FAB2(SCH_1):VR_PVCCIO_CPU1_AVSP

RES_0402-0.0,5%,1/16W,CHIP,G21A  I90  R6P41
   1 FM_PVCCIO_CPU1_EN      A @BASEBOARD_FAB2_LIB.BASEBOARD_FAB2(SCH_1):FM_PVCCIO_CPU1_EN
   2 VR_PVCCIO_CPU1_EN      B @BASEBOARD_FAB2_LIB.BASEBOARD_FAB2(SCH_1):VR_PVCCIO_CPU1_EN

RES_0402-100.0K,1%,1/16W,EMPTYA  I91  R6P40
   1 P3V3_STBY      A @BASEBOARD_FAB2_LIB.BASEBOARD_FAB2(SCH_1):P3V3_STBY
   2 VR_PVCCIO_CPU1_EN      B @BASEBOARD_FAB2_LIB.BASEBOARD_FAB2(SCH_1):VR_PVCCIO_CPU1_EN

PXE1110B_QFN-IC,H89187-001  I96  EU4D5
   1     NC DNC<0>     NC
   2     NC DNC<1>     NC
   3     NC  BPWM1     NC
   4     NC DNC<2>     NC
   5 VR_PVCCIO_CPU1_PWM1  APWM1 @BASEBOARD_FAB2_LIB.BASEBOARD_FAB2(SCH_1):VR_PVCCIO_CPU1_PWM1
   6 SMB_VR_STBY_LVC3_SDA    SDA @BASEBOARD_FAB2_LIB.BASEBOARD_FAB2(SCH_1):SMB_VR_STBY_LVC3_SDA
   7 SMB_VR_STBY_LVC3_SCL    SCL @BASEBOARD_FAB2_LIB.BASEBOARD_FAB2(SCH_1):SMB_VR_STBY_LVC3_SCL
   8     NC RESET_N     NC
   9 PWRGD_PVCCIO_CPU1_R AVRRDY @BASEBOARD_FAB2_LIB.BASEBOARD_FAB2(SCH_1):PWRGD_PVCCIO_CPU1_R
  10 VR_PVCCIO_CPU1_EN  AVREN @BASEBOARD_FAB2_LIB.BASEBOARD_FAB2(SCH_1):VR_PVCCIO_CPU1_EN
  11 IRQ_PVCCIO_CPU1_VRHOT_N VRHOT_N @BASEBOARD_FAB2_LIB.BASEBOARD_FAB2(SCH_1):IRQ_PVCCIO_CPU1_VRHOT_N
  12     NC PINALRT_N     NC
  13     NC    MP0     NC
  14     NC    MP1     NC
  15 SVID_CLK_PVCCIO_CPU1   VCLK @BASEBOARD_FAB2_LIB.BASEBOARD_FAB2(SCH_1):SVID_CLK_PVCCIO_CPU1
  16 SVID_VDIO_PVCCIO_CPU1   VDIO @BASEBOARD_FAB2_LIB.BASEBOARD_FAB2(SCH_1):SVID_VDIO_PVCCIO_CPU1
  17 SVID_ALERT_PVCCIO_CPU1 VALRT_N @BASEBOARD_FAB2_LIB.BASEBOARD_FAB2(SCH_1):SVID_ALERT_PVCCIO_CPU1
  18     NC    MP2     NC
  19 VR_PVCCIO_CPU1_AVSP  AVSEN @BASEBOARD_FAB2_LIB.BASEBOARD_FAB2(SCH_1):VR_PVCCIO_CPU1_AVSP
  20 VSENSE_PVCCIO_CPU1_AVSN  AVREF @BASEBOARD_FAB2_LIB.BASEBOARD_FAB2(SCH_1):VSENSE_PVCCIO_CPU1_AVSN
  21 VR_PVCCIO_CPU1_AIREF1 AIREF1 @BASEBOARD_FAB2_LIB.BASEBOARD_FAB2(SCH_1):VR_PVCCIO_CPU1_AIREF1
  22 ISENSE_PVCCIO_CPU1_PH1_IMON AISEN1 @BASEBOARD_FAB2_LIB.BASEBOARD_FAB2(SCH_1):ISENSE_PVCCIO_CPU1_PH1_IMON
  23    GND GND<1> @BASEBOARD_FAB2_LIB.BASEBOARD_FAB2(SCH_1):GND
  24     NC DNC<3>     NC
  25     NC BIREF1     NC
  26    GND BISEN1 @BASEBOARD_FAB2_LIB.BASEBOARD_FAB2(SCH_1):GND
  27    GND GND<0> @BASEBOARD_FAB2_LIB.BASEBOARD_FAB2(SCH_1):GND
  28     NC DNC<4>     NC
  29     NC  BVSEN     NC
  30     NC  BVREF     NC
  31     NC    MP3     NC
  32 PU_VR_PVCCIO_CPU1_FAULT1    MP4 @BASEBOARD_FAB2_LIB.BASEBOARD_FAB2(SCH_1):PU_VR_PVCCIO_CPU1_FAULT1
  33 VR_PVCCIO_CPU1_XADDR2 XADDR2 @BASEBOARD_FAB2_LIB.BASEBOARD_FAB2(SCH_1):VR_PVCCIO_CPU1_XADDR2
  34     NC  BTSEN     NC
  35 A_TSENSE_PVCCIO_CPU1  ATSEN @BASEBOARD_FAB2_LIB.BASEBOARD_FAB2(SCH_1):A_TSENSE_PVCCIO_CPU1
  36 VR_PVCCIO_CPU1_XADDR1 XADDR1 @BASEBOARD_FAB2_LIB.BASEBOARD_FAB2(SCH_1):VR_PVCCIO_CPU1_XADDR1
  37 VR_PVCCIO_CPU1_VINSEN VINSEN @BASEBOARD_FAB2_LIB.BASEBOARD_FAB2(SCH_1):VR_PVCCIO_CPU1_VINSEN
  38     NC IINSEN     NC
  39 VR_PVCCIO_CPU1_VDD    VDD @BASEBOARD_FAB2_LIB.BASEBOARD_FAB2(SCH_1):VR_PVCCIO_CPU1_VDD
  40 VR_PVCCIO_CPU1_VD12   VD12 @BASEBOARD_FAB2_LIB.BASEBOARD_FAB2(SCH_1):VR_PVCCIO_CPU1_VD12
  41    GND  THPAD @BASEBOARD_FAB2_LIB.BASEBOARD_FAB2(SCH_1):GND

SC22P50V2JN-4GP_SMD-BCG-SC22P5A  I98  CF14
   1 VR_PVCCIO_CPU1_AIREF1      1 @BASEBOARD_FAB2_LIB.BASEBOARD_FAB2(SCH_1):VR_PVCCIO_CPU1_AIREF1
   2 ISENSE_PVCCIO_CPU1_PH1_IMON      2 @BASEBOARD_FAB2_LIB.BASEBOARD_FAB2(SCH_1):ISENSE_PVCCIO_CPU1_PH1_IMON

RES_0402-1.0K,0.1%,1/16W,CHIP,A  I99  RF14
   1 VR_PVCCIO_CPU1_AIREF1      A @BASEBOARD_FAB2_LIB.BASEBOARD_FAB2(SCH_1):VR_PVCCIO_CPU1_AIREF1
   2 ISENSE_PVCCIO_CPU1_PH1_IMON      B @BASEBOARD_FAB2_LIB.BASEBOARD_FAB2(SCH_1):ISENSE_PVCCIO_CPU1_PH1_IMON

CAP_0402LF-220PF,50V,10%,X7R,AA  I101  C4W2
   1 A_TSENSE_PVCCIO_CPU1      A @BASEBOARD_FAB2_LIB.BASEBOARD_FAB2(SCH_1):A_TSENSE_PVCCIO_CPU1
   2    GND      B @BASEBOARD_FAB2_LIB.BASEBOARD_FAB2(SCH_1):GND

RES_0402-3.16K,1%,1/16W,CHIP,GA  I103  R4E2
   1 VR_PVCCIO_CPU1_XADDR2      A @BASEBOARD_FAB2_LIB.BASEBOARD_FAB2(SCH_1):VR_PVCCIO_CPU1_XADDR2
   2    GND      B @BASEBOARD_FAB2_LIB.BASEBOARD_FAB2(SCH_1):GND

RES_0402-3.16K,1%,1/16W,CHIP,GA  I104  R4D64
   1 VR_PVCCIO_CPU1_XADDR1      A @BASEBOARD_FAB2_LIB.BASEBOARD_FAB2(SCH_1):VR_PVCCIO_CPU1_XADDR1
   2    GND      B @BASEBOARD_FAB2_LIB.BASEBOARD_FAB2(SCH_1):GND

CAP_A_0402V-0.1UF,16V,10%,X7R,A  I105  C4D40
   1 VR_PVCCIO_CPU1_VINSEN      A @BASEBOARD_FAB2_LIB.BASEBOARD_FAB2(SCH_1):VR_PVCCIO_CPU1_VINSEN
   2    GND      B @BASEBOARD_FAB2_LIB.BASEBOARD_FAB2(SCH_1):GND


DRAWING: @BASEBOARD_FAB2_LIB.BASEBOARD_FAB2(SCH_1):PAGE214 

CAPP_3018-470UF,2.5V,20%,ALUM,A  I24  C6R5
   1 PVCCIO_CPU1      A @BASEBOARD_FAB2_LIB.BASEBOARD_FAB2(SCH_1):PVCCIO_CPU1
   2    GND      B @BASEBOARD_FAB2_LIB.BASEBOARD_FAB2(SCH_1):GND

CAP_A_0603V-22.0UF,4V,20%,X6S,A  I65  C7R1
   1 PVCCIO_CPU1      A @BASEBOARD_FAB2_LIB.BASEBOARD_FAB2(SCH_1):PVCCIO_CPU1
   2    GND      B @BASEBOARD_FAB2_LIB.BASEBOARD_FAB2(SCH_1):GND

CAP_0402-0.22UF,16V,10%,X7R,A3A  I73  C4E23
   1 P5V_STBY      A @BASEBOARD_FAB2_LIB.BASEBOARD_FAB2(SCH_1):P5V_STBY
   2    GND      B @BASEBOARD_FAB2_LIB.BASEBOARD_FAB2(SCH_1):GND

CAP_0402-1.0UF,16V,10%,X6S,D97A  I76  C4E22
   1 VR_PVCCIO_CPU1_PH1_VCIN      A @BASEBOARD_FAB2_LIB.BASEBOARD_FAB2(SCH_1):VR_PVCCIO_CPU1_PH1_VCIN
   2    GND      B @BASEBOARD_FAB2_LIB.BASEBOARD_FAB2(SCH_1):GND

CAP_A_0402V-0.1UF,16V,10%,X7R,A  I77  C4E13
   1 VR_FET_SW_P12V_STBY_PVCCIN_CPU0      A @BASEBOARD_FAB2_LIB.BASEBOARD_FAB2(SCH_1):VR_FET_SW_P12V_STBY_PVCCIN_CPU0
   2    GND      B @BASEBOARD_FAB2_LIB.BASEBOARD_FAB2(SCH_1):GND

CAP_0402-0.220UF,16V,10%,X7R,AA  I78  C4E18
   1 VR_PVCCIO_CPU1_PH1_BOOT      A @BASEBOARD_FAB2_LIB.BASEBOARD_FAB2(SCH_1):VR_PVCCIO_CPU1_PH1_BOOT
   2 VR_PVCCIO_CPU1_PH1_PHASE      B @BASEBOARD_FAB2_LIB.BASEBOARD_FAB2(SCH_1):VR_PVCCIO_CPU1_PH1_PHASE

CAP_0402-1.0UF,16V,10%,X6S,D97A  I79  C4E15
   1 VR_FET_SW_P12V_STBY_PVCCIN_CPU0      A @BASEBOARD_FAB2_LIB.BASEBOARD_FAB2(SCH_1):VR_FET_SW_P12V_STBY_PVCCIN_CPU0
   2    GND      B @BASEBOARD_FAB2_LIB.BASEBOARD_FAB2(SCH_1):GND

CAP_0805-10UF,16V,10%,X6S,C953A  I80  C6R14
   1 VR_FET_SW_P12V_STBY_PVCCIN_CPU0      A @BASEBOARD_FAB2_LIB.BASEBOARD_FAB2(SCH_1):VR_FET_SW_P12V_STBY_PVCCIN_CPU0
   2    GND      B @BASEBOARD_FAB2_LIB.BASEBOARD_FAB2(SCH_1):GND

CAP_0805-10UF,16V,10%,X6S,C953A  I81  C6R10
   1 VR_FET_SW_P12V_STBY_PVCCIN_CPU0      A @BASEBOARD_FAB2_LIB.BASEBOARD_FAB2(SCH_1):VR_FET_SW_P12V_STBY_PVCCIN_CPU0
   2    GND      B @BASEBOARD_FAB2_LIB.BASEBOARD_FAB2(SCH_1):GND

CAP_0805-10UF,16V,10%,X6S,C953A  I83  C6R8
   1 VR_FET_SW_P12V_STBY_PVCCIN_CPU0      A @BASEBOARD_FAB2_LIB.BASEBOARD_FAB2(SCH_1):VR_FET_SW_P12V_STBY_PVCCIN_CPU0
   2    GND      B @BASEBOARD_FAB2_LIB.BASEBOARD_FAB2(SCH_1):GND

CAP_A_0402V-0.1UF,16V,10%,EMPTA  I96  C3D27
   1 VSENSE_PVCCIO_CPU1_SKT_VSEN      A @BASEBOARD_FAB2_LIB.BASEBOARD_FAB2(SCH_1):VSENSE_PVCCIO_CPU1_SKT_VSEN
   2 VSENSE_PVCCIO_CPU1_SKT_VRTN      B @BASEBOARD_FAB2_LIB.BASEBOARD_FAB2(SCH_1):VSENSE_PVCCIO_CPU1_SKT_VRTN

RES_0402-100.0,1%,1/16W,CHIP,GA  I101  R3D28
   1 VSENSE_PVCCIO_CPU1_AVSN      A @BASEBOARD_FAB2_LIB.BASEBOARD_FAB2(SCH_1):VSENSE_PVCCIO_CPU1_AVSN
   2    GND      B @BASEBOARD_FAB2_LIB.BASEBOARD_FAB2(SCH_1):GND

RES_0402-100.0,1%,1/16W,CHIP,GA  I105  R3E1
   1 VSENSE_PVCCIO_CPU1_AVSP      A @BASEBOARD_FAB2_LIB.BASEBOARD_FAB2(SCH_1):VSENSE_PVCCIO_CPU1_AVSP
   2 PVCCIO_CPU1      B @BASEBOARD_FAB2_LIB.BASEBOARD_FAB2(SCH_1):PVCCIO_CPU1

CAP_A_0603V-22.0UF,4V,20%,X6S,A  I108  C3E1
   1 PVCCIO_CPU1      A @BASEBOARD_FAB2_LIB.BASEBOARD_FAB2(SCH_1):PVCCIO_CPU1
   2    GND      B @BASEBOARD_FAB2_LIB.BASEBOARD_FAB2(SCH_1):GND

RES_0402-51.1,1.0%,1/16W,CHIP,A  I109  R7R1
   1 PVCCIO_CPU1      A @BASEBOARD_FAB2_LIB.BASEBOARD_FAB2(SCH_1):PVCCIO_CPU1
   2    GND      B @BASEBOARD_FAB2_LIB.BASEBOARD_FAB2(SCH_1):GND

IR354XX_SM-IR35412,IC,H73684-0A  I126  EU4E2
  33 VR_PVCCIO_CPU1_PH1_BOOT_R  BOOST @BASEBOARD_FAB2_LIB.BASEBOARD_FAB2(SCH_1):VR_PVCCIO_CPU1_PH1_BOOT_R
  35 P5V_STBY     EN @BASEBOARD_FAB2_LIB.BASEBOARD_FAB2(SCH_1):P5V_STBY
  41 TP_PVCCIO_CPU1_GL_1  GL<1> @BASEBOARD_FAB2_LIB.BASEBOARD_FAB2(SCH_1):TP_PVCCIO_CPU1_GL_1
   6 TP_PVCCIO_CPU1_GL_0  GL<0> @BASEBOARD_FAB2_LIB.BASEBOARD_FAB2(SCH_1):TP_PVCCIO_CPU1_GL_0
  38 ISENSE_PVCCIO_CPU1_PH1_IMON   IOUT @BASEBOARD_FAB2_LIB.BASEBOARD_FAB2(SCH_1):ISENSE_PVCCIO_CPU1_PH1_IMON
   2    GND   LGND @BASEBOARD_FAB2_LIB.BASEBOARD_FAB2(SCH_1):GND
  31     NC     NC     NC
  37 VR_PVCCIO_CPU1_OCSET  OCSET @BASEBOARD_FAB2_LIB.BASEBOARD_FAB2(SCH_1):VR_PVCCIO_CPU1_OCSET
  40    GND PGND<2> @BASEBOARD_FAB2_LIB.BASEBOARD_FAB2(SCH_1):GND
   7    GND PGND<1> @BASEBOARD_FAB2_LIB.BASEBOARD_FAB2(SCH_1):GND
   5    GND PGND<0> @BASEBOARD_FAB2_LIB.BASEBOARD_FAB2(SCH_1):GND
  32 VR_PVCCIO_CPU1_PH1_PHASE  PHASE @BASEBOARD_FAB2_LIB.BASEBOARD_FAB2(SCH_1):VR_PVCCIO_CPU1_PH1_PHASE
  34 VR_PVCCIO_CPU1_PWM1    PWM @BASEBOARD_FAB2_LIB.BASEBOARD_FAB2(SCH_1):VR_PVCCIO_CPU1_PWM1
  39 VR_PVCCIO_CPU1_AIREF1  REFIN @BASEBOARD_FAB2_LIB.BASEBOARD_FAB2(SCH_1):VR_PVCCIO_CPU1_AIREF1
  10 VR_PVCCIO_CPU1_PH1_SW     SW @BASEBOARD_FAB2_LIB.BASEBOARD_FAB2(SCH_1):VR_PVCCIO_CPU1_PH1_SW
  36 A_TSENSE_PVCCIO_CPU1 TOUT_FLT @BASEBOARD_FAB2_LIB.BASEBOARD_FAB2(SCH_1):A_TSENSE_PVCCIO_CPU1
   3 VR_PVCCIO_CPU1_PH1_VCIN    VCC @BASEBOARD_FAB2_LIB.BASEBOARD_FAB2(SCH_1):VR_PVCCIO_CPU1_PH1_VCIN
   4 P5V_STBY   VDRV @BASEBOARD_FAB2_LIB.BASEBOARD_FAB2(SCH_1):P5V_STBY
  30 VR_FET_SW_P12V_STBY_PVCCIN_CPU0 VIN<1> @BASEBOARD_FAB2_LIB.BASEBOARD_FAB2(SCH_1):VR_FET_SW_P12V_STBY_PVCCIN_CPU0
  25 VR_FET_SW_P12V_STBY_PVCCIN_CPU0 VIN<0> @BASEBOARD_FAB2_LIB.BASEBOARD_FAB2(SCH_1):VR_FET_SW_P12V_STBY_PVCCIN_CPU0
   1 PVCCIO_CPU1    VOS @BASEBOARD_FAB2_LIB.BASEBOARD_FAB2(SCH_1):PVCCIO_CPU1

RES_0402-68.1K,1%,1/16W,EMPTY,A  I127  R4E21
   1 VR_PVCCIO_CPU1_OCSET      A @BASEBOARD_FAB2_LIB.BASEBOARD_FAB2(SCH_1):VR_PVCCIO_CPU1_OCSET
   2    GND      B @BASEBOARD_FAB2_LIB.BASEBOARD_FAB2(SCH_1):GND

SHUNT_SH0201-EMPTY,N_A  I129  SH3D2
   1 VSENSE_PVCCIO_CPU1_SKT_VSEN      A @BASEBOARD_FAB2_LIB.BASEBOARD_FAB2(SCH_1):VSENSE_PVCCIO_CPU1_SKT_VSEN
   2 VSENSE_PVCCIO_CPU1_AVSP      B @BASEBOARD_FAB2_LIB.BASEBOARD_FAB2(SCH_1):VSENSE_PVCCIO_CPU1_AVSP

SHUNT_SH0201-EMPTY,N_A  I130  SH3D1
   1 VSENSE_PVCCIO_CPU1_SKT_VRTN      A @BASEBOARD_FAB2_LIB.BASEBOARD_FAB2(SCH_1):VSENSE_PVCCIO_CPU1_SKT_VRTN
   2 VSENSE_PVCCIO_CPU1_AVSN      B @BASEBOARD_FAB2_LIB.BASEBOARD_FAB2(SCH_1):VSENSE_PVCCIO_CPU1_AVSN

CAP_0402LF-1000PF,50V,10%,X7R,A  I134  CT61
   1 A_TSENSE_PVCCIO_CPU1      A @BASEBOARD_FAB2_LIB.BASEBOARD_FAB2(SCH_1):A_TSENSE_PVCCIO_CPU1
   2    GND      B @BASEBOARD_FAB2_LIB.BASEBOARD_FAB2(SCH_1):GND

CAP_A_0402V-0.1UF,16V,10%,X7R,A  I137  CT63
   1 VR_PVCCIO_CPU1_AIREF1      A @BASEBOARD_FAB2_LIB.BASEBOARD_FAB2(SCH_1):VR_PVCCIO_CPU1_AIREF1
   2    GND      B @BASEBOARD_FAB2_LIB.BASEBOARD_FAB2(SCH_1):GND

CAP_0402LF-1000PF,50V,10%,X7R,A  I143  CT62
   1 VR_PVCCIO_CPU1_PH1_SW      A @BASEBOARD_FAB2_LIB.BASEBOARD_FAB2(SCH_1):VR_PVCCIO_CPU1_PH1_SW
   2 VR_PVCCIO_CPU1_PH1_SW_RC      B @BASEBOARD_FAB2_LIB.BASEBOARD_FAB2(SCH_1):VR_PVCCIO_CPU1_PH1_SW_RC

RES_0603-0,5.0%,1/10W,CHIP,G22A  I145  RT41
   1 VR_PVCCIO_CPU1_PH1_BOOT      A @BASEBOARD_FAB2_LIB.BASEBOARD_FAB2(SCH_1):VR_PVCCIO_CPU1_PH1_BOOT
   2 VR_PVCCIO_CPU1_PH1_BOOT_R      B @BASEBOARD_FAB2_LIB.BASEBOARD_FAB2(SCH_1):VR_PVCCIO_CPU1_PH1_BOOT_R

SC22U16V5MX-4-GP_SMD-BCG5-SC22A  I148  C4E14
   1 VR_FET_SW_P12V_STBY_PVCCIN_CPU0      1 @BASEBOARD_FAB2_LIB.BASEBOARD_FAB2(SCH_1):VR_FET_SW_P12V_STBY_PVCCIN_CPU0
   2    GND      2 @BASEBOARD_FAB2_LIB.BASEBOARD_FAB2(SCH_1):GND

SC22U16V5MX-4-GP_SMD-BCG5-SC22A  I149  C22W13
   1 VR_FET_SW_P12V_STBY_PVCCIN_CPU0      1 @BASEBOARD_FAB2_LIB.BASEBOARD_FAB2(SCH_1):VR_FET_SW_P12V_STBY_PVCCIN_CPU0
   2    GND      2 @BASEBOARD_FAB2_LIB.BASEBOARD_FAB2(SCH_1):GND

SC22U16V5MX-4-GP_SMD-BCG5-SC22A  I152  C22W14
   1 VR_FET_SW_P12V_STBY_PVCCIN_CPU0      1 @BASEBOARD_FAB2_LIB.BASEBOARD_FAB2(SCH_1):VR_FET_SW_P12V_STBY_PVCCIN_CPU0
   2    GND      2 @BASEBOARD_FAB2_LIB.BASEBOARD_FAB2(SCH_1):GND

SC22U16V5MX-4-GP_SMD-BCG5-SC22A  I154  C22W15
   1 VR_FET_SW_P12V_STBY_PVCCIN_CPU0      1 @BASEBOARD_FAB2_LIB.BASEBOARD_FAB2(SCH_1):VR_FET_SW_P12V_STBY_PVCCIN_CPU0
   2    GND      2 @BASEBOARD_FAB2_LIB.BASEBOARD_FAB2(SCH_1):GND

SC22U16V5MX-4-GP_SMD-BCG5-SC22A  I156  C22W18
   1 VR_FET_SW_P12V_STBY_PVCCIN_CPU0      1 @BASEBOARD_FAB2_LIB.BASEBOARD_FAB2(SCH_1):VR_FET_SW_P12V_STBY_PVCCIN_CPU0
   2    GND      2 @BASEBOARD_FAB2_LIB.BASEBOARD_FAB2(SCH_1):GND

SC22U16V5MX-4-GP_SMD-BCG5-SC22A  I158  C22W17
   1 VR_FET_SW_P12V_STBY_PVCCIN_CPU0      1 @BASEBOARD_FAB2_LIB.BASEBOARD_FAB2(SCH_1):VR_FET_SW_P12V_STBY_PVCCIN_CPU0
   2    GND      2 @BASEBOARD_FAB2_LIB.BASEBOARD_FAB2(SCH_1):GND

SC22U16V5MX-4-GP_SMD-BCG5-SC22A  I160  C22W16
   1 VR_FET_SW_P12V_STBY_PVCCIN_CPU0      1 @BASEBOARD_FAB2_LIB.BASEBOARD_FAB2(SCH_1):VR_FET_SW_P12V_STBY_PVCCIN_CPU0
   2    GND      2 @BASEBOARD_FAB2_LIB.BASEBOARD_FAB2(SCH_1):GND

SC22U16V5MX-4-GP_SMD-BCG5-SC22A  I161  C4E8
   1 VR_FET_SW_P12V_STBY_PVCCIN_CPU0      1 @BASEBOARD_FAB2_LIB.BASEBOARD_FAB2(SCH_1):VR_FET_SW_P12V_STBY_PVCCIN_CPU0
   2    GND      2 @BASEBOARD_FAB2_LIB.BASEBOARD_FAB2(SCH_1):GND

SC22U16V5MX-4-GP_SMD-BCG5-SC22A  I164  C4E9
   1 VR_FET_SW_P12V_STBY_PVCCIN_CPU0      1 @BASEBOARD_FAB2_LIB.BASEBOARD_FAB2(SCH_1):VR_FET_SW_P12V_STBY_PVCCIN_CPU0
   2    GND      2 @BASEBOARD_FAB2_LIB.BASEBOARD_FAB2(SCH_1):GND

SC22U16V5MX-4-GP_SMD-BCG5-SC22A  I166  C22W21
   1 VR_FET_SW_P12V_STBY_PVCCIN_CPU0      1 @BASEBOARD_FAB2_LIB.BASEBOARD_FAB2(SCH_1):VR_FET_SW_P12V_STBY_PVCCIN_CPU0
   2    GND      2 @BASEBOARD_FAB2_LIB.BASEBOARD_FAB2(SCH_1):GND

SC22U16V5MX-4-GP_SMD-BCG5-SC22A  I168  C22W20
   1 VR_FET_SW_P12V_STBY_PVCCIN_CPU0      1 @BASEBOARD_FAB2_LIB.BASEBOARD_FAB2(SCH_1):VR_FET_SW_P12V_STBY_PVCCIN_CPU0
   2    GND      2 @BASEBOARD_FAB2_LIB.BASEBOARD_FAB2(SCH_1):GND

SC22U16V5MX-4-GP_SMD-BCG5-SC22A  I169  C22W19
   1 VR_FET_SW_P12V_STBY_PVCCIN_CPU0      1 @BASEBOARD_FAB2_LIB.BASEBOARD_FAB2(SCH_1):VR_FET_SW_P12V_STBY_PVCCIN_CPU0
   2    GND      2 @BASEBOARD_FAB2_LIB.BASEBOARD_FAB2(SCH_1):GND

RES_0402-0.0,5%,1/16W,CHIP,G21A  I173  R6R5
   1 VR_PVCCIO_CPU1_PH1_VCIN      A @BASEBOARD_FAB2_LIB.BASEBOARD_FAB2(SCH_1):VR_PVCCIO_CPU1_PH1_VCIN
   2 P5V_STBY      B @BASEBOARD_FAB2_LIB.BASEBOARD_FAB2(SCH_1):P5V_STBY

IND-150NH-56-GP_DISCRET-GA1-INA  I174  L4E2
   1 VR_PVCCIO_CPU1_PH1_SW      S @BASEBOARD_FAB2_LIB.BASEBOARD_FAB2(SCH_1):VR_PVCCIO_CPU1_PH1_SW
   2 PVCCIO_CPU1      F @BASEBOARD_FAB2_LIB.BASEBOARD_FAB2(SCH_1):PVCCIO_CPU1

SC1U10V2KX-4-GP_SMD-BCG6-SC1U1A  I175  C4E28
   1 P5V_STBY      1 @BASEBOARD_FAB2_LIB.BASEBOARD_FAB2(SCH_1):P5V_STBY
   2    GND      2 @BASEBOARD_FAB2_LIB.BASEBOARD_FAB2(SCH_1):GND

1R3F-GP_RCL_GP-1R3F-GP,64.1R00A  I176  RT42
   1 VR_PVCCIO_CPU1_PH1_SW_RC      1 @BASEBOARD_FAB2_LIB.BASEBOARD_FAB2(SCH_1):VR_PVCCIO_CPU1_PH1_SW_RC
   2    GND      2 @BASEBOARD_FAB2_LIB.BASEBOARD_FAB2(SCH_1):GND

CAPP_3018-470UF,2.5V,20%,ALUM,A  I177  C6R12
   1 PVCCIO_CPU1      A @BASEBOARD_FAB2_LIB.BASEBOARD_FAB2(SCH_1):PVCCIO_CPU1
   2    GND      B @BASEBOARD_FAB2_LIB.BASEBOARD_FAB2(SCH_1):GND

CAPP_3018-470UF,2.5V,20%,ALUM,A  I178  C4E7
   1 PVCCIO_CPU1      A @BASEBOARD_FAB2_LIB.BASEBOARD_FAB2(SCH_1):PVCCIO_CPU1
   2    GND      B @BASEBOARD_FAB2_LIB.BASEBOARD_FAB2(SCH_1):GND


DRAWING: @BASEBOARD_FAB2_LIB.BASEBOARD_FAB2(SCH_1):PAGE216 

CAP_0805LF-22UF,4V,20%,X6S,C95A  I6  C6G3
   1 PVDDQ_ABC      A @BASEBOARD_FAB2_LIB.BASEBOARD_FAB2(SCH_1):PVDDQ_ABC
   2    GND      B @BASEBOARD_FAB2_LIB.BASEBOARD_FAB2(SCH_1):GND

CAP_0402-0.220UF,16V,10%,X7R,AA  I44  C7G31
   1 VR_PVDDQ_ABC_PH1_BOOT      A @BASEBOARD_FAB2_LIB.BASEBOARD_FAB2(SCH_1):VR_PVDDQ_ABC_PH1_BOOT
   2 VR_PVDDQ_ABC_PH1_PHASE      B @BASEBOARD_FAB2_LIB.BASEBOARD_FAB2(SCH_1):VR_PVDDQ_ABC_PH1_PHASE

CAP_0805-10UF,16V,10%,X6S,C953A  I45  C3U2
   1 VR_FET_SW_P12V_STBY_PVDDQ_ABC      A @BASEBOARD_FAB2_LIB.BASEBOARD_FAB2(SCH_1):VR_FET_SW_P12V_STBY_PVDDQ_ABC
   2    GND      B @BASEBOARD_FAB2_LIB.BASEBOARD_FAB2(SCH_1):GND

CAP_0805-10UF,16V,10%,X6S,C953A  I46  C3U3
   1 VR_FET_SW_P12V_STBY_PVDDQ_ABC      A @BASEBOARD_FAB2_LIB.BASEBOARD_FAB2(SCH_1):VR_FET_SW_P12V_STBY_PVDDQ_ABC
   2    GND      B @BASEBOARD_FAB2_LIB.BASEBOARD_FAB2(SCH_1):GND

CAP_0805-10UF,16V,10%,X6S,C953A  I47  C3U4
   1 VR_FET_SW_P12V_STBY_PVDDQ_ABC      A @BASEBOARD_FAB2_LIB.BASEBOARD_FAB2(SCH_1):VR_FET_SW_P12V_STBY_PVDDQ_ABC
   2    GND      B @BASEBOARD_FAB2_LIB.BASEBOARD_FAB2(SCH_1):GND

CAP_0402-1.0UF,16V,10%,X6S,D97A  I48  C7G37
   1 VR_FET_SW_P12V_STBY_PVDDQ_ABC      A @BASEBOARD_FAB2_LIB.BASEBOARD_FAB2(SCH_1):VR_FET_SW_P12V_STBY_PVDDQ_ABC
   2    GND      B @BASEBOARD_FAB2_LIB.BASEBOARD_FAB2(SCH_1):GND

CAP_0402-1.0UF,16V,10%,X6S,D97A  I50  C7G33
   1 VR_PVDDQ_ABC_PH1_VCIN      A @BASEBOARD_FAB2_LIB.BASEBOARD_FAB2(SCH_1):VR_PVDDQ_ABC_PH1_VCIN
   2    GND      B @BASEBOARD_FAB2_LIB.BASEBOARD_FAB2(SCH_1):GND

CAP_A_0402V-0.1UF,16V,10%,X7R,A  I51  C7G29
   1 VR_FET_SW_P12V_STBY_PVDDQ_ABC      A @BASEBOARD_FAB2_LIB.BASEBOARD_FAB2(SCH_1):VR_FET_SW_P12V_STBY_PVDDQ_ABC
   2    GND      B @BASEBOARD_FAB2_LIB.BASEBOARD_FAB2(SCH_1):GND

CAP_0402-0.22UF,16V,10%,X7R,A3A  I54  C7G34
   1 P5V_STBY      A @BASEBOARD_FAB2_LIB.BASEBOARD_FAB2(SCH_1):P5V_STBY
   2    GND      B @BASEBOARD_FAB2_LIB.BASEBOARD_FAB2(SCH_1):GND

CAP_0805LF-22UF,4V,20%,X6S,C95A  I68  C7G27
   1 PVDDQ_ABC      A @BASEBOARD_FAB2_LIB.BASEBOARD_FAB2(SCH_1):PVDDQ_ABC
   2    GND      B @BASEBOARD_FAB2_LIB.BASEBOARD_FAB2(SCH_1):GND

CAP_0402-0.22UF,16V,10%,X7R,A3A  I72  C7G41
   1 P5V_STBY      A @BASEBOARD_FAB2_LIB.BASEBOARD_FAB2(SCH_1):P5V_STBY
   2    GND      B @BASEBOARD_FAB2_LIB.BASEBOARD_FAB2(SCH_1):GND

CAP_0402-1.0UF,16V,10%,X6S,D97A  I77  C7G40
   1 VR_PVDDQ_ABC_PH2_VCIN      A @BASEBOARD_FAB2_LIB.BASEBOARD_FAB2(SCH_1):VR_PVDDQ_ABC_PH2_VCIN
   2    GND      B @BASEBOARD_FAB2_LIB.BASEBOARD_FAB2(SCH_1):GND

CAP_A_0402V-0.1UF,16V,10%,X7R,A  I78  C7G36
   1 VR_FET_SW_P12V_STBY_PVDDQ_ABC      A @BASEBOARD_FAB2_LIB.BASEBOARD_FAB2(SCH_1):VR_FET_SW_P12V_STBY_PVDDQ_ABC
   2    GND      B @BASEBOARD_FAB2_LIB.BASEBOARD_FAB2(SCH_1):GND

CAP_0402-1.0UF,16V,10%,X6S,D97A  I79  C7G30
   1 VR_FET_SW_P12V_STBY_PVDDQ_ABC      A @BASEBOARD_FAB2_LIB.BASEBOARD_FAB2(SCH_1):VR_FET_SW_P12V_STBY_PVDDQ_ABC
   2    GND      B @BASEBOARD_FAB2_LIB.BASEBOARD_FAB2(SCH_1):GND

CAP_0805-10UF,16V,10%,X6S,C953A  I80  C3U9
   1 VR_FET_SW_P12V_STBY_PVDDQ_ABC      A @BASEBOARD_FAB2_LIB.BASEBOARD_FAB2(SCH_1):VR_FET_SW_P12V_STBY_PVDDQ_ABC
   2    GND      B @BASEBOARD_FAB2_LIB.BASEBOARD_FAB2(SCH_1):GND

CAP_0805-10UF,16V,10%,X6S,C953A  I81  C3U7
   1 VR_FET_SW_P12V_STBY_PVDDQ_ABC      A @BASEBOARD_FAB2_LIB.BASEBOARD_FAB2(SCH_1):VR_FET_SW_P12V_STBY_PVDDQ_ABC
   2    GND      B @BASEBOARD_FAB2_LIB.BASEBOARD_FAB2(SCH_1):GND

CAP_0805-10UF,16V,10%,X6S,C953A  I84  C3U6
   1 VR_FET_SW_P12V_STBY_PVDDQ_ABC      A @BASEBOARD_FAB2_LIB.BASEBOARD_FAB2(SCH_1):VR_FET_SW_P12V_STBY_PVDDQ_ABC
   2    GND      B @BASEBOARD_FAB2_LIB.BASEBOARD_FAB2(SCH_1):GND

IR354XX_SM-IR35411,IC,H73688-0A  I102  EU7G2
  33 VR_PVDDQ_ABC_PH1_BOOT_R  BOOST @BASEBOARD_FAB2_LIB.BASEBOARD_FAB2(SCH_1):VR_PVDDQ_ABC_PH1_BOOT_R
  35 P5V_STBY     EN @BASEBOARD_FAB2_LIB.BASEBOARD_FAB2(SCH_1):P5V_STBY
  41 TP_PVDDQ_ABC_PH1_GL_1  GL<1> @BASEBOARD_FAB2_LIB.BASEBOARD_FAB2(SCH_1):TP_PVDDQ_ABC_PH1_GL_1
   6 TP_PVDDQ_ABC_PH1_GL_0  GL<0> @BASEBOARD_FAB2_LIB.BASEBOARD_FAB2(SCH_1):TP_PVDDQ_ABC_PH1_GL_0
  38 ISENSE_PVDDQ_ABC_PH1_IMON   IOUT @BASEBOARD_FAB2_LIB.BASEBOARD_FAB2(SCH_1):ISENSE_PVDDQ_ABC_PH1_IMON
   2    GND   LGND @BASEBOARD_FAB2_LIB.BASEBOARD_FAB2(SCH_1):GND
  31     NC     NC     NC
  37 VR_PVDDQ_ABC_PH1_OCSET  OCSET @BASEBOARD_FAB2_LIB.BASEBOARD_FAB2(SCH_1):VR_PVDDQ_ABC_PH1_OCSET
  40    GND PGND<2> @BASEBOARD_FAB2_LIB.BASEBOARD_FAB2(SCH_1):GND
   7    GND PGND<1> @BASEBOARD_FAB2_LIB.BASEBOARD_FAB2(SCH_1):GND
   5    GND PGND<0> @BASEBOARD_FAB2_LIB.BASEBOARD_FAB2(SCH_1):GND
  32 VR_PVDDQ_ABC_PH1_PHASE  PHASE @BASEBOARD_FAB2_LIB.BASEBOARD_FAB2(SCH_1):VR_PVDDQ_ABC_PH1_PHASE
  34 VR_PVDDQ_ABC_PWM1    PWM @BASEBOARD_FAB2_LIB.BASEBOARD_FAB2(SCH_1):VR_PVDDQ_ABC_PWM1
  39 VR_PVDDQ_ABC_AIREF1  REFIN @BASEBOARD_FAB2_LIB.BASEBOARD_FAB2(SCH_1):VR_PVDDQ_ABC_AIREF1
  10 VR_PVDDQ_ABC_PH1_SW     SW @BASEBOARD_FAB2_LIB.BASEBOARD_FAB2(SCH_1):VR_PVDDQ_ABC_PH1_SW
  36 A_TSENSE_PVDDQ_ABC TOUT_FLT @BASEBOARD_FAB2_LIB.BASEBOARD_FAB2(SCH_1):A_TSENSE_PVDDQ_ABC
   3 VR_PVDDQ_ABC_PH1_VCIN    VCC @BASEBOARD_FAB2_LIB.BASEBOARD_FAB2(SCH_1):VR_PVDDQ_ABC_PH1_VCIN
   4 P5V_STBY   VDRV @BASEBOARD_FAB2_LIB.BASEBOARD_FAB2(SCH_1):P5V_STBY
  30 VR_FET_SW_P12V_STBY_PVDDQ_ABC VIN<1> @BASEBOARD_FAB2_LIB.BASEBOARD_FAB2(SCH_1):VR_FET_SW_P12V_STBY_PVDDQ_ABC
  25 VR_FET_SW_P12V_STBY_PVDDQ_ABC VIN<0> @BASEBOARD_FAB2_LIB.BASEBOARD_FAB2(SCH_1):VR_FET_SW_P12V_STBY_PVDDQ_ABC
   1 PVDDQ_ABC    VOS @BASEBOARD_FAB2_LIB.BASEBOARD_FAB2(SCH_1):PVDDQ_ABC

IR354XX_SM-IR35411,IC,H73688-0A  I103  EU7G3
  33 VR_PVDDQ_ABC_PH2_BOOT_R  BOOST @BASEBOARD_FAB2_LIB.BASEBOARD_FAB2(SCH_1):VR_PVDDQ_ABC_PH2_BOOT_R
  35 P5V_STBY     EN @BASEBOARD_FAB2_LIB.BASEBOARD_FAB2(SCH_1):P5V_STBY
  41 TP_PVDDQ_ABC_PH2_GL_1  GL<1> @BASEBOARD_FAB2_LIB.BASEBOARD_FAB2(SCH_1):TP_PVDDQ_ABC_PH2_GL_1
   6 TP_PVDDQ_ABC_PH2_GL_0  GL<0> @BASEBOARD_FAB2_LIB.BASEBOARD_FAB2(SCH_1):TP_PVDDQ_ABC_PH2_GL_0
  38 ISENSE_PVDDQ_ABC_PH2_IMON   IOUT @BASEBOARD_FAB2_LIB.BASEBOARD_FAB2(SCH_1):ISENSE_PVDDQ_ABC_PH2_IMON
   2    GND   LGND @BASEBOARD_FAB2_LIB.BASEBOARD_FAB2(SCH_1):GND
  31     NC     NC     NC
  37 VR_PVDDQ_ABC_PH2_OCSET  OCSET @BASEBOARD_FAB2_LIB.BASEBOARD_FAB2(SCH_1):VR_PVDDQ_ABC_PH2_OCSET
  40    GND PGND<2> @BASEBOARD_FAB2_LIB.BASEBOARD_FAB2(SCH_1):GND
   7    GND PGND<1> @BASEBOARD_FAB2_LIB.BASEBOARD_FAB2(SCH_1):GND
   5    GND PGND<0> @BASEBOARD_FAB2_LIB.BASEBOARD_FAB2(SCH_1):GND
  32 VR_PVDDQ_ABC_PH2_PHASE  PHASE @BASEBOARD_FAB2_LIB.BASEBOARD_FAB2(SCH_1):VR_PVDDQ_ABC_PH2_PHASE
  34 VR_PVDDQ_ABC_PWM2    PWM @BASEBOARD_FAB2_LIB.BASEBOARD_FAB2(SCH_1):VR_PVDDQ_ABC_PWM2
  39 VR_PVDDQ_ABC_AIREF2  REFIN @BASEBOARD_FAB2_LIB.BASEBOARD_FAB2(SCH_1):VR_PVDDQ_ABC_AIREF2
  10 VR_PVDDQ_ABC_PH2_SW     SW @BASEBOARD_FAB2_LIB.BASEBOARD_FAB2(SCH_1):VR_PVDDQ_ABC_PH2_SW
  36 A_TSENSE_PVDDQ_ABC TOUT_FLT @BASEBOARD_FAB2_LIB.BASEBOARD_FAB2(SCH_1):A_TSENSE_PVDDQ_ABC
   3 VR_PVDDQ_ABC_PH2_VCIN    VCC @BASEBOARD_FAB2_LIB.BASEBOARD_FAB2(SCH_1):VR_PVDDQ_ABC_PH2_VCIN
   4 P5V_STBY   VDRV @BASEBOARD_FAB2_LIB.BASEBOARD_FAB2(SCH_1):P5V_STBY
  30 VR_FET_SW_P12V_STBY_PVDDQ_ABC VIN<1> @BASEBOARD_FAB2_LIB.BASEBOARD_FAB2(SCH_1):VR_FET_SW_P12V_STBY_PVDDQ_ABC
  25 VR_FET_SW_P12V_STBY_PVDDQ_ABC VIN<0> @BASEBOARD_FAB2_LIB.BASEBOARD_FAB2(SCH_1):VR_FET_SW_P12V_STBY_PVDDQ_ABC
   1 PVDDQ_ABC    VOS @BASEBOARD_FAB2_LIB.BASEBOARD_FAB2(SCH_1):PVDDQ_ABC

RES_0402-68.1K,1%,1/16W,EMPTY,A  I104  R7G25
   1 VR_PVDDQ_ABC_PH1_OCSET      A @BASEBOARD_FAB2_LIB.BASEBOARD_FAB2(SCH_1):VR_PVDDQ_ABC_PH1_OCSET
   2    GND      B @BASEBOARD_FAB2_LIB.BASEBOARD_FAB2(SCH_1):GND

RES_0402-68.1K,1%,1/16W,EMPTY,A  I106  R7G30
   1 VR_PVDDQ_ABC_PH2_OCSET      A @BASEBOARD_FAB2_LIB.BASEBOARD_FAB2(SCH_1):VR_PVDDQ_ABC_PH2_OCSET
   2    GND      B @BASEBOARD_FAB2_LIB.BASEBOARD_FAB2(SCH_1):GND

CAP_A_0402V-0.1UF,16V,10%,X7R,A  I108  CT51
   1 VR_PVDDQ_ABC_AIREF1      A @BASEBOARD_FAB2_LIB.BASEBOARD_FAB2(SCH_1):VR_PVDDQ_ABC_AIREF1
   2    GND      B @BASEBOARD_FAB2_LIB.BASEBOARD_FAB2(SCH_1):GND

CAP_A_0402V-0.1UF,16V,10%,X7R,A  I111  CT52
   1 VR_PVDDQ_ABC_AIREF2      A @BASEBOARD_FAB2_LIB.BASEBOARD_FAB2(SCH_1):VR_PVDDQ_ABC_AIREF2
   2    GND      B @BASEBOARD_FAB2_LIB.BASEBOARD_FAB2(SCH_1):GND

CAP_0402LF-1000PF,50V,10%,X7R,A  I118  CT49
   1 A_TSENSE_PVDDQ_ABC      A @BASEBOARD_FAB2_LIB.BASEBOARD_FAB2(SCH_1):A_TSENSE_PVDDQ_ABC
   2    GND      B @BASEBOARD_FAB2_LIB.BASEBOARD_FAB2(SCH_1):GND

CAP_0402LF-1000PF,50V,10%,X7R,A  I121  CT54
   1 A_TSENSE_PVDDQ_ABC      A @BASEBOARD_FAB2_LIB.BASEBOARD_FAB2(SCH_1):A_TSENSE_PVDDQ_ABC
   2    GND      B @BASEBOARD_FAB2_LIB.BASEBOARD_FAB2(SCH_1):GND

CAP_0402-0.220UF,16V,10%,X7R,AA  I128  C7G38
   1 VR_PVDDQ_ABC_PH2_BOOT      A @BASEBOARD_FAB2_LIB.BASEBOARD_FAB2(SCH_1):VR_PVDDQ_ABC_PH2_BOOT
   2 VR_PVDDQ_ABC_PH2_PHASE      B @BASEBOARD_FAB2_LIB.BASEBOARD_FAB2(SCH_1):VR_PVDDQ_ABC_PH2_PHASE

CAP_0402LF-1000PF,50V,10%,X7R,A  I135  CT50
   1 VR_PVDDQ_ABC_PH1_SW      A @BASEBOARD_FAB2_LIB.BASEBOARD_FAB2(SCH_1):VR_PVDDQ_ABC_PH1_SW
   2 VR_PVDDQ_ABC_PH1_SW_RC      B @BASEBOARD_FAB2_LIB.BASEBOARD_FAB2(SCH_1):VR_PVDDQ_ABC_PH1_SW_RC

CAP_0402LF-1000PF,50V,10%,X7R,A  I136  CT53
   1 VR_PVDDQ_ABC_PH2_SW      A @BASEBOARD_FAB2_LIB.BASEBOARD_FAB2(SCH_1):VR_PVDDQ_ABC_PH2_SW
   2 VR_PVDDQ_ABC_PH2_SW_RC      B @BASEBOARD_FAB2_LIB.BASEBOARD_FAB2(SCH_1):VR_PVDDQ_ABC_PH2_SW_RC

RES_0603-0,5.0%,1/10W,CHIP,G22A  I139  RT33
   1 VR_PVDDQ_ABC_PH1_BOOT      A @BASEBOARD_FAB2_LIB.BASEBOARD_FAB2(SCH_1):VR_PVDDQ_ABC_PH1_BOOT
   2 VR_PVDDQ_ABC_PH1_BOOT_R      B @BASEBOARD_FAB2_LIB.BASEBOARD_FAB2(SCH_1):VR_PVDDQ_ABC_PH1_BOOT_R

RES_0603-0,5.0%,1/10W,CHIP,G22A  I140  RT36
   1 VR_PVDDQ_ABC_PH2_BOOT      A @BASEBOARD_FAB2_LIB.BASEBOARD_FAB2(SCH_1):VR_PVDDQ_ABC_PH2_BOOT
   2 VR_PVDDQ_ABC_PH2_BOOT_R      B @BASEBOARD_FAB2_LIB.BASEBOARD_FAB2(SCH_1):VR_PVDDQ_ABC_PH2_BOOT_R

RES_0402-0.0,5%,1/16W,CHIP,G21A  I145  R3U6
   1 VR_PVDDQ_ABC_PH1_VCIN      A @BASEBOARD_FAB2_LIB.BASEBOARD_FAB2(SCH_1):VR_PVDDQ_ABC_PH1_VCIN
   2 P5V_STBY      B @BASEBOARD_FAB2_LIB.BASEBOARD_FAB2(SCH_1):P5V_STBY

RES_0402-0.0,5%,1/16W,CHIP,G21A  I146  R3U9
   1 VR_PVDDQ_ABC_PH2_VCIN      A @BASEBOARD_FAB2_LIB.BASEBOARD_FAB2(SCH_1):VR_PVDDQ_ABC_PH2_VCIN
   2 P5V_STBY      B @BASEBOARD_FAB2_LIB.BASEBOARD_FAB2(SCH_1):P5V_STBY

SC1U10V2KX-4-GP_SMD-BCG6-SC1U1A  I149  C7G35
   1 P5V_STBY      1 @BASEBOARD_FAB2_LIB.BASEBOARD_FAB2(SCH_1):P5V_STBY
   2    GND      2 @BASEBOARD_FAB2_LIB.BASEBOARD_FAB2(SCH_1):GND

SC1U10V2KX-4-GP_SMD-BCG6-SC1U1A  I150  C7G42
   1 P5V_STBY      1 @BASEBOARD_FAB2_LIB.BASEBOARD_FAB2(SCH_1):P5V_STBY
   2    GND      2 @BASEBOARD_FAB2_LIB.BASEBOARD_FAB2(SCH_1):GND

1R3F-GP_RCL_GP-1R3F-GP,64.1R00A  I151  RT34
   1 VR_PVDDQ_ABC_PH1_SW_RC      1 @BASEBOARD_FAB2_LIB.BASEBOARD_FAB2(SCH_1):VR_PVDDQ_ABC_PH1_SW_RC
   2    GND      2 @BASEBOARD_FAB2_LIB.BASEBOARD_FAB2(SCH_1):GND

1R3F-GP_RCL_GP-1R3F-GP,64.1R00A  I152  RT35
   1 VR_PVDDQ_ABC_PH2_SW_RC      1 @BASEBOARD_FAB2_LIB.BASEBOARD_FAB2(SCH_1):VR_PVDDQ_ABC_PH2_SW_RC
   2    GND      2 @BASEBOARD_FAB2_LIB.BASEBOARD_FAB2(SCH_1):GND

IND-120NH-30-GP_DISCRET-GB2-INA  I153  L7G1
   1 VR_PVDDQ_ABC_PH1_SW      S @BASEBOARD_FAB2_LIB.BASEBOARD_FAB2(SCH_1):VR_PVDDQ_ABC_PH1_SW
   2 PVDDQ_ABC      F @BASEBOARD_FAB2_LIB.BASEBOARD_FAB2(SCH_1):PVDDQ_ABC

IND-120NH-30-GP_DISCRET-GB2-INA  I155  L7G2
   1 VR_PVDDQ_ABC_PH2_SW      S @BASEBOARD_FAB2_LIB.BASEBOARD_FAB2(SCH_1):VR_PVDDQ_ABC_PH2_SW
   2 PVDDQ_ABC      F @BASEBOARD_FAB2_LIB.BASEBOARD_FAB2(SCH_1):PVDDQ_ABC


DRAWING: @BASEBOARD_FAB2_LIB.BASEBOARD_FAB2(SCH_1):PAGE217 

RES_0603-120.0,1%,1/10W,CHIP,GA  I58  R3U4
   1 PVDDQ_ABC      A @BASEBOARD_FAB2_LIB.BASEBOARD_FAB2(SCH_1):PVDDQ_ABC
   2    GND      B @BASEBOARD_FAB2_LIB.BASEBOARD_FAB2(SCH_1):GND

RES_0402-100.0,1%,1/16W,EMPTY,A  I74  R4U6
   1 VSENSE_PVDDQ_ABC_P      A @BASEBOARD_FAB2_LIB.BASEBOARD_FAB2(SCH_1):VSENSE_PVDDQ_ABC_P
   2 VSENSE_PVDDQ_ABC_N      B @BASEBOARD_FAB2_LIB.BASEBOARD_FAB2(SCH_1):VSENSE_PVDDQ_ABC_N

CAPP_3018-470UF,2.5V,20%,ALUM,A  I75  C7G28
   1 PVDDQ_ABC      A @BASEBOARD_FAB2_LIB.BASEBOARD_FAB2(SCH_1):PVDDQ_ABC
   2    GND      B @BASEBOARD_FAB2_LIB.BASEBOARD_FAB2(SCH_1):GND

CAPP_3018-470UF,2.5V,20%,ALUM,A  I76  C3U1
   1 PVDDQ_ABC      A @BASEBOARD_FAB2_LIB.BASEBOARD_FAB2(SCH_1):PVDDQ_ABC
   2    GND      B @BASEBOARD_FAB2_LIB.BASEBOARD_FAB2(SCH_1):GND

CAPP_3018-470UF,2.5V,20%,ALUM,A  I77  C3U5
   1 PVDDQ_ABC      A @BASEBOARD_FAB2_LIB.BASEBOARD_FAB2(SCH_1):PVDDQ_ABC
   2    GND      B @BASEBOARD_FAB2_LIB.BASEBOARD_FAB2(SCH_1):GND

CAPP_3018-470UF,2.5V,20%,ALUM,A  I78  C3U8
   1 PVDDQ_ABC      A @BASEBOARD_FAB2_LIB.BASEBOARD_FAB2(SCH_1):PVDDQ_ABC
   2    GND      B @BASEBOARD_FAB2_LIB.BASEBOARD_FAB2(SCH_1):GND

CAPP_2626-270UF,16V,20%,OSCON,A  I175  C7G2
   1 VR_FET_SW_P12V_STBY_PVDDQ_ABC      A @BASEBOARD_FAB2_LIB.BASEBOARD_FAB2(SCH_1):VR_FET_SW_P12V_STBY_PVDDQ_ABC
   2    GND      B @BASEBOARD_FAB2_LIB.BASEBOARD_FAB2(SCH_1):GND

CAP_A_0603V-47UF,4V,20%,X5R,60A  I205  C5F2
   1 PVDDQ_ABC      A @BASEBOARD_FAB2_LIB.BASEBOARD_FAB2(SCH_1):PVDDQ_ABC
   2    GND      B @BASEBOARD_FAB2_LIB.BASEBOARD_FAB2(SCH_1):GND

CAP_A_0603V-47UF,4V,20%,X5R,60A  I206  C5F1
   1 PVDDQ_ABC      A @BASEBOARD_FAB2_LIB.BASEBOARD_FAB2(SCH_1):PVDDQ_ABC
   2    GND      B @BASEBOARD_FAB2_LIB.BASEBOARD_FAB2(SCH_1):GND

CAP_A_0603V-47UF,4V,20%,X5R,60A  I207  C5G10
   1 PVDDQ_ABC      A @BASEBOARD_FAB2_LIB.BASEBOARD_FAB2(SCH_1):PVDDQ_ABC
   2    GND      B @BASEBOARD_FAB2_LIB.BASEBOARD_FAB2(SCH_1):GND

CAP_A_0603V-47UF,4V,20%,X5R,60A  I208  C5T2
   1 PVDDQ_ABC      A @BASEBOARD_FAB2_LIB.BASEBOARD_FAB2(SCH_1):PVDDQ_ABC
   2    GND      B @BASEBOARD_FAB2_LIB.BASEBOARD_FAB2(SCH_1):GND

CAP_A_0603V-47UF,4V,20%,X5R,60A  I209  C5U11
   1 PVDDQ_ABC      A @BASEBOARD_FAB2_LIB.BASEBOARD_FAB2(SCH_1):PVDDQ_ABC
   2    GND      B @BASEBOARD_FAB2_LIB.BASEBOARD_FAB2(SCH_1):GND

CAP_A_0603V-47UF,4V,20%,X5R,60A  I210  C5T13
   1 PVDDQ_ABC      A @BASEBOARD_FAB2_LIB.BASEBOARD_FAB2(SCH_1):PVDDQ_ABC
   2    GND      B @BASEBOARD_FAB2_LIB.BASEBOARD_FAB2(SCH_1):GND

CAP_A_0603V-47UF,4V,20%,X5R,60A  I211  C5T4
   1 PVDDQ_ABC      A @BASEBOARD_FAB2_LIB.BASEBOARD_FAB2(SCH_1):PVDDQ_ABC
   2    GND      B @BASEBOARD_FAB2_LIB.BASEBOARD_FAB2(SCH_1):GND

CAP_A_0603V-47UF,4V,20%,X5R,60A  I212  C5T1
   1 PVDDQ_ABC      A @BASEBOARD_FAB2_LIB.BASEBOARD_FAB2(SCH_1):PVDDQ_ABC
   2    GND      B @BASEBOARD_FAB2_LIB.BASEBOARD_FAB2(SCH_1):GND

CAP_A_0603V-47UF,4V,20%,X5R,60A  I213  C5G19
   1 PVDDQ_ABC      A @BASEBOARD_FAB2_LIB.BASEBOARD_FAB2(SCH_1):PVDDQ_ABC
   2    GND      B @BASEBOARD_FAB2_LIB.BASEBOARD_FAB2(SCH_1):GND

SHUNT_SH0201-EMPTY,N_A  I259  SH4U1
   1 VSENSE_PVDDQ_ABC_N      A @BASEBOARD_FAB2_LIB.BASEBOARD_FAB2(SCH_1):VSENSE_PVDDQ_ABC_N
   2    GND      B @BASEBOARD_FAB2_LIB.BASEBOARD_FAB2(SCH_1):GND

SHUNT_SH0201-EMPTY,N_A  I260  SH4U2
   1 VSENSE_PVDDQ_ABC_P      A @BASEBOARD_FAB2_LIB.BASEBOARD_FAB2(SCH_1):VSENSE_PVDDQ_ABC_P
   2 PVDDQ_ABC      B @BASEBOARD_FAB2_LIB.BASEBOARD_FAB2(SCH_1):PVDDQ_ABC

IND-100NH-35-GP_DISCRET-G8-INDA  I261  L7F2
   1 P12V_STBY      S @BASEBOARD_FAB2_LIB.BASEBOARD_FAB2(SCH_1):P12V_STBY
   2 VR_FET_SW_P12V_STBY_PVDDQ_ABC      F @BASEBOARD_FAB2_LIB.BASEBOARD_FAB2(SCH_1):VR_FET_SW_P12V_STBY_PVDDQ_ABC

CAP_A_0603V-22.0UF,4V,20%,X6S,A  I269  C5D58
   1 PVDDQ_ABC      A @BASEBOARD_FAB2_LIB.BASEBOARD_FAB2(SCH_1):PVDDQ_ABC
   2    GND      B @BASEBOARD_FAB2_LIB.BASEBOARD_FAB2(SCH_1):GND

CAP_A_0603V-22.0UF,4V,20%,X6S,A  I270  C5D61
   1 PVDDQ_ABC      A @BASEBOARD_FAB2_LIB.BASEBOARD_FAB2(SCH_1):PVDDQ_ABC
   2    GND      B @BASEBOARD_FAB2_LIB.BASEBOARD_FAB2(SCH_1):GND

CAP_A_0603V-22.0UF,4V,20%,X6S,A  I271  C5D59
   1 PVDDQ_ABC      A @BASEBOARD_FAB2_LIB.BASEBOARD_FAB2(SCH_1):PVDDQ_ABC
   2    GND      B @BASEBOARD_FAB2_LIB.BASEBOARD_FAB2(SCH_1):GND

CAP_A_0603V-22.0UF,4V,20%,X6S,A  I272  C5D60
   1 PVDDQ_ABC      A @BASEBOARD_FAB2_LIB.BASEBOARD_FAB2(SCH_1):PVDDQ_ABC
   2    GND      B @BASEBOARD_FAB2_LIB.BASEBOARD_FAB2(SCH_1):GND

CAP_A_0603V-22.0UF,4V,20%,X6S,A  I279  C5D54
   1 PVDDQ_ABC      A @BASEBOARD_FAB2_LIB.BASEBOARD_FAB2(SCH_1):PVDDQ_ABC
   2    GND      B @BASEBOARD_FAB2_LIB.BASEBOARD_FAB2(SCH_1):GND

CAP_A_0603V-22.0UF,4V,20%,X6S,A  I280  C5D55
   1 PVDDQ_ABC      A @BASEBOARD_FAB2_LIB.BASEBOARD_FAB2(SCH_1):PVDDQ_ABC
   2    GND      B @BASEBOARD_FAB2_LIB.BASEBOARD_FAB2(SCH_1):GND

CAP_A_0603V-22.0UF,4V,20%,X6S,A  I281  C5D56
   1 PVDDQ_ABC      A @BASEBOARD_FAB2_LIB.BASEBOARD_FAB2(SCH_1):PVDDQ_ABC
   2    GND      B @BASEBOARD_FAB2_LIB.BASEBOARD_FAB2(SCH_1):GND

CAP_A_0603V-22.0UF,4V,20%,X6S,A  I282  C5D57
   1 PVDDQ_ABC      A @BASEBOARD_FAB2_LIB.BASEBOARD_FAB2(SCH_1):PVDDQ_ABC
   2    GND      B @BASEBOARD_FAB2_LIB.BASEBOARD_FAB2(SCH_1):GND

CAP_A_0603V-47UF,4V,20%,X5R,60A  I283  C5U2
   1 PVDDQ_ABC      A @BASEBOARD_FAB2_LIB.BASEBOARD_FAB2(SCH_1):PVDDQ_ABC
   2    GND      B @BASEBOARD_FAB2_LIB.BASEBOARD_FAB2(SCH_1):GND

CAP_A_0603V-47UF,4V,20%,X5R,60A  I284  C5U3
   1 PVDDQ_ABC      A @BASEBOARD_FAB2_LIB.BASEBOARD_FAB2(SCH_1):PVDDQ_ABC
   2    GND      B @BASEBOARD_FAB2_LIB.BASEBOARD_FAB2(SCH_1):GND

CAP_A_0603V-47UF,4V,20%,X5R,60A  I285  C5U4
   1 PVDDQ_ABC      A @BASEBOARD_FAB2_LIB.BASEBOARD_FAB2(SCH_1):PVDDQ_ABC
   2    GND      B @BASEBOARD_FAB2_LIB.BASEBOARD_FAB2(SCH_1):GND

CAP_A_0603V-47UF,4V,20%,X5R,60A  I286  C5U5
   1 PVDDQ_ABC      A @BASEBOARD_FAB2_LIB.BASEBOARD_FAB2(SCH_1):PVDDQ_ABC
   2    GND      B @BASEBOARD_FAB2_LIB.BASEBOARD_FAB2(SCH_1):GND

CAP_A_0603V-47UF,4V,20%,X5R,60A  I287  C5U6
   1 PVDDQ_ABC      A @BASEBOARD_FAB2_LIB.BASEBOARD_FAB2(SCH_1):PVDDQ_ABC
   2    GND      B @BASEBOARD_FAB2_LIB.BASEBOARD_FAB2(SCH_1):GND

CAP_A_0603V-47UF,4V,20%,X5R,60A  I288  C5U7
   1 PVDDQ_ABC      A @BASEBOARD_FAB2_LIB.BASEBOARD_FAB2(SCH_1):PVDDQ_ABC
   2    GND      B @BASEBOARD_FAB2_LIB.BASEBOARD_FAB2(SCH_1):GND

CAP_A_0603V-47UF,4V,20%,X5R,60A  I289  C5U8
   1 PVDDQ_ABC      A @BASEBOARD_FAB2_LIB.BASEBOARD_FAB2(SCH_1):PVDDQ_ABC
   2    GND      B @BASEBOARD_FAB2_LIB.BASEBOARD_FAB2(SCH_1):GND

CAP_A_0603V-47UF,4V,20%,X5R,60A  I290  C5U9
   1 PVDDQ_ABC      A @BASEBOARD_FAB2_LIB.BASEBOARD_FAB2(SCH_1):PVDDQ_ABC
   2    GND      B @BASEBOARD_FAB2_LIB.BASEBOARD_FAB2(SCH_1):GND

CAP_A_0603V-47UF,4V,20%,X5R,60A  I291  C5T12
   1 PVDDQ_ABC      A @BASEBOARD_FAB2_LIB.BASEBOARD_FAB2(SCH_1):PVDDQ_ABC
   2    GND      B @BASEBOARD_FAB2_LIB.BASEBOARD_FAB2(SCH_1):GND

CAP_A_0603V-47UF,4V,20%,X5R,60A  I292  C5T11
   1 PVDDQ_ABC      A @BASEBOARD_FAB2_LIB.BASEBOARD_FAB2(SCH_1):PVDDQ_ABC
   2    GND      B @BASEBOARD_FAB2_LIB.BASEBOARD_FAB2(SCH_1):GND

CAP_A_0603V-47UF,4V,20%,X5R,60A  I293  C5T10
   1 PVDDQ_ABC      A @BASEBOARD_FAB2_LIB.BASEBOARD_FAB2(SCH_1):PVDDQ_ABC
   2    GND      B @BASEBOARD_FAB2_LIB.BASEBOARD_FAB2(SCH_1):GND

CAP_A_0603V-47UF,4V,20%,X5R,60A  I294  C5T9
   1 PVDDQ_ABC      A @BASEBOARD_FAB2_LIB.BASEBOARD_FAB2(SCH_1):PVDDQ_ABC
   2    GND      B @BASEBOARD_FAB2_LIB.BASEBOARD_FAB2(SCH_1):GND

CAP_A_0603V-47UF,4V,20%,X5R,60A  I295  C5T8
   1 PVDDQ_ABC      A @BASEBOARD_FAB2_LIB.BASEBOARD_FAB2(SCH_1):PVDDQ_ABC
   2    GND      B @BASEBOARD_FAB2_LIB.BASEBOARD_FAB2(SCH_1):GND

CAP_A_0603V-47UF,4V,20%,X5R,60A  I296  C5T7
   1 PVDDQ_ABC      A @BASEBOARD_FAB2_LIB.BASEBOARD_FAB2(SCH_1):PVDDQ_ABC
   2    GND      B @BASEBOARD_FAB2_LIB.BASEBOARD_FAB2(SCH_1):GND

CAP_A_0603V-47UF,4V,20%,X5R,60A  I297  C5T6
   1 PVDDQ_ABC      A @BASEBOARD_FAB2_LIB.BASEBOARD_FAB2(SCH_1):PVDDQ_ABC
   2    GND      B @BASEBOARD_FAB2_LIB.BASEBOARD_FAB2(SCH_1):GND

CAP_A_0603V-47UF,4V,20%,X5R,60A  I298  C5T5
   1 PVDDQ_ABC      A @BASEBOARD_FAB2_LIB.BASEBOARD_FAB2(SCH_1):PVDDQ_ABC
   2    GND      B @BASEBOARD_FAB2_LIB.BASEBOARD_FAB2(SCH_1):GND

CAP_A_0603V-47UF,4V,20%,X5R,60A  I299  C5G11
   1 PVDDQ_ABC      A @BASEBOARD_FAB2_LIB.BASEBOARD_FAB2(SCH_1):PVDDQ_ABC
   2    GND      B @BASEBOARD_FAB2_LIB.BASEBOARD_FAB2(SCH_1):GND

CAP_A_0603V-47UF,4V,20%,X5R,60A  I300  C5G12
   1 PVDDQ_ABC      A @BASEBOARD_FAB2_LIB.BASEBOARD_FAB2(SCH_1):PVDDQ_ABC
   2    GND      B @BASEBOARD_FAB2_LIB.BASEBOARD_FAB2(SCH_1):GND

CAP_A_0603V-47UF,4V,20%,X5R,60A  I301  C5G2
   1 PVDDQ_ABC      A @BASEBOARD_FAB2_LIB.BASEBOARD_FAB2(SCH_1):PVDDQ_ABC
   2    GND      B @BASEBOARD_FAB2_LIB.BASEBOARD_FAB2(SCH_1):GND

CAP_A_0603V-47UF,4V,20%,X5R,60A  I302  C5G4
   1 PVDDQ_ABC      A @BASEBOARD_FAB2_LIB.BASEBOARD_FAB2(SCH_1):PVDDQ_ABC
   2    GND      B @BASEBOARD_FAB2_LIB.BASEBOARD_FAB2(SCH_1):GND

CAP_A_0603V-47UF,4V,20%,X5R,60A  I303  C5G13
   1 PVDDQ_ABC      A @BASEBOARD_FAB2_LIB.BASEBOARD_FAB2(SCH_1):PVDDQ_ABC
   2    GND      B @BASEBOARD_FAB2_LIB.BASEBOARD_FAB2(SCH_1):GND

CAP_A_0603V-47UF,4V,20%,X5R,60A  I304  C5G6
   1 PVDDQ_ABC      A @BASEBOARD_FAB2_LIB.BASEBOARD_FAB2(SCH_1):PVDDQ_ABC
   2    GND      B @BASEBOARD_FAB2_LIB.BASEBOARD_FAB2(SCH_1):GND

CAP_A_0603V-47UF,4V,20%,X5R,60A  I305  C5G5
   1 PVDDQ_ABC      A @BASEBOARD_FAB2_LIB.BASEBOARD_FAB2(SCH_1):PVDDQ_ABC
   2    GND      B @BASEBOARD_FAB2_LIB.BASEBOARD_FAB2(SCH_1):GND

CAP_A_0603V-47UF,4V,20%,X5R,60A  I306  C5G7
   1 PVDDQ_ABC      A @BASEBOARD_FAB2_LIB.BASEBOARD_FAB2(SCH_1):PVDDQ_ABC
   2    GND      B @BASEBOARD_FAB2_LIB.BASEBOARD_FAB2(SCH_1):GND

CAP_A_0603V-47UF,4V,20%,X5R,60A  I307  C5G1
   1 PVDDQ_ABC      A @BASEBOARD_FAB2_LIB.BASEBOARD_FAB2(SCH_1):PVDDQ_ABC
   2    GND      B @BASEBOARD_FAB2_LIB.BASEBOARD_FAB2(SCH_1):GND

CAP_A_0603V-47UF,4V,20%,X5R,60A  I308  C5G8
   1 PVDDQ_ABC      A @BASEBOARD_FAB2_LIB.BASEBOARD_FAB2(SCH_1):PVDDQ_ABC
   2    GND      B @BASEBOARD_FAB2_LIB.BASEBOARD_FAB2(SCH_1):GND

CAP_A_0603V-47UF,4V,20%,X5R,60A  I309  C5G18
   1 PVDDQ_ABC      A @BASEBOARD_FAB2_LIB.BASEBOARD_FAB2(SCH_1):PVDDQ_ABC
   2    GND      B @BASEBOARD_FAB2_LIB.BASEBOARD_FAB2(SCH_1):GND

CAP_A_0603V-47UF,4V,20%,X5R,60A  I310  C5G17
   1 PVDDQ_ABC      A @BASEBOARD_FAB2_LIB.BASEBOARD_FAB2(SCH_1):PVDDQ_ABC
   2    GND      B @BASEBOARD_FAB2_LIB.BASEBOARD_FAB2(SCH_1):GND

CAP_A_0603V-47UF,4V,20%,X5R,60A  I311  C5G14
   1 PVDDQ_ABC      A @BASEBOARD_FAB2_LIB.BASEBOARD_FAB2(SCH_1):PVDDQ_ABC
   2    GND      B @BASEBOARD_FAB2_LIB.BASEBOARD_FAB2(SCH_1):GND

CAP_A_0603V-47UF,4V,20%,X5R,60A  I312  C5G16
   1 PVDDQ_ABC      A @BASEBOARD_FAB2_LIB.BASEBOARD_FAB2(SCH_1):PVDDQ_ABC
   2    GND      B @BASEBOARD_FAB2_LIB.BASEBOARD_FAB2(SCH_1):GND

CAP_A_0603V-47UF,4V,20%,X5R,60A  I313  C5G15
   1 PVDDQ_ABC      A @BASEBOARD_FAB2_LIB.BASEBOARD_FAB2(SCH_1):PVDDQ_ABC
   2    GND      B @BASEBOARD_FAB2_LIB.BASEBOARD_FAB2(SCH_1):GND

CAP_A_0603V-47UF,4V,20%,X5R,60A  I314  C5G3
   1 PVDDQ_ABC      A @BASEBOARD_FAB2_LIB.BASEBOARD_FAB2(SCH_1):PVDDQ_ABC
   2    GND      B @BASEBOARD_FAB2_LIB.BASEBOARD_FAB2(SCH_1):GND

CAP_0805-100UF,4V,20%,X5R,6024A  I316  C5U1
   1 PVDDQ_ABC      A @BASEBOARD_FAB2_LIB.BASEBOARD_FAB2(SCH_1):PVDDQ_ABC
   2    GND      B @BASEBOARD_FAB2_LIB.BASEBOARD_FAB2(SCH_1):GND

CAP_0805-100UF,4V,20%,X5R,6024A  I317  C5U10
   1 PVDDQ_ABC      A @BASEBOARD_FAB2_LIB.BASEBOARD_FAB2(SCH_1):PVDDQ_ABC
   2    GND      B @BASEBOARD_FAB2_LIB.BASEBOARD_FAB2(SCH_1):GND

CAP_0805-100UF,4V,20%,X5R,6024A  I318  C5G9
   1 PVDDQ_ABC      A @BASEBOARD_FAB2_LIB.BASEBOARD_FAB2(SCH_1):PVDDQ_ABC
   2    GND      B @BASEBOARD_FAB2_LIB.BASEBOARD_FAB2(SCH_1):GND

CAP_0805-100UF,4V,20%,X5R,6024A  I319  C4T4
   1 PVDDQ_ABC      A @BASEBOARD_FAB2_LIB.BASEBOARD_FAB2(SCH_1):PVDDQ_ABC
   2    GND      B @BASEBOARD_FAB2_LIB.BASEBOARD_FAB2(SCH_1):GND

CAP_0805-100UF,4V,20%,X5R,6024A  I320  C5U15
   1 PVDDQ_ABC      A @BASEBOARD_FAB2_LIB.BASEBOARD_FAB2(SCH_1):PVDDQ_ABC
   2    GND      B @BASEBOARD_FAB2_LIB.BASEBOARD_FAB2(SCH_1):GND

CAP_0805-100UF,4V,20%,X5R,6024A  I321  C5U13
   1 PVDDQ_ABC      A @BASEBOARD_FAB2_LIB.BASEBOARD_FAB2(SCH_1):PVDDQ_ABC
   2    GND      B @BASEBOARD_FAB2_LIB.BASEBOARD_FAB2(SCH_1):GND

CAP_0805-100UF,4V,20%,X5R,6024A  I322  C5U14
   1 PVDDQ_ABC      A @BASEBOARD_FAB2_LIB.BASEBOARD_FAB2(SCH_1):PVDDQ_ABC
   2    GND      B @BASEBOARD_FAB2_LIB.BASEBOARD_FAB2(SCH_1):GND

CAP_0805-100UF,4V,20%,X5R,6024A  I323  C5P41
   1 PVDDQ_ABC      A @BASEBOARD_FAB2_LIB.BASEBOARD_FAB2(SCH_1):PVDDQ_ABC
   2    GND      B @BASEBOARD_FAB2_LIB.BASEBOARD_FAB2(SCH_1):GND

CAP_0805-100UF,4V,20%,X5R,6024A  I324  C5P44
   1 PVDDQ_ABC      A @BASEBOARD_FAB2_LIB.BASEBOARD_FAB2(SCH_1):PVDDQ_ABC
   2    GND      B @BASEBOARD_FAB2_LIB.BASEBOARD_FAB2(SCH_1):GND

CAP_0805-100UF,4V,20%,X5R,6024A  I325  C5P42
   1 PVDDQ_ABC      A @BASEBOARD_FAB2_LIB.BASEBOARD_FAB2(SCH_1):PVDDQ_ABC
   2    GND      B @BASEBOARD_FAB2_LIB.BASEBOARD_FAB2(SCH_1):GND

CAP_0805-100UF,4V,20%,X5R,6024A  I326  C5P43
   1 PVDDQ_ABC      A @BASEBOARD_FAB2_LIB.BASEBOARD_FAB2(SCH_1):PVDDQ_ABC
   2    GND      B @BASEBOARD_FAB2_LIB.BASEBOARD_FAB2(SCH_1):GND

CAP_0805-100UF,4V,20%,X5R,6024A  I327  C5P38
   1 PVDDQ_ABC      A @BASEBOARD_FAB2_LIB.BASEBOARD_FAB2(SCH_1):PVDDQ_ABC
   2    GND      B @BASEBOARD_FAB2_LIB.BASEBOARD_FAB2(SCH_1):GND

CAP_0805-100UF,4V,20%,X5R,6024A  I328  C5P39
   1 PVDDQ_ABC      A @BASEBOARD_FAB2_LIB.BASEBOARD_FAB2(SCH_1):PVDDQ_ABC
   2    GND      B @BASEBOARD_FAB2_LIB.BASEBOARD_FAB2(SCH_1):GND

CAP_0805-100UF,4V,20%,X5R,6024A  I329  C5G20
   1 PVDDQ_ABC      A @BASEBOARD_FAB2_LIB.BASEBOARD_FAB2(SCH_1):PVDDQ_ABC
   2    GND      B @BASEBOARD_FAB2_LIB.BASEBOARD_FAB2(SCH_1):GND


DRAWING: @BASEBOARD_FAB2_LIB.BASEBOARD_FAB2(SCH_1):PAGE218 

RES_0402-0.0,5%,1/16W,CHIP,G21A  I15  R3M6
   1 FM_PVDDQ_DEF_EN      A @BASEBOARD_FAB2_LIB.BASEBOARD_FAB2(SCH_1):FM_PVDDQ_DEF_EN
   2 VR_PVDDQ_DEF_VREN      B @BASEBOARD_FAB2_LIB.BASEBOARD_FAB2(SCH_1):VR_PVDDQ_DEF_VREN

RES_0402-150.0,1%,1/16W,CHIP,GA  I21  R7A17
   1 SVID_CLK1_CPU0_R      A @BASEBOARD_FAB2_LIB.BASEBOARD_FAB2(SCH_1):SVID_CLK1_CPU0_R
   2 SVID_CLK_PVDDQ_DEF      B @BASEBOARD_FAB2_LIB.BASEBOARD_FAB2(SCH_1):SVID_CLK_PVDDQ_DEF

RES_0402-100.0K,1%,1/16W,EMPTYA  I34  R3M5
   1 P3V3_STBY      A @BASEBOARD_FAB2_LIB.BASEBOARD_FAB2(SCH_1):P3V3_STBY
   2 VR_PVDDQ_DEF_VREN      B @BASEBOARD_FAB2_LIB.BASEBOARD_FAB2(SCH_1):VR_PVDDQ_DEF_VREN

RES_0402-0.0,5%,1/16W,CHIP,G21A  I35  R3M1
   1 P3V3_STBY      A @BASEBOARD_FAB2_LIB.BASEBOARD_FAB2(SCH_1):P3V3_STBY
   2 VR_PVDDQ_DEF_VDD      B @BASEBOARD_FAB2_LIB.BASEBOARD_FAB2(SCH_1):VR_PVDDQ_DEF_VDD

RES_0402-33.2,1%,1/16W,CHIP,G2A  I59  R7B1
   1 IRQ_PVDDQ_DEF_VRHOT_LVT3_R_N      A @BASEBOARD_FAB2_LIB.BASEBOARD_FAB2(SCH_1):IRQ_PVDDQ_DEF_VRHOT_LVT3_R_N
   2 IRQ_PVDDQ_DEF_VRHOT_LVT3_N      B @BASEBOARD_FAB2_LIB.BASEBOARD_FAB2(SCH_1):IRQ_PVDDQ_DEF_VRHOT_LVT3_N

RES_0402-22.1,1.0%,1/16W,CHIP,A  I60  R3M3
   1 PWRGD_PVDDQ_DEF_R      A @BASEBOARD_FAB2_LIB.BASEBOARD_FAB2(SCH_1):PWRGD_PVDDQ_DEF_R
   2 PWRGD_PVDDQ_DEF      B @BASEBOARD_FAB2_LIB.BASEBOARD_FAB2(SCH_1):PWRGD_PVDDQ_DEF

RES_0402-10.0,1%,1/16W,CHIP,G2A  I13  R7A7
   1 VSENSE_PVDDQ_DEF_P      A @BASEBOARD_FAB2_LIB.BASEBOARD_FAB2(SCH_1):VSENSE_PVDDQ_DEF_P
   2 VR_PVDDQ_DEF_AVSP      B @BASEBOARD_FAB2_LIB.BASEBOARD_FAB2(SCH_1):VR_PVDDQ_DEF_AVSP

RES_0402-1.0K,0.1%,1/16W,CHIP,A  I18  RF17
   1 VR_PVDDQ_DEF_AIREF1      A @BASEBOARD_FAB2_LIB.BASEBOARD_FAB2(SCH_1):VR_PVDDQ_DEF_AIREF1
   2 ISENSE_PVDDQ_DEF_PH1_IMON      B @BASEBOARD_FAB2_LIB.BASEBOARD_FAB2(SCH_1):ISENSE_PVDDQ_DEF_PH1_IMON

RES_0402-1.0K,0.1%,1/16W,CHIP,A  I19  RF18
   1 VR_PVDDQ_DEF_AIREF2      A @BASEBOARD_FAB2_LIB.BASEBOARD_FAB2(SCH_1):VR_PVDDQ_DEF_AIREF2
   2 ISENSE_PVDDQ_DEF_PH2_IMON      B @BASEBOARD_FAB2_LIB.BASEBOARD_FAB2(SCH_1):ISENSE_PVDDQ_DEF_PH2_IMON

SC22P50V2JN-4GP_SMD-BCG-SC22P5A  I20  CF18
   1 VR_PVDDQ_DEF_AIREF2      1 @BASEBOARD_FAB2_LIB.BASEBOARD_FAB2(SCH_1):VR_PVDDQ_DEF_AIREF2
   2 ISENSE_PVDDQ_DEF_PH2_IMON      2 @BASEBOARD_FAB2_LIB.BASEBOARD_FAB2(SCH_1):ISENSE_PVDDQ_DEF_PH2_IMON

CAP_A_0402V-0.1UF,16V,10%,X7R,A  I28  C7B2
   1 VR_PVDDQ_DEF_VD12      A @BASEBOARD_FAB2_LIB.BASEBOARD_FAB2(SCH_1):VR_PVDDQ_DEF_VD12
   2    GND      B @BASEBOARD_FAB2_LIB.BASEBOARD_FAB2(SCH_1):GND

CAP_A_0402V-1.0UF,6.3V,10%,X6SA  I30  C7B1
   1 VR_PVDDQ_DEF_VD12      A @BASEBOARD_FAB2_LIB.BASEBOARD_FAB2(SCH_1):VR_PVDDQ_DEF_VD12
   2    GND      B @BASEBOARD_FAB2_LIB.BASEBOARD_FAB2(SCH_1):GND

CAP_A_0402V-0.1UF,16V,10%,X7R,A  I38  C7A38
   1 VR_PVDDQ_DEF_VDD      A @BASEBOARD_FAB2_LIB.BASEBOARD_FAB2(SCH_1):VR_PVDDQ_DEF_VDD
   2    GND      B @BASEBOARD_FAB2_LIB.BASEBOARD_FAB2(SCH_1):GND

CAP_0402LF-1000PF,50V,10%,X7R,A  I41  C7B3
   1 PWRGD_PVDDQ_DEF_R      A @BASEBOARD_FAB2_LIB.BASEBOARD_FAB2(SCH_1):PWRGD_PVDDQ_DEF_R
   2    GND      B @BASEBOARD_FAB2_LIB.BASEBOARD_FAB2(SCH_1):GND

RES_0402-0.0,5%,1/16W,CHIP,G21A  I45  R7A12
   1 SVID_VDIO_PVDDQ_DEF      A @BASEBOARD_FAB2_LIB.BASEBOARD_FAB2(SCH_1):SVID_VDIO_PVDDQ_DEF
   2 SVID_DIO1_CPU0_R      B @BASEBOARD_FAB2_LIB.BASEBOARD_FAB2(SCH_1):SVID_DIO1_CPU0_R

RES_0402-0.0,5%,1/16W,EMPTY,G2A  I46  R12W29
   1 TP_PVDDQ_DEF_MP1      A @BASEBOARD_FAB2_LIB.BASEBOARD_FAB2(SCH_1):TP_PVDDQ_DEF_MP1
   2 PWRGD_PVDDQ_DEF      B @BASEBOARD_FAB2_LIB.BASEBOARD_FAB2(SCH_1):PWRGD_PVDDQ_DEF

RES_0402-0.0,5%,1/16W,EMPTY,G2A  I55  R12W30
   1 TP_PVDDQ_DEF_MP2      A @BASEBOARD_FAB2_LIB.BASEBOARD_FAB2(SCH_1):TP_PVDDQ_DEF_MP2
   2 PWRGD_PVDDQ_DEF      B @BASEBOARD_FAB2_LIB.BASEBOARD_FAB2(SCH_1):PWRGD_PVDDQ_DEF

RES_0402-0.0,5%,1/16W,CHIP,G21A  I56  R7A11
   1 SVID_ALERT_PVDDQ_DEF      A @BASEBOARD_FAB2_LIB.BASEBOARD_FAB2(SCH_1):SVID_ALERT_PVDDQ_DEF
   2 SVID_ALERT1_CPU0_R_N      B @BASEBOARD_FAB2_LIB.BASEBOARD_FAB2(SCH_1):SVID_ALERT1_CPU0_R_N

RES_0402-1.00K,1%,1/16W,CHIP,GA  I57  R7B4
   1 P3V3_STBY      A @BASEBOARD_FAB2_LIB.BASEBOARD_FAB2(SCH_1):P3V3_STBY
   2 IRQ_PVDDQ_DEF_VRHOT_LVT3_R_N      B @BASEBOARD_FAB2_LIB.BASEBOARD_FAB2(SCH_1):IRQ_PVDDQ_DEF_VRHOT_LVT3_R_N

RES_0402-1.00K,1%,1/16W,CHIP,GA  I58  R7B5
   1 P3V3_STBY      A @BASEBOARD_FAB2_LIB.BASEBOARD_FAB2(SCH_1):P3V3_STBY
   2 PWRGD_PVDDQ_DEF_R      B @BASEBOARD_FAB2_LIB.BASEBOARD_FAB2(SCH_1):PWRGD_PVDDQ_DEF_R

RES_0402-100.0,1%,1/16W,EMPTY,A  I67  R3L11
   1 PVCCIO_CPU0      A @BASEBOARD_FAB2_LIB.BASEBOARD_FAB2(SCH_1):PVCCIO_CPU0
   2 SVID_DIO1_CPU0_R      B @BASEBOARD_FAB2_LIB.BASEBOARD_FAB2(SCH_1):SVID_DIO1_CPU0_R

PXM1310B_QFN-IC,H89186-001  I69  EU7A5
   1     NC  BPWM1     NC
   2     NC DNC<0>     NC
   3     NC  APWM3     NC
   4 VR_PVDDQ_DEF_PWM2  APWM2 @BASEBOARD_FAB2_LIB.BASEBOARD_FAB2(SCH_1):VR_PVDDQ_DEF_PWM2
   5 VR_PVDDQ_DEF_PWM1  APWM1 @BASEBOARD_FAB2_LIB.BASEBOARD_FAB2(SCH_1):VR_PVDDQ_DEF_PWM1
   6 SMB_VR_STBY_LVC3_SDA    SDA @BASEBOARD_FAB2_LIB.BASEBOARD_FAB2(SCH_1):SMB_VR_STBY_LVC3_SDA
   7 SMB_VR_STBY_LVC3_SCL    SCL @BASEBOARD_FAB2_LIB.BASEBOARD_FAB2(SCH_1):SMB_VR_STBY_LVC3_SCL
   8     NC RESET_N     NC
   9 PWRGD_PVDDQ_DEF_R AVRRDY @BASEBOARD_FAB2_LIB.BASEBOARD_FAB2(SCH_1):PWRGD_PVDDQ_DEF_R
  10 VR_PVDDQ_DEF_VREN  AVREN @BASEBOARD_FAB2_LIB.BASEBOARD_FAB2(SCH_1):VR_PVDDQ_DEF_VREN
  11 IRQ_PVDDQ_DEF_VRHOT_LVT3_R_N VRHOT_N @BASEBOARD_FAB2_LIB.BASEBOARD_FAB2(SCH_1):IRQ_PVDDQ_DEF_VRHOT_LVT3_R_N
  12     NC PINALRT_N     NC
  13 PU_VR_PVDDQ_DEF_FAULT1    MP0 @BASEBOARD_FAB2_LIB.BASEBOARD_FAB2(SCH_1):PU_VR_PVDDQ_DEF_FAULT1
  14 TP_PVDDQ_DEF_MP1    MP1 @BASEBOARD_FAB2_LIB.BASEBOARD_FAB2(SCH_1):TP_PVDDQ_DEF_MP1
  15 SVID_CLK_PVDDQ_DEF   VCLK @BASEBOARD_FAB2_LIB.BASEBOARD_FAB2(SCH_1):SVID_CLK_PVDDQ_DEF
  16 SVID_VDIO_PVDDQ_DEF   VDIO @BASEBOARD_FAB2_LIB.BASEBOARD_FAB2(SCH_1):SVID_VDIO_PVDDQ_DEF
  17 SVID_ALERT_PVDDQ_DEF VALRT_N @BASEBOARD_FAB2_LIB.BASEBOARD_FAB2(SCH_1):SVID_ALERT_PVDDQ_DEF
  18 TP_PVDDQ_DEF_MP2    MP2 @BASEBOARD_FAB2_LIB.BASEBOARD_FAB2(SCH_1):TP_PVDDQ_DEF_MP2
  19 VR_PVDDQ_DEF_AVSP  AVSEN @BASEBOARD_FAB2_LIB.BASEBOARD_FAB2(SCH_1):VR_PVDDQ_DEF_AVSP
  20 VSENSE_PVDDQ_DEF_N  AVREF @BASEBOARD_FAB2_LIB.BASEBOARD_FAB2(SCH_1):VSENSE_PVDDQ_DEF_N
  21 VR_PVDDQ_DEF_AIREF1 AIREF1 @BASEBOARD_FAB2_LIB.BASEBOARD_FAB2(SCH_1):VR_PVDDQ_DEF_AIREF1
  22 ISENSE_PVDDQ_DEF_PH1_IMON AISEN1 @BASEBOARD_FAB2_LIB.BASEBOARD_FAB2(SCH_1):ISENSE_PVDDQ_DEF_PH1_IMON
  23 VR_PVDDQ_DEF_AIREF2 AIREF2 @BASEBOARD_FAB2_LIB.BASEBOARD_FAB2(SCH_1):VR_PVDDQ_DEF_AIREF2
  24 ISENSE_PVDDQ_DEF_PH2_IMON AISEN2 @BASEBOARD_FAB2_LIB.BASEBOARD_FAB2(SCH_1):ISENSE_PVDDQ_DEF_PH2_IMON
  25     NC AIREF3     NC
  26     NC AISEN3     NC
  27    GND    GND @BASEBOARD_FAB2_LIB.BASEBOARD_FAB2(SCH_1):GND
  28     NC DNC<1>     NC
  29     NC  BVSEN     NC
  30     NC  BVREF     NC
  31     NC BIREF1     NC
  32    GND BISEN1 @BASEBOARD_FAB2_LIB.BASEBOARD_FAB2(SCH_1):GND
  33 VR_PVDDQ_DEF_XADDR2 XADDR2 @BASEBOARD_FAB2_LIB.BASEBOARD_FAB2(SCH_1):VR_PVDDQ_DEF_XADDR2
  34     NC  BTSEN     NC
  35 A_TSENSE_PVDDQ_DEF  ATSEN @BASEBOARD_FAB2_LIB.BASEBOARD_FAB2(SCH_1):A_TSENSE_PVDDQ_DEF
  36 VR_PVDDQ_DEF_XADDR1 XADDR1 @BASEBOARD_FAB2_LIB.BASEBOARD_FAB2(SCH_1):VR_PVDDQ_DEF_XADDR1
  37 VR_PVDDQ_DEF_VINSEN VINSEN @BASEBOARD_FAB2_LIB.BASEBOARD_FAB2(SCH_1):VR_PVDDQ_DEF_VINSEN
  38 VR_PVDDQ_DEF_AIINSEN IINSEN @BASEBOARD_FAB2_LIB.BASEBOARD_FAB2(SCH_1):VR_PVDDQ_DEF_AIINSEN
  39 VR_PVDDQ_DEF_VDD    VDD @BASEBOARD_FAB2_LIB.BASEBOARD_FAB2(SCH_1):VR_PVDDQ_DEF_VDD
  40 VR_PVDDQ_DEF_VD12   VD12 @BASEBOARD_FAB2_LIB.BASEBOARD_FAB2(SCH_1):VR_PVDDQ_DEF_VD12
  41    GND  THPAD @BASEBOARD_FAB2_LIB.BASEBOARD_FAB2(SCH_1):GND

CAP_0402LF-220PF,50V,10%,X7R,AA  I14  C7A28
   1 VR_PVDDQ_DEF_AVSP      A @BASEBOARD_FAB2_LIB.BASEBOARD_FAB2(SCH_1):VR_PVDDQ_DEF_AVSP
   2 VSENSE_PVDDQ_DEF_N      B @BASEBOARD_FAB2_LIB.BASEBOARD_FAB2(SCH_1):VSENSE_PVDDQ_DEF_N

CAP_0402LF-220PF,50V,10%,X7R,AA  I16  C7A29
   1 A_TSENSE_PVDDQ_DEF      A @BASEBOARD_FAB2_LIB.BASEBOARD_FAB2(SCH_1):A_TSENSE_PVDDQ_DEF
   2    GND      B @BASEBOARD_FAB2_LIB.BASEBOARD_FAB2(SCH_1):GND

SC22P50V2JN-4GP_SMD-BCG-SC22P5A  I17  CF17
   1 VR_PVDDQ_DEF_AIREF1      1 @BASEBOARD_FAB2_LIB.BASEBOARD_FAB2(SCH_1):VR_PVDDQ_DEF_AIREF1
   2 ISENSE_PVDDQ_DEF_PH1_IMON      2 @BASEBOARD_FAB2_LIB.BASEBOARD_FAB2(SCH_1):ISENSE_PVDDQ_DEF_PH1_IMON

CAP_A_0402V-1.0UF,6.3V,10%,X6SA  I40  C7A37
   1 VR_PVDDQ_DEF_VDD      A @BASEBOARD_FAB2_LIB.BASEBOARD_FAB2(SCH_1):VR_PVDDQ_DEF_VDD
   2    GND      B @BASEBOARD_FAB2_LIB.BASEBOARD_FAB2(SCH_1):GND

RES_0402-49.9,1%,1/16W,EMPTY,GA  I70  R3L13
   1 PVCCIO_CPU0      A @BASEBOARD_FAB2_LIB.BASEBOARD_FAB2(SCH_1):PVCCIO_CPU0
   2 SVID_CLK1_CPU0_R      B @BASEBOARD_FAB2_LIB.BASEBOARD_FAB2(SCH_1):SVID_CLK1_CPU0_R

RES_0402-16K,1.0%,1/16W,CHIP,GA  I73  R7A10
   1 VR_PVDDQ_DEF_XADDR1      A @BASEBOARD_FAB2_LIB.BASEBOARD_FAB2(SCH_1):VR_PVDDQ_DEF_XADDR1
   2    GND      B @BASEBOARD_FAB2_LIB.BASEBOARD_FAB2(SCH_1):GND

RES_0402-2.26K,1.0%,1/16W,CHIPA  I74  R7A8
   1 VR_PVDDQ_DEF_XADDR2      A @BASEBOARD_FAB2_LIB.BASEBOARD_FAB2(SCH_1):VR_PVDDQ_DEF_XADDR2
   2    GND      B @BASEBOARD_FAB2_LIB.BASEBOARD_FAB2(SCH_1):GND

RES_0402-0.0,5%,1/16W,CHIP,G21A  I75  R12W28
   1 PU_VR_PVDDQ_DEF_FAULT1      A @BASEBOARD_FAB2_LIB.BASEBOARD_FAB2(SCH_1):PU_VR_PVDDQ_DEF_FAULT1
   2 PWRGD_PVDDQ_DEF      B @BASEBOARD_FAB2_LIB.BASEBOARD_FAB2(SCH_1):PWRGD_PVDDQ_DEF

RES_0402-2.26K,1.0%,1/16W,CHIPA  I76  R7A9
   1 P3V3_STBY      A @BASEBOARD_FAB2_LIB.BASEBOARD_FAB2(SCH_1):P3V3_STBY
   2 PWRGD_PVDDQ_DEF      B @BASEBOARD_FAB2_LIB.BASEBOARD_FAB2(SCH_1):PWRGD_PVDDQ_DEF


DRAWING: @BASEBOARD_FAB2_LIB.BASEBOARD_FAB2(SCH_1):PAGE219 

CAP_0402-0.220UF,16V,10%,X7R,AA  I44  C7A12
   1 VR_PVDDQ_DEF_PH1_BOOT      A @BASEBOARD_FAB2_LIB.BASEBOARD_FAB2(SCH_1):VR_PVDDQ_DEF_PH1_BOOT
   2 VR_PVDDQ_DEF_PH1_PHASE      B @BASEBOARD_FAB2_LIB.BASEBOARD_FAB2(SCH_1):VR_PVDDQ_DEF_PH1_PHASE

CAP_0805-10UF,16V,10%,X6S,C953A  I45  C3L2
   1 VR_FET_SW_P12V_STBY_PVDDQ_DEF      A @BASEBOARD_FAB2_LIB.BASEBOARD_FAB2(SCH_1):VR_FET_SW_P12V_STBY_PVDDQ_DEF
   2    GND      B @BASEBOARD_FAB2_LIB.BASEBOARD_FAB2(SCH_1):GND

CAP_0805-10UF,16V,10%,X6S,C953A  I46  C3L4
   1 VR_FET_SW_P12V_STBY_PVDDQ_DEF      A @BASEBOARD_FAB2_LIB.BASEBOARD_FAB2(SCH_1):VR_FET_SW_P12V_STBY_PVDDQ_DEF
   2    GND      B @BASEBOARD_FAB2_LIB.BASEBOARD_FAB2(SCH_1):GND

CAP_0805-10UF,16V,10%,X6S,C953A  I47  C3L13
   1 VR_FET_SW_P12V_STBY_PVDDQ_DEF      A @BASEBOARD_FAB2_LIB.BASEBOARD_FAB2(SCH_1):VR_FET_SW_P12V_STBY_PVDDQ_DEF
   2    GND      B @BASEBOARD_FAB2_LIB.BASEBOARD_FAB2(SCH_1):GND

CAP_0402-1.0UF,16V,10%,X6S,D97A  I48  C7A11
   1 VR_FET_SW_P12V_STBY_PVDDQ_DEF      A @BASEBOARD_FAB2_LIB.BASEBOARD_FAB2(SCH_1):VR_FET_SW_P12V_STBY_PVDDQ_DEF
   2    GND      B @BASEBOARD_FAB2_LIB.BASEBOARD_FAB2(SCH_1):GND

CAP_0402-1.0UF,16V,10%,X6S,D97A  I50  C7A16
   1 VR_PVDDQ_DEF_PH1_VCIN      A @BASEBOARD_FAB2_LIB.BASEBOARD_FAB2(SCH_1):VR_PVDDQ_DEF_PH1_VCIN
   2    GND      B @BASEBOARD_FAB2_LIB.BASEBOARD_FAB2(SCH_1):GND

CAP_A_0402V-0.1UF,16V,10%,X7R,A  I51  C7A5
   1 VR_FET_SW_P12V_STBY_PVDDQ_DEF      A @BASEBOARD_FAB2_LIB.BASEBOARD_FAB2(SCH_1):VR_FET_SW_P12V_STBY_PVDDQ_DEF
   2    GND      B @BASEBOARD_FAB2_LIB.BASEBOARD_FAB2(SCH_1):GND

CAP_0402-0.22UF,16V,10%,X7R,A3A  I54  C7A17
   1 P5V_STBY      A @BASEBOARD_FAB2_LIB.BASEBOARD_FAB2(SCH_1):P5V_STBY
   2    GND      B @BASEBOARD_FAB2_LIB.BASEBOARD_FAB2(SCH_1):GND

CAP_0805LF-22UF,4V,20%,X6S,C95A  I68  C6A4
   1 PVDDQ_DEF      A @BASEBOARD_FAB2_LIB.BASEBOARD_FAB2(SCH_1):PVDDQ_DEF
   2    GND      B @BASEBOARD_FAB2_LIB.BASEBOARD_FAB2(SCH_1):GND

CAP_0402-0.22UF,16V,10%,X7R,A3A  I72  C7A25
   1 P5V_STBY      A @BASEBOARD_FAB2_LIB.BASEBOARD_FAB2(SCH_1):P5V_STBY
   2    GND      B @BASEBOARD_FAB2_LIB.BASEBOARD_FAB2(SCH_1):GND

CAP_0402-0.220UF,16V,10%,X7R,AA  I75  C7A22
   1 VR_PVDDQ_DEF_PH2_BOOT      A @BASEBOARD_FAB2_LIB.BASEBOARD_FAB2(SCH_1):VR_PVDDQ_DEF_PH2_BOOT
   2 VR_PVDDQ_DEF_PH2_PHASE      B @BASEBOARD_FAB2_LIB.BASEBOARD_FAB2(SCH_1):VR_PVDDQ_DEF_PH2_PHASE

CAP_0402-1.0UF,16V,10%,X6S,D97A  I77  C7A24
   1 VR_PVDDQ_DEF_PH2_VCIN      A @BASEBOARD_FAB2_LIB.BASEBOARD_FAB2(SCH_1):VR_PVDDQ_DEF_PH2_VCIN
   2    GND      B @BASEBOARD_FAB2_LIB.BASEBOARD_FAB2(SCH_1):GND

CAP_A_0402V-0.1UF,16V,10%,X7R,A  I78  C7A20
   1 VR_FET_SW_P12V_STBY_PVDDQ_DEF      A @BASEBOARD_FAB2_LIB.BASEBOARD_FAB2(SCH_1):VR_FET_SW_P12V_STBY_PVDDQ_DEF
   2    GND      B @BASEBOARD_FAB2_LIB.BASEBOARD_FAB2(SCH_1):GND

CAP_0402-1.0UF,16V,10%,X6S,D97A  I79  C7A21
   1 VR_FET_SW_P12V_STBY_PVDDQ_DEF      A @BASEBOARD_FAB2_LIB.BASEBOARD_FAB2(SCH_1):VR_FET_SW_P12V_STBY_PVDDQ_DEF
   2    GND      B @BASEBOARD_FAB2_LIB.BASEBOARD_FAB2(SCH_1):GND

CAP_0805-10UF,16V,10%,X6S,C953A  I80  C3L17
   1 VR_FET_SW_P12V_STBY_PVDDQ_DEF      A @BASEBOARD_FAB2_LIB.BASEBOARD_FAB2(SCH_1):VR_FET_SW_P12V_STBY_PVDDQ_DEF
   2    GND      B @BASEBOARD_FAB2_LIB.BASEBOARD_FAB2(SCH_1):GND

CAP_0805-10UF,16V,10%,X6S,C953A  I81  C3L16
   1 VR_FET_SW_P12V_STBY_PVDDQ_DEF      A @BASEBOARD_FAB2_LIB.BASEBOARD_FAB2(SCH_1):VR_FET_SW_P12V_STBY_PVDDQ_DEF
   2    GND      B @BASEBOARD_FAB2_LIB.BASEBOARD_FAB2(SCH_1):GND

CAP_0805-10UF,16V,10%,X6S,C953A  I84  C3L15
   1 VR_FET_SW_P12V_STBY_PVDDQ_DEF      A @BASEBOARD_FAB2_LIB.BASEBOARD_FAB2(SCH_1):VR_FET_SW_P12V_STBY_PVDDQ_DEF
   2    GND      B @BASEBOARD_FAB2_LIB.BASEBOARD_FAB2(SCH_1):GND

CAP_0805LF-22UF,4V,20%,X6S,C95A  I87  C6A1
   1 PVDDQ_DEF      A @BASEBOARD_FAB2_LIB.BASEBOARD_FAB2(SCH_1):PVDDQ_DEF
   2    GND      B @BASEBOARD_FAB2_LIB.BASEBOARD_FAB2(SCH_1):GND

IR354XX_SM-IR35411,IC,H73688-0A  I106  EU7A1
  33 VR_PVDDQ_DEF_PH1_BOOT_R  BOOST @BASEBOARD_FAB2_LIB.BASEBOARD_FAB2(SCH_1):VR_PVDDQ_DEF_PH1_BOOT_R
  35 P5V_STBY     EN @BASEBOARD_FAB2_LIB.BASEBOARD_FAB2(SCH_1):P5V_STBY
  41 TP_PVDDQ_DEF_PH1_GL_1  GL<1> @BASEBOARD_FAB2_LIB.BASEBOARD_FAB2(SCH_1):TP_PVDDQ_DEF_PH1_GL_1
   6 TP_PVDDQ_DEF_PH1_GL_0  GL<0> @BASEBOARD_FAB2_LIB.BASEBOARD_FAB2(SCH_1):TP_PVDDQ_DEF_PH1_GL_0
  38 ISENSE_PVDDQ_DEF_PH1_IMON   IOUT @BASEBOARD_FAB2_LIB.BASEBOARD_FAB2(SCH_1):ISENSE_PVDDQ_DEF_PH1_IMON
   2    GND   LGND @BASEBOARD_FAB2_LIB.BASEBOARD_FAB2(SCH_1):GND
  31     NC     NC     NC
  37 VR_PVDDQ_DEF_PH1_OCSET  OCSET @BASEBOARD_FAB2_LIB.BASEBOARD_FAB2(SCH_1):VR_PVDDQ_DEF_PH1_OCSET
  40    GND PGND<2> @BASEBOARD_FAB2_LIB.BASEBOARD_FAB2(SCH_1):GND
   7    GND PGND<1> @BASEBOARD_FAB2_LIB.BASEBOARD_FAB2(SCH_1):GND
   5    GND PGND<0> @BASEBOARD_FAB2_LIB.BASEBOARD_FAB2(SCH_1):GND
  32 VR_PVDDQ_DEF_PH1_PHASE  PHASE @BASEBOARD_FAB2_LIB.BASEBOARD_FAB2(SCH_1):VR_PVDDQ_DEF_PH1_PHASE
  34 VR_PVDDQ_DEF_PWM1    PWM @BASEBOARD_FAB2_LIB.BASEBOARD_FAB2(SCH_1):VR_PVDDQ_DEF_PWM1
  39 VR_PVDDQ_DEF_AIREF1  REFIN @BASEBOARD_FAB2_LIB.BASEBOARD_FAB2(SCH_1):VR_PVDDQ_DEF_AIREF1
  10 VR_PVDDQ_DEF_PH1_SW     SW @BASEBOARD_FAB2_LIB.BASEBOARD_FAB2(SCH_1):VR_PVDDQ_DEF_PH1_SW
  36 A_TSENSE_PVDDQ_DEF TOUT_FLT @BASEBOARD_FAB2_LIB.BASEBOARD_FAB2(SCH_1):A_TSENSE_PVDDQ_DEF
   3 VR_PVDDQ_DEF_PH1_VCIN    VCC @BASEBOARD_FAB2_LIB.BASEBOARD_FAB2(SCH_1):VR_PVDDQ_DEF_PH1_VCIN
   4 P5V_STBY   VDRV @BASEBOARD_FAB2_LIB.BASEBOARD_FAB2(SCH_1):P5V_STBY
  30 VR_FET_SW_P12V_STBY_PVDDQ_DEF VIN<1> @BASEBOARD_FAB2_LIB.BASEBOARD_FAB2(SCH_1):VR_FET_SW_P12V_STBY_PVDDQ_DEF
  25 VR_FET_SW_P12V_STBY_PVDDQ_DEF VIN<0> @BASEBOARD_FAB2_LIB.BASEBOARD_FAB2(SCH_1):VR_FET_SW_P12V_STBY_PVDDQ_DEF
   1 PVDDQ_DEF    VOS @BASEBOARD_FAB2_LIB.BASEBOARD_FAB2(SCH_1):PVDDQ_DEF

IR354XX_SM-IR35411,IC,H73688-0A  I107  EU7A4
  33 VR_PVDDQ_DEF_PH2_BOOT_R  BOOST @BASEBOARD_FAB2_LIB.BASEBOARD_FAB2(SCH_1):VR_PVDDQ_DEF_PH2_BOOT_R
  35 P5V_STBY     EN @BASEBOARD_FAB2_LIB.BASEBOARD_FAB2(SCH_1):P5V_STBY
  41 TP_PVDDQ_DEF_PH2_GL_1  GL<1> @BASEBOARD_FAB2_LIB.BASEBOARD_FAB2(SCH_1):TP_PVDDQ_DEF_PH2_GL_1
   6 TP_PVDDQ_DEF_PH2_GL_0  GL<0> @BASEBOARD_FAB2_LIB.BASEBOARD_FAB2(SCH_1):TP_PVDDQ_DEF_PH2_GL_0
  38 ISENSE_PVDDQ_DEF_PH2_IMON   IOUT @BASEBOARD_FAB2_LIB.BASEBOARD_FAB2(SCH_1):ISENSE_PVDDQ_DEF_PH2_IMON
   2    GND   LGND @BASEBOARD_FAB2_LIB.BASEBOARD_FAB2(SCH_1):GND
  31     NC     NC     NC
  37 VR_PVDDQ_DEF_PH2_OCSET  OCSET @BASEBOARD_FAB2_LIB.BASEBOARD_FAB2(SCH_1):VR_PVDDQ_DEF_PH2_OCSET
  40    GND PGND<2> @BASEBOARD_FAB2_LIB.BASEBOARD_FAB2(SCH_1):GND
   7    GND PGND<1> @BASEBOARD_FAB2_LIB.BASEBOARD_FAB2(SCH_1):GND
   5    GND PGND<0> @BASEBOARD_FAB2_LIB.BASEBOARD_FAB2(SCH_1):GND
  32 VR_PVDDQ_DEF_PH2_PHASE  PHASE @BASEBOARD_FAB2_LIB.BASEBOARD_FAB2(SCH_1):VR_PVDDQ_DEF_PH2_PHASE
  34 VR_PVDDQ_DEF_PWM2    PWM @BASEBOARD_FAB2_LIB.BASEBOARD_FAB2(SCH_1):VR_PVDDQ_DEF_PWM2
  39 VR_PVDDQ_DEF_AIREF2  REFIN @BASEBOARD_FAB2_LIB.BASEBOARD_FAB2(SCH_1):VR_PVDDQ_DEF_AIREF2
  10 VR_PVDDQ_DEF_PH2_SW     SW @BASEBOARD_FAB2_LIB.BASEBOARD_FAB2(SCH_1):VR_PVDDQ_DEF_PH2_SW
  36 A_TSENSE_PVDDQ_DEF TOUT_FLT @BASEBOARD_FAB2_LIB.BASEBOARD_FAB2(SCH_1):A_TSENSE_PVDDQ_DEF
   3 VR_PVDDQ_DEF_PH2_VCIN    VCC @BASEBOARD_FAB2_LIB.BASEBOARD_FAB2(SCH_1):VR_PVDDQ_DEF_PH2_VCIN
   4 P5V_STBY   VDRV @BASEBOARD_FAB2_LIB.BASEBOARD_FAB2(SCH_1):P5V_STBY
  30 VR_FET_SW_P12V_STBY_PVDDQ_DEF VIN<1> @BASEBOARD_FAB2_LIB.BASEBOARD_FAB2(SCH_1):VR_FET_SW_P12V_STBY_PVDDQ_DEF
  25 VR_FET_SW_P12V_STBY_PVDDQ_DEF VIN<0> @BASEBOARD_FAB2_LIB.BASEBOARD_FAB2(SCH_1):VR_FET_SW_P12V_STBY_PVDDQ_DEF
   1 PVDDQ_DEF    VOS @BASEBOARD_FAB2_LIB.BASEBOARD_FAB2(SCH_1):PVDDQ_DEF

RES_0402-68.1K,1%,1/16W,EMPTY,A  I108  R7A20
   1 VR_PVDDQ_DEF_PH1_OCSET      A @BASEBOARD_FAB2_LIB.BASEBOARD_FAB2(SCH_1):VR_PVDDQ_DEF_PH1_OCSET
   2    GND      B @BASEBOARD_FAB2_LIB.BASEBOARD_FAB2(SCH_1):GND

RES_0402-68.1K,1%,1/16W,EMPTY,A  I110  R7A21
   1 VR_PVDDQ_DEF_PH2_OCSET      A @BASEBOARD_FAB2_LIB.BASEBOARD_FAB2(SCH_1):VR_PVDDQ_DEF_PH2_OCSET
   2    GND      B @BASEBOARD_FAB2_LIB.BASEBOARD_FAB2(SCH_1):GND

CAP_A_0402V-0.1UF,16V,10%,X7R,A  I113  CT46
   1 VR_PVDDQ_DEF_AIREF2      A @BASEBOARD_FAB2_LIB.BASEBOARD_FAB2(SCH_1):VR_PVDDQ_DEF_AIREF2
   2    GND      B @BASEBOARD_FAB2_LIB.BASEBOARD_FAB2(SCH_1):GND

CAP_A_0402V-0.1UF,16V,10%,X7R,A  I116  CT45
   1 VR_PVDDQ_DEF_AIREF1      A @BASEBOARD_FAB2_LIB.BASEBOARD_FAB2(SCH_1):VR_PVDDQ_DEF_AIREF1
   2    GND      B @BASEBOARD_FAB2_LIB.BASEBOARD_FAB2(SCH_1):GND

CAP_0402LF-1000PF,50V,10%,X7R,A  I119  CT48
   1 A_TSENSE_PVDDQ_DEF      A @BASEBOARD_FAB2_LIB.BASEBOARD_FAB2(SCH_1):A_TSENSE_PVDDQ_DEF
   2    GND      B @BASEBOARD_FAB2_LIB.BASEBOARD_FAB2(SCH_1):GND

CAP_0402LF-1000PF,50V,10%,X7R,A  I124  CT43
   1 A_TSENSE_PVDDQ_DEF      A @BASEBOARD_FAB2_LIB.BASEBOARD_FAB2(SCH_1):A_TSENSE_PVDDQ_DEF
   2    GND      B @BASEBOARD_FAB2_LIB.BASEBOARD_FAB2(SCH_1):GND

CAP_0402LF-1000PF,50V,10%,X7R,A  I137  CT44
   1 VR_PVDDQ_DEF_PH1_SW      A @BASEBOARD_FAB2_LIB.BASEBOARD_FAB2(SCH_1):VR_PVDDQ_DEF_PH1_SW
   2 VR_PVDDQ_DEF_PH1_SW_RC      B @BASEBOARD_FAB2_LIB.BASEBOARD_FAB2(SCH_1):VR_PVDDQ_DEF_PH1_SW_RC

CAP_0402LF-1000PF,50V,10%,X7R,A  I138  CT47
   1 VR_PVDDQ_DEF_PH2_SW      A @BASEBOARD_FAB2_LIB.BASEBOARD_FAB2(SCH_1):VR_PVDDQ_DEF_PH2_SW
   2 VR_PVDDQ_DEF_PH2_SW_RC      B @BASEBOARD_FAB2_LIB.BASEBOARD_FAB2(SCH_1):VR_PVDDQ_DEF_PH2_SW_RC

RES_0603-0,5.0%,1/10W,CHIP,G22A  I141  RT30
   1 VR_PVDDQ_DEF_PH1_BOOT      A @BASEBOARD_FAB2_LIB.BASEBOARD_FAB2(SCH_1):VR_PVDDQ_DEF_PH1_BOOT
   2 VR_PVDDQ_DEF_PH1_BOOT_R      B @BASEBOARD_FAB2_LIB.BASEBOARD_FAB2(SCH_1):VR_PVDDQ_DEF_PH1_BOOT_R

RES_0603-0,5.0%,1/10W,CHIP,G22A  I142  RT31
   1 VR_PVDDQ_DEF_PH2_BOOT      A @BASEBOARD_FAB2_LIB.BASEBOARD_FAB2(SCH_1):VR_PVDDQ_DEF_PH2_BOOT
   2 VR_PVDDQ_DEF_PH2_BOOT_R      B @BASEBOARD_FAB2_LIB.BASEBOARD_FAB2(SCH_1):VR_PVDDQ_DEF_PH2_BOOT_R

RES_0402-0.0,5%,1/16W,CHIP,G21A  I147  R3L6
   1 VR_PVDDQ_DEF_PH1_VCIN      A @BASEBOARD_FAB2_LIB.BASEBOARD_FAB2(SCH_1):VR_PVDDQ_DEF_PH1_VCIN
   2 P5V_STBY      B @BASEBOARD_FAB2_LIB.BASEBOARD_FAB2(SCH_1):P5V_STBY

RES_0402-0.0,5%,1/16W,CHIP,G21A  I148  R3L8
   1 VR_PVDDQ_DEF_PH2_VCIN      A @BASEBOARD_FAB2_LIB.BASEBOARD_FAB2(SCH_1):VR_PVDDQ_DEF_PH2_VCIN
   2 P5V_STBY      B @BASEBOARD_FAB2_LIB.BASEBOARD_FAB2(SCH_1):P5V_STBY

SC1U10V2KX-4-GP_SMD-BCG6-SC1U1A  I151  C7A18
   1 P5V_STBY      1 @BASEBOARD_FAB2_LIB.BASEBOARD_FAB2(SCH_1):P5V_STBY
   2    GND      2 @BASEBOARD_FAB2_LIB.BASEBOARD_FAB2(SCH_1):GND

SC1U10V2KX-4-GP_SMD-BCG6-SC1U1A  I152  C7A26
   1 P5V_STBY      1 @BASEBOARD_FAB2_LIB.BASEBOARD_FAB2(SCH_1):P5V_STBY
   2    GND      2 @BASEBOARD_FAB2_LIB.BASEBOARD_FAB2(SCH_1):GND

1R3F-GP_RCL_GP-1R3F-GP,64.1R00A  I153  RT29
   1 VR_PVDDQ_DEF_PH1_SW_RC      1 @BASEBOARD_FAB2_LIB.BASEBOARD_FAB2(SCH_1):VR_PVDDQ_DEF_PH1_SW_RC
   2    GND      2 @BASEBOARD_FAB2_LIB.BASEBOARD_FAB2(SCH_1):GND

1R3F-GP_RCL_GP-1R3F-GP,64.1R00A  I154  RT32
   1 VR_PVDDQ_DEF_PH2_SW_RC      1 @BASEBOARD_FAB2_LIB.BASEBOARD_FAB2(SCH_1):VR_PVDDQ_DEF_PH2_SW_RC
   2    GND      2 @BASEBOARD_FAB2_LIB.BASEBOARD_FAB2(SCH_1):GND

IND-120NH-30-GP_DISCRET-GB2-INA  I157  L7A1
   1 VR_PVDDQ_DEF_PH1_SW      S @BASEBOARD_FAB2_LIB.BASEBOARD_FAB2(SCH_1):VR_PVDDQ_DEF_PH1_SW
   2 PVDDQ_DEF      F @BASEBOARD_FAB2_LIB.BASEBOARD_FAB2(SCH_1):PVDDQ_DEF

IND-120NH-30-GP_DISCRET-GB2-INA  I158  L7A3
   1 VR_PVDDQ_DEF_PH2_SW      S @BASEBOARD_FAB2_LIB.BASEBOARD_FAB2(SCH_1):VR_PVDDQ_DEF_PH2_SW
   2 PVDDQ_DEF      F @BASEBOARD_FAB2_LIB.BASEBOARD_FAB2(SCH_1):PVDDQ_DEF


DRAWING: @BASEBOARD_FAB2_LIB.BASEBOARD_FAB2(SCH_1):PAGE220 

RES_0603-120.0,1%,1/10W,CHIP,GA  I58  R4L4
   1 PVDDQ_DEF      A @BASEBOARD_FAB2_LIB.BASEBOARD_FAB2(SCH_1):PVDDQ_DEF
   2    GND      B @BASEBOARD_FAB2_LIB.BASEBOARD_FAB2(SCH_1):GND

RES_0402-100.0,1%,1/16W,EMPTY,A  I74  R4L2
   1 VSENSE_PVDDQ_DEF_P      A @BASEBOARD_FAB2_LIB.BASEBOARD_FAB2(SCH_1):VSENSE_PVDDQ_DEF_P
   2 VSENSE_PVDDQ_DEF_N      B @BASEBOARD_FAB2_LIB.BASEBOARD_FAB2(SCH_1):VSENSE_PVDDQ_DEF_N

CAPP_3018-470UF,2.5V,20%,ALUM,A  I75  C3L6
   1 PVDDQ_DEF      A @BASEBOARD_FAB2_LIB.BASEBOARD_FAB2(SCH_1):PVDDQ_DEF
   2    GND      B @BASEBOARD_FAB2_LIB.BASEBOARD_FAB2(SCH_1):GND

CAPP_3018-470UF,2.5V,20%,ALUM,A  I76  C3L14
   1 PVDDQ_DEF      A @BASEBOARD_FAB2_LIB.BASEBOARD_FAB2(SCH_1):PVDDQ_DEF
   2    GND      B @BASEBOARD_FAB2_LIB.BASEBOARD_FAB2(SCH_1):GND

CAPP_3018-470UF,2.5V,20%,ALUM,A  I77  C6A5
   1 PVDDQ_DEF      A @BASEBOARD_FAB2_LIB.BASEBOARD_FAB2(SCH_1):PVDDQ_DEF
   2    GND      B @BASEBOARD_FAB2_LIB.BASEBOARD_FAB2(SCH_1):GND

CAPP_3018-470UF,2.5V,20%,ALUM,A  I78  C4L5
   1 PVDDQ_DEF      A @BASEBOARD_FAB2_LIB.BASEBOARD_FAB2(SCH_1):PVDDQ_DEF
   2    GND      B @BASEBOARD_FAB2_LIB.BASEBOARD_FAB2(SCH_1):GND

CAP_A_0603V-47UF,4V,20%,X5R,60A  I192  C5L15
   1 PVDDQ_DEF      A @BASEBOARD_FAB2_LIB.BASEBOARD_FAB2(SCH_1):PVDDQ_DEF
   2    GND      B @BASEBOARD_FAB2_LIB.BASEBOARD_FAB2(SCH_1):GND

CAP_A_0603V-47UF,4V,20%,X5R,60A  I193  C5A5
   1 PVDDQ_DEF      A @BASEBOARD_FAB2_LIB.BASEBOARD_FAB2(SCH_1):PVDDQ_DEF
   2    GND      B @BASEBOARD_FAB2_LIB.BASEBOARD_FAB2(SCH_1):GND

CAP_A_0603V-47UF,4V,20%,X5R,60A  I194  C5B1
   1 PVDDQ_DEF      A @BASEBOARD_FAB2_LIB.BASEBOARD_FAB2(SCH_1):PVDDQ_DEF
   2    GND      B @BASEBOARD_FAB2_LIB.BASEBOARD_FAB2(SCH_1):GND

CAP_A_0603V-47UF,4V,20%,X5R,60A  I195  C5M9
   1 PVDDQ_DEF      A @BASEBOARD_FAB2_LIB.BASEBOARD_FAB2(SCH_1):PVDDQ_DEF
   2    GND      B @BASEBOARD_FAB2_LIB.BASEBOARD_FAB2(SCH_1):GND

CAP_A_0603V-47UF,4V,20%,X5R,60A  I196  C4M5
   1 PVDDQ_DEF      A @BASEBOARD_FAB2_LIB.BASEBOARD_FAB2(SCH_1):PVDDQ_DEF
   2    GND      B @BASEBOARD_FAB2_LIB.BASEBOARD_FAB2(SCH_1):GND

CAP_A_0603V-47UF,4V,20%,X5R,60A  I197  C5B2
   1 PVDDQ_DEF      A @BASEBOARD_FAB2_LIB.BASEBOARD_FAB2(SCH_1):PVDDQ_DEF
   2    GND      B @BASEBOARD_FAB2_LIB.BASEBOARD_FAB2(SCH_1):GND

CAP_A_0603V-47UF,4V,20%,X5R,60A  I198  C5M10
   1 PVDDQ_DEF      A @BASEBOARD_FAB2_LIB.BASEBOARD_FAB2(SCH_1):PVDDQ_DEF
   2    GND      B @BASEBOARD_FAB2_LIB.BASEBOARD_FAB2(SCH_1):GND

CAP_A_0603V-47UF,4V,20%,X5R,60A  I199  C5M3
   1 PVDDQ_DEF      A @BASEBOARD_FAB2_LIB.BASEBOARD_FAB2(SCH_1):PVDDQ_DEF
   2    GND      B @BASEBOARD_FAB2_LIB.BASEBOARD_FAB2(SCH_1):GND

CAP_A_0603V-47UF,4V,20%,X5R,60A  I200  C5M11
   1 PVDDQ_DEF      A @BASEBOARD_FAB2_LIB.BASEBOARD_FAB2(SCH_1):PVDDQ_DEF
   2    GND      B @BASEBOARD_FAB2_LIB.BASEBOARD_FAB2(SCH_1):GND

SHUNT_SH0201-EMPTY,N_A  I239  SH4L2
   1 VSENSE_PVDDQ_DEF_P      A @BASEBOARD_FAB2_LIB.BASEBOARD_FAB2(SCH_1):VSENSE_PVDDQ_DEF_P
   2 PVDDQ_DEF      B @BASEBOARD_FAB2_LIB.BASEBOARD_FAB2(SCH_1):PVDDQ_DEF

SHUNT_SH0201-EMPTY,N_A  I240  SH4L1
   1 VSENSE_PVDDQ_DEF_N      A @BASEBOARD_FAB2_LIB.BASEBOARD_FAB2(SCH_1):VSENSE_PVDDQ_DEF_N
   2    GND      B @BASEBOARD_FAB2_LIB.BASEBOARD_FAB2(SCH_1):GND

IND-100NH-35-GP_DISCRET-G8-INDA  I241  L7A5
   1 P12V_STBY      S @BASEBOARD_FAB2_LIB.BASEBOARD_FAB2(SCH_1):P12V_STBY
   2 VR_FET_SW_P12V_STBY_PVDDQ_DEF      F @BASEBOARD_FAB2_LIB.BASEBOARD_FAB2(SCH_1):VR_FET_SW_P12V_STBY_PVDDQ_DEF

CAP_A_0603V-22.0UF,4V,20%,X6S,A  I249  C5D4
   1 PVDDQ_DEF      A @BASEBOARD_FAB2_LIB.BASEBOARD_FAB2(SCH_1):PVDDQ_DEF
   2    GND      B @BASEBOARD_FAB2_LIB.BASEBOARD_FAB2(SCH_1):GND

CAP_A_0603V-22.0UF,4V,20%,X6S,A  I250  C5D3
   1 PVDDQ_DEF      A @BASEBOARD_FAB2_LIB.BASEBOARD_FAB2(SCH_1):PVDDQ_DEF
   2    GND      B @BASEBOARD_FAB2_LIB.BASEBOARD_FAB2(SCH_1):GND

CAP_A_0603V-22.0UF,4V,20%,X6S,A  I251  C5D2
   1 PVDDQ_DEF      A @BASEBOARD_FAB2_LIB.BASEBOARD_FAB2(SCH_1):PVDDQ_DEF
   2    GND      B @BASEBOARD_FAB2_LIB.BASEBOARD_FAB2(SCH_1):GND

CAP_A_0603V-22.0UF,4V,20%,X6S,A  I252  C5D1
   1 PVDDQ_DEF      A @BASEBOARD_FAB2_LIB.BASEBOARD_FAB2(SCH_1):PVDDQ_DEF
   2    GND      B @BASEBOARD_FAB2_LIB.BASEBOARD_FAB2(SCH_1):GND

CAP_A_0603V-22.0UF,4V,20%,X6S,A  I258  C5D9
   1 PVDDQ_DEF      A @BASEBOARD_FAB2_LIB.BASEBOARD_FAB2(SCH_1):PVDDQ_DEF
   2    GND      B @BASEBOARD_FAB2_LIB.BASEBOARD_FAB2(SCH_1):GND

CAP_A_0603V-22.0UF,4V,20%,X6S,A  I259  C5D6
   1 PVDDQ_DEF      A @BASEBOARD_FAB2_LIB.BASEBOARD_FAB2(SCH_1):PVDDQ_DEF
   2    GND      B @BASEBOARD_FAB2_LIB.BASEBOARD_FAB2(SCH_1):GND

CAP_A_0603V-22.0UF,4V,20%,X6S,A  I260  C5D7
   1 PVDDQ_DEF      A @BASEBOARD_FAB2_LIB.BASEBOARD_FAB2(SCH_1):PVDDQ_DEF
   2    GND      B @BASEBOARD_FAB2_LIB.BASEBOARD_FAB2(SCH_1):GND

CAP_A_0603V-22.0UF,4V,20%,X6S,A  I261  C5D8
   1 PVDDQ_DEF      A @BASEBOARD_FAB2_LIB.BASEBOARD_FAB2(SCH_1):PVDDQ_DEF
   2    GND      B @BASEBOARD_FAB2_LIB.BASEBOARD_FAB2(SCH_1):GND

CAP_A_0603V-47UF,4V,20%,X5R,60A  I262  C5A1
   1 PVDDQ_DEF      A @BASEBOARD_FAB2_LIB.BASEBOARD_FAB2(SCH_1):PVDDQ_DEF
   2    GND      B @BASEBOARD_FAB2_LIB.BASEBOARD_FAB2(SCH_1):GND

CAP_A_0603V-47UF,4V,20%,X5R,60A  I263  C5A15
   1 PVDDQ_DEF      A @BASEBOARD_FAB2_LIB.BASEBOARD_FAB2(SCH_1):PVDDQ_DEF
   2    GND      B @BASEBOARD_FAB2_LIB.BASEBOARD_FAB2(SCH_1):GND

CAP_A_0603V-47UF,4V,20%,X5R,60A  I264  C5A12
   1 PVDDQ_DEF      A @BASEBOARD_FAB2_LIB.BASEBOARD_FAB2(SCH_1):PVDDQ_DEF
   2    GND      B @BASEBOARD_FAB2_LIB.BASEBOARD_FAB2(SCH_1):GND

CAP_A_0603V-47UF,4V,20%,X5R,60A  I265  C5A13
   1 PVDDQ_DEF      A @BASEBOARD_FAB2_LIB.BASEBOARD_FAB2(SCH_1):PVDDQ_DEF
   2    GND      B @BASEBOARD_FAB2_LIB.BASEBOARD_FAB2(SCH_1):GND

CAP_A_0603V-47UF,4V,20%,X5R,60A  I266  C5A2
   1 PVDDQ_DEF      A @BASEBOARD_FAB2_LIB.BASEBOARD_FAB2(SCH_1):PVDDQ_DEF
   2    GND      B @BASEBOARD_FAB2_LIB.BASEBOARD_FAB2(SCH_1):GND

CAP_A_0603V-47UF,4V,20%,X5R,60A  I267  C5A14
   1 PVDDQ_DEF      A @BASEBOARD_FAB2_LIB.BASEBOARD_FAB2(SCH_1):PVDDQ_DEF
   2    GND      B @BASEBOARD_FAB2_LIB.BASEBOARD_FAB2(SCH_1):GND

CAP_A_0603V-47UF,4V,20%,X5R,60A  I268  C5A6
   1 PVDDQ_DEF      A @BASEBOARD_FAB2_LIB.BASEBOARD_FAB2(SCH_1):PVDDQ_DEF
   2    GND      B @BASEBOARD_FAB2_LIB.BASEBOARD_FAB2(SCH_1):GND

CAP_A_0603V-47UF,4V,20%,X5R,60A  I269  C5A7
   1 PVDDQ_DEF      A @BASEBOARD_FAB2_LIB.BASEBOARD_FAB2(SCH_1):PVDDQ_DEF
   2    GND      B @BASEBOARD_FAB2_LIB.BASEBOARD_FAB2(SCH_1):GND

CAP_A_0603V-47UF,4V,20%,X5R,60A  I270  C5A3
   1 PVDDQ_DEF      A @BASEBOARD_FAB2_LIB.BASEBOARD_FAB2(SCH_1):PVDDQ_DEF
   2    GND      B @BASEBOARD_FAB2_LIB.BASEBOARD_FAB2(SCH_1):GND

CAP_A_0603V-47UF,4V,20%,X5R,60A  I271  C5A8
   1 PVDDQ_DEF      A @BASEBOARD_FAB2_LIB.BASEBOARD_FAB2(SCH_1):PVDDQ_DEF
   2    GND      B @BASEBOARD_FAB2_LIB.BASEBOARD_FAB2(SCH_1):GND

CAP_A_0603V-47UF,4V,20%,X5R,60A  I272  C5A9
   1 PVDDQ_DEF      A @BASEBOARD_FAB2_LIB.BASEBOARD_FAB2(SCH_1):PVDDQ_DEF
   2    GND      B @BASEBOARD_FAB2_LIB.BASEBOARD_FAB2(SCH_1):GND

CAP_A_0603V-47UF,4V,20%,X5R,60A  I273  C5A16
   1 PVDDQ_DEF      A @BASEBOARD_FAB2_LIB.BASEBOARD_FAB2(SCH_1):PVDDQ_DEF
   2    GND      B @BASEBOARD_FAB2_LIB.BASEBOARD_FAB2(SCH_1):GND

CAP_A_0603V-47UF,4V,20%,X5R,60A  I274  C5A4
   1 PVDDQ_DEF      A @BASEBOARD_FAB2_LIB.BASEBOARD_FAB2(SCH_1):PVDDQ_DEF
   2    GND      B @BASEBOARD_FAB2_LIB.BASEBOARD_FAB2(SCH_1):GND

CAP_A_0603V-47UF,4V,20%,X5R,60A  I275  C5A17
   1 PVDDQ_DEF      A @BASEBOARD_FAB2_LIB.BASEBOARD_FAB2(SCH_1):PVDDQ_DEF
   2    GND      B @BASEBOARD_FAB2_LIB.BASEBOARD_FAB2(SCH_1):GND

CAP_A_0603V-47UF,4V,20%,X5R,60A  I276  C5A18
   1 PVDDQ_DEF      A @BASEBOARD_FAB2_LIB.BASEBOARD_FAB2(SCH_1):PVDDQ_DEF
   2    GND      B @BASEBOARD_FAB2_LIB.BASEBOARD_FAB2(SCH_1):GND

CAP_A_0603V-47UF,4V,20%,X5R,60A  I277  C5A19
   1 PVDDQ_DEF      A @BASEBOARD_FAB2_LIB.BASEBOARD_FAB2(SCH_1):PVDDQ_DEF
   2    GND      B @BASEBOARD_FAB2_LIB.BASEBOARD_FAB2(SCH_1):GND

CAP_A_0603V-47UF,4V,20%,X5R,60A  I278  C5L6
   1 PVDDQ_DEF      A @BASEBOARD_FAB2_LIB.BASEBOARD_FAB2(SCH_1):PVDDQ_DEF
   2    GND      B @BASEBOARD_FAB2_LIB.BASEBOARD_FAB2(SCH_1):GND

CAP_A_0603V-47UF,4V,20%,X5R,60A  I279  C5L7
   1 PVDDQ_DEF      A @BASEBOARD_FAB2_LIB.BASEBOARD_FAB2(SCH_1):PVDDQ_DEF
   2    GND      B @BASEBOARD_FAB2_LIB.BASEBOARD_FAB2(SCH_1):GND

CAP_A_0603V-47UF,4V,20%,X5R,60A  I280  C5L8
   1 PVDDQ_DEF      A @BASEBOARD_FAB2_LIB.BASEBOARD_FAB2(SCH_1):PVDDQ_DEF
   2    GND      B @BASEBOARD_FAB2_LIB.BASEBOARD_FAB2(SCH_1):GND

CAP_A_0603V-47UF,4V,20%,X5R,60A  I281  C5L9
   1 PVDDQ_DEF      A @BASEBOARD_FAB2_LIB.BASEBOARD_FAB2(SCH_1):PVDDQ_DEF
   2    GND      B @BASEBOARD_FAB2_LIB.BASEBOARD_FAB2(SCH_1):GND

CAP_A_0603V-47UF,4V,20%,X5R,60A  I282  C5L10
   1 PVDDQ_DEF      A @BASEBOARD_FAB2_LIB.BASEBOARD_FAB2(SCH_1):PVDDQ_DEF
   2    GND      B @BASEBOARD_FAB2_LIB.BASEBOARD_FAB2(SCH_1):GND

CAP_A_0603V-47UF,4V,20%,X5R,60A  I283  C5L11
   1 PVDDQ_DEF      A @BASEBOARD_FAB2_LIB.BASEBOARD_FAB2(SCH_1):PVDDQ_DEF
   2    GND      B @BASEBOARD_FAB2_LIB.BASEBOARD_FAB2(SCH_1):GND

CAP_A_0603V-47UF,4V,20%,X5R,60A  I284  C5L12
   1 PVDDQ_DEF      A @BASEBOARD_FAB2_LIB.BASEBOARD_FAB2(SCH_1):PVDDQ_DEF
   2    GND      B @BASEBOARD_FAB2_LIB.BASEBOARD_FAB2(SCH_1):GND

CAP_A_0603V-47UF,4V,20%,X5R,60A  I285  C5L13
   1 PVDDQ_DEF      A @BASEBOARD_FAB2_LIB.BASEBOARD_FAB2(SCH_1):PVDDQ_DEF
   2    GND      B @BASEBOARD_FAB2_LIB.BASEBOARD_FAB2(SCH_1):GND

CAP_A_0603V-47UF,4V,20%,X5R,60A  I286  C5M7
   1 PVDDQ_DEF      A @BASEBOARD_FAB2_LIB.BASEBOARD_FAB2(SCH_1):PVDDQ_DEF
   2    GND      B @BASEBOARD_FAB2_LIB.BASEBOARD_FAB2(SCH_1):GND

CAP_A_0603V-47UF,4V,20%,X5R,60A  I287  C5M6
   1 PVDDQ_DEF      A @BASEBOARD_FAB2_LIB.BASEBOARD_FAB2(SCH_1):PVDDQ_DEF
   2    GND      B @BASEBOARD_FAB2_LIB.BASEBOARD_FAB2(SCH_1):GND

CAP_A_0603V-47UF,4V,20%,X5R,60A  I288  C5M5
   1 PVDDQ_DEF      A @BASEBOARD_FAB2_LIB.BASEBOARD_FAB2(SCH_1):PVDDQ_DEF
   2    GND      B @BASEBOARD_FAB2_LIB.BASEBOARD_FAB2(SCH_1):GND

CAP_A_0603V-47UF,4V,20%,X5R,60A  I289  C5M4
   1 PVDDQ_DEF      A @BASEBOARD_FAB2_LIB.BASEBOARD_FAB2(SCH_1):PVDDQ_DEF
   2    GND      B @BASEBOARD_FAB2_LIB.BASEBOARD_FAB2(SCH_1):GND

CAP_A_0603V-47UF,4V,20%,X5R,60A  I290  C5M2
   1 PVDDQ_DEF      A @BASEBOARD_FAB2_LIB.BASEBOARD_FAB2(SCH_1):PVDDQ_DEF
   2    GND      B @BASEBOARD_FAB2_LIB.BASEBOARD_FAB2(SCH_1):GND

CAP_A_0603V-47UF,4V,20%,X5R,60A  I291  C5M1
   1 PVDDQ_DEF      A @BASEBOARD_FAB2_LIB.BASEBOARD_FAB2(SCH_1):PVDDQ_DEF
   2    GND      B @BASEBOARD_FAB2_LIB.BASEBOARD_FAB2(SCH_1):GND

CAP_A_0603V-47UF,4V,20%,X5R,60A  I292  C4M2
   1 PVDDQ_DEF      A @BASEBOARD_FAB2_LIB.BASEBOARD_FAB2(SCH_1):PVDDQ_DEF
   2    GND      B @BASEBOARD_FAB2_LIB.BASEBOARD_FAB2(SCH_1):GND

CAP_A_0603V-47UF,4V,20%,X5R,60A  I293  C5A11
   1 PVDDQ_DEF      A @BASEBOARD_FAB2_LIB.BASEBOARD_FAB2(SCH_1):PVDDQ_DEF
   2    GND      B @BASEBOARD_FAB2_LIB.BASEBOARD_FAB2(SCH_1):GND

SC22U16V5MX-4-GP_SMD-BCG5-SC22A  I298  C7W5
   1 VR_FET_SW_P12V_STBY_PVDDQ_DEF      1 @BASEBOARD_FAB2_LIB.BASEBOARD_FAB2(SCH_1):VR_FET_SW_P12V_STBY_PVDDQ_DEF
   2    GND      2 @BASEBOARD_FAB2_LIB.BASEBOARD_FAB2(SCH_1):GND

SC22U16V5MX-4-GP_SMD-BCG5-SC22A  I299  C7W9
   1 VR_FET_SW_P12V_STBY_PVDDQ_DEF      1 @BASEBOARD_FAB2_LIB.BASEBOARD_FAB2(SCH_1):VR_FET_SW_P12V_STBY_PVDDQ_DEF
   2    GND      2 @BASEBOARD_FAB2_LIB.BASEBOARD_FAB2(SCH_1):GND

SC22U16V5MX-4-GP_SMD-BCG5-SC22A  I300  C7W8
   1 VR_FET_SW_P12V_STBY_PVDDQ_DEF      1 @BASEBOARD_FAB2_LIB.BASEBOARD_FAB2(SCH_1):VR_FET_SW_P12V_STBY_PVDDQ_DEF
   2    GND      2 @BASEBOARD_FAB2_LIB.BASEBOARD_FAB2(SCH_1):GND

SC22U16V5MX-4-GP_SMD-BCG5-SC22A  I301  C7W7
   1 VR_FET_SW_P12V_STBY_PVDDQ_DEF      1 @BASEBOARD_FAB2_LIB.BASEBOARD_FAB2(SCH_1):VR_FET_SW_P12V_STBY_PVDDQ_DEF
   2    GND      2 @BASEBOARD_FAB2_LIB.BASEBOARD_FAB2(SCH_1):GND

SC22U16V5MX-4-GP_SMD-BCG5-SC22A  I302  C7W6
   1 VR_FET_SW_P12V_STBY_PVDDQ_DEF      1 @BASEBOARD_FAB2_LIB.BASEBOARD_FAB2(SCH_1):VR_FET_SW_P12V_STBY_PVDDQ_DEF
   2    GND      2 @BASEBOARD_FAB2_LIB.BASEBOARD_FAB2(SCH_1):GND

SC22U16V5MX-4-GP_SMD-BCG5-SC22A  I303  C7W13
   1 VR_FET_SW_P12V_STBY_PVDDQ_DEF      1 @BASEBOARD_FAB2_LIB.BASEBOARD_FAB2(SCH_1):VR_FET_SW_P12V_STBY_PVDDQ_DEF
   2    GND      2 @BASEBOARD_FAB2_LIB.BASEBOARD_FAB2(SCH_1):GND

SC22U16V5MX-4-GP_SMD-BCG5-SC22A  I304  C7W12
   1 VR_FET_SW_P12V_STBY_PVDDQ_DEF      1 @BASEBOARD_FAB2_LIB.BASEBOARD_FAB2(SCH_1):VR_FET_SW_P12V_STBY_PVDDQ_DEF
   2    GND      2 @BASEBOARD_FAB2_LIB.BASEBOARD_FAB2(SCH_1):GND

SC22U16V5MX-4-GP_SMD-BCG5-SC22A  I305  C7W11
   1 VR_FET_SW_P12V_STBY_PVDDQ_DEF      1 @BASEBOARD_FAB2_LIB.BASEBOARD_FAB2(SCH_1):VR_FET_SW_P12V_STBY_PVDDQ_DEF
   2    GND      2 @BASEBOARD_FAB2_LIB.BASEBOARD_FAB2(SCH_1):GND

SC22U16V5MX-4-GP_SMD-BCG5-SC22A  I306  C7W10
   1 VR_FET_SW_P12V_STBY_PVDDQ_DEF      1 @BASEBOARD_FAB2_LIB.BASEBOARD_FAB2(SCH_1):VR_FET_SW_P12V_STBY_PVDDQ_DEF
   2    GND      2 @BASEBOARD_FAB2_LIB.BASEBOARD_FAB2(SCH_1):GND

CAP_0805-100UF,4V,20%,X5R,6024A  I308  C5A20
   1 PVDDQ_DEF      A @BASEBOARD_FAB2_LIB.BASEBOARD_FAB2(SCH_1):PVDDQ_DEF
   2    GND      B @BASEBOARD_FAB2_LIB.BASEBOARD_FAB2(SCH_1):GND

CAP_0805-100UF,4V,20%,X5R,6024A  I309  C5L1
   1 PVDDQ_DEF      A @BASEBOARD_FAB2_LIB.BASEBOARD_FAB2(SCH_1):PVDDQ_DEF
   2    GND      B @BASEBOARD_FAB2_LIB.BASEBOARD_FAB2(SCH_1):GND

CAP_0805-100UF,4V,20%,X5R,6024A  I310  C5L3
   1 PVDDQ_DEF      A @BASEBOARD_FAB2_LIB.BASEBOARD_FAB2(SCH_1):PVDDQ_DEF
   2    GND      B @BASEBOARD_FAB2_LIB.BASEBOARD_FAB2(SCH_1):GND

CAP_0805-100UF,4V,20%,X5R,6024A  I311  C5L2
   1 PVDDQ_DEF      A @BASEBOARD_FAB2_LIB.BASEBOARD_FAB2(SCH_1):PVDDQ_DEF
   2    GND      B @BASEBOARD_FAB2_LIB.BASEBOARD_FAB2(SCH_1):GND

CAP_0805-100UF,4V,20%,X5R,6024A  I312  C5M12
   1 PVDDQ_DEF      A @BASEBOARD_FAB2_LIB.BASEBOARD_FAB2(SCH_1):PVDDQ_DEF
   2    GND      B @BASEBOARD_FAB2_LIB.BASEBOARD_FAB2(SCH_1):GND

CAP_0805-100UF,4V,20%,X5R,6024A  I313  C5L14
   1 PVDDQ_DEF      A @BASEBOARD_FAB2_LIB.BASEBOARD_FAB2(SCH_1):PVDDQ_DEF
   2    GND      B @BASEBOARD_FAB2_LIB.BASEBOARD_FAB2(SCH_1):GND

CAP_0805-100UF,4V,20%,X5R,6024A  I314  C5M8
   1 PVDDQ_DEF      A @BASEBOARD_FAB2_LIB.BASEBOARD_FAB2(SCH_1):PVDDQ_DEF
   2    GND      B @BASEBOARD_FAB2_LIB.BASEBOARD_FAB2(SCH_1):GND

CAP_0805-100UF,4V,20%,X5R,6024A  I315  C5P3
   1 PVDDQ_DEF      A @BASEBOARD_FAB2_LIB.BASEBOARD_FAB2(SCH_1):PVDDQ_DEF
   2    GND      B @BASEBOARD_FAB2_LIB.BASEBOARD_FAB2(SCH_1):GND

CAP_0805-100UF,4V,20%,X5R,6024A  I316  C5P6
   1 PVDDQ_DEF      A @BASEBOARD_FAB2_LIB.BASEBOARD_FAB2(SCH_1):PVDDQ_DEF
   2    GND      B @BASEBOARD_FAB2_LIB.BASEBOARD_FAB2(SCH_1):GND

CAP_0805-100UF,4V,20%,X5R,6024A  I317  C5P5
   1 PVDDQ_DEF      A @BASEBOARD_FAB2_LIB.BASEBOARD_FAB2(SCH_1):PVDDQ_DEF
   2    GND      B @BASEBOARD_FAB2_LIB.BASEBOARD_FAB2(SCH_1):GND

CAP_0805-100UF,4V,20%,X5R,6024A  I318  C5P4
   1 PVDDQ_DEF      A @BASEBOARD_FAB2_LIB.BASEBOARD_FAB2(SCH_1):PVDDQ_DEF
   2    GND      B @BASEBOARD_FAB2_LIB.BASEBOARD_FAB2(SCH_1):GND

CAP_0805-100UF,4V,20%,X5R,6024A  I319  C5P2
   1 PVDDQ_DEF      A @BASEBOARD_FAB2_LIB.BASEBOARD_FAB2(SCH_1):PVDDQ_DEF
   2    GND      B @BASEBOARD_FAB2_LIB.BASEBOARD_FAB2(SCH_1):GND

CAP_0805-100UF,4V,20%,X5R,6024A  I320  C5P1
   1 PVDDQ_DEF      A @BASEBOARD_FAB2_LIB.BASEBOARD_FAB2(SCH_1):PVDDQ_DEF
   2    GND      B @BASEBOARD_FAB2_LIB.BASEBOARD_FAB2(SCH_1):GND

CAP_0805-100UF,4V,20%,X5R,6024A  I321  C5A10
   1 PVDDQ_DEF      A @BASEBOARD_FAB2_LIB.BASEBOARD_FAB2(SCH_1):PVDDQ_DEF
   2    GND      B @BASEBOARD_FAB2_LIB.BASEBOARD_FAB2(SCH_1):GND

SE100U16VM-48-GP_SMD-TCG2-SE10A  I324  C7W2
   1 VR_FET_SW_P12V_STBY_PVDDQ_DEF      1 @BASEBOARD_FAB2_LIB.BASEBOARD_FAB2(SCH_1):VR_FET_SW_P12V_STBY_PVDDQ_DEF
   2    GND      2 @BASEBOARD_FAB2_LIB.BASEBOARD_FAB2(SCH_1):GND


DRAWING: @BASEBOARD_FAB2_LIB.BASEBOARD_FAB2(SCH_1):PAGE221 

CAP_0402-1.0UF,16V,10%,X6S,D97A  I22  C4G16
   1 VR_PVTT_ABC_VREF      A @BASEBOARD_FAB2_LIB.BASEBOARD_FAB2(SCH_1):VR_PVTT_ABC_VREF
   2    GND      B @BASEBOARD_FAB2_LIB.BASEBOARD_FAB2(SCH_1):GND

CAP_0805LF-22UF,4V,20%,X6S,C95A  I24  C4G24
   1 PVTT_ABC      A @BASEBOARD_FAB2_LIB.BASEBOARD_FAB2(SCH_1):PVTT_ABC
   2    GND      B @BASEBOARD_FAB2_LIB.BASEBOARD_FAB2(SCH_1):GND

CAP_0402LF-1000PF,50V,10%,EMPTA  I2  C4G23
   1 FM_PVTT_ABC_EN_R      A @BASEBOARD_FAB2_LIB.BASEBOARD_FAB2(SCH_1):FM_PVTT_ABC_EN_R
   2    GND      B @BASEBOARD_FAB2_LIB.BASEBOARD_FAB2(SCH_1):GND

RES_0402-0.0,5%,1/16W,CHIP,G21A  I4  R4G23
   1 PWRGD_PVDDQ_ABC_R      A @BASEBOARD_FAB2_LIB.BASEBOARD_FAB2(SCH_1):PWRGD_PVDDQ_ABC_R
   2 FM_PVTT_ABC_EN_R      B @BASEBOARD_FAB2_LIB.BASEBOARD_FAB2(SCH_1):FM_PVTT_ABC_EN_R

RES_0402-1.0M,1%,1/16W,EMPTY,GA  I5  R6U15
   1   P3V3      A @BASEBOARD_FAB2_LIB.BASEBOARD_FAB2(SCH_1):P3V3
   2 FM_PVTT_ABC_EN_R      B @BASEBOARD_FAB2_LIB.BASEBOARD_FAB2(SCH_1):FM_PVTT_ABC_EN_R

RES_0402-0.0,5%,1/16W,CHIP,G21A  I6  R6U5
   1 PVDDQ_ABC      A @BASEBOARD_FAB2_LIB.BASEBOARD_FAB2(SCH_1):PVDDQ_ABC
   2 VSENSE_PVDDQ_ABC_VTT      B @BASEBOARD_FAB2_LIB.BASEBOARD_FAB2(SCH_1):VSENSE_PVDDQ_ABC_VTT

SHUNT_SH0201-EMPTY,N_A  I9  SH5U1
   1 VR_PVTT_ABC_SNS      A @BASEBOARD_FAB2_LIB.BASEBOARD_FAB2(SCH_1):VR_PVTT_ABC_SNS
   2 PVTT_ABC      B @BASEBOARD_FAB2_LIB.BASEBOARD_FAB2(SCH_1):PVTT_ABC

CAP_0603-4.7UF,6.3V,10%,X6S,E1A  I11  C6U12
   1 VSENSE_PVDDQ_ABC_VTT      A @BASEBOARD_FAB2_LIB.BASEBOARD_FAB2(SCH_1):VSENSE_PVDDQ_ABC_VTT
   2    GND      B @BASEBOARD_FAB2_LIB.BASEBOARD_FAB2(SCH_1):GND

CAP_0402-1.0UF,16V,10%,X6S,D97A  I13  C4G15
   1 VR_PVTT_ABC_BIAS      A @BASEBOARD_FAB2_LIB.BASEBOARD_FAB2(SCH_1):VR_PVTT_ABC_BIAS
   2    GND      B @BASEBOARD_FAB2_LIB.BASEBOARD_FAB2(SCH_1):GND

RES_0402-0.0,5%,1/16W,CHIP,G21A  I14  R6U4
   1   P3V3      A @BASEBOARD_FAB2_LIB.BASEBOARD_FAB2(SCH_1):P3V3
   2 VR_PVTT_ABC_BIAS      B @BASEBOARD_FAB2_LIB.BASEBOARD_FAB2(SCH_1):VR_PVTT_ABC_BIAS

CAP_0603LF-10UF,4V,20%,X6S,E15A  I18  C6U15
   1 PVDDQ_ABC      A @BASEBOARD_FAB2_LIB.BASEBOARD_FAB2(SCH_1):PVDDQ_ABC
   2    GND      B @BASEBOARD_FAB2_LIB.BASEBOARD_FAB2(SCH_1):GND

CAP_0603LF-10UF,4V,20%,X6S,E15A  I19  C6U16
   1 PVDDQ_ABC      A @BASEBOARD_FAB2_LIB.BASEBOARD_FAB2(SCH_1):PVDDQ_ABC
   2    GND      B @BASEBOARD_FAB2_LIB.BASEBOARD_FAB2(SCH_1):GND

RES_0402-10.0K,1%,1/16W,CHIP,GA  I25  R4G18
   1   P3V3      A @BASEBOARD_FAB2_LIB.BASEBOARD_FAB2(SCH_1):P3V3
   2 PWRGD_PVTT_ABC_CPU0_R      B @BASEBOARD_FAB2_LIB.BASEBOARD_FAB2(SCH_1):PWRGD_PVTT_ABC_CPU0_R

CAP_0402LF-1000PF,50V,10%,X7R,A  I30  C4G14
   1 PWRGD_PVTT_ABC_CPU0_R      A @BASEBOARD_FAB2_LIB.BASEBOARD_FAB2(SCH_1):PWRGD_PVTT_ABC_CPU0_R
   2    GND      B @BASEBOARD_FAB2_LIB.BASEBOARD_FAB2(SCH_1):GND

RES_0402-33.2,1%,1/16W,CHIP,G2A  I33  R4G19
   1 PWRGD_PVTT_ABC_CPU0_R      A @BASEBOARD_FAB2_LIB.BASEBOARD_FAB2(SCH_1):PWRGD_PVTT_ABC_CPU0_R
   2 PWRGD_PVTT_CPU0      B @BASEBOARD_FAB2_LIB.BASEBOARD_FAB2(SCH_1):PWRGD_PVTT_CPU0

MIC5166_DFN-IC,H55101-001  I15  EU4G3
   7 FM_PVTT_ABC_EN_R     EN @BASEBOARD_FAB2_LIB.BASEBOARD_FAB2(SCH_1):FM_PVTT_ABC_EN_R
  10 PVDDQ_ABC    VIN @BASEBOARD_FAB2_LIB.BASEBOARD_FAB2(SCH_1):PVDDQ_ABC
   1 VR_PVTT_ABC_VREF   VREF @BASEBOARD_FAB2_LIB.BASEBOARD_FAB2(SCH_1):VR_PVTT_ABC_VREF
   2 VR_PVTT_ABC_BIAS   BIAS @BASEBOARD_FAB2_LIB.BASEBOARD_FAB2(SCH_1):VR_PVTT_ABC_BIAS
   3    GND   AGND @BASEBOARD_FAB2_LIB.BASEBOARD_FAB2(SCH_1):GND
   5 PWRGD_PVTT_ABC_CPU0_R     PG @BASEBOARD_FAB2_LIB.BASEBOARD_FAB2(SCH_1):PWRGD_PVTT_ABC_CPU0_R
   4 VSENSE_PVDDQ_ABC_VTT   VDDQ @BASEBOARD_FAB2_LIB.BASEBOARD_FAB2(SCH_1):VSENSE_PVDDQ_ABC_VTT
   6 VR_PVTT_ABC_SNS    SNS @BASEBOARD_FAB2_LIB.BASEBOARD_FAB2(SCH_1):VR_PVTT_ABC_SNS
   8    GND   PGND @BASEBOARD_FAB2_LIB.BASEBOARD_FAB2(SCH_1):GND
   9 PVTT_ABC    VTT @BASEBOARD_FAB2_LIB.BASEBOARD_FAB2(SCH_1):PVTT_ABC
  11    GND  THPAD @BASEBOARD_FAB2_LIB.BASEBOARD_FAB2(SCH_1):GND

CAP_A_0603V-47UF,4V,20%,X5R,60A  I40  C5T3
   1 PVTT_ABC      A @BASEBOARD_FAB2_LIB.BASEBOARD_FAB2(SCH_1):PVTT_ABC
   2    GND      B @BASEBOARD_FAB2_LIB.BASEBOARD_FAB2(SCH_1):GND

CAP_0805-100UF,4V,20%,X5R,6024A  I44  C6W11
   1 PVTT_ABC      A @BASEBOARD_FAB2_LIB.BASEBOARD_FAB2(SCH_1):PVTT_ABC
   2    GND      B @BASEBOARD_FAB2_LIB.BASEBOARD_FAB2(SCH_1):GND

CAP_0805-100UF,4V,20%,X5R,6024A  I45  C5U12
   1 PVTT_ABC      A @BASEBOARD_FAB2_LIB.BASEBOARD_FAB2(SCH_1):PVTT_ABC
   2    GND      B @BASEBOARD_FAB2_LIB.BASEBOARD_FAB2(SCH_1):GND

CAP_0805-100UF,4V,20%,X5R,6024A  I46  C5U16
   1 PVTT_ABC      A @BASEBOARD_FAB2_LIB.BASEBOARD_FAB2(SCH_1):PVTT_ABC
   2    GND      B @BASEBOARD_FAB2_LIB.BASEBOARD_FAB2(SCH_1):GND


DRAWING: @BASEBOARD_FAB2_LIB.BASEBOARD_FAB2(SCH_1):PAGE222 

CAP_0402-1.0UF,16V,10%,X6S,D97A  I12  C4A10
   1 VR_PVTT_DEF_BIAS      A @BASEBOARD_FAB2_LIB.BASEBOARD_FAB2(SCH_1):VR_PVTT_DEF_BIAS
   2    GND      B @BASEBOARD_FAB2_LIB.BASEBOARD_FAB2(SCH_1):GND

CAP_0805LF-22UF,4V,20%,X6S,C95A  I28  C4A1
   1 PVTT_DEF      A @BASEBOARD_FAB2_LIB.BASEBOARD_FAB2(SCH_1):PVTT_DEF
   2    GND      B @BASEBOARD_FAB2_LIB.BASEBOARD_FAB2(SCH_1):GND

CAP_0402LF-1000PF,50V,10%,EMPTA  I2  C4A2
   1 FM_PVTT_DEF_EN_R      A @BASEBOARD_FAB2_LIB.BASEBOARD_FAB2(SCH_1):FM_PVTT_DEF_EN_R
   2    GND      B @BASEBOARD_FAB2_LIB.BASEBOARD_FAB2(SCH_1):GND

RES_0402-0.0,5%,1/16W,CHIP,G21A  I4  R4A2
   1 PWRGD_PVDDQ_DEF_R      A @BASEBOARD_FAB2_LIB.BASEBOARD_FAB2(SCH_1):PWRGD_PVDDQ_DEF_R
   2 FM_PVTT_DEF_EN_R      B @BASEBOARD_FAB2_LIB.BASEBOARD_FAB2(SCH_1):FM_PVTT_DEF_EN_R

RES_0402-1.0M,1%,1/16W,EMPTY,GA  I5  R6L4
   1   P3V3      A @BASEBOARD_FAB2_LIB.BASEBOARD_FAB2(SCH_1):P3V3
   2 FM_PVTT_DEF_EN_R      B @BASEBOARD_FAB2_LIB.BASEBOARD_FAB2(SCH_1):FM_PVTT_DEF_EN_R

RES_0402-0.0,5%,1/16W,CHIP,G21A  I6  R6L10
   1 PVDDQ_DEF      A @BASEBOARD_FAB2_LIB.BASEBOARD_FAB2(SCH_1):PVDDQ_DEF
   2 VSENSE_PVDDQ_DEF_VTT      B @BASEBOARD_FAB2_LIB.BASEBOARD_FAB2(SCH_1):VSENSE_PVDDQ_DEF_VTT

CAP_0603-4.7UF,6.3V,10%,X6S,E1A  I9  C4A11
   1 VSENSE_PVDDQ_DEF_VTT      A @BASEBOARD_FAB2_LIB.BASEBOARD_FAB2(SCH_1):VSENSE_PVDDQ_DEF_VTT
   2    GND      B @BASEBOARD_FAB2_LIB.BASEBOARD_FAB2(SCH_1):GND

RES_0402-0.0,5%,1/16W,CHIP,G21A  I10  R6L11
   1   P3V3      A @BASEBOARD_FAB2_LIB.BASEBOARD_FAB2(SCH_1):P3V3
   2 VR_PVTT_DEF_BIAS      B @BASEBOARD_FAB2_LIB.BASEBOARD_FAB2(SCH_1):VR_PVTT_DEF_BIAS

MIC5166_DFN-IC,H55101-001  I13  EU4A1
   7 FM_PVTT_DEF_EN_R     EN @BASEBOARD_FAB2_LIB.BASEBOARD_FAB2(SCH_1):FM_PVTT_DEF_EN_R
  10 PVDDQ_DEF    VIN @BASEBOARD_FAB2_LIB.BASEBOARD_FAB2(SCH_1):PVDDQ_DEF
   1 VR_PVTT_DEF_VREF   VREF @BASEBOARD_FAB2_LIB.BASEBOARD_FAB2(SCH_1):VR_PVTT_DEF_VREF
   2 VR_PVTT_DEF_BIAS   BIAS @BASEBOARD_FAB2_LIB.BASEBOARD_FAB2(SCH_1):VR_PVTT_DEF_BIAS
   3    GND   AGND @BASEBOARD_FAB2_LIB.BASEBOARD_FAB2(SCH_1):GND
   5 PWRGD_PVTT_DEF_CPU0_R     PG @BASEBOARD_FAB2_LIB.BASEBOARD_FAB2(SCH_1):PWRGD_PVTT_DEF_CPU0_R
   4 VSENSE_PVDDQ_DEF_VTT   VDDQ @BASEBOARD_FAB2_LIB.BASEBOARD_FAB2(SCH_1):VSENSE_PVDDQ_DEF_VTT
   6 VR_PVTT_DEF_SNS    SNS @BASEBOARD_FAB2_LIB.BASEBOARD_FAB2(SCH_1):VR_PVTT_DEF_SNS
   8    GND   PGND @BASEBOARD_FAB2_LIB.BASEBOARD_FAB2(SCH_1):GND
   9 PVTT_DEF    VTT @BASEBOARD_FAB2_LIB.BASEBOARD_FAB2(SCH_1):PVTT_DEF
  11    GND  THPAD @BASEBOARD_FAB2_LIB.BASEBOARD_FAB2(SCH_1):GND

CAP_0603LF-10UF,4V,20%,X6S,E15A  I15  C6L4
   1 PVDDQ_DEF      A @BASEBOARD_FAB2_LIB.BASEBOARD_FAB2(SCH_1):PVDDQ_DEF
   2    GND      B @BASEBOARD_FAB2_LIB.BASEBOARD_FAB2(SCH_1):GND

CAP_0603LF-10UF,4V,20%,X6S,E15A  I17  C6L3
   1 PVDDQ_DEF      A @BASEBOARD_FAB2_LIB.BASEBOARD_FAB2(SCH_1):PVDDQ_DEF
   2    GND      B @BASEBOARD_FAB2_LIB.BASEBOARD_FAB2(SCH_1):GND

CAP_0402-1.0UF,16V,10%,X6S,D97A  I20  C4A9
   1 VR_PVTT_DEF_VREF      A @BASEBOARD_FAB2_LIB.BASEBOARD_FAB2(SCH_1):VR_PVTT_DEF_VREF
   2    GND      B @BASEBOARD_FAB2_LIB.BASEBOARD_FAB2(SCH_1):GND

CAP_0402LF-1000PF,50V,10%,X7R,A  I22  C4A12
   1 PWRGD_PVTT_DEF_CPU0_R      A @BASEBOARD_FAB2_LIB.BASEBOARD_FAB2(SCH_1):PWRGD_PVTT_DEF_CPU0_R
   2    GND      B @BASEBOARD_FAB2_LIB.BASEBOARD_FAB2(SCH_1):GND

RES_0402-10.0K,1%,1/16W,CHIP,GA  I23  R6L9
   1   P3V3      A @BASEBOARD_FAB2_LIB.BASEBOARD_FAB2(SCH_1):P3V3
   2 PWRGD_PVTT_DEF_CPU0_R      B @BASEBOARD_FAB2_LIB.BASEBOARD_FAB2(SCH_1):PWRGD_PVTT_DEF_CPU0_R

SHUNT_SH0201-EMPTY,N_A  I30  SH5L1
   1 VR_PVTT_DEF_SNS      A @BASEBOARD_FAB2_LIB.BASEBOARD_FAB2(SCH_1):VR_PVTT_DEF_SNS
   2 PVTT_DEF      B @BASEBOARD_FAB2_LIB.BASEBOARD_FAB2(SCH_1):PVTT_DEF

RES_0402-33.2,1%,1/16W,CHIP,G2A  I31  R4A6
   1 PWRGD_PVTT_DEF_CPU0_R      A @BASEBOARD_FAB2_LIB.BASEBOARD_FAB2(SCH_1):PWRGD_PVTT_DEF_CPU0_R
   2 PWRGD_PVTT_CPU0      B @BASEBOARD_FAB2_LIB.BASEBOARD_FAB2(SCH_1):PWRGD_PVTT_CPU0

CAP_A_0603V-47UF,4V,20%,X5R,60A  I41  C5M13
   1 PVTT_DEF      A @BASEBOARD_FAB2_LIB.BASEBOARD_FAB2(SCH_1):PVTT_DEF
   2    GND      B @BASEBOARD_FAB2_LIB.BASEBOARD_FAB2(SCH_1):GND

CAP_0805-100UF,4V,20%,X5R,6024A  I44  C5L5
   1 PVTT_DEF      A @BASEBOARD_FAB2_LIB.BASEBOARD_FAB2(SCH_1):PVTT_DEF
   2    GND      B @BASEBOARD_FAB2_LIB.BASEBOARD_FAB2(SCH_1):GND

CAP_0805-100UF,4V,20%,X5R,6024A  I45  C5L4
   1 PVTT_DEF      A @BASEBOARD_FAB2_LIB.BASEBOARD_FAB2(SCH_1):PVTT_DEF
   2    GND      B @BASEBOARD_FAB2_LIB.BASEBOARD_FAB2(SCH_1):GND

CAP_0805-100UF,4V,20%,X5R,6024A  I46  C4W5
   1 PVTT_DEF      A @BASEBOARD_FAB2_LIB.BASEBOARD_FAB2(SCH_1):PVTT_DEF
   2    GND      B @BASEBOARD_FAB2_LIB.BASEBOARD_FAB2(SCH_1):GND


DRAWING: @BASEBOARD_FAB2_LIB.BASEBOARD_FAB2(SCH_1):PAGE223 

RES_0402-0.0,5%,1/16W,CHIP,G21A  I14  R9U7
   1 FM_PVDDQ_GHJ_EN      A @BASEBOARD_FAB2_LIB.BASEBOARD_FAB2(SCH_1):FM_PVDDQ_GHJ_EN
   2 VR_PVDDQ_GHJ_VREN      B @BASEBOARD_FAB2_LIB.BASEBOARD_FAB2(SCH_1):VR_PVDDQ_GHJ_VREN

RES_0402-1.0K,0.1%,1/16W,CHIP,A  I16  RF19
   1 VR_PVDDQ_GHJ_AIREF1      A @BASEBOARD_FAB2_LIB.BASEBOARD_FAB2(SCH_1):VR_PVDDQ_GHJ_AIREF1
   2 ISENSE_PVDDQ_GHJ_PH1_IMON      B @BASEBOARD_FAB2_LIB.BASEBOARD_FAB2(SCH_1):ISENSE_PVDDQ_GHJ_PH1_IMON

CAP_A_0402V-1.0UF,6.3V,10%,X6SA  I44  C1G23
   1 VR_PVDDQ_GHJ_VD12      A @BASEBOARD_FAB2_LIB.BASEBOARD_FAB2(SCH_1):VR_PVDDQ_GHJ_VD12
   2    GND      B @BASEBOARD_FAB2_LIB.BASEBOARD_FAB2(SCH_1):GND

RES_0402-0.0,5%,1/16W,EMPTY,G2A  I53  R12W33
   1 TP_PVDDQ_GHJ_MP2      A @BASEBOARD_FAB2_LIB.BASEBOARD_FAB2(SCH_1):TP_PVDDQ_GHJ_MP2
   2 PWRGD_PVDDQ_GHJ      B @BASEBOARD_FAB2_LIB.BASEBOARD_FAB2(SCH_1):PWRGD_PVDDQ_GHJ

CAP_0402LF-220PF,50V,10%,X7R,AA  I12  C1G16
   1 VR_PVDDQ_GHJ_AVSP      A @BASEBOARD_FAB2_LIB.BASEBOARD_FAB2(SCH_1):VR_PVDDQ_GHJ_AVSP
   2 VSENSE_PVDDQ_GHJ_N      B @BASEBOARD_FAB2_LIB.BASEBOARD_FAB2(SCH_1):VSENSE_PVDDQ_GHJ_N

SC22P50V2JN-4GP_SMD-BCG-SC22P5A  I15  CF19
   1 VR_PVDDQ_GHJ_AIREF1      1 @BASEBOARD_FAB2_LIB.BASEBOARD_FAB2(SCH_1):VR_PVDDQ_GHJ_AIREF1
   2 ISENSE_PVDDQ_GHJ_PH1_IMON      2 @BASEBOARD_FAB2_LIB.BASEBOARD_FAB2(SCH_1):ISENSE_PVDDQ_GHJ_PH1_IMON

RES_0402-150.0,1%,1/16W,CHIP,GA  I18  R1G7
   1 SVID_CLK1_CPU1_R      A @BASEBOARD_FAB2_LIB.BASEBOARD_FAB2(SCH_1):SVID_CLK1_CPU1_R
   2 SVID_CLK_PVDDQ_GHJ      B @BASEBOARD_FAB2_LIB.BASEBOARD_FAB2(SCH_1):SVID_CLK_PVDDQ_GHJ

RES_0402-1.0K,0.1%,1/16W,CHIP,A  I19  RF20
   1 VR_PVDDQ_GHJ_AIREF2      A @BASEBOARD_FAB2_LIB.BASEBOARD_FAB2(SCH_1):VR_PVDDQ_GHJ_AIREF2
   2 ISENSE_PVDDQ_GHJ_PH2_IMON      B @BASEBOARD_FAB2_LIB.BASEBOARD_FAB2(SCH_1):ISENSE_PVDDQ_GHJ_PH2_IMON

RES_0402-100.0K,1%,1/16W,EMPTYA  I31  R9U8
   1 P3V3_STBY      A @BASEBOARD_FAB2_LIB.BASEBOARD_FAB2(SCH_1):P3V3_STBY
   2 VR_PVDDQ_GHJ_VREN      B @BASEBOARD_FAB2_LIB.BASEBOARD_FAB2(SCH_1):VR_PVDDQ_GHJ_VREN

CAP_A_0402V-0.1UF,16V,10%,X7R,A  I35  C1G25
   1 VR_PVDDQ_GHJ_VDD      A @BASEBOARD_FAB2_LIB.BASEBOARD_FAB2(SCH_1):VR_PVDDQ_GHJ_VDD
   2    GND      B @BASEBOARD_FAB2_LIB.BASEBOARD_FAB2(SCH_1):GND

CAP_0402LF-1000PF,50V,10%,X7R,A  I40  C1G21
   1 PWRGD_PVDDQ_GHJ_R      A @BASEBOARD_FAB2_LIB.BASEBOARD_FAB2(SCH_1):PWRGD_PVDDQ_GHJ_R
   2    GND      B @BASEBOARD_FAB2_LIB.BASEBOARD_FAB2(SCH_1):GND

CAP_A_0402V-0.1UF,16V,10%,X7R,A  I43  C1G22
   1 VR_PVDDQ_GHJ_VD12      A @BASEBOARD_FAB2_LIB.BASEBOARD_FAB2(SCH_1):VR_PVDDQ_GHJ_VD12
   2    GND      B @BASEBOARD_FAB2_LIB.BASEBOARD_FAB2(SCH_1):GND

RES_0402-0.0,5%,1/16W,EMPTY,G2A  I45  R12W32
   1 TP_PVDDQ_GHJ_MP1      A @BASEBOARD_FAB2_LIB.BASEBOARD_FAB2(SCH_1):TP_PVDDQ_GHJ_MP1
   2 PWRGD_PVDDQ_GHJ      B @BASEBOARD_FAB2_LIB.BASEBOARD_FAB2(SCH_1):PWRGD_PVDDQ_GHJ

RES_0402-1.00K,1%,1/16W,CHIP,GA  I48  R1G16
   1 P3V3_STBY      A @BASEBOARD_FAB2_LIB.BASEBOARD_FAB2(SCH_1):P3V3_STBY
   2 PWRGD_PVDDQ_GHJ_R      B @BASEBOARD_FAB2_LIB.BASEBOARD_FAB2(SCH_1):PWRGD_PVDDQ_GHJ_R

RES_0402-1.00K,1%,1/16W,CHIP,GA  I49  R1G11
   1 P3V3_STBY      A @BASEBOARD_FAB2_LIB.BASEBOARD_FAB2(SCH_1):P3V3_STBY
   2 IRQ_PVDDQ_GHJ_VRHOT_LVT3_R_N      B @BASEBOARD_FAB2_LIB.BASEBOARD_FAB2(SCH_1):IRQ_PVDDQ_GHJ_VRHOT_LVT3_R_N

RES_0402-22.1,1.0%,1/16W,CHIP,A  I54  R1G12
   1 PWRGD_PVDDQ_GHJ_R      A @BASEBOARD_FAB2_LIB.BASEBOARD_FAB2(SCH_1):PWRGD_PVDDQ_GHJ_R
   2 PWRGD_PVDDQ_GHJ      B @BASEBOARD_FAB2_LIB.BASEBOARD_FAB2(SCH_1):PWRGD_PVDDQ_GHJ

RES_0402-33.2,1%,1/16W,CHIP,G2A  I55  R1G8
   1 IRQ_PVDDQ_GHJ_VRHOT_LVT3_R_N      A @BASEBOARD_FAB2_LIB.BASEBOARD_FAB2(SCH_1):IRQ_PVDDQ_GHJ_VRHOT_LVT3_R_N
   2 IRQ_PVDDQ_GHJ_VRHOT_LVT3_N      B @BASEBOARD_FAB2_LIB.BASEBOARD_FAB2(SCH_1):IRQ_PVDDQ_GHJ_VRHOT_LVT3_N

RES_0402-100.0,1%,1/16W,CHIP,GA  I57  R9U3
   1 PVCCIO_CPU1      A @BASEBOARD_FAB2_LIB.BASEBOARD_FAB2(SCH_1):PVCCIO_CPU1
   2 SVID_DIO1_CPU1_R      B @BASEBOARD_FAB2_LIB.BASEBOARD_FAB2(SCH_1):SVID_DIO1_CPU1_R

PXM1310B_QFN-IC,H89186-001  I69  EU1G2
   1     NC  BPWM1     NC
   2     NC DNC<0>     NC
   3     NC  APWM3     NC
   4 VR_PVDDQ_GHJ_PWM2  APWM2 @BASEBOARD_FAB2_LIB.BASEBOARD_FAB2(SCH_1):VR_PVDDQ_GHJ_PWM2
   5 VR_PVDDQ_GHJ_PWM1  APWM1 @BASEBOARD_FAB2_LIB.BASEBOARD_FAB2(SCH_1):VR_PVDDQ_GHJ_PWM1
   6 SMB_VR_STBY_LVC3_SDA    SDA @BASEBOARD_FAB2_LIB.BASEBOARD_FAB2(SCH_1):SMB_VR_STBY_LVC3_SDA
   7 SMB_VR_STBY_LVC3_SCL    SCL @BASEBOARD_FAB2_LIB.BASEBOARD_FAB2(SCH_1):SMB_VR_STBY_LVC3_SCL
   8     NC RESET_N     NC
   9 PWRGD_PVDDQ_GHJ_R AVRRDY @BASEBOARD_FAB2_LIB.BASEBOARD_FAB2(SCH_1):PWRGD_PVDDQ_GHJ_R
  10 VR_PVDDQ_GHJ_VREN  AVREN @BASEBOARD_FAB2_LIB.BASEBOARD_FAB2(SCH_1):VR_PVDDQ_GHJ_VREN
  11 IRQ_PVDDQ_GHJ_VRHOT_LVT3_R_N VRHOT_N @BASEBOARD_FAB2_LIB.BASEBOARD_FAB2(SCH_1):IRQ_PVDDQ_GHJ_VRHOT_LVT3_R_N
  12     NC PINALRT_N     NC
  13 PU_VR_PVDDQ_GHJ_FAULT1    MP0 @BASEBOARD_FAB2_LIB.BASEBOARD_FAB2(SCH_1):PU_VR_PVDDQ_GHJ_FAULT1
  14 TP_PVDDQ_GHJ_MP1    MP1 @BASEBOARD_FAB2_LIB.BASEBOARD_FAB2(SCH_1):TP_PVDDQ_GHJ_MP1
  15 SVID_CLK_PVDDQ_GHJ   VCLK @BASEBOARD_FAB2_LIB.BASEBOARD_FAB2(SCH_1):SVID_CLK_PVDDQ_GHJ
  16 SVID_VDIO_PVDDQ_GHJ   VDIO @BASEBOARD_FAB2_LIB.BASEBOARD_FAB2(SCH_1):SVID_VDIO_PVDDQ_GHJ
  17 SVID_ALERT_PVDDQ_GHJ VALRT_N @BASEBOARD_FAB2_LIB.BASEBOARD_FAB2(SCH_1):SVID_ALERT_PVDDQ_GHJ
  18 TP_PVDDQ_GHJ_MP2    MP2 @BASEBOARD_FAB2_LIB.BASEBOARD_FAB2(SCH_1):TP_PVDDQ_GHJ_MP2
  19 VR_PVDDQ_GHJ_AVSP  AVSEN @BASEBOARD_FAB2_LIB.BASEBOARD_FAB2(SCH_1):VR_PVDDQ_GHJ_AVSP
  20 VSENSE_PVDDQ_GHJ_N  AVREF @BASEBOARD_FAB2_LIB.BASEBOARD_FAB2(SCH_1):VSENSE_PVDDQ_GHJ_N
  21 VR_PVDDQ_GHJ_AIREF1 AIREF1 @BASEBOARD_FAB2_LIB.BASEBOARD_FAB2(SCH_1):VR_PVDDQ_GHJ_AIREF1
  22 ISENSE_PVDDQ_GHJ_PH1_IMON AISEN1 @BASEBOARD_FAB2_LIB.BASEBOARD_FAB2(SCH_1):ISENSE_PVDDQ_GHJ_PH1_IMON
  23 VR_PVDDQ_GHJ_AIREF2 AIREF2 @BASEBOARD_FAB2_LIB.BASEBOARD_FAB2(SCH_1):VR_PVDDQ_GHJ_AIREF2
  24 ISENSE_PVDDQ_GHJ_PH2_IMON AISEN2 @BASEBOARD_FAB2_LIB.BASEBOARD_FAB2(SCH_1):ISENSE_PVDDQ_GHJ_PH2_IMON
  25     NC AIREF3     NC
  26     NC AISEN3     NC
  27    GND    GND @BASEBOARD_FAB2_LIB.BASEBOARD_FAB2(SCH_1):GND
  28     NC DNC<1>     NC
  29     NC  BVSEN     NC
  30     NC  BVREF     NC
  31     NC BIREF1     NC
  32    GND BISEN1 @BASEBOARD_FAB2_LIB.BASEBOARD_FAB2(SCH_1):GND
  33 VR_PVDDQ_GHJ_XADDR2 XADDR2 @BASEBOARD_FAB2_LIB.BASEBOARD_FAB2(SCH_1):VR_PVDDQ_GHJ_XADDR2
  34     NC  BTSEN     NC
  35 A_TSENSE_PVDDQ_GHJ  ATSEN @BASEBOARD_FAB2_LIB.BASEBOARD_FAB2(SCH_1):A_TSENSE_PVDDQ_GHJ
  36 VR_PVDDQ_GHJ_XADDR1 XADDR1 @BASEBOARD_FAB2_LIB.BASEBOARD_FAB2(SCH_1):VR_PVDDQ_GHJ_XADDR1
  37 VR_PVDDQ_GHJ_VINSEN VINSEN @BASEBOARD_FAB2_LIB.BASEBOARD_FAB2(SCH_1):VR_PVDDQ_GHJ_VINSEN
  38 VR_PVDDQ_GHJ_AIINSEN IINSEN @BASEBOARD_FAB2_LIB.BASEBOARD_FAB2(SCH_1):VR_PVDDQ_GHJ_AIINSEN
  39 VR_PVDDQ_GHJ_VDD    VDD @BASEBOARD_FAB2_LIB.BASEBOARD_FAB2(SCH_1):VR_PVDDQ_GHJ_VDD
  40 VR_PVDDQ_GHJ_VD12   VD12 @BASEBOARD_FAB2_LIB.BASEBOARD_FAB2(SCH_1):VR_PVDDQ_GHJ_VD12
  41    GND  THPAD @BASEBOARD_FAB2_LIB.BASEBOARD_FAB2(SCH_1):GND

RES_0402-10.0,1%,1/16W,CHIP,G2A  I13  R1G5
   1 VSENSE_PVDDQ_GHJ_P      A @BASEBOARD_FAB2_LIB.BASEBOARD_FAB2(SCH_1):VSENSE_PVDDQ_GHJ_P
   2 VR_PVDDQ_GHJ_AVSP      B @BASEBOARD_FAB2_LIB.BASEBOARD_FAB2(SCH_1):VR_PVDDQ_GHJ_AVSP

SC22P50V2JN-4GP_SMD-BCG-SC22P5A  I17  CF20
   1 VR_PVDDQ_GHJ_AIREF2      1 @BASEBOARD_FAB2_LIB.BASEBOARD_FAB2(SCH_1):VR_PVDDQ_GHJ_AIREF2
   2 ISENSE_PVDDQ_GHJ_PH2_IMON      2 @BASEBOARD_FAB2_LIB.BASEBOARD_FAB2(SCH_1):ISENSE_PVDDQ_GHJ_PH2_IMON

CAP_0402LF-220PF,50V,10%,X7R,AA  I27  C1G24
   1 A_TSENSE_PVDDQ_GHJ      A @BASEBOARD_FAB2_LIB.BASEBOARD_FAB2(SCH_1):A_TSENSE_PVDDQ_GHJ
   2    GND      B @BASEBOARD_FAB2_LIB.BASEBOARD_FAB2(SCH_1):GND

RES_0402-0.0,5%,1/16W,CHIP,G21A  I32  R9U10
   1 P3V3_STBY      A @BASEBOARD_FAB2_LIB.BASEBOARD_FAB2(SCH_1):P3V3_STBY
   2 VR_PVDDQ_GHJ_VDD      B @BASEBOARD_FAB2_LIB.BASEBOARD_FAB2(SCH_1):VR_PVDDQ_GHJ_VDD

CAP_A_0402V-1.0UF,6.3V,10%,X6SA  I36  C1G27
   1 VR_PVDDQ_GHJ_VDD      A @BASEBOARD_FAB2_LIB.BASEBOARD_FAB2(SCH_1):VR_PVDDQ_GHJ_VDD
   2    GND      B @BASEBOARD_FAB2_LIB.BASEBOARD_FAB2(SCH_1):GND

RES_0402-0.0,5%,1/16W,CHIP,G21A  I41  R1G10
   1 SVID_VDIO_PVDDQ_GHJ      A @BASEBOARD_FAB2_LIB.BASEBOARD_FAB2(SCH_1):SVID_VDIO_PVDDQ_GHJ
   2 SVID_DIO1_CPU1_R      B @BASEBOARD_FAB2_LIB.BASEBOARD_FAB2(SCH_1):SVID_DIO1_CPU1_R

RES_0402-0.0,5%,1/16W,CHIP,G21A  I50  R1G9
   1 SVID_ALERT_PVDDQ_GHJ      A @BASEBOARD_FAB2_LIB.BASEBOARD_FAB2(SCH_1):SVID_ALERT_PVDDQ_GHJ
   2 SVID_ALERT1_CPU1_R_N      B @BASEBOARD_FAB2_LIB.BASEBOARD_FAB2(SCH_1):SVID_ALERT1_CPU1_R_N

RES_0402-49.9,1%,1/16W,CHIP,G2A  I70  R9U4
   1 PVCCIO_CPU1      A @BASEBOARD_FAB2_LIB.BASEBOARD_FAB2(SCH_1):PVCCIO_CPU1
   2 SVID_CLK1_CPU1_R      B @BASEBOARD_FAB2_LIB.BASEBOARD_FAB2(SCH_1):SVID_CLK1_CPU1_R

RES_0402-5.36K,1.0%,1/16W,CHIPA  I73  R1G23
   1 VR_PVDDQ_GHJ_XADDR1      A @BASEBOARD_FAB2_LIB.BASEBOARD_FAB2(SCH_1):VR_PVDDQ_GHJ_XADDR1
   2    GND      B @BASEBOARD_FAB2_LIB.BASEBOARD_FAB2(SCH_1):GND

RES_0402-3.16K,1%,1/16W,CHIP,GA  I74  R1G22
   1 VR_PVDDQ_GHJ_XADDR2      A @BASEBOARD_FAB2_LIB.BASEBOARD_FAB2(SCH_1):VR_PVDDQ_GHJ_XADDR2
   2    GND      B @BASEBOARD_FAB2_LIB.BASEBOARD_FAB2(SCH_1):GND

RES_0402-0.0,5%,1/16W,CHIP,G21A  I75  R12W31
   1 PU_VR_PVDDQ_GHJ_FAULT1      A @BASEBOARD_FAB2_LIB.BASEBOARD_FAB2(SCH_1):PU_VR_PVDDQ_GHJ_FAULT1
   2 PWRGD_PVDDQ_GHJ      B @BASEBOARD_FAB2_LIB.BASEBOARD_FAB2(SCH_1):PWRGD_PVDDQ_GHJ

RES_0402-2.26K,1.0%,1/16W,CHIPA  I76  R1G6
   1 P3V3_STBY      A @BASEBOARD_FAB2_LIB.BASEBOARD_FAB2(SCH_1):P3V3_STBY
   2 PWRGD_PVDDQ_GHJ      B @BASEBOARD_FAB2_LIB.BASEBOARD_FAB2(SCH_1):PWRGD_PVDDQ_GHJ


DRAWING: @BASEBOARD_FAB2_LIB.BASEBOARD_FAB2(SCH_1):PAGE224 

CAP_0805LF-22UF,4V,20%,X6S,C95A  I6  C1G17
   1 PVDDQ_GHJ      A @BASEBOARD_FAB2_LIB.BASEBOARD_FAB2(SCH_1):PVDDQ_GHJ
   2    GND      B @BASEBOARD_FAB2_LIB.BASEBOARD_FAB2(SCH_1):GND

CAP_0402-0.220UF,16V,10%,X7R,AA  I44  C1G11
   1 VR_PVDDQ_GHJ_PH1_BOOT      A @BASEBOARD_FAB2_LIB.BASEBOARD_FAB2(SCH_1):VR_PVDDQ_GHJ_PH1_BOOT
   2 VR_PVDDQ_GHJ_PH1_PHASE      B @BASEBOARD_FAB2_LIB.BASEBOARD_FAB2(SCH_1):VR_PVDDQ_GHJ_PH1_PHASE

CAP_0805-10UF,16V,10%,X6S,C953A  I45  C9U6
   1 VR_FET_SW_P12V_STBY_PVDDQ_GHJ      A @BASEBOARD_FAB2_LIB.BASEBOARD_FAB2(SCH_1):VR_FET_SW_P12V_STBY_PVDDQ_GHJ
   2    GND      B @BASEBOARD_FAB2_LIB.BASEBOARD_FAB2(SCH_1):GND

CAP_0805-10UF,16V,10%,X6S,C953A  I46  C9U4
   1 VR_FET_SW_P12V_STBY_PVDDQ_GHJ      A @BASEBOARD_FAB2_LIB.BASEBOARD_FAB2(SCH_1):VR_FET_SW_P12V_STBY_PVDDQ_GHJ
   2    GND      B @BASEBOARD_FAB2_LIB.BASEBOARD_FAB2(SCH_1):GND

CAP_0805-10UF,16V,10%,X6S,C953A  I47  C9T4
   1 VR_FET_SW_P12V_STBY_PVDDQ_GHJ      A @BASEBOARD_FAB2_LIB.BASEBOARD_FAB2(SCH_1):VR_FET_SW_P12V_STBY_PVDDQ_GHJ
   2    GND      B @BASEBOARD_FAB2_LIB.BASEBOARD_FAB2(SCH_1):GND

CAP_0402-1.0UF,16V,10%,X6S,D97A  I48  C1F27
   1 VR_FET_SW_P12V_STBY_PVDDQ_GHJ      A @BASEBOARD_FAB2_LIB.BASEBOARD_FAB2(SCH_1):VR_FET_SW_P12V_STBY_PVDDQ_GHJ
   2    GND      B @BASEBOARD_FAB2_LIB.BASEBOARD_FAB2(SCH_1):GND

CAP_0402-1.0UF,16V,10%,X6S,D97A  I50  C1G6
   1 VR_PVDDQ_GHJ_PH1_VCIN      A @BASEBOARD_FAB2_LIB.BASEBOARD_FAB2(SCH_1):VR_PVDDQ_GHJ_PH1_VCIN
   2    GND      B @BASEBOARD_FAB2_LIB.BASEBOARD_FAB2(SCH_1):GND

CAP_A_0402V-0.1UF,16V,10%,X7R,A  I51  C1G14
   1 VR_FET_SW_P12V_STBY_PVDDQ_GHJ      A @BASEBOARD_FAB2_LIB.BASEBOARD_FAB2(SCH_1):VR_FET_SW_P12V_STBY_PVDDQ_GHJ
   2    GND      B @BASEBOARD_FAB2_LIB.BASEBOARD_FAB2(SCH_1):GND

CAP_0402-0.22UF,16V,10%,X7R,A3A  I54  C1G5
   1 P5V_STBY      A @BASEBOARD_FAB2_LIB.BASEBOARD_FAB2(SCH_1):P5V_STBY
   2    GND      B @BASEBOARD_FAB2_LIB.BASEBOARD_FAB2(SCH_1):GND

CAP_0805LF-22UF,4V,20%,X6S,C95A  I68  C1G20
   1 PVDDQ_GHJ      A @BASEBOARD_FAB2_LIB.BASEBOARD_FAB2(SCH_1):PVDDQ_GHJ
   2    GND      B @BASEBOARD_FAB2_LIB.BASEBOARD_FAB2(SCH_1):GND

CAP_0402-0.22UF,16V,10%,X7R,A3A  I72  C1G29
   1 P5V_STBY      A @BASEBOARD_FAB2_LIB.BASEBOARD_FAB2(SCH_1):P5V_STBY
   2    GND      B @BASEBOARD_FAB2_LIB.BASEBOARD_FAB2(SCH_1):GND

CAP_0402-0.220UF,16V,10%,X7R,AA  I75  C1F26
   1 VR_PVDDQ_GHJ_PH2_BOOT      A @BASEBOARD_FAB2_LIB.BASEBOARD_FAB2(SCH_1):VR_PVDDQ_GHJ_PH2_BOOT
   2 VR_PVDDQ_GHJ_PH2_PHASE      B @BASEBOARD_FAB2_LIB.BASEBOARD_FAB2(SCH_1):VR_PVDDQ_GHJ_PH2_PHASE

CAP_0402-1.0UF,16V,10%,X6S,D97A  I77  C1G28
   1 VR_PVDDQ_GHJ_PH2_VCIN      A @BASEBOARD_FAB2_LIB.BASEBOARD_FAB2(SCH_1):VR_PVDDQ_GHJ_PH2_VCIN
   2    GND      B @BASEBOARD_FAB2_LIB.BASEBOARD_FAB2(SCH_1):GND

CAP_A_0402V-0.1UF,16V,10%,X7R,A  I78  C1F28
   1 VR_FET_SW_P12V_STBY_PVDDQ_GHJ      A @BASEBOARD_FAB2_LIB.BASEBOARD_FAB2(SCH_1):VR_FET_SW_P12V_STBY_PVDDQ_GHJ
   2    GND      B @BASEBOARD_FAB2_LIB.BASEBOARD_FAB2(SCH_1):GND

CAP_0402-1.0UF,16V,10%,X6S,D97A  I79  C1G13
   1 VR_FET_SW_P12V_STBY_PVDDQ_GHJ      A @BASEBOARD_FAB2_LIB.BASEBOARD_FAB2(SCH_1):VR_FET_SW_P12V_STBY_PVDDQ_GHJ
   2    GND      B @BASEBOARD_FAB2_LIB.BASEBOARD_FAB2(SCH_1):GND

CAP_0805-10UF,16V,10%,X6S,C953A  I80  C9U3
   1 VR_FET_SW_P12V_STBY_PVDDQ_GHJ      A @BASEBOARD_FAB2_LIB.BASEBOARD_FAB2(SCH_1):VR_FET_SW_P12V_STBY_PVDDQ_GHJ
   2    GND      B @BASEBOARD_FAB2_LIB.BASEBOARD_FAB2(SCH_1):GND

CAP_0805-10UF,16V,10%,X6S,C953A  I81  C9T6
   1 VR_FET_SW_P12V_STBY_PVDDQ_GHJ      A @BASEBOARD_FAB2_LIB.BASEBOARD_FAB2(SCH_1):VR_FET_SW_P12V_STBY_PVDDQ_GHJ
   2    GND      B @BASEBOARD_FAB2_LIB.BASEBOARD_FAB2(SCH_1):GND

CAP_0805-10UF,16V,10%,X6S,C953A  I84  C9T9
   1 VR_FET_SW_P12V_STBY_PVDDQ_GHJ      A @BASEBOARD_FAB2_LIB.BASEBOARD_FAB2(SCH_1):VR_FET_SW_P12V_STBY_PVDDQ_GHJ
   2    GND      B @BASEBOARD_FAB2_LIB.BASEBOARD_FAB2(SCH_1):GND

IR354XX_SM-IR35411,IC,H73688-0A  I110  EU1G1
  33 VR_PVDDQ_GHJ_PH1_BOOT_R  BOOST @BASEBOARD_FAB2_LIB.BASEBOARD_FAB2(SCH_1):VR_PVDDQ_GHJ_PH1_BOOT_R
  35 P5V_STBY     EN @BASEBOARD_FAB2_LIB.BASEBOARD_FAB2(SCH_1):P5V_STBY
  41 TP_PVDDQ_GHJ_PH1_GL_1  GL<1> @BASEBOARD_FAB2_LIB.BASEBOARD_FAB2(SCH_1):TP_PVDDQ_GHJ_PH1_GL_1
   6 TP_PVDDQ_GHJ_PH1_GL_0  GL<0> @BASEBOARD_FAB2_LIB.BASEBOARD_FAB2(SCH_1):TP_PVDDQ_GHJ_PH1_GL_0
  38 ISENSE_PVDDQ_GHJ_PH1_IMON   IOUT @BASEBOARD_FAB2_LIB.BASEBOARD_FAB2(SCH_1):ISENSE_PVDDQ_GHJ_PH1_IMON
   2    GND   LGND @BASEBOARD_FAB2_LIB.BASEBOARD_FAB2(SCH_1):GND
  31     NC     NC     NC
  37 VR_PVDDQ_GHJ_PH1_OCSET  OCSET @BASEBOARD_FAB2_LIB.BASEBOARD_FAB2(SCH_1):VR_PVDDQ_GHJ_PH1_OCSET
  40    GND PGND<2> @BASEBOARD_FAB2_LIB.BASEBOARD_FAB2(SCH_1):GND
   7    GND PGND<1> @BASEBOARD_FAB2_LIB.BASEBOARD_FAB2(SCH_1):GND
   5    GND PGND<0> @BASEBOARD_FAB2_LIB.BASEBOARD_FAB2(SCH_1):GND
  32 VR_PVDDQ_GHJ_PH1_PHASE  PHASE @BASEBOARD_FAB2_LIB.BASEBOARD_FAB2(SCH_1):VR_PVDDQ_GHJ_PH1_PHASE
  34 VR_PVDDQ_GHJ_PWM1    PWM @BASEBOARD_FAB2_LIB.BASEBOARD_FAB2(SCH_1):VR_PVDDQ_GHJ_PWM1
  39 VR_PVDDQ_GHJ_AIREF1  REFIN @BASEBOARD_FAB2_LIB.BASEBOARD_FAB2(SCH_1):VR_PVDDQ_GHJ_AIREF1
  10 VR_PVDDQ_GHJ_PH1_SW     SW @BASEBOARD_FAB2_LIB.BASEBOARD_FAB2(SCH_1):VR_PVDDQ_GHJ_PH1_SW
  36 A_TSENSE_PVDDQ_GHJ TOUT_FLT @BASEBOARD_FAB2_LIB.BASEBOARD_FAB2(SCH_1):A_TSENSE_PVDDQ_GHJ
   3 VR_PVDDQ_GHJ_PH1_VCIN    VCC @BASEBOARD_FAB2_LIB.BASEBOARD_FAB2(SCH_1):VR_PVDDQ_GHJ_PH1_VCIN
   4 P5V_STBY   VDRV @BASEBOARD_FAB2_LIB.BASEBOARD_FAB2(SCH_1):P5V_STBY
  30 VR_FET_SW_P12V_STBY_PVDDQ_GHJ VIN<1> @BASEBOARD_FAB2_LIB.BASEBOARD_FAB2(SCH_1):VR_FET_SW_P12V_STBY_PVDDQ_GHJ
  25 VR_FET_SW_P12V_STBY_PVDDQ_GHJ VIN<0> @BASEBOARD_FAB2_LIB.BASEBOARD_FAB2(SCH_1):VR_FET_SW_P12V_STBY_PVDDQ_GHJ
   1 PVDDQ_GHJ    VOS @BASEBOARD_FAB2_LIB.BASEBOARD_FAB2(SCH_1):PVDDQ_GHJ

IR354XX_SM-IR35411,IC,H73688-0A  I111  EU1F1
  33 VR_PVDDQ_GHJ_PH2_BOOT_R  BOOST @BASEBOARD_FAB2_LIB.BASEBOARD_FAB2(SCH_1):VR_PVDDQ_GHJ_PH2_BOOT_R
  35 P5V_STBY     EN @BASEBOARD_FAB2_LIB.BASEBOARD_FAB2(SCH_1):P5V_STBY
  41 TP_PVDDQ_GHJ_PH2_GL_1  GL<1> @BASEBOARD_FAB2_LIB.BASEBOARD_FAB2(SCH_1):TP_PVDDQ_GHJ_PH2_GL_1
   6 TP_PVDDQ_GHJ_PH2_GL_0  GL<0> @BASEBOARD_FAB2_LIB.BASEBOARD_FAB2(SCH_1):TP_PVDDQ_GHJ_PH2_GL_0
  38 ISENSE_PVDDQ_GHJ_PH2_IMON   IOUT @BASEBOARD_FAB2_LIB.BASEBOARD_FAB2(SCH_1):ISENSE_PVDDQ_GHJ_PH2_IMON
   2    GND   LGND @BASEBOARD_FAB2_LIB.BASEBOARD_FAB2(SCH_1):GND
  31     NC     NC     NC
  37 VR_PVDDQ_GHJ_PH2_OCSET  OCSET @BASEBOARD_FAB2_LIB.BASEBOARD_FAB2(SCH_1):VR_PVDDQ_GHJ_PH2_OCSET
  40    GND PGND<2> @BASEBOARD_FAB2_LIB.BASEBOARD_FAB2(SCH_1):GND
   7    GND PGND<1> @BASEBOARD_FAB2_LIB.BASEBOARD_FAB2(SCH_1):GND
   5    GND PGND<0> @BASEBOARD_FAB2_LIB.BASEBOARD_FAB2(SCH_1):GND
  32 VR_PVDDQ_GHJ_PH2_PHASE  PHASE @BASEBOARD_FAB2_LIB.BASEBOARD_FAB2(SCH_1):VR_PVDDQ_GHJ_PH2_PHASE
  34 VR_PVDDQ_GHJ_PWM2    PWM @BASEBOARD_FAB2_LIB.BASEBOARD_FAB2(SCH_1):VR_PVDDQ_GHJ_PWM2
  39 VR_PVDDQ_GHJ_AIREF2  REFIN @BASEBOARD_FAB2_LIB.BASEBOARD_FAB2(SCH_1):VR_PVDDQ_GHJ_AIREF2
  10 VR_PVDDQ_GHJ_PH2_SW     SW @BASEBOARD_FAB2_LIB.BASEBOARD_FAB2(SCH_1):VR_PVDDQ_GHJ_PH2_SW
  36 A_TSENSE_PVDDQ_GHJ TOUT_FLT @BASEBOARD_FAB2_LIB.BASEBOARD_FAB2(SCH_1):A_TSENSE_PVDDQ_GHJ
   3 VR_PVDDQ_GHJ_PH2_VCIN    VCC @BASEBOARD_FAB2_LIB.BASEBOARD_FAB2(SCH_1):VR_PVDDQ_GHJ_PH2_VCIN
   4 P5V_STBY   VDRV @BASEBOARD_FAB2_LIB.BASEBOARD_FAB2(SCH_1):P5V_STBY
  30 VR_FET_SW_P12V_STBY_PVDDQ_GHJ VIN<1> @BASEBOARD_FAB2_LIB.BASEBOARD_FAB2(SCH_1):VR_FET_SW_P12V_STBY_PVDDQ_GHJ
  25 VR_FET_SW_P12V_STBY_PVDDQ_GHJ VIN<0> @BASEBOARD_FAB2_LIB.BASEBOARD_FAB2(SCH_1):VR_FET_SW_P12V_STBY_PVDDQ_GHJ
   1 PVDDQ_GHJ    VOS @BASEBOARD_FAB2_LIB.BASEBOARD_FAB2(SCH_1):PVDDQ_GHJ

RES_0402-68.1K,1%,1/16W,EMPTY,A  I112  R1G26
   1 VR_PVDDQ_GHJ_PH1_OCSET      A @BASEBOARD_FAB2_LIB.BASEBOARD_FAB2(SCH_1):VR_PVDDQ_GHJ_PH1_OCSET
   2    GND      B @BASEBOARD_FAB2_LIB.BASEBOARD_FAB2(SCH_1):GND

RES_0402-68.1K,1%,1/16W,EMPTY,A  I114  R1G25
   1 VR_PVDDQ_GHJ_PH2_OCSET      A @BASEBOARD_FAB2_LIB.BASEBOARD_FAB2(SCH_1):VR_PVDDQ_GHJ_PH2_OCSET
   2    GND      B @BASEBOARD_FAB2_LIB.BASEBOARD_FAB2(SCH_1):GND

CAP_A_0402V-0.1UF,16V,10%,X7R,A  I117  CT30
   1 VR_PVDDQ_GHJ_AIREF1      A @BASEBOARD_FAB2_LIB.BASEBOARD_FAB2(SCH_1):VR_PVDDQ_GHJ_AIREF1
   2    GND      B @BASEBOARD_FAB2_LIB.BASEBOARD_FAB2(SCH_1):GND

CAP_0402LF-1000PF,50V,10%,X7R,A  I122  CT28
   1 A_TSENSE_PVDDQ_GHJ      A @BASEBOARD_FAB2_LIB.BASEBOARD_FAB2(SCH_1):A_TSENSE_PVDDQ_GHJ
   2    GND      B @BASEBOARD_FAB2_LIB.BASEBOARD_FAB2(SCH_1):GND

CAP_A_0402V-0.1UF,16V,10%,X7R,A  I124  CT31
   1 VR_PVDDQ_GHJ_AIREF2      A @BASEBOARD_FAB2_LIB.BASEBOARD_FAB2(SCH_1):VR_PVDDQ_GHJ_AIREF2
   2    GND      B @BASEBOARD_FAB2_LIB.BASEBOARD_FAB2(SCH_1):GND

CAP_0402LF-1000PF,50V,10%,X7R,A  I130  CT32
   1 A_TSENSE_PVDDQ_GHJ      A @BASEBOARD_FAB2_LIB.BASEBOARD_FAB2(SCH_1):A_TSENSE_PVDDQ_GHJ
   2    GND      B @BASEBOARD_FAB2_LIB.BASEBOARD_FAB2(SCH_1):GND

CAP_0402LF-1000PF,50V,10%,X7R,A  I140  CT29
   1 VR_PVDDQ_GHJ_PH1_SW      A @BASEBOARD_FAB2_LIB.BASEBOARD_FAB2(SCH_1):VR_PVDDQ_GHJ_PH1_SW
   2 VR_PVDDQ_GHJ_PH1_SW_RC      B @BASEBOARD_FAB2_LIB.BASEBOARD_FAB2(SCH_1):VR_PVDDQ_GHJ_PH1_SW_RC

CAP_0402LF-1000PF,50V,10%,X7R,A  I141  CT33
   1 VR_PVDDQ_GHJ_PH2_SW      A @BASEBOARD_FAB2_LIB.BASEBOARD_FAB2(SCH_1):VR_PVDDQ_GHJ_PH2_SW
   2 VR_PVDDQ_GHJ_PH2_SW_RC      B @BASEBOARD_FAB2_LIB.BASEBOARD_FAB2(SCH_1):VR_PVDDQ_GHJ_PH2_SW_RC

RES_0603-0,5.0%,1/10W,CHIP,G22A  I144  RT19
   1 VR_PVDDQ_GHJ_PH1_BOOT      A @BASEBOARD_FAB2_LIB.BASEBOARD_FAB2(SCH_1):VR_PVDDQ_GHJ_PH1_BOOT
   2 VR_PVDDQ_GHJ_PH1_BOOT_R      B @BASEBOARD_FAB2_LIB.BASEBOARD_FAB2(SCH_1):VR_PVDDQ_GHJ_PH1_BOOT_R

RES_0603-0,5.0%,1/10W,CHIP,G22A  I145  RT21
   1 VR_PVDDQ_GHJ_PH2_BOOT      A @BASEBOARD_FAB2_LIB.BASEBOARD_FAB2(SCH_1):VR_PVDDQ_GHJ_PH2_BOOT
   2 VR_PVDDQ_GHJ_PH2_BOOT_R      B @BASEBOARD_FAB2_LIB.BASEBOARD_FAB2(SCH_1):VR_PVDDQ_GHJ_PH2_BOOT_R

RES_0402-0.0,5%,1/16W,CHIP,G21A  I150  R9U1
   1 VR_PVDDQ_GHJ_PH1_VCIN      A @BASEBOARD_FAB2_LIB.BASEBOARD_FAB2(SCH_1):VR_PVDDQ_GHJ_PH1_VCIN
   2 P5V_STBY      B @BASEBOARD_FAB2_LIB.BASEBOARD_FAB2(SCH_1):P5V_STBY

RES_0402-0.0,5%,1/16W,CHIP,G21A  I151  R9U12
   1 VR_PVDDQ_GHJ_PH2_VCIN      A @BASEBOARD_FAB2_LIB.BASEBOARD_FAB2(SCH_1):VR_PVDDQ_GHJ_PH2_VCIN
   2 P5V_STBY      B @BASEBOARD_FAB2_LIB.BASEBOARD_FAB2(SCH_1):P5V_STBY

SC1U10V2KX-4-GP_SMD-BCG6-SC1U1A  I154  C1F21
   1 P5V_STBY      1 @BASEBOARD_FAB2_LIB.BASEBOARD_FAB2(SCH_1):P5V_STBY
   2    GND      2 @BASEBOARD_FAB2_LIB.BASEBOARD_FAB2(SCH_1):GND

SC1U10V2KX-4-GP_SMD-BCG6-SC1U1A  I155  C1G4
   1 P5V_STBY      1 @BASEBOARD_FAB2_LIB.BASEBOARD_FAB2(SCH_1):P5V_STBY
   2    GND      2 @BASEBOARD_FAB2_LIB.BASEBOARD_FAB2(SCH_1):GND

1R3F-GP_RCL_GP-1R3F-GP,64.1R00A  I156  RT20
   1 VR_PVDDQ_GHJ_PH1_SW_RC      1 @BASEBOARD_FAB2_LIB.BASEBOARD_FAB2(SCH_1):VR_PVDDQ_GHJ_PH1_SW_RC
   2    GND      2 @BASEBOARD_FAB2_LIB.BASEBOARD_FAB2(SCH_1):GND

1R3F-GP_RCL_GP-1R3F-GP,64.1R00A  I157  RT22
   1 VR_PVDDQ_GHJ_PH2_SW_RC      1 @BASEBOARD_FAB2_LIB.BASEBOARD_FAB2(SCH_1):VR_PVDDQ_GHJ_PH2_SW_RC
   2    GND      2 @BASEBOARD_FAB2_LIB.BASEBOARD_FAB2(SCH_1):GND

IND-120NH-30-GP_DISCRET-GB2-INA  I160  L1G1
   1 VR_PVDDQ_GHJ_PH1_SW      S @BASEBOARD_FAB2_LIB.BASEBOARD_FAB2(SCH_1):VR_PVDDQ_GHJ_PH1_SW
   2 PVDDQ_GHJ      F @BASEBOARD_FAB2_LIB.BASEBOARD_FAB2(SCH_1):PVDDQ_GHJ

IND-120NH-30-GP_DISCRET-GB2-INA  I161  L1F2
   1 VR_PVDDQ_GHJ_PH2_SW      S @BASEBOARD_FAB2_LIB.BASEBOARD_FAB2(SCH_1):VR_PVDDQ_GHJ_PH2_SW
   2 PVDDQ_GHJ      F @BASEBOARD_FAB2_LIB.BASEBOARD_FAB2(SCH_1):PVDDQ_GHJ


DRAWING: @BASEBOARD_FAB2_LIB.BASEBOARD_FAB2(SCH_1):PAGE225 

RES_0603-120.0,1%,1/10W,CHIP,GA  I58  R1G20
   1 PVDDQ_GHJ      A @BASEBOARD_FAB2_LIB.BASEBOARD_FAB2(SCH_1):PVDDQ_GHJ
   2    GND      B @BASEBOARD_FAB2_LIB.BASEBOARD_FAB2(SCH_1):GND

RES_0402-100.0,1%,1/16W,EMPTY,A  I74  R7U2
   1 VSENSE_PVDDQ_GHJ_P      A @BASEBOARD_FAB2_LIB.BASEBOARD_FAB2(SCH_1):VSENSE_PVDDQ_GHJ_P
   2 VSENSE_PVDDQ_GHJ_N      B @BASEBOARD_FAB2_LIB.BASEBOARD_FAB2(SCH_1):VSENSE_PVDDQ_GHJ_N

CAPP_3018-470UF,2.5V,20%,ALUM,A  I75  C9T5
   1 PVDDQ_GHJ      A @BASEBOARD_FAB2_LIB.BASEBOARD_FAB2(SCH_1):PVDDQ_GHJ
   2    GND      B @BASEBOARD_FAB2_LIB.BASEBOARD_FAB2(SCH_1):GND

CAPP_3018-470UF,2.5V,20%,ALUM,A  I76  C9U2
   1 PVDDQ_GHJ      A @BASEBOARD_FAB2_LIB.BASEBOARD_FAB2(SCH_1):PVDDQ_GHJ
   2    GND      B @BASEBOARD_FAB2_LIB.BASEBOARD_FAB2(SCH_1):GND

CAPP_3018-470UF,2.5V,20%,ALUM,A  I77  C9U9
   1 PVDDQ_GHJ      A @BASEBOARD_FAB2_LIB.BASEBOARD_FAB2(SCH_1):PVDDQ_GHJ
   2    GND      B @BASEBOARD_FAB2_LIB.BASEBOARD_FAB2(SCH_1):GND

CAPP_3018-470UF,2.5V,20%,ALUM,A  I78  C9U5
   1 PVDDQ_GHJ      A @BASEBOARD_FAB2_LIB.BASEBOARD_FAB2(SCH_1):PVDDQ_GHJ
   2    GND      B @BASEBOARD_FAB2_LIB.BASEBOARD_FAB2(SCH_1):GND

CAP_A_0603V-47UF,4V,20%,X5R,60A  I196  C8T4
   1 PVDDQ_GHJ      A @BASEBOARD_FAB2_LIB.BASEBOARD_FAB2(SCH_1):PVDDQ_GHJ
   2    GND      B @BASEBOARD_FAB2_LIB.BASEBOARD_FAB2(SCH_1):GND

CAP_A_0603V-47UF,4V,20%,X5R,60A  I197  C2G8
   1 PVDDQ_GHJ      A @BASEBOARD_FAB2_LIB.BASEBOARD_FAB2(SCH_1):PVDDQ_GHJ
   2    GND      B @BASEBOARD_FAB2_LIB.BASEBOARD_FAB2(SCH_1):GND

CAP_A_0603V-47UF,4V,20%,X5R,60A  I198  C8T2
   1 PVDDQ_GHJ      A @BASEBOARD_FAB2_LIB.BASEBOARD_FAB2(SCH_1):PVDDQ_GHJ
   2    GND      B @BASEBOARD_FAB2_LIB.BASEBOARD_FAB2(SCH_1):GND

CAP_A_0603V-47UF,4V,20%,X5R,60A  I199  C8U13
   1 PVDDQ_GHJ      A @BASEBOARD_FAB2_LIB.BASEBOARD_FAB2(SCH_1):PVDDQ_GHJ
   2    GND      B @BASEBOARD_FAB2_LIB.BASEBOARD_FAB2(SCH_1):GND

CAP_A_0603V-47UF,4V,20%,X5R,60A  I200  C2G15
   1 PVDDQ_GHJ      A @BASEBOARD_FAB2_LIB.BASEBOARD_FAB2(SCH_1):PVDDQ_GHJ
   2    GND      B @BASEBOARD_FAB2_LIB.BASEBOARD_FAB2(SCH_1):GND

CAP_A_0603V-47UF,4V,20%,X5R,60A  I201  C2F1
   1 PVDDQ_GHJ      A @BASEBOARD_FAB2_LIB.BASEBOARD_FAB2(SCH_1):PVDDQ_GHJ
   2    GND      B @BASEBOARD_FAB2_LIB.BASEBOARD_FAB2(SCH_1):GND

CAP_A_0603V-47UF,4V,20%,X5R,60A  I202  C8T1
   1 PVDDQ_GHJ      A @BASEBOARD_FAB2_LIB.BASEBOARD_FAB2(SCH_1):PVDDQ_GHJ
   2    GND      B @BASEBOARD_FAB2_LIB.BASEBOARD_FAB2(SCH_1):GND

CAP_A_0603V-47UF,4V,20%,X5R,60A  I203  C8U9
   1 PVDDQ_GHJ      A @BASEBOARD_FAB2_LIB.BASEBOARD_FAB2(SCH_1):PVDDQ_GHJ
   2    GND      B @BASEBOARD_FAB2_LIB.BASEBOARD_FAB2(SCH_1):GND

CAP_A_0603V-47UF,4V,20%,X5R,60A  I204  C8T11
   1 PVDDQ_GHJ      A @BASEBOARD_FAB2_LIB.BASEBOARD_FAB2(SCH_1):PVDDQ_GHJ
   2    GND      B @BASEBOARD_FAB2_LIB.BASEBOARD_FAB2(SCH_1):GND

SHUNT_SH0201-EMPTY,N_A  I243  SH7U1
   1 VSENSE_PVDDQ_GHJ_P      A @BASEBOARD_FAB2_LIB.BASEBOARD_FAB2(SCH_1):VSENSE_PVDDQ_GHJ_P
   2 PVDDQ_GHJ      B @BASEBOARD_FAB2_LIB.BASEBOARD_FAB2(SCH_1):PVDDQ_GHJ

SHUNT_SH0201-EMPTY,N_A  I244  SH7U2
   1 VSENSE_PVDDQ_GHJ_N      A @BASEBOARD_FAB2_LIB.BASEBOARD_FAB2(SCH_1):VSENSE_PVDDQ_GHJ_N
   2    GND      B @BASEBOARD_FAB2_LIB.BASEBOARD_FAB2(SCH_1):GND

SC22U16V5MX-4-GP_SMD-BCG5-SC22A  I246  C22W1
   1 VR_FET_SW_P12V_STBY_PVDDQ_GHJ      1 @BASEBOARD_FAB2_LIB.BASEBOARD_FAB2(SCH_1):VR_FET_SW_P12V_STBY_PVDDQ_GHJ
   2    GND      2 @BASEBOARD_FAB2_LIB.BASEBOARD_FAB2(SCH_1):GND

SC22U16V5MX-4-GP_SMD-BCG5-SC22A  I247  C22W2
   1 VR_FET_SW_P12V_STBY_PVDDQ_GHJ      1 @BASEBOARD_FAB2_LIB.BASEBOARD_FAB2(SCH_1):VR_FET_SW_P12V_STBY_PVDDQ_GHJ
   2    GND      2 @BASEBOARD_FAB2_LIB.BASEBOARD_FAB2(SCH_1):GND

SC22U16V5MX-4-GP_SMD-BCG5-SC22A  I249  C22W3
   1 VR_FET_SW_P12V_STBY_PVDDQ_GHJ      1 @BASEBOARD_FAB2_LIB.BASEBOARD_FAB2(SCH_1):VR_FET_SW_P12V_STBY_PVDDQ_GHJ
   2    GND      2 @BASEBOARD_FAB2_LIB.BASEBOARD_FAB2(SCH_1):GND

SC22U16V5MX-4-GP_SMD-BCG5-SC22A  I250  C1G2
   1 VR_FET_SW_P12V_STBY_PVDDQ_GHJ      1 @BASEBOARD_FAB2_LIB.BASEBOARD_FAB2(SCH_1):VR_FET_SW_P12V_STBY_PVDDQ_GHJ
   2    GND      2 @BASEBOARD_FAB2_LIB.BASEBOARD_FAB2(SCH_1):GND

SC22U16V5MX-4-GP_SMD-BCG5-SC22A  I251  C22W4
   1 VR_FET_SW_P12V_STBY_PVDDQ_GHJ      1 @BASEBOARD_FAB2_LIB.BASEBOARD_FAB2(SCH_1):VR_FET_SW_P12V_STBY_PVDDQ_GHJ
   2    GND      2 @BASEBOARD_FAB2_LIB.BASEBOARD_FAB2(SCH_1):GND

IND-100NH-35-GP_DISCRET-G8-INDA  I253  L1F1
   1 P12V_STBY      S @BASEBOARD_FAB2_LIB.BASEBOARD_FAB2(SCH_1):P12V_STBY
   2 VR_FET_SW_P12V_STBY_PVDDQ_GHJ      F @BASEBOARD_FAB2_LIB.BASEBOARD_FAB2(SCH_1):VR_FET_SW_P12V_STBY_PVDDQ_GHJ

CAP_A_0603V-22.0UF,4V,20%,X6S,A  I261  C2D45
   1 PVDDQ_GHJ      A @BASEBOARD_FAB2_LIB.BASEBOARD_FAB2(SCH_1):PVDDQ_GHJ
   2    GND      B @BASEBOARD_FAB2_LIB.BASEBOARD_FAB2(SCH_1):GND

CAP_A_0603V-22.0UF,4V,20%,X6S,A  I262  C3D25
   1 PVDDQ_GHJ      A @BASEBOARD_FAB2_LIB.BASEBOARD_FAB2(SCH_1):PVDDQ_GHJ
   2    GND      B @BASEBOARD_FAB2_LIB.BASEBOARD_FAB2(SCH_1):GND

CAP_A_0603V-22.0UF,4V,20%,X6S,A  I263  C2D47
   1 PVDDQ_GHJ      A @BASEBOARD_FAB2_LIB.BASEBOARD_FAB2(SCH_1):PVDDQ_GHJ
   2    GND      B @BASEBOARD_FAB2_LIB.BASEBOARD_FAB2(SCH_1):GND

CAP_A_0603V-22.0UF,4V,20%,X6S,A  I264  C2D46
   1 PVDDQ_GHJ      A @BASEBOARD_FAB2_LIB.BASEBOARD_FAB2(SCH_1):PVDDQ_GHJ
   2    GND      B @BASEBOARD_FAB2_LIB.BASEBOARD_FAB2(SCH_1):GND

CAP_A_0603V-22.0UF,4V,20%,X6S,A  I270  C2D43
   1 PVDDQ_GHJ      A @BASEBOARD_FAB2_LIB.BASEBOARD_FAB2(SCH_1):PVDDQ_GHJ
   2    GND      B @BASEBOARD_FAB2_LIB.BASEBOARD_FAB2(SCH_1):GND

CAP_A_0603V-22.0UF,4V,20%,X6S,A  I271  C2D41
   1 PVDDQ_GHJ      A @BASEBOARD_FAB2_LIB.BASEBOARD_FAB2(SCH_1):PVDDQ_GHJ
   2    GND      B @BASEBOARD_FAB2_LIB.BASEBOARD_FAB2(SCH_1):GND

CAP_A_0603V-22.0UF,4V,20%,X6S,A  I272  C2D44
   1 PVDDQ_GHJ      A @BASEBOARD_FAB2_LIB.BASEBOARD_FAB2(SCH_1):PVDDQ_GHJ
   2    GND      B @BASEBOARD_FAB2_LIB.BASEBOARD_FAB2(SCH_1):GND

CAP_A_0603V-22.0UF,4V,20%,X6S,A  I273  C2D42
   1 PVDDQ_GHJ      A @BASEBOARD_FAB2_LIB.BASEBOARD_FAB2(SCH_1):PVDDQ_GHJ
   2    GND      B @BASEBOARD_FAB2_LIB.BASEBOARD_FAB2(SCH_1):GND

CAP_A_0603V-47UF,4V,20%,X5R,60A  I274  C2G10
   1 PVDDQ_GHJ      A @BASEBOARD_FAB2_LIB.BASEBOARD_FAB2(SCH_1):PVDDQ_GHJ
   2    GND      B @BASEBOARD_FAB2_LIB.BASEBOARD_FAB2(SCH_1):GND

CAP_A_0603V-47UF,4V,20%,X5R,60A  I275  C2G11
   1 PVDDQ_GHJ      A @BASEBOARD_FAB2_LIB.BASEBOARD_FAB2(SCH_1):PVDDQ_GHJ
   2    GND      B @BASEBOARD_FAB2_LIB.BASEBOARD_FAB2(SCH_1):GND

CAP_A_0603V-47UF,4V,20%,X5R,60A  I276  C2G12
   1 PVDDQ_GHJ      A @BASEBOARD_FAB2_LIB.BASEBOARD_FAB2(SCH_1):PVDDQ_GHJ
   2    GND      B @BASEBOARD_FAB2_LIB.BASEBOARD_FAB2(SCH_1):GND

CAP_A_0603V-47UF,4V,20%,X5R,60A  I277  C2G1
   1 PVDDQ_GHJ      A @BASEBOARD_FAB2_LIB.BASEBOARD_FAB2(SCH_1):PVDDQ_GHJ
   2    GND      B @BASEBOARD_FAB2_LIB.BASEBOARD_FAB2(SCH_1):GND

CAP_A_0603V-47UF,4V,20%,X5R,60A  I278  C2G9
   1 PVDDQ_GHJ      A @BASEBOARD_FAB2_LIB.BASEBOARD_FAB2(SCH_1):PVDDQ_GHJ
   2    GND      B @BASEBOARD_FAB2_LIB.BASEBOARD_FAB2(SCH_1):GND

CAP_A_0603V-47UF,4V,20%,X5R,60A  I279  C2G2
   1 PVDDQ_GHJ      A @BASEBOARD_FAB2_LIB.BASEBOARD_FAB2(SCH_1):PVDDQ_GHJ
   2    GND      B @BASEBOARD_FAB2_LIB.BASEBOARD_FAB2(SCH_1):GND

CAP_A_0603V-47UF,4V,20%,X5R,60A  I280  C2G3
   1 PVDDQ_GHJ      A @BASEBOARD_FAB2_LIB.BASEBOARD_FAB2(SCH_1):PVDDQ_GHJ
   2    GND      B @BASEBOARD_FAB2_LIB.BASEBOARD_FAB2(SCH_1):GND

CAP_A_0603V-47UF,4V,20%,X5R,60A  I281  C2G4
   1 PVDDQ_GHJ      A @BASEBOARD_FAB2_LIB.BASEBOARD_FAB2(SCH_1):PVDDQ_GHJ
   2    GND      B @BASEBOARD_FAB2_LIB.BASEBOARD_FAB2(SCH_1):GND

CAP_A_0603V-47UF,4V,20%,X5R,60A  I282  C2G5
   1 PVDDQ_GHJ      A @BASEBOARD_FAB2_LIB.BASEBOARD_FAB2(SCH_1):PVDDQ_GHJ
   2    GND      B @BASEBOARD_FAB2_LIB.BASEBOARD_FAB2(SCH_1):GND

CAP_A_0603V-47UF,4V,20%,X5R,60A  I283  C2G6
   1 PVDDQ_GHJ      A @BASEBOARD_FAB2_LIB.BASEBOARD_FAB2(SCH_1):PVDDQ_GHJ
   2    GND      B @BASEBOARD_FAB2_LIB.BASEBOARD_FAB2(SCH_1):GND

CAP_A_0603V-47UF,4V,20%,X5R,60A  I284  C3G1
   1 PVDDQ_GHJ      A @BASEBOARD_FAB2_LIB.BASEBOARD_FAB2(SCH_1):PVDDQ_GHJ
   2    GND      B @BASEBOARD_FAB2_LIB.BASEBOARD_FAB2(SCH_1):GND

CAP_A_0603V-47UF,4V,20%,X5R,60A  I285  C3G2
   1 PVDDQ_GHJ      A @BASEBOARD_FAB2_LIB.BASEBOARD_FAB2(SCH_1):PVDDQ_GHJ
   2    GND      B @BASEBOARD_FAB2_LIB.BASEBOARD_FAB2(SCH_1):GND

CAP_A_0603V-47UF,4V,20%,X5R,60A  I286  C2G13
   1 PVDDQ_GHJ      A @BASEBOARD_FAB2_LIB.BASEBOARD_FAB2(SCH_1):PVDDQ_GHJ
   2    GND      B @BASEBOARD_FAB2_LIB.BASEBOARD_FAB2(SCH_1):GND

CAP_A_0603V-47UF,4V,20%,X5R,60A  I287  C2G14
   1 PVDDQ_GHJ      A @BASEBOARD_FAB2_LIB.BASEBOARD_FAB2(SCH_1):PVDDQ_GHJ
   2    GND      B @BASEBOARD_FAB2_LIB.BASEBOARD_FAB2(SCH_1):GND

CAP_A_0603V-47UF,4V,20%,X5R,60A  I288  C3G5
   1 PVDDQ_GHJ      A @BASEBOARD_FAB2_LIB.BASEBOARD_FAB2(SCH_1):PVDDQ_GHJ
   2    GND      B @BASEBOARD_FAB2_LIB.BASEBOARD_FAB2(SCH_1):GND

CAP_A_0603V-47UF,4V,20%,X5R,60A  I289  C3G6
   1 PVDDQ_GHJ      A @BASEBOARD_FAB2_LIB.BASEBOARD_FAB2(SCH_1):PVDDQ_GHJ
   2    GND      B @BASEBOARD_FAB2_LIB.BASEBOARD_FAB2(SCH_1):GND

CAP_A_0603V-47UF,4V,20%,X5R,60A  I290  C8U7
   1 PVDDQ_GHJ      A @BASEBOARD_FAB2_LIB.BASEBOARD_FAB2(SCH_1):PVDDQ_GHJ
   2    GND      B @BASEBOARD_FAB2_LIB.BASEBOARD_FAB2(SCH_1):GND

CAP_A_0603V-47UF,4V,20%,X5R,60A  I291  C8U2
   1 PVDDQ_GHJ      A @BASEBOARD_FAB2_LIB.BASEBOARD_FAB2(SCH_1):PVDDQ_GHJ
   2    GND      B @BASEBOARD_FAB2_LIB.BASEBOARD_FAB2(SCH_1):GND

CAP_A_0603V-47UF,4V,20%,X5R,60A  I292  C7U2
   1 PVDDQ_GHJ      A @BASEBOARD_FAB2_LIB.BASEBOARD_FAB2(SCH_1):PVDDQ_GHJ
   2    GND      B @BASEBOARD_FAB2_LIB.BASEBOARD_FAB2(SCH_1):GND

CAP_A_0603V-47UF,4V,20%,X5R,60A  I293  C7U1
   1 PVDDQ_GHJ      A @BASEBOARD_FAB2_LIB.BASEBOARD_FAB2(SCH_1):PVDDQ_GHJ
   2    GND      B @BASEBOARD_FAB2_LIB.BASEBOARD_FAB2(SCH_1):GND

CAP_A_0603V-47UF,4V,20%,X5R,60A  I294  C8U3
   1 PVDDQ_GHJ      A @BASEBOARD_FAB2_LIB.BASEBOARD_FAB2(SCH_1):PVDDQ_GHJ
   2    GND      B @BASEBOARD_FAB2_LIB.BASEBOARD_FAB2(SCH_1):GND

CAP_A_0603V-47UF,4V,20%,X5R,60A  I295  C7T4
   1 PVDDQ_GHJ      A @BASEBOARD_FAB2_LIB.BASEBOARD_FAB2(SCH_1):PVDDQ_GHJ
   2    GND      B @BASEBOARD_FAB2_LIB.BASEBOARD_FAB2(SCH_1):GND

CAP_A_0603V-47UF,4V,20%,X5R,60A  I296  C7T5
   1 PVDDQ_GHJ      A @BASEBOARD_FAB2_LIB.BASEBOARD_FAB2(SCH_1):PVDDQ_GHJ
   2    GND      B @BASEBOARD_FAB2_LIB.BASEBOARD_FAB2(SCH_1):GND

CAP_A_0603V-47UF,4V,20%,X5R,60A  I297  C8T5
   1 PVDDQ_GHJ      A @BASEBOARD_FAB2_LIB.BASEBOARD_FAB2(SCH_1):PVDDQ_GHJ
   2    GND      B @BASEBOARD_FAB2_LIB.BASEBOARD_FAB2(SCH_1):GND

CAP_A_0603V-47UF,4V,20%,X5R,60A  I298  C8U6
   1 PVDDQ_GHJ      A @BASEBOARD_FAB2_LIB.BASEBOARD_FAB2(SCH_1):PVDDQ_GHJ
   2    GND      B @BASEBOARD_FAB2_LIB.BASEBOARD_FAB2(SCH_1):GND

CAP_A_0603V-47UF,4V,20%,X5R,60A  I299  C8T6
   1 PVDDQ_GHJ      A @BASEBOARD_FAB2_LIB.BASEBOARD_FAB2(SCH_1):PVDDQ_GHJ
   2    GND      B @BASEBOARD_FAB2_LIB.BASEBOARD_FAB2(SCH_1):GND

CAP_A_0603V-47UF,4V,20%,X5R,60A  I300  C8T7
   1 PVDDQ_GHJ      A @BASEBOARD_FAB2_LIB.BASEBOARD_FAB2(SCH_1):PVDDQ_GHJ
   2    GND      B @BASEBOARD_FAB2_LIB.BASEBOARD_FAB2(SCH_1):GND

CAP_A_0603V-47UF,4V,20%,X5R,60A  I301  C8T8
   1 PVDDQ_GHJ      A @BASEBOARD_FAB2_LIB.BASEBOARD_FAB2(SCH_1):PVDDQ_GHJ
   2    GND      B @BASEBOARD_FAB2_LIB.BASEBOARD_FAB2(SCH_1):GND

CAP_A_0603V-47UF,4V,20%,X5R,60A  I302  C8U5
   1 PVDDQ_GHJ      A @BASEBOARD_FAB2_LIB.BASEBOARD_FAB2(SCH_1):PVDDQ_GHJ
   2    GND      B @BASEBOARD_FAB2_LIB.BASEBOARD_FAB2(SCH_1):GND

CAP_A_0603V-47UF,4V,20%,X5R,60A  I303  C8T9
   1 PVDDQ_GHJ      A @BASEBOARD_FAB2_LIB.BASEBOARD_FAB2(SCH_1):PVDDQ_GHJ
   2    GND      B @BASEBOARD_FAB2_LIB.BASEBOARD_FAB2(SCH_1):GND

CAP_A_0603V-47UF,4V,20%,X5R,60A  I304  C8T10
   1 PVDDQ_GHJ      A @BASEBOARD_FAB2_LIB.BASEBOARD_FAB2(SCH_1):PVDDQ_GHJ
   2    GND      B @BASEBOARD_FAB2_LIB.BASEBOARD_FAB2(SCH_1):GND

CAP_A_0603V-47UF,4V,20%,X5R,60A  I305  C8U4
   1 PVDDQ_GHJ      A @BASEBOARD_FAB2_LIB.BASEBOARD_FAB2(SCH_1):PVDDQ_GHJ
   2    GND      B @BASEBOARD_FAB2_LIB.BASEBOARD_FAB2(SCH_1):GND

CAP_0805-100UF,4V,20%,X5R,6024A  I307  C8U11
   1 PVDDQ_GHJ      A @BASEBOARD_FAB2_LIB.BASEBOARD_FAB2(SCH_1):PVDDQ_GHJ
   2    GND      B @BASEBOARD_FAB2_LIB.BASEBOARD_FAB2(SCH_1):GND

CAP_0805-100UF,4V,20%,X5R,6024A  I308  C7U7
   1 PVDDQ_GHJ      A @BASEBOARD_FAB2_LIB.BASEBOARD_FAB2(SCH_1):PVDDQ_GHJ
   2    GND      B @BASEBOARD_FAB2_LIB.BASEBOARD_FAB2(SCH_1):GND

CAP_0805-100UF,4V,20%,X5R,6024A  I309  C7T1
   1 PVDDQ_GHJ      A @BASEBOARD_FAB2_LIB.BASEBOARD_FAB2(SCH_1):PVDDQ_GHJ
   2    GND      B @BASEBOARD_FAB2_LIB.BASEBOARD_FAB2(SCH_1):GND

CAP_0805-100UF,4V,20%,X5R,6024A  I310  C8U12
   1 PVDDQ_GHJ      A @BASEBOARD_FAB2_LIB.BASEBOARD_FAB2(SCH_1):PVDDQ_GHJ
   2    GND      B @BASEBOARD_FAB2_LIB.BASEBOARD_FAB2(SCH_1):GND

CAP_0805-100UF,4V,20%,X5R,6024A  I311  C2G16
   1 PVDDQ_GHJ      A @BASEBOARD_FAB2_LIB.BASEBOARD_FAB2(SCH_1):PVDDQ_GHJ
   2    GND      B @BASEBOARD_FAB2_LIB.BASEBOARD_FAB2(SCH_1):GND

CAP_0805-100UF,4V,20%,X5R,6024A  I312  C2G7
   1 PVDDQ_GHJ      A @BASEBOARD_FAB2_LIB.BASEBOARD_FAB2(SCH_1):PVDDQ_GHJ
   2    GND      B @BASEBOARD_FAB2_LIB.BASEBOARD_FAB2(SCH_1):GND

CAP_0805-100UF,4V,20%,X5R,6024A  I313  C8P30
   1 PVDDQ_GHJ      A @BASEBOARD_FAB2_LIB.BASEBOARD_FAB2(SCH_1):PVDDQ_GHJ
   2    GND      B @BASEBOARD_FAB2_LIB.BASEBOARD_FAB2(SCH_1):GND

CAP_0805-100UF,4V,20%,X5R,6024A  I314  C8P31
   1 PVDDQ_GHJ      A @BASEBOARD_FAB2_LIB.BASEBOARD_FAB2(SCH_1):PVDDQ_GHJ
   2    GND      B @BASEBOARD_FAB2_LIB.BASEBOARD_FAB2(SCH_1):GND

CAP_0805-100UF,4V,20%,X5R,6024A  I315  C8P34
   1 PVDDQ_GHJ      A @BASEBOARD_FAB2_LIB.BASEBOARD_FAB2(SCH_1):PVDDQ_GHJ
   2    GND      B @BASEBOARD_FAB2_LIB.BASEBOARD_FAB2(SCH_1):GND

CAP_0805-100UF,4V,20%,X5R,6024A  I316  C8P33
   1 PVDDQ_GHJ      A @BASEBOARD_FAB2_LIB.BASEBOARD_FAB2(SCH_1):PVDDQ_GHJ
   2    GND      B @BASEBOARD_FAB2_LIB.BASEBOARD_FAB2(SCH_1):GND

CAP_0805-100UF,4V,20%,X5R,6024A  I317  C8P32
   1 PVDDQ_GHJ      A @BASEBOARD_FAB2_LIB.BASEBOARD_FAB2(SCH_1):PVDDQ_GHJ
   2    GND      B @BASEBOARD_FAB2_LIB.BASEBOARD_FAB2(SCH_1):GND

CAP_0805-100UF,4V,20%,X5R,6024A  I318  C7P20
   1 PVDDQ_GHJ      A @BASEBOARD_FAB2_LIB.BASEBOARD_FAB2(SCH_1):PVDDQ_GHJ
   2    GND      B @BASEBOARD_FAB2_LIB.BASEBOARD_FAB2(SCH_1):GND

CAP_0805-100UF,4V,20%,X5R,6024A  I319  C8U1
   1 PVDDQ_GHJ      A @BASEBOARD_FAB2_LIB.BASEBOARD_FAB2(SCH_1):PVDDQ_GHJ
   2    GND      B @BASEBOARD_FAB2_LIB.BASEBOARD_FAB2(SCH_1):GND

CAP_0805-100UF,4V,20%,X5R,6024A  I320  C8U8
   1 PVDDQ_GHJ      A @BASEBOARD_FAB2_LIB.BASEBOARD_FAB2(SCH_1):PVDDQ_GHJ
   2    GND      B @BASEBOARD_FAB2_LIB.BASEBOARD_FAB2(SCH_1):GND

ST270U2D5VBM-GP_SMD-TCG2-ST270A  I327  C1G15
   1 VR_FET_SW_P12V_STBY_PVDDQ_GHJ      1 @BASEBOARD_FAB2_LIB.BASEBOARD_FAB2(SCH_1):VR_FET_SW_P12V_STBY_PVDDQ_GHJ
   2    GND      2 @BASEBOARD_FAB2_LIB.BASEBOARD_FAB2(SCH_1):GND

ST270U2D5VBM-GP_SMD-TCG2-ST270A  I328  C1G12
   1 VR_FET_SW_P12V_STBY_PVDDQ_GHJ      1 @BASEBOARD_FAB2_LIB.BASEBOARD_FAB2(SCH_1):VR_FET_SW_P12V_STBY_PVDDQ_GHJ
   2    GND      2 @BASEBOARD_FAB2_LIB.BASEBOARD_FAB2(SCH_1):GND

ST270U2D5VBM-GP_SMD-TCG2-ST270A  I329  C1G7
   1 VR_FET_SW_P12V_STBY_PVDDQ_GHJ      1 @BASEBOARD_FAB2_LIB.BASEBOARD_FAB2(SCH_1):VR_FET_SW_P12V_STBY_PVDDQ_GHJ
   2    GND      2 @BASEBOARD_FAB2_LIB.BASEBOARD_FAB2(SCH_1):GND


DRAWING: @BASEBOARD_FAB2_LIB.BASEBOARD_FAB2(SCH_1):PAGE226 

RES_0402-0.0,5%,1/16W,CHIP,G21A  I14  R9M9
   1 FM_PVDDQ_KLM_EN      A @BASEBOARD_FAB2_LIB.BASEBOARD_FAB2(SCH_1):FM_PVDDQ_KLM_EN
   2 VR_PVDDQ_KLM_VREN      B @BASEBOARD_FAB2_LIB.BASEBOARD_FAB2(SCH_1):VR_PVDDQ_KLM_VREN

RES_0402-1.0K,0.1%,1/16W,CHIP,A  I16  RF21
   1 VR_PVDDQ_KLM_AIREF1      A @BASEBOARD_FAB2_LIB.BASEBOARD_FAB2(SCH_1):VR_PVDDQ_KLM_AIREF1
   2 ISENSE_PVDDQ_KLM_PH1_IMON      B @BASEBOARD_FAB2_LIB.BASEBOARD_FAB2(SCH_1):ISENSE_PVDDQ_KLM_PH1_IMON

CAP_A_0402V-0.1UF,16V,10%,X7R,A  I44  C1B2
   1 VR_PVDDQ_KLM_VD12      A @BASEBOARD_FAB2_LIB.BASEBOARD_FAB2(SCH_1):VR_PVDDQ_KLM_VD12
   2    GND      B @BASEBOARD_FAB2_LIB.BASEBOARD_FAB2(SCH_1):GND

RES_0402-1.00K,1%,1/16W,CHIP,GA  I50  R1B2
   1 P3V3_STBY      A @BASEBOARD_FAB2_LIB.BASEBOARD_FAB2(SCH_1):P3V3_STBY
   2 PWRGD_PVDDQ_KLM_R      B @BASEBOARD_FAB2_LIB.BASEBOARD_FAB2(SCH_1):PWRGD_PVDDQ_KLM_R

RES_0402-0.0,5%,1/16W,EMPTY,G2A  I53  R12W36
   1 NC_PVDDQ_KLM_GP0      A @BASEBOARD_FAB2_LIB.BASEBOARD_FAB2(SCH_1):NC_PVDDQ_KLM_GP0
   2 PWRGD_PVDDQ_KLM      B @BASEBOARD_FAB2_LIB.BASEBOARD_FAB2(SCH_1):PWRGD_PVDDQ_KLM

CAP_0402LF-220PF,50V,10%,X7R,AA  I12  C1B12
   1 VR_PVDDQ_KLM_AVSP      A @BASEBOARD_FAB2_LIB.BASEBOARD_FAB2(SCH_1):VR_PVDDQ_KLM_AVSP
   2 VSENSE_PVDDQ_KLM_N      B @BASEBOARD_FAB2_LIB.BASEBOARD_FAB2(SCH_1):VSENSE_PVDDQ_KLM_N

SC22P50V2JN-4GP_SMD-BCG-SC22P5A  I15  CF21
   1 VR_PVDDQ_KLM_AIREF1      1 @BASEBOARD_FAB2_LIB.BASEBOARD_FAB2(SCH_1):VR_PVDDQ_KLM_AIREF1
   2 ISENSE_PVDDQ_KLM_PH1_IMON      2 @BASEBOARD_FAB2_LIB.BASEBOARD_FAB2(SCH_1):ISENSE_PVDDQ_KLM_PH1_IMON

RES_0402-1.0K,0.1%,1/16W,CHIP,A  I18  RF22
   1 VR_PVDDQ_KLM_AIREF2      A @BASEBOARD_FAB2_LIB.BASEBOARD_FAB2(SCH_1):VR_PVDDQ_KLM_AIREF2
   2 ISENSE_PVDDQ_KLM_PH2_IMON      B @BASEBOARD_FAB2_LIB.BASEBOARD_FAB2(SCH_1):ISENSE_PVDDQ_KLM_PH2_IMON

RES_0402-150.0,1%,1/16W,CHIP,GA  I19  R1B8
   1 SVID_CLK1_CPU1_R      A @BASEBOARD_FAB2_LIB.BASEBOARD_FAB2(SCH_1):SVID_CLK1_CPU1_R
   2 SVID_CLK_PVDDQ_KLM      B @BASEBOARD_FAB2_LIB.BASEBOARD_FAB2(SCH_1):SVID_CLK_PVDDQ_KLM

RES_0402-100.0K,1%,1/16W,EMPTYA  I34  R9M5
   1 P3V3_STBY      A @BASEBOARD_FAB2_LIB.BASEBOARD_FAB2(SCH_1):P3V3_STBY
   2 VR_PVDDQ_KLM_VREN      B @BASEBOARD_FAB2_LIB.BASEBOARD_FAB2(SCH_1):VR_PVDDQ_KLM_VREN

CAP_A_0402V-1.0UF,6.3V,10%,X6SA  I38  C1B6
   1 VR_PVDDQ_KLM_VDD      A @BASEBOARD_FAB2_LIB.BASEBOARD_FAB2(SCH_1):VR_PVDDQ_KLM_VDD
   2    GND      B @BASEBOARD_FAB2_LIB.BASEBOARD_FAB2(SCH_1):GND

CAP_0402LF-1000PF,50V,10%,X7R,A  I40  C1B4
   1 PWRGD_PVDDQ_KLM_R      A @BASEBOARD_FAB2_LIB.BASEBOARD_FAB2(SCH_1):PWRGD_PVDDQ_KLM_R
   2    GND      B @BASEBOARD_FAB2_LIB.BASEBOARD_FAB2(SCH_1):GND

CAP_A_0402V-1.0UF,6.3V,10%,X6SA  I45  C1B3
   1 VR_PVDDQ_KLM_VD12      A @BASEBOARD_FAB2_LIB.BASEBOARD_FAB2(SCH_1):VR_PVDDQ_KLM_VD12
   2    GND      B @BASEBOARD_FAB2_LIB.BASEBOARD_FAB2(SCH_1):GND

RES_0402-0.0,5%,1/16W,EMPTY,G2A  I46  R12W35
   1 NC_PVDDQ_KLM_GP1      A @BASEBOARD_FAB2_LIB.BASEBOARD_FAB2(SCH_1):NC_PVDDQ_KLM_GP1
   2 PWRGD_PVDDQ_KLM      B @BASEBOARD_FAB2_LIB.BASEBOARD_FAB2(SCH_1):PWRGD_PVDDQ_KLM

RES_0402-0.0,5%,1/16W,CHIP,G21A  I48  R1B11
   1 SVID_ALERT_PVDDQ_KLM      A @BASEBOARD_FAB2_LIB.BASEBOARD_FAB2(SCH_1):SVID_ALERT_PVDDQ_KLM
   2 SVID_ALERT1_CPU1_R_N      B @BASEBOARD_FAB2_LIB.BASEBOARD_FAB2(SCH_1):SVID_ALERT1_CPU1_R_N

RES_0402-1.00K,1%,1/16W,CHIP,GA  I49  R1B1
   1 P3V3_STBY      A @BASEBOARD_FAB2_LIB.BASEBOARD_FAB2(SCH_1):P3V3_STBY
   2 IRQ_PVDDQ_KLM_VRHOT_LVT3_R_N      B @BASEBOARD_FAB2_LIB.BASEBOARD_FAB2(SCH_1):IRQ_PVDDQ_KLM_VRHOT_LVT3_R_N

RES_0402-33.2,1%,1/16W,CHIP,G2A  I54  R1B4
   1 IRQ_PVDDQ_KLM_VRHOT_LVT3_R_N      A @BASEBOARD_FAB2_LIB.BASEBOARD_FAB2(SCH_1):IRQ_PVDDQ_KLM_VRHOT_LVT3_R_N
   2 IRQ_PVDDQ_KLM_VRHOT_LVT3_N      B @BASEBOARD_FAB2_LIB.BASEBOARD_FAB2(SCH_1):IRQ_PVDDQ_KLM_VRHOT_LVT3_N

RES_0402-22.1,1.0%,1/16W,CHIP,A  I55  R1B5
   1 PWRGD_PVDDQ_KLM_R      A @BASEBOARD_FAB2_LIB.BASEBOARD_FAB2(SCH_1):PWRGD_PVDDQ_KLM_R
   2 PWRGD_PVDDQ_KLM      B @BASEBOARD_FAB2_LIB.BASEBOARD_FAB2(SCH_1):PWRGD_PVDDQ_KLM

RES_0402-100.0,1%,1/16W,EMPTY,A  I57  R9M7
   1 PVCCIO_CPU1      A @BASEBOARD_FAB2_LIB.BASEBOARD_FAB2(SCH_1):PVCCIO_CPU1
   2 SVID_DIO1_CPU1_R      B @BASEBOARD_FAB2_LIB.BASEBOARD_FAB2(SCH_1):SVID_DIO1_CPU1_R

PXM1310B_QFN-IC,H89186-001  I69  EU1B1
   1     NC  BPWM1     NC
   2     NC DNC<0>     NC
   3     NC  APWM3     NC
   4 VR_PVDDQ_KLM_PWM2  APWM2 @BASEBOARD_FAB2_LIB.BASEBOARD_FAB2(SCH_1):VR_PVDDQ_KLM_PWM2
   5 VR_PVDDQ_KLM_PWM1  APWM1 @BASEBOARD_FAB2_LIB.BASEBOARD_FAB2(SCH_1):VR_PVDDQ_KLM_PWM1
   6 SMB_VR_STBY_LVC3_SDA    SDA @BASEBOARD_FAB2_LIB.BASEBOARD_FAB2(SCH_1):SMB_VR_STBY_LVC3_SDA
   7 SMB_VR_STBY_LVC3_SCL    SCL @BASEBOARD_FAB2_LIB.BASEBOARD_FAB2(SCH_1):SMB_VR_STBY_LVC3_SCL
   8     NC RESET_N     NC
   9 PWRGD_PVDDQ_KLM_R AVRRDY @BASEBOARD_FAB2_LIB.BASEBOARD_FAB2(SCH_1):PWRGD_PVDDQ_KLM_R
  10 VR_PVDDQ_KLM_VREN  AVREN @BASEBOARD_FAB2_LIB.BASEBOARD_FAB2(SCH_1):VR_PVDDQ_KLM_VREN
  11 IRQ_PVDDQ_KLM_VRHOT_LVT3_R_N VRHOT_N @BASEBOARD_FAB2_LIB.BASEBOARD_FAB2(SCH_1):IRQ_PVDDQ_KLM_VRHOT_LVT3_R_N
  12     NC PINALRT_N     NC
  13 PU_VR_PVDDQ_KLM_FAULT1    MP0 @BASEBOARD_FAB2_LIB.BASEBOARD_FAB2(SCH_1):PU_VR_PVDDQ_KLM_FAULT1
  14 NC_PVDDQ_KLM_GP1    MP1 @BASEBOARD_FAB2_LIB.BASEBOARD_FAB2(SCH_1):NC_PVDDQ_KLM_GP1
  15 SVID_CLK_PVDDQ_KLM   VCLK @BASEBOARD_FAB2_LIB.BASEBOARD_FAB2(SCH_1):SVID_CLK_PVDDQ_KLM
  16 SVID_VDIO_PVDDQ_KLM   VDIO @BASEBOARD_FAB2_LIB.BASEBOARD_FAB2(SCH_1):SVID_VDIO_PVDDQ_KLM
  17 SVID_ALERT_PVDDQ_KLM VALRT_N @BASEBOARD_FAB2_LIB.BASEBOARD_FAB2(SCH_1):SVID_ALERT_PVDDQ_KLM
  18 NC_PVDDQ_KLM_GP0    MP2 @BASEBOARD_FAB2_LIB.BASEBOARD_FAB2(SCH_1):NC_PVDDQ_KLM_GP0
  19 VR_PVDDQ_KLM_AVSP  AVSEN @BASEBOARD_FAB2_LIB.BASEBOARD_FAB2(SCH_1):VR_PVDDQ_KLM_AVSP
  20 VSENSE_PVDDQ_KLM_N  AVREF @BASEBOARD_FAB2_LIB.BASEBOARD_FAB2(SCH_1):VSENSE_PVDDQ_KLM_N
  21 VR_PVDDQ_KLM_AIREF1 AIREF1 @BASEBOARD_FAB2_LIB.BASEBOARD_FAB2(SCH_1):VR_PVDDQ_KLM_AIREF1
  22 ISENSE_PVDDQ_KLM_PH1_IMON AISEN1 @BASEBOARD_FAB2_LIB.BASEBOARD_FAB2(SCH_1):ISENSE_PVDDQ_KLM_PH1_IMON
  23 VR_PVDDQ_KLM_AIREF2 AIREF2 @BASEBOARD_FAB2_LIB.BASEBOARD_FAB2(SCH_1):VR_PVDDQ_KLM_AIREF2
  24 ISENSE_PVDDQ_KLM_PH2_IMON AISEN2 @BASEBOARD_FAB2_LIB.BASEBOARD_FAB2(SCH_1):ISENSE_PVDDQ_KLM_PH2_IMON
  25     NC AIREF3     NC
  26     NC AISEN3     NC
  27    GND    GND @BASEBOARD_FAB2_LIB.BASEBOARD_FAB2(SCH_1):GND
  28     NC DNC<1>     NC
  29     NC  BVSEN     NC
  30     NC  BVREF     NC
  31     NC BIREF1     NC
  32    GND BISEN1 @BASEBOARD_FAB2_LIB.BASEBOARD_FAB2(SCH_1):GND
  33 VR_PVDDQ_KLM_XADDR2 XADDR2 @BASEBOARD_FAB2_LIB.BASEBOARD_FAB2(SCH_1):VR_PVDDQ_KLM_XADDR2
  34     NC  BTSEN     NC
  35 A_TSENSE_PVDDQ_KLM  ATSEN @BASEBOARD_FAB2_LIB.BASEBOARD_FAB2(SCH_1):A_TSENSE_PVDDQ_KLM
  36 VR_PVDDQ_KLM_XADDR1 XADDR1 @BASEBOARD_FAB2_LIB.BASEBOARD_FAB2(SCH_1):VR_PVDDQ_KLM_XADDR1
  37 VR_PVDDQ_KLM_VINSEN VINSEN @BASEBOARD_FAB2_LIB.BASEBOARD_FAB2(SCH_1):VR_PVDDQ_KLM_VINSEN
  38 VR_PVDDQ_KLM_AIINSEN IINSEN @BASEBOARD_FAB2_LIB.BASEBOARD_FAB2(SCH_1):VR_PVDDQ_KLM_AIINSEN
  39 VR_PVDDQ_KLM_VDD    VDD @BASEBOARD_FAB2_LIB.BASEBOARD_FAB2(SCH_1):VR_PVDDQ_KLM_VDD
  40 VR_PVDDQ_KLM_VD12   VD12 @BASEBOARD_FAB2_LIB.BASEBOARD_FAB2(SCH_1):VR_PVDDQ_KLM_VD12
  41    GND  THPAD @BASEBOARD_FAB2_LIB.BASEBOARD_FAB2(SCH_1):GND

RES_0402-10.0,1%,1/16W,CHIP,G2A  I13  R1B16
   1 VSENSE_PVDDQ_KLM_P      A @BASEBOARD_FAB2_LIB.BASEBOARD_FAB2(SCH_1):VSENSE_PVDDQ_KLM_P
   2 VR_PVDDQ_KLM_AVSP      B @BASEBOARD_FAB2_LIB.BASEBOARD_FAB2(SCH_1):VR_PVDDQ_KLM_AVSP

SC22P50V2JN-4GP_SMD-BCG-SC22P5A  I17  CF22
   1 VR_PVDDQ_KLM_AIREF2      1 @BASEBOARD_FAB2_LIB.BASEBOARD_FAB2(SCH_1):VR_PVDDQ_KLM_AIREF2
   2 ISENSE_PVDDQ_KLM_PH2_IMON      2 @BASEBOARD_FAB2_LIB.BASEBOARD_FAB2(SCH_1):ISENSE_PVDDQ_KLM_PH2_IMON

CAP_0402LF-220PF,50V,10%,X7R,AA  I23  C1B11
   1 A_TSENSE_PVDDQ_KLM      A @BASEBOARD_FAB2_LIB.BASEBOARD_FAB2(SCH_1):A_TSENSE_PVDDQ_KLM
   2    GND      B @BASEBOARD_FAB2_LIB.BASEBOARD_FAB2(SCH_1):GND

CAP_A_0402V-0.1UF,16V,10%,X7R,A  I32  C1B5
   1 VR_PVDDQ_KLM_VDD      A @BASEBOARD_FAB2_LIB.BASEBOARD_FAB2(SCH_1):VR_PVDDQ_KLM_VDD
   2    GND      B @BASEBOARD_FAB2_LIB.BASEBOARD_FAB2(SCH_1):GND

RES_0402-0.0,5%,1/16W,CHIP,G21A  I36  R9M3
   1 P3V3_STBY      A @BASEBOARD_FAB2_LIB.BASEBOARD_FAB2(SCH_1):P3V3_STBY
   2 VR_PVDDQ_KLM_VDD      B @BASEBOARD_FAB2_LIB.BASEBOARD_FAB2(SCH_1):VR_PVDDQ_KLM_VDD

RES_0402-0.0,5%,1/16W,CHIP,G21A  I41  R1B10
   1 SVID_VDIO_PVDDQ_KLM      A @BASEBOARD_FAB2_LIB.BASEBOARD_FAB2(SCH_1):SVID_VDIO_PVDDQ_KLM
   2 SVID_DIO1_CPU1_R      B @BASEBOARD_FAB2_LIB.BASEBOARD_FAB2(SCH_1):SVID_DIO1_CPU1_R

RES_0402-49.9,1%,1/16W,EMPTY,GA  I70  R9M6
   1 PVCCIO_CPU1      A @BASEBOARD_FAB2_LIB.BASEBOARD_FAB2(SCH_1):PVCCIO_CPU1
   2 SVID_CLK1_CPU1_R      B @BASEBOARD_FAB2_LIB.BASEBOARD_FAB2(SCH_1):SVID_CLK1_CPU1_R

RES_0402-16K,1.0%,1/16W,CHIP,GA  I72  R1B12
   1 VR_PVDDQ_KLM_XADDR1      A @BASEBOARD_FAB2_LIB.BASEBOARD_FAB2(SCH_1):VR_PVDDQ_KLM_XADDR1
   2    GND      B @BASEBOARD_FAB2_LIB.BASEBOARD_FAB2(SCH_1):GND

RES_0402-3.16K,1%,1/16W,CHIP,GA  I73  R1B15
   1 VR_PVDDQ_KLM_XADDR2      A @BASEBOARD_FAB2_LIB.BASEBOARD_FAB2(SCH_1):VR_PVDDQ_KLM_XADDR2
   2    GND      B @BASEBOARD_FAB2_LIB.BASEBOARD_FAB2(SCH_1):GND

RES_0402-0.0,5%,1/16W,CHIP,G21A  I74  R12W34
   1 PU_VR_PVDDQ_KLM_FAULT1      A @BASEBOARD_FAB2_LIB.BASEBOARD_FAB2(SCH_1):PU_VR_PVDDQ_KLM_FAULT1
   2 PWRGD_PVDDQ_KLM      B @BASEBOARD_FAB2_LIB.BASEBOARD_FAB2(SCH_1):PWRGD_PVDDQ_KLM

RES_0402-2.26K,1.0%,1/16W,CHIPA  I75  R1B13
   1 P3V3_STBY      A @BASEBOARD_FAB2_LIB.BASEBOARD_FAB2(SCH_1):P3V3_STBY
   2 PWRGD_PVDDQ_KLM      B @BASEBOARD_FAB2_LIB.BASEBOARD_FAB2(SCH_1):PWRGD_PVDDQ_KLM


DRAWING: @BASEBOARD_FAB2_LIB.BASEBOARD_FAB2(SCH_1):PAGE227 

CAP_0805LF-22UF,4V,20%,X6S,C95A  I6  C1A12
   1 PVDDQ_KLM      A @BASEBOARD_FAB2_LIB.BASEBOARD_FAB2(SCH_1):PVDDQ_KLM
   2    GND      B @BASEBOARD_FAB2_LIB.BASEBOARD_FAB2(SCH_1):GND

CAP_0402-0.220UF,16V,10%,X7R,AA  I44  C1A18
   1 VR_PVDDQ_KLM_PH1_BOOT      A @BASEBOARD_FAB2_LIB.BASEBOARD_FAB2(SCH_1):VR_PVDDQ_KLM_PH1_BOOT
   2 VR_PVDDQ_KLM_PH1_PHASE      B @BASEBOARD_FAB2_LIB.BASEBOARD_FAB2(SCH_1):VR_PVDDQ_KLM_PH1_PHASE

CAP_0805-10UF,16V,10%,X6S,C953A  I45  C9L11
   1 VR_FET_SW_P12V_STBY_PVDDQ_KLM      A @BASEBOARD_FAB2_LIB.BASEBOARD_FAB2(SCH_1):VR_FET_SW_P12V_STBY_PVDDQ_KLM
   2    GND      B @BASEBOARD_FAB2_LIB.BASEBOARD_FAB2(SCH_1):GND

CAP_0805-10UF,16V,10%,X6S,C953A  I46  C9L10
   1 VR_FET_SW_P12V_STBY_PVDDQ_KLM      A @BASEBOARD_FAB2_LIB.BASEBOARD_FAB2(SCH_1):VR_FET_SW_P12V_STBY_PVDDQ_KLM
   2    GND      B @BASEBOARD_FAB2_LIB.BASEBOARD_FAB2(SCH_1):GND

CAP_0805-10UF,16V,10%,X6S,C953A  I47  C9L6
   1 VR_FET_SW_P12V_STBY_PVDDQ_KLM      A @BASEBOARD_FAB2_LIB.BASEBOARD_FAB2(SCH_1):VR_FET_SW_P12V_STBY_PVDDQ_KLM
   2    GND      B @BASEBOARD_FAB2_LIB.BASEBOARD_FAB2(SCH_1):GND

CAP_0402-1.0UF,16V,10%,X6S,D97A  I48  C1A19
   1 VR_FET_SW_P12V_STBY_PVDDQ_KLM      A @BASEBOARD_FAB2_LIB.BASEBOARD_FAB2(SCH_1):VR_FET_SW_P12V_STBY_PVDDQ_KLM
   2    GND      B @BASEBOARD_FAB2_LIB.BASEBOARD_FAB2(SCH_1):GND

CAP_0402-1.0UF,16V,10%,X6S,D97A  I50  C1B20
   1 VR_PVDDQ_KLM_PH1_VCIN      A @BASEBOARD_FAB2_LIB.BASEBOARD_FAB2(SCH_1):VR_PVDDQ_KLM_PH1_VCIN
   2    GND      B @BASEBOARD_FAB2_LIB.BASEBOARD_FAB2(SCH_1):GND

CAP_A_0402V-0.1UF,16V,10%,X7R,A  I51  C1A10
   1 VR_FET_SW_P12V_STBY_PVDDQ_KLM      A @BASEBOARD_FAB2_LIB.BASEBOARD_FAB2(SCH_1):VR_FET_SW_P12V_STBY_PVDDQ_KLM
   2    GND      B @BASEBOARD_FAB2_LIB.BASEBOARD_FAB2(SCH_1):GND

CAP_0402-0.22UF,16V,10%,X7R,A3A  I54  C1B21
   1 P5V_STBY      A @BASEBOARD_FAB2_LIB.BASEBOARD_FAB2(SCH_1):P5V_STBY
   2    GND      B @BASEBOARD_FAB2_LIB.BASEBOARD_FAB2(SCH_1):GND

CAP_0805LF-22UF,4V,20%,X6S,C95A  I68  C1A1
   1 PVDDQ_KLM      A @BASEBOARD_FAB2_LIB.BASEBOARD_FAB2(SCH_1):PVDDQ_KLM
   2    GND      B @BASEBOARD_FAB2_LIB.BASEBOARD_FAB2(SCH_1):GND

CAP_0402-0.22UF,16V,10%,X7R,A3A  I72  C1A13
   1 P5V_STBY      A @BASEBOARD_FAB2_LIB.BASEBOARD_FAB2(SCH_1):P5V_STBY
   2    GND      B @BASEBOARD_FAB2_LIB.BASEBOARD_FAB2(SCH_1):GND

CAP_0402-0.220UF,16V,10%,X7R,AA  I75  C1A8
   1 VR_PVDDQ_KLM_PH2_BOOT      A @BASEBOARD_FAB2_LIB.BASEBOARD_FAB2(SCH_1):VR_PVDDQ_KLM_PH2_BOOT
   2 VR_PVDDQ_KLM_PH2_PHASE      B @BASEBOARD_FAB2_LIB.BASEBOARD_FAB2(SCH_1):VR_PVDDQ_KLM_PH2_PHASE

CAP_0402-1.0UF,16V,10%,X6S,D97A  I77  C1A6
   1 VR_PVDDQ_KLM_PH2_VCIN      A @BASEBOARD_FAB2_LIB.BASEBOARD_FAB2(SCH_1):VR_PVDDQ_KLM_PH2_VCIN
   2    GND      B @BASEBOARD_FAB2_LIB.BASEBOARD_FAB2(SCH_1):GND

CAP_A_0402V-0.1UF,16V,10%,X7R,A  I78  C1A20
   1 VR_FET_SW_P12V_STBY_PVDDQ_KLM      A @BASEBOARD_FAB2_LIB.BASEBOARD_FAB2(SCH_1):VR_FET_SW_P12V_STBY_PVDDQ_KLM
   2    GND      B @BASEBOARD_FAB2_LIB.BASEBOARD_FAB2(SCH_1):GND

CAP_0402-1.0UF,16V,10%,X6S,D97A  I79  C1A9
   1 VR_FET_SW_P12V_STBY_PVDDQ_KLM      A @BASEBOARD_FAB2_LIB.BASEBOARD_FAB2(SCH_1):VR_FET_SW_P12V_STBY_PVDDQ_KLM
   2    GND      B @BASEBOARD_FAB2_LIB.BASEBOARD_FAB2(SCH_1):GND

CAP_0805-10UF,16V,10%,X6S,C953A  I80  C9L5
   1 VR_FET_SW_P12V_STBY_PVDDQ_KLM      A @BASEBOARD_FAB2_LIB.BASEBOARD_FAB2(SCH_1):VR_FET_SW_P12V_STBY_PVDDQ_KLM
   2    GND      B @BASEBOARD_FAB2_LIB.BASEBOARD_FAB2(SCH_1):GND

CAP_0805-10UF,16V,10%,X6S,C953A  I81  C9L13
   1 VR_FET_SW_P12V_STBY_PVDDQ_KLM      A @BASEBOARD_FAB2_LIB.BASEBOARD_FAB2(SCH_1):VR_FET_SW_P12V_STBY_PVDDQ_KLM
   2    GND      B @BASEBOARD_FAB2_LIB.BASEBOARD_FAB2(SCH_1):GND

CAP_0805-10UF,16V,10%,X6S,C953A  I84  C9L14
   1 VR_FET_SW_P12V_STBY_PVDDQ_KLM      A @BASEBOARD_FAB2_LIB.BASEBOARD_FAB2(SCH_1):VR_FET_SW_P12V_STBY_PVDDQ_KLM
   2    GND      B @BASEBOARD_FAB2_LIB.BASEBOARD_FAB2(SCH_1):GND

IR354XX_SM-IR35411,IC,H73688-0A  I101  EU1A2
  33 VR_PVDDQ_KLM_PH1_BOOT_R  BOOST @BASEBOARD_FAB2_LIB.BASEBOARD_FAB2(SCH_1):VR_PVDDQ_KLM_PH1_BOOT_R
  35 P5V_STBY     EN @BASEBOARD_FAB2_LIB.BASEBOARD_FAB2(SCH_1):P5V_STBY
  41 TP_PVDDQ_KLM_PH1_GL_1  GL<1> @BASEBOARD_FAB2_LIB.BASEBOARD_FAB2(SCH_1):TP_PVDDQ_KLM_PH1_GL_1
   6 TP_PVDDQ_KLM_PH1_GL_0  GL<0> @BASEBOARD_FAB2_LIB.BASEBOARD_FAB2(SCH_1):TP_PVDDQ_KLM_PH1_GL_0
  38 ISENSE_PVDDQ_KLM_PH1_IMON   IOUT @BASEBOARD_FAB2_LIB.BASEBOARD_FAB2(SCH_1):ISENSE_PVDDQ_KLM_PH1_IMON
   2    GND   LGND @BASEBOARD_FAB2_LIB.BASEBOARD_FAB2(SCH_1):GND
  31     NC     NC     NC
  37 VR_PVDDQ_KLM_PH1_OCSET  OCSET @BASEBOARD_FAB2_LIB.BASEBOARD_FAB2(SCH_1):VR_PVDDQ_KLM_PH1_OCSET
  40    GND PGND<2> @BASEBOARD_FAB2_LIB.BASEBOARD_FAB2(SCH_1):GND
   7    GND PGND<1> @BASEBOARD_FAB2_LIB.BASEBOARD_FAB2(SCH_1):GND
   5    GND PGND<0> @BASEBOARD_FAB2_LIB.BASEBOARD_FAB2(SCH_1):GND
  32 VR_PVDDQ_KLM_PH1_PHASE  PHASE @BASEBOARD_FAB2_LIB.BASEBOARD_FAB2(SCH_1):VR_PVDDQ_KLM_PH1_PHASE
  34 VR_PVDDQ_KLM_PWM1    PWM @BASEBOARD_FAB2_LIB.BASEBOARD_FAB2(SCH_1):VR_PVDDQ_KLM_PWM1
  39 VR_PVDDQ_KLM_AIREF1  REFIN @BASEBOARD_FAB2_LIB.BASEBOARD_FAB2(SCH_1):VR_PVDDQ_KLM_AIREF1
  10 VR_PVDDQ_KLM_PH1_SW     SW @BASEBOARD_FAB2_LIB.BASEBOARD_FAB2(SCH_1):VR_PVDDQ_KLM_PH1_SW
  36 A_TSENSE_PVDDQ_KLM TOUT_FLT @BASEBOARD_FAB2_LIB.BASEBOARD_FAB2(SCH_1):A_TSENSE_PVDDQ_KLM
   3 VR_PVDDQ_KLM_PH1_VCIN    VCC @BASEBOARD_FAB2_LIB.BASEBOARD_FAB2(SCH_1):VR_PVDDQ_KLM_PH1_VCIN
   4 P5V_STBY   VDRV @BASEBOARD_FAB2_LIB.BASEBOARD_FAB2(SCH_1):P5V_STBY
  30 VR_FET_SW_P12V_STBY_PVDDQ_KLM VIN<1> @BASEBOARD_FAB2_LIB.BASEBOARD_FAB2(SCH_1):VR_FET_SW_P12V_STBY_PVDDQ_KLM
  25 VR_FET_SW_P12V_STBY_PVDDQ_KLM VIN<0> @BASEBOARD_FAB2_LIB.BASEBOARD_FAB2(SCH_1):VR_FET_SW_P12V_STBY_PVDDQ_KLM
   1 PVDDQ_KLM    VOS @BASEBOARD_FAB2_LIB.BASEBOARD_FAB2(SCH_1):PVDDQ_KLM

IR354XX_SM-IR35411,IC,H73688-0A  I102  EU1A1
  33 VR_PVDDQ_KLM_PH2_BOOT_R  BOOST @BASEBOARD_FAB2_LIB.BASEBOARD_FAB2(SCH_1):VR_PVDDQ_KLM_PH2_BOOT_R
  35 P5V_STBY     EN @BASEBOARD_FAB2_LIB.BASEBOARD_FAB2(SCH_1):P5V_STBY
  41 TP_PVDDQ_KLM_PH2_GL_1  GL<1> @BASEBOARD_FAB2_LIB.BASEBOARD_FAB2(SCH_1):TP_PVDDQ_KLM_PH2_GL_1
   6 TP_PVDDQ_KLM_PH2_GL_0  GL<0> @BASEBOARD_FAB2_LIB.BASEBOARD_FAB2(SCH_1):TP_PVDDQ_KLM_PH2_GL_0
  38 ISENSE_PVDDQ_KLM_PH2_IMON   IOUT @BASEBOARD_FAB2_LIB.BASEBOARD_FAB2(SCH_1):ISENSE_PVDDQ_KLM_PH2_IMON
   2    GND   LGND @BASEBOARD_FAB2_LIB.BASEBOARD_FAB2(SCH_1):GND
  31     NC     NC     NC
  37 VR_PVDDQ_KLM_PH2_OCSET  OCSET @BASEBOARD_FAB2_LIB.BASEBOARD_FAB2(SCH_1):VR_PVDDQ_KLM_PH2_OCSET
  40    GND PGND<2> @BASEBOARD_FAB2_LIB.BASEBOARD_FAB2(SCH_1):GND
   7    GND PGND<1> @BASEBOARD_FAB2_LIB.BASEBOARD_FAB2(SCH_1):GND
   5    GND PGND<0> @BASEBOARD_FAB2_LIB.BASEBOARD_FAB2(SCH_1):GND
  32 VR_PVDDQ_KLM_PH2_PHASE  PHASE @BASEBOARD_FAB2_LIB.BASEBOARD_FAB2(SCH_1):VR_PVDDQ_KLM_PH2_PHASE
  34 VR_PVDDQ_KLM_PWM2    PWM @BASEBOARD_FAB2_LIB.BASEBOARD_FAB2(SCH_1):VR_PVDDQ_KLM_PWM2
  39 VR_PVDDQ_KLM_AIREF2  REFIN @BASEBOARD_FAB2_LIB.BASEBOARD_FAB2(SCH_1):VR_PVDDQ_KLM_AIREF2
  10 VR_PVDDQ_KLM_PH2_SW     SW @BASEBOARD_FAB2_LIB.BASEBOARD_FAB2(SCH_1):VR_PVDDQ_KLM_PH2_SW
  36 A_TSENSE_PVDDQ_KLM TOUT_FLT @BASEBOARD_FAB2_LIB.BASEBOARD_FAB2(SCH_1):A_TSENSE_PVDDQ_KLM
   3 VR_PVDDQ_KLM_PH2_VCIN    VCC @BASEBOARD_FAB2_LIB.BASEBOARD_FAB2(SCH_1):VR_PVDDQ_KLM_PH2_VCIN
   4 P5V_STBY   VDRV @BASEBOARD_FAB2_LIB.BASEBOARD_FAB2(SCH_1):P5V_STBY
  30 VR_FET_SW_P12V_STBY_PVDDQ_KLM VIN<1> @BASEBOARD_FAB2_LIB.BASEBOARD_FAB2(SCH_1):VR_FET_SW_P12V_STBY_PVDDQ_KLM
  25 VR_FET_SW_P12V_STBY_PVDDQ_KLM VIN<0> @BASEBOARD_FAB2_LIB.BASEBOARD_FAB2(SCH_1):VR_FET_SW_P12V_STBY_PVDDQ_KLM
   1 PVDDQ_KLM    VOS @BASEBOARD_FAB2_LIB.BASEBOARD_FAB2(SCH_1):PVDDQ_KLM

RES_0402-68.1K,1%,1/16W,EMPTY,A  I103  R1A3
   1 VR_PVDDQ_KLM_PH1_OCSET      A @BASEBOARD_FAB2_LIB.BASEBOARD_FAB2(SCH_1):VR_PVDDQ_KLM_PH1_OCSET
   2    GND      B @BASEBOARD_FAB2_LIB.BASEBOARD_FAB2(SCH_1):GND

RES_0402-68.1K,1%,1/16W,EMPTY,A  I105  R1A2
   1 VR_PVDDQ_KLM_PH2_OCSET      A @BASEBOARD_FAB2_LIB.BASEBOARD_FAB2(SCH_1):VR_PVDDQ_KLM_PH2_OCSET
   2    GND      B @BASEBOARD_FAB2_LIB.BASEBOARD_FAB2(SCH_1):GND

CAP_A_0402V-0.1UF,16V,10%,X7R,A  I109  CT7
   1 VR_PVDDQ_KLM_AIREF1      A @BASEBOARD_FAB2_LIB.BASEBOARD_FAB2(SCH_1):VR_PVDDQ_KLM_AIREF1
   2    GND      B @BASEBOARD_FAB2_LIB.BASEBOARD_FAB2(SCH_1):GND

CAP_0402LF-1000PF,50V,10%,X7R,A  I114  CT8
   1 A_TSENSE_PVDDQ_KLM      A @BASEBOARD_FAB2_LIB.BASEBOARD_FAB2(SCH_1):A_TSENSE_PVDDQ_KLM
   2    GND      B @BASEBOARD_FAB2_LIB.BASEBOARD_FAB2(SCH_1):GND

CAP_0402LF-1000PF,50V,10%,X7R,A  I119  CT10
   1 A_TSENSE_PVDDQ_KLM      A @BASEBOARD_FAB2_LIB.BASEBOARD_FAB2(SCH_1):A_TSENSE_PVDDQ_KLM
   2    GND      B @BASEBOARD_FAB2_LIB.BASEBOARD_FAB2(SCH_1):GND

CAP_A_0402V-0.1UF,16V,10%,X7R,A  I122  CT12
   1 VR_PVDDQ_KLM_AIREF2      A @BASEBOARD_FAB2_LIB.BASEBOARD_FAB2(SCH_1):VR_PVDDQ_KLM_AIREF2
   2    GND      B @BASEBOARD_FAB2_LIB.BASEBOARD_FAB2(SCH_1):GND

CAP_0402LF-1000PF,50V,10%,X7R,A  I134  CT9
   1 VR_PVDDQ_KLM_PH1_SW      A @BASEBOARD_FAB2_LIB.BASEBOARD_FAB2(SCH_1):VR_PVDDQ_KLM_PH1_SW
   2 VR_PVDDQ_KLM_PH1_RC      B @BASEBOARD_FAB2_LIB.BASEBOARD_FAB2(SCH_1):VR_PVDDQ_KLM_PH1_RC

CAP_0402LF-1000PF,50V,10%,X7R,A  I135  CT11
   1 VR_PVDDQ_KLM_PH2_SW      A @BASEBOARD_FAB2_LIB.BASEBOARD_FAB2(SCH_1):VR_PVDDQ_KLM_PH2_SW
   2 VR_PVDDQ_KLM_PH2_RC      B @BASEBOARD_FAB2_LIB.BASEBOARD_FAB2(SCH_1):VR_PVDDQ_KLM_PH2_RC

RES_0603-0,5.0%,1/10W,CHIP,G22A  I138  RT5
   1 VR_PVDDQ_KLM_PH1_BOOT      A @BASEBOARD_FAB2_LIB.BASEBOARD_FAB2(SCH_1):VR_PVDDQ_KLM_PH1_BOOT
   2 VR_PVDDQ_KLM_PH1_BOOT_R      B @BASEBOARD_FAB2_LIB.BASEBOARD_FAB2(SCH_1):VR_PVDDQ_KLM_PH1_BOOT_R

RES_0603-0,5.0%,1/10W,CHIP,G22A  I139  RT8
   1 VR_PVDDQ_KLM_PH2_BOOT      A @BASEBOARD_FAB2_LIB.BASEBOARD_FAB2(SCH_1):VR_PVDDQ_KLM_PH2_BOOT
   2 VR_PVDDQ_KLM_PH2_BOOT_R      B @BASEBOARD_FAB2_LIB.BASEBOARD_FAB2(SCH_1):VR_PVDDQ_KLM_PH2_BOOT_R

SC1U10V2KX-4-GP_SMD-BCG6-SC1U1A  I147  C1A11
   1 P5V_STBY      1 @BASEBOARD_FAB2_LIB.BASEBOARD_FAB2(SCH_1):P5V_STBY
   2    GND      2 @BASEBOARD_FAB2_LIB.BASEBOARD_FAB2(SCH_1):GND

SC1U10V2KX-4-GP_SMD-BCG6-SC1U1A  I148  C1A2
   1 P5V_STBY      1 @BASEBOARD_FAB2_LIB.BASEBOARD_FAB2(SCH_1):P5V_STBY
   2    GND      2 @BASEBOARD_FAB2_LIB.BASEBOARD_FAB2(SCH_1):GND

1R3F-GP_RCL_GP-1R3F-GP,64.1R00A  I149  RT6
   1 VR_PVDDQ_KLM_PH1_RC      1 @BASEBOARD_FAB2_LIB.BASEBOARD_FAB2(SCH_1):VR_PVDDQ_KLM_PH1_RC
   2    GND      2 @BASEBOARD_FAB2_LIB.BASEBOARD_FAB2(SCH_1):GND

1R3F-GP_RCL_GP-1R3F-GP,64.1R00A  I150  RT7
   1 VR_PVDDQ_KLM_PH2_RC      1 @BASEBOARD_FAB2_LIB.BASEBOARD_FAB2(SCH_1):VR_PVDDQ_KLM_PH2_RC
   2    GND      2 @BASEBOARD_FAB2_LIB.BASEBOARD_FAB2(SCH_1):GND

IND-120NH-30-GP_DISCRET-GB2-INA  I152  L1A2
   1 VR_PVDDQ_KLM_PH1_SW      S @BASEBOARD_FAB2_LIB.BASEBOARD_FAB2(SCH_1):VR_PVDDQ_KLM_PH1_SW
   2 PVDDQ_KLM      F @BASEBOARD_FAB2_LIB.BASEBOARD_FAB2(SCH_1):PVDDQ_KLM

IND-120NH-30-GP_DISCRET-GB2-INA  I153  L1A1
   1 VR_PVDDQ_KLM_PH2_SW      S @BASEBOARD_FAB2_LIB.BASEBOARD_FAB2(SCH_1):VR_PVDDQ_KLM_PH2_SW
   2 PVDDQ_KLM      F @BASEBOARD_FAB2_LIB.BASEBOARD_FAB2(SCH_1):PVDDQ_KLM

RES_0402-0.0,5%,1/16W,CHIP,G21A  I154  R9L9
   1 VR_PVDDQ_KLM_PH1_VCIN      A @BASEBOARD_FAB2_LIB.BASEBOARD_FAB2(SCH_1):VR_PVDDQ_KLM_PH1_VCIN
   2 P5V_STBY      B @BASEBOARD_FAB2_LIB.BASEBOARD_FAB2(SCH_1):P5V_STBY

RES_0402-0.0,5%,1/16W,CHIP,G21A  I155  R9L4
   1 VR_PVDDQ_KLM_PH2_VCIN      A @BASEBOARD_FAB2_LIB.BASEBOARD_FAB2(SCH_1):VR_PVDDQ_KLM_PH2_VCIN
   2 P5V_STBY      B @BASEBOARD_FAB2_LIB.BASEBOARD_FAB2(SCH_1):P5V_STBY


DRAWING: @BASEBOARD_FAB2_LIB.BASEBOARD_FAB2(SCH_1):PAGE228 

RES_0603-120.0,1%,1/10W,CHIP,GA  I58  R1A1
   1 PVDDQ_KLM      A @BASEBOARD_FAB2_LIB.BASEBOARD_FAB2(SCH_1):PVDDQ_KLM
   2    GND      B @BASEBOARD_FAB2_LIB.BASEBOARD_FAB2(SCH_1):GND

RES_0402-100.0,1%,1/16W,EMPTY,A  I74  R7L2
   1 VSENSE_PVDDQ_KLM_P      A @BASEBOARD_FAB2_LIB.BASEBOARD_FAB2(SCH_1):VSENSE_PVDDQ_KLM_P
   2 VSENSE_PVDDQ_KLM_N      B @BASEBOARD_FAB2_LIB.BASEBOARD_FAB2(SCH_1):VSENSE_PVDDQ_KLM_N

CAPP_3018-470UF,2.5V,20%,ALUM,A  I75  C9L9
   1 PVDDQ_KLM      A @BASEBOARD_FAB2_LIB.BASEBOARD_FAB2(SCH_1):PVDDQ_KLM
   2    GND      B @BASEBOARD_FAB2_LIB.BASEBOARD_FAB2(SCH_1):GND

CAPP_3018-470UF,2.5V,20%,ALUM,A  I76  C9L12
   1 PVDDQ_KLM      A @BASEBOARD_FAB2_LIB.BASEBOARD_FAB2(SCH_1):PVDDQ_KLM
   2    GND      B @BASEBOARD_FAB2_LIB.BASEBOARD_FAB2(SCH_1):GND

CAPP_3018-470UF,2.5V,20%,ALUM,A  I77  C9L4
   1 PVDDQ_KLM      A @BASEBOARD_FAB2_LIB.BASEBOARD_FAB2(SCH_1):PVDDQ_KLM
   2    GND      B @BASEBOARD_FAB2_LIB.BASEBOARD_FAB2(SCH_1):GND

CAPP_3018-470UF,2.5V,20%,ALUM,A  I78  C9L2
   1 PVDDQ_KLM      A @BASEBOARD_FAB2_LIB.BASEBOARD_FAB2(SCH_1):PVDDQ_KLM
   2    GND      B @BASEBOARD_FAB2_LIB.BASEBOARD_FAB2(SCH_1):GND

CAPP_2626-270UF,16V,20%,OSCON,A  I175  C1B10
   1 VR_FET_SW_P12V_STBY_PVDDQ_KLM      A @BASEBOARD_FAB2_LIB.BASEBOARD_FAB2(SCH_1):VR_FET_SW_P12V_STBY_PVDDQ_KLM
   2    GND      B @BASEBOARD_FAB2_LIB.BASEBOARD_FAB2(SCH_1):GND

CAP_A_0603V-47UF,4V,20%,X5R,60A  I198  C8M8
   1 PVDDQ_KLM      A @BASEBOARD_FAB2_LIB.BASEBOARD_FAB2(SCH_1):PVDDQ_KLM
   2    GND      B @BASEBOARD_FAB2_LIB.BASEBOARD_FAB2(SCH_1):GND

CAP_A_0603V-47UF,4V,20%,X5R,60A  I199  C2A5
   1 PVDDQ_KLM      A @BASEBOARD_FAB2_LIB.BASEBOARD_FAB2(SCH_1):PVDDQ_KLM
   2    GND      B @BASEBOARD_FAB2_LIB.BASEBOARD_FAB2(SCH_1):GND

CAP_A_0603V-47UF,4V,20%,X5R,60A  I200  C2B1
   1 PVDDQ_KLM      A @BASEBOARD_FAB2_LIB.BASEBOARD_FAB2(SCH_1):PVDDQ_KLM
   2    GND      B @BASEBOARD_FAB2_LIB.BASEBOARD_FAB2(SCH_1):GND

CAP_A_0603V-47UF,4V,20%,X5R,60A  I201  C8L12
   1 PVDDQ_KLM      A @BASEBOARD_FAB2_LIB.BASEBOARD_FAB2(SCH_1):PVDDQ_KLM
   2    GND      B @BASEBOARD_FAB2_LIB.BASEBOARD_FAB2(SCH_1):GND

CAP_A_0603V-47UF,4V,20%,X5R,60A  I202  C7M5
   1 PVDDQ_KLM      A @BASEBOARD_FAB2_LIB.BASEBOARD_FAB2(SCH_1):PVDDQ_KLM
   2    GND      B @BASEBOARD_FAB2_LIB.BASEBOARD_FAB2(SCH_1):GND

CAP_A_0603V-47UF,4V,20%,X5R,60A  I203  C8M10
   1 PVDDQ_KLM      A @BASEBOARD_FAB2_LIB.BASEBOARD_FAB2(SCH_1):PVDDQ_KLM
   2    GND      B @BASEBOARD_FAB2_LIB.BASEBOARD_FAB2(SCH_1):GND

CAP_A_0603V-47UF,4V,20%,X5R,60A  I204  C2B2
   1 PVDDQ_KLM      A @BASEBOARD_FAB2_LIB.BASEBOARD_FAB2(SCH_1):PVDDQ_KLM
   2    GND      B @BASEBOARD_FAB2_LIB.BASEBOARD_FAB2(SCH_1):GND

CAP_A_0603V-47UF,4V,20%,X5R,60A  I205  C8M9
   1 PVDDQ_KLM      A @BASEBOARD_FAB2_LIB.BASEBOARD_FAB2(SCH_1):PVDDQ_KLM
   2    GND      B @BASEBOARD_FAB2_LIB.BASEBOARD_FAB2(SCH_1):GND

CAP_A_0603V-47UF,4V,20%,X5R,60A  I206  C8M2
   1 PVDDQ_KLM      A @BASEBOARD_FAB2_LIB.BASEBOARD_FAB2(SCH_1):PVDDQ_KLM
   2    GND      B @BASEBOARD_FAB2_LIB.BASEBOARD_FAB2(SCH_1):GND

SHUNT_SH0201-EMPTY,N_A  I245  SH7L2
   1 VSENSE_PVDDQ_KLM_P      A @BASEBOARD_FAB2_LIB.BASEBOARD_FAB2(SCH_1):VSENSE_PVDDQ_KLM_P
   2 PVDDQ_KLM      B @BASEBOARD_FAB2_LIB.BASEBOARD_FAB2(SCH_1):PVDDQ_KLM

SHUNT_SH0201-EMPTY,N_A  I246  SH7L1
   1 VSENSE_PVDDQ_KLM_N      A @BASEBOARD_FAB2_LIB.BASEBOARD_FAB2(SCH_1):VSENSE_PVDDQ_KLM_N
   2    GND      B @BASEBOARD_FAB2_LIB.BASEBOARD_FAB2(SCH_1):GND

IND-100NH-35-GP_DISCRET-G8-INDA  I247  L1B1
   1 P12V_STBY      S @BASEBOARD_FAB2_LIB.BASEBOARD_FAB2(SCH_1):P12V_STBY
   2 VR_FET_SW_P12V_STBY_PVDDQ_KLM      F @BASEBOARD_FAB2_LIB.BASEBOARD_FAB2(SCH_1):VR_FET_SW_P12V_STBY_PVDDQ_KLM

CAP_A_0603V-22.0UF,4V,20%,X6S,A  I255  C3D1
   1 PVDDQ_KLM      A @BASEBOARD_FAB2_LIB.BASEBOARD_FAB2(SCH_1):PVDDQ_KLM
   2    GND      B @BASEBOARD_FAB2_LIB.BASEBOARD_FAB2(SCH_1):GND

CAP_A_0603V-22.0UF,4V,20%,X6S,A  I256  C2D3
   1 PVDDQ_KLM      A @BASEBOARD_FAB2_LIB.BASEBOARD_FAB2(SCH_1):PVDDQ_KLM
   2    GND      B @BASEBOARD_FAB2_LIB.BASEBOARD_FAB2(SCH_1):GND

CAP_A_0603V-22.0UF,4V,20%,X6S,A  I257  C2D2
   1 PVDDQ_KLM      A @BASEBOARD_FAB2_LIB.BASEBOARD_FAB2(SCH_1):PVDDQ_KLM
   2    GND      B @BASEBOARD_FAB2_LIB.BASEBOARD_FAB2(SCH_1):GND

CAP_A_0603V-22.0UF,4V,20%,X6S,A  I258  C2D1
   1 PVDDQ_KLM      A @BASEBOARD_FAB2_LIB.BASEBOARD_FAB2(SCH_1):PVDDQ_KLM
   2    GND      B @BASEBOARD_FAB2_LIB.BASEBOARD_FAB2(SCH_1):GND

CAP_A_0603V-22.0UF,4V,20%,X6S,A  I264  C2D7
   1 PVDDQ_KLM      A @BASEBOARD_FAB2_LIB.BASEBOARD_FAB2(SCH_1):PVDDQ_KLM
   2    GND      B @BASEBOARD_FAB2_LIB.BASEBOARD_FAB2(SCH_1):GND

CAP_A_0603V-22.0UF,4V,20%,X6S,A  I265  C2D4
   1 PVDDQ_KLM      A @BASEBOARD_FAB2_LIB.BASEBOARD_FAB2(SCH_1):PVDDQ_KLM
   2    GND      B @BASEBOARD_FAB2_LIB.BASEBOARD_FAB2(SCH_1):GND

CAP_A_0603V-22.0UF,4V,20%,X6S,A  I266  C2D5
   1 PVDDQ_KLM      A @BASEBOARD_FAB2_LIB.BASEBOARD_FAB2(SCH_1):PVDDQ_KLM
   2    GND      B @BASEBOARD_FAB2_LIB.BASEBOARD_FAB2(SCH_1):GND

CAP_A_0603V-22.0UF,4V,20%,X6S,A  I267  C2D6
   1 PVDDQ_KLM      A @BASEBOARD_FAB2_LIB.BASEBOARD_FAB2(SCH_1):PVDDQ_KLM
   2    GND      B @BASEBOARD_FAB2_LIB.BASEBOARD_FAB2(SCH_1):GND

CAP_A_0603V-47UF,4V,20%,X5R,60A  I268  C7L5
   1 PVDDQ_KLM      A @BASEBOARD_FAB2_LIB.BASEBOARD_FAB2(SCH_1):PVDDQ_KLM
   2    GND      B @BASEBOARD_FAB2_LIB.BASEBOARD_FAB2(SCH_1):GND

CAP_A_0603V-47UF,4V,20%,X5R,60A  I269  C3A6
   1 PVDDQ_KLM      A @BASEBOARD_FAB2_LIB.BASEBOARD_FAB2(SCH_1):PVDDQ_KLM
   2    GND      B @BASEBOARD_FAB2_LIB.BASEBOARD_FAB2(SCH_1):GND

CAP_A_0603V-47UF,4V,20%,X5R,60A  I270  C3A5
   1 PVDDQ_KLM      A @BASEBOARD_FAB2_LIB.BASEBOARD_FAB2(SCH_1):PVDDQ_KLM
   2    GND      B @BASEBOARD_FAB2_LIB.BASEBOARD_FAB2(SCH_1):GND

CAP_A_0603V-47UF,4V,20%,X5R,60A  I271  C2A15
   1 PVDDQ_KLM      A @BASEBOARD_FAB2_LIB.BASEBOARD_FAB2(SCH_1):PVDDQ_KLM
   2    GND      B @BASEBOARD_FAB2_LIB.BASEBOARD_FAB2(SCH_1):GND

CAP_A_0603V-47UF,4V,20%,X5R,60A  I272  C2A14
   1 PVDDQ_KLM      A @BASEBOARD_FAB2_LIB.BASEBOARD_FAB2(SCH_1):PVDDQ_KLM
   2    GND      B @BASEBOARD_FAB2_LIB.BASEBOARD_FAB2(SCH_1):GND

CAP_A_0603V-47UF,4V,20%,X5R,60A  I273  C2A6
   1 PVDDQ_KLM      A @BASEBOARD_FAB2_LIB.BASEBOARD_FAB2(SCH_1):PVDDQ_KLM
   2    GND      B @BASEBOARD_FAB2_LIB.BASEBOARD_FAB2(SCH_1):GND

CAP_A_0603V-47UF,4V,20%,X5R,60A  I274  C2A7
   1 PVDDQ_KLM      A @BASEBOARD_FAB2_LIB.BASEBOARD_FAB2(SCH_1):PVDDQ_KLM
   2    GND      B @BASEBOARD_FAB2_LIB.BASEBOARD_FAB2(SCH_1):GND

CAP_A_0603V-47UF,4V,20%,X5R,60A  I275  C3A1
   1 PVDDQ_KLM      A @BASEBOARD_FAB2_LIB.BASEBOARD_FAB2(SCH_1):PVDDQ_KLM
   2    GND      B @BASEBOARD_FAB2_LIB.BASEBOARD_FAB2(SCH_1):GND

CAP_A_0603V-47UF,4V,20%,X5R,60A  I276  C3A2
   1 PVDDQ_KLM      A @BASEBOARD_FAB2_LIB.BASEBOARD_FAB2(SCH_1):PVDDQ_KLM
   2    GND      B @BASEBOARD_FAB2_LIB.BASEBOARD_FAB2(SCH_1):GND

CAP_A_0603V-47UF,4V,20%,X5R,60A  I277  C2A9
   1 PVDDQ_KLM      A @BASEBOARD_FAB2_LIB.BASEBOARD_FAB2(SCH_1):PVDDQ_KLM
   2    GND      B @BASEBOARD_FAB2_LIB.BASEBOARD_FAB2(SCH_1):GND

CAP_A_0603V-47UF,4V,20%,X5R,60A  I278  C2A10
   1 PVDDQ_KLM      A @BASEBOARD_FAB2_LIB.BASEBOARD_FAB2(SCH_1):PVDDQ_KLM
   2    GND      B @BASEBOARD_FAB2_LIB.BASEBOARD_FAB2(SCH_1):GND

CAP_A_0603V-47UF,4V,20%,X5R,60A  I279  C2A11
   1 PVDDQ_KLM      A @BASEBOARD_FAB2_LIB.BASEBOARD_FAB2(SCH_1):PVDDQ_KLM
   2    GND      B @BASEBOARD_FAB2_LIB.BASEBOARD_FAB2(SCH_1):GND

CAP_A_0603V-47UF,4V,20%,X5R,60A  I280  C2A13
   1 PVDDQ_KLM      A @BASEBOARD_FAB2_LIB.BASEBOARD_FAB2(SCH_1):PVDDQ_KLM
   2    GND      B @BASEBOARD_FAB2_LIB.BASEBOARD_FAB2(SCH_1):GND

CAP_A_0603V-47UF,4V,20%,X5R,60A  I281  C2A12
   1 PVDDQ_KLM      A @BASEBOARD_FAB2_LIB.BASEBOARD_FAB2(SCH_1):PVDDQ_KLM
   2    GND      B @BASEBOARD_FAB2_LIB.BASEBOARD_FAB2(SCH_1):GND

CAP_A_0603V-47UF,4V,20%,X5R,60A  I282  C2A1
   1 PVDDQ_KLM      A @BASEBOARD_FAB2_LIB.BASEBOARD_FAB2(SCH_1):PVDDQ_KLM
   2    GND      B @BASEBOARD_FAB2_LIB.BASEBOARD_FAB2(SCH_1):GND

CAP_A_0603V-47UF,4V,20%,X5R,60A  I283  C2A2
   1 PVDDQ_KLM      A @BASEBOARD_FAB2_LIB.BASEBOARD_FAB2(SCH_1):PVDDQ_KLM
   2    GND      B @BASEBOARD_FAB2_LIB.BASEBOARD_FAB2(SCH_1):GND

CAP_A_0603V-47UF,4V,20%,X5R,60A  I284  C8M1
   1 PVDDQ_KLM      A @BASEBOARD_FAB2_LIB.BASEBOARD_FAB2(SCH_1):PVDDQ_KLM
   2    GND      B @BASEBOARD_FAB2_LIB.BASEBOARD_FAB2(SCH_1):GND

CAP_A_0603V-47UF,4V,20%,X5R,60A  I285  C8L5
   1 PVDDQ_KLM      A @BASEBOARD_FAB2_LIB.BASEBOARD_FAB2(SCH_1):PVDDQ_KLM
   2    GND      B @BASEBOARD_FAB2_LIB.BASEBOARD_FAB2(SCH_1):GND

CAP_A_0603V-47UF,4V,20%,X5R,60A  I286  C8L6
   1 PVDDQ_KLM      A @BASEBOARD_FAB2_LIB.BASEBOARD_FAB2(SCH_1):PVDDQ_KLM
   2    GND      B @BASEBOARD_FAB2_LIB.BASEBOARD_FAB2(SCH_1):GND

CAP_A_0603V-47UF,4V,20%,X5R,60A  I287  C8L7
   1 PVDDQ_KLM      A @BASEBOARD_FAB2_LIB.BASEBOARD_FAB2(SCH_1):PVDDQ_KLM
   2    GND      B @BASEBOARD_FAB2_LIB.BASEBOARD_FAB2(SCH_1):GND

CAP_A_0603V-47UF,4V,20%,X5R,60A  I288  C7L4
   1 PVDDQ_KLM      A @BASEBOARD_FAB2_LIB.BASEBOARD_FAB2(SCH_1):PVDDQ_KLM
   2    GND      B @BASEBOARD_FAB2_LIB.BASEBOARD_FAB2(SCH_1):GND

CAP_A_0603V-47UF,4V,20%,X5R,60A  I289  C8L8
   1 PVDDQ_KLM      A @BASEBOARD_FAB2_LIB.BASEBOARD_FAB2(SCH_1):PVDDQ_KLM
   2    GND      B @BASEBOARD_FAB2_LIB.BASEBOARD_FAB2(SCH_1):GND

CAP_A_0603V-47UF,4V,20%,X5R,60A  I290  C8L9
   1 PVDDQ_KLM      A @BASEBOARD_FAB2_LIB.BASEBOARD_FAB2(SCH_1):PVDDQ_KLM
   2    GND      B @BASEBOARD_FAB2_LIB.BASEBOARD_FAB2(SCH_1):GND

CAP_A_0603V-47UF,4V,20%,X5R,60A  I291  C8M6
   1 PVDDQ_KLM      A @BASEBOARD_FAB2_LIB.BASEBOARD_FAB2(SCH_1):PVDDQ_KLM
   2    GND      B @BASEBOARD_FAB2_LIB.BASEBOARD_FAB2(SCH_1):GND

CAP_A_0603V-47UF,4V,20%,X5R,60A  I292  C2A4
   1 PVDDQ_KLM      A @BASEBOARD_FAB2_LIB.BASEBOARD_FAB2(SCH_1):PVDDQ_KLM
   2    GND      B @BASEBOARD_FAB2_LIB.BASEBOARD_FAB2(SCH_1):GND

CAP_A_0603V-47UF,4V,20%,X5R,60A  I293  C8M4
   1 PVDDQ_KLM      A @BASEBOARD_FAB2_LIB.BASEBOARD_FAB2(SCH_1):PVDDQ_KLM
   2    GND      B @BASEBOARD_FAB2_LIB.BASEBOARD_FAB2(SCH_1):GND

CAP_A_0603V-47UF,4V,20%,X5R,60A  I294  C7M2
   1 PVDDQ_KLM      A @BASEBOARD_FAB2_LIB.BASEBOARD_FAB2(SCH_1):PVDDQ_KLM
   2    GND      B @BASEBOARD_FAB2_LIB.BASEBOARD_FAB2(SCH_1):GND

CAP_A_0603V-47UF,4V,20%,X5R,60A  I295  C7M1
   1 PVDDQ_KLM      A @BASEBOARD_FAB2_LIB.BASEBOARD_FAB2(SCH_1):PVDDQ_KLM
   2    GND      B @BASEBOARD_FAB2_LIB.BASEBOARD_FAB2(SCH_1):GND

CAP_A_0603V-47UF,4V,20%,X5R,60A  I296  C2A3
   1 PVDDQ_KLM      A @BASEBOARD_FAB2_LIB.BASEBOARD_FAB2(SCH_1):PVDDQ_KLM
   2    GND      B @BASEBOARD_FAB2_LIB.BASEBOARD_FAB2(SCH_1):GND

CAP_A_0603V-47UF,4V,20%,X5R,60A  I297  C8L10
   1 PVDDQ_KLM      A @BASEBOARD_FAB2_LIB.BASEBOARD_FAB2(SCH_1):PVDDQ_KLM
   2    GND      B @BASEBOARD_FAB2_LIB.BASEBOARD_FAB2(SCH_1):GND

CAP_A_0603V-47UF,4V,20%,X5R,60A  I298  C8M5
   1 PVDDQ_KLM      A @BASEBOARD_FAB2_LIB.BASEBOARD_FAB2(SCH_1):PVDDQ_KLM
   2    GND      B @BASEBOARD_FAB2_LIB.BASEBOARD_FAB2(SCH_1):GND

CAP_A_0603V-47UF,4V,20%,X5R,60A  I299  C8M3
   1 PVDDQ_KLM      A @BASEBOARD_FAB2_LIB.BASEBOARD_FAB2(SCH_1):PVDDQ_KLM
   2    GND      B @BASEBOARD_FAB2_LIB.BASEBOARD_FAB2(SCH_1):GND

CAP_0805-100UF,4V,20%,X5R,6024A  I301  C8L1
   1 PVDDQ_KLM      A @BASEBOARD_FAB2_LIB.BASEBOARD_FAB2(SCH_1):PVDDQ_KLM
   2    GND      B @BASEBOARD_FAB2_LIB.BASEBOARD_FAB2(SCH_1):GND

CAP_0805-100UF,4V,20%,X5R,6024A  I302  C8L11
   1 PVDDQ_KLM      A @BASEBOARD_FAB2_LIB.BASEBOARD_FAB2(SCH_1):PVDDQ_KLM
   2    GND      B @BASEBOARD_FAB2_LIB.BASEBOARD_FAB2(SCH_1):GND

CAP_0805-100UF,4V,20%,X5R,6024A  I303  C8P2
   1 PVDDQ_KLM      A @BASEBOARD_FAB2_LIB.BASEBOARD_FAB2(SCH_1):PVDDQ_KLM
   2    GND      B @BASEBOARD_FAB2_LIB.BASEBOARD_FAB2(SCH_1):GND

CAP_0805-100UF,4V,20%,X5R,6024A  I304  C8P1
   1 PVDDQ_KLM      A @BASEBOARD_FAB2_LIB.BASEBOARD_FAB2(SCH_1):PVDDQ_KLM
   2    GND      B @BASEBOARD_FAB2_LIB.BASEBOARD_FAB2(SCH_1):GND

CAP_0805-100UF,4V,20%,X5R,6024A  I305  C7P2
   1 PVDDQ_KLM      A @BASEBOARD_FAB2_LIB.BASEBOARD_FAB2(SCH_1):PVDDQ_KLM
   2    GND      B @BASEBOARD_FAB2_LIB.BASEBOARD_FAB2(SCH_1):GND

CAP_0805-100UF,4V,20%,X5R,6024A  I306  C8P3
   1 PVDDQ_KLM      A @BASEBOARD_FAB2_LIB.BASEBOARD_FAB2(SCH_1):PVDDQ_KLM
   2    GND      B @BASEBOARD_FAB2_LIB.BASEBOARD_FAB2(SCH_1):GND

CAP_0805-100UF,4V,20%,X5R,6024A  I307  C8P4
   1 PVDDQ_KLM      A @BASEBOARD_FAB2_LIB.BASEBOARD_FAB2(SCH_1):PVDDQ_KLM
   2    GND      B @BASEBOARD_FAB2_LIB.BASEBOARD_FAB2(SCH_1):GND

CAP_0805-100UF,4V,20%,X5R,6024A  I308  C7P1
   1 PVDDQ_KLM      A @BASEBOARD_FAB2_LIB.BASEBOARD_FAB2(SCH_1):PVDDQ_KLM
   2    GND      B @BASEBOARD_FAB2_LIB.BASEBOARD_FAB2(SCH_1):GND

CAP_0805-100UF,4V,20%,X5R,6024A  I309  C2A8
   1 PVDDQ_KLM      A @BASEBOARD_FAB2_LIB.BASEBOARD_FAB2(SCH_1):PVDDQ_KLM
   2    GND      B @BASEBOARD_FAB2_LIB.BASEBOARD_FAB2(SCH_1):GND

CAP_0805-100UF,4V,20%,X5R,6024A  I310  C8L2
   1 PVDDQ_KLM      A @BASEBOARD_FAB2_LIB.BASEBOARD_FAB2(SCH_1):PVDDQ_KLM
   2    GND      B @BASEBOARD_FAB2_LIB.BASEBOARD_FAB2(SCH_1):GND

CAP_0805-100UF,4V,20%,X5R,6024A  I311  C8M11
   1 PVDDQ_KLM      A @BASEBOARD_FAB2_LIB.BASEBOARD_FAB2(SCH_1):PVDDQ_KLM
   2    GND      B @BASEBOARD_FAB2_LIB.BASEBOARD_FAB2(SCH_1):GND

CAP_0805-100UF,4V,20%,X5R,6024A  I312  C8M7
   1 PVDDQ_KLM      A @BASEBOARD_FAB2_LIB.BASEBOARD_FAB2(SCH_1):PVDDQ_KLM
   2    GND      B @BASEBOARD_FAB2_LIB.BASEBOARD_FAB2(SCH_1):GND

CAP_0805-100UF,4V,20%,X5R,6024A  I313  C2A16
   1 PVDDQ_KLM      A @BASEBOARD_FAB2_LIB.BASEBOARD_FAB2(SCH_1):PVDDQ_KLM
   2    GND      B @BASEBOARD_FAB2_LIB.BASEBOARD_FAB2(SCH_1):GND

CAP_0805-100UF,4V,20%,X5R,6024A  I314  C7L1
   1 PVDDQ_KLM      A @BASEBOARD_FAB2_LIB.BASEBOARD_FAB2(SCH_1):PVDDQ_KLM
   2    GND      B @BASEBOARD_FAB2_LIB.BASEBOARD_FAB2(SCH_1):GND


DRAWING: @BASEBOARD_FAB2_LIB.BASEBOARD_FAB2(SCH_1):PAGE229 

CAP_0402-1.0UF,16V,10%,X6S,D97A  I21  C4G21
   1 VR_PVTT_GHJ_VREF      A @BASEBOARD_FAB2_LIB.BASEBOARD_FAB2(SCH_1):VR_PVTT_GHJ_VREF
   2    GND      B @BASEBOARD_FAB2_LIB.BASEBOARD_FAB2(SCH_1):GND

RES_0402-33.2,1%,1/16W,CHIP,G2A  I32  R4G15
   1 PWRGD_PVTT_GHJ_CPU1_R      A @BASEBOARD_FAB2_LIB.BASEBOARD_FAB2(SCH_1):PWRGD_PVTT_GHJ_CPU1_R
   2 PWRGD_PVTT_CPU1      B @BASEBOARD_FAB2_LIB.BASEBOARD_FAB2(SCH_1):PWRGD_PVTT_CPU1

CAP_0402LF-1000PF,50V,10%,EMPTA  I2  C4G12
   1 FM_PVTT_GHJ_EN_R      A @BASEBOARD_FAB2_LIB.BASEBOARD_FAB2(SCH_1):FM_PVTT_GHJ_EN_R
   2    GND      B @BASEBOARD_FAB2_LIB.BASEBOARD_FAB2(SCH_1):GND

RES_0402-0.0,5%,1/16W,CHIP,G21A  I4  R4G16
   1 PWRGD_PVDDQ_GHJ_R      A @BASEBOARD_FAB2_LIB.BASEBOARD_FAB2(SCH_1):PWRGD_PVDDQ_GHJ_R
   2 FM_PVTT_GHJ_EN_R      B @BASEBOARD_FAB2_LIB.BASEBOARD_FAB2(SCH_1):FM_PVTT_GHJ_EN_R

RES_0402-1.0M,1%,1/16W,EMPTY,GA  I5  R6U3
   1   P3V3      A @BASEBOARD_FAB2_LIB.BASEBOARD_FAB2(SCH_1):P3V3
   2 FM_PVTT_GHJ_EN_R      B @BASEBOARD_FAB2_LIB.BASEBOARD_FAB2(SCH_1):FM_PVTT_GHJ_EN_R

RES_0402-0.0,5%,1/16W,CHIP,G21A  I6  R6U6
   1 PVDDQ_GHJ      A @BASEBOARD_FAB2_LIB.BASEBOARD_FAB2(SCH_1):PVDDQ_GHJ
   2 VSENSE_PVDDQ_GHJ_VTT      B @BASEBOARD_FAB2_LIB.BASEBOARD_FAB2(SCH_1):VSENSE_PVDDQ_GHJ_VTT

RES_0402-0.0,5%,1/16W,CHIP,G21A  I9  R6U7
   1   P3V3      A @BASEBOARD_FAB2_LIB.BASEBOARD_FAB2(SCH_1):P3V3
   2 VR_PVTT_GHJ_BIAS      B @BASEBOARD_FAB2_LIB.BASEBOARD_FAB2(SCH_1):VR_PVTT_GHJ_BIAS

CAP_0603LF-10UF,4V,20%,X6S,E15A  I11  C6U13
   1 PVDDQ_GHJ      A @BASEBOARD_FAB2_LIB.BASEBOARD_FAB2(SCH_1):PVDDQ_GHJ
   2    GND      B @BASEBOARD_FAB2_LIB.BASEBOARD_FAB2(SCH_1):GND

SHUNT_SH0201-EMPTY,N_A  I12  SH8U1
   1 VR_PVTT_GHJ_SNS      A @BASEBOARD_FAB2_LIB.BASEBOARD_FAB2(SCH_1):VR_PVTT_GHJ_SNS
   2 PVTT_GHJ      B @BASEBOARD_FAB2_LIB.BASEBOARD_FAB2(SCH_1):PVTT_GHJ

CAP_0402-1.0UF,16V,10%,X6S,D97A  I16  C4G18
   1 VR_PVTT_GHJ_BIAS      A @BASEBOARD_FAB2_LIB.BASEBOARD_FAB2(SCH_1):VR_PVTT_GHJ_BIAS
   2    GND      B @BASEBOARD_FAB2_LIB.BASEBOARD_FAB2(SCH_1):GND

CAP_0603LF-10UF,4V,20%,X6S,E15A  I18  C6U14
   1 PVDDQ_GHJ      A @BASEBOARD_FAB2_LIB.BASEBOARD_FAB2(SCH_1):PVDDQ_GHJ
   2    GND      B @BASEBOARD_FAB2_LIB.BASEBOARD_FAB2(SCH_1):GND

CAP_0805LF-22UF,4V,20%,X6S,C95A  I23  C4G20
   1 PVTT_GHJ      A @BASEBOARD_FAB2_LIB.BASEBOARD_FAB2(SCH_1):PVTT_GHJ
   2    GND      B @BASEBOARD_FAB2_LIB.BASEBOARD_FAB2(SCH_1):GND

CAP_0402LF-1000PF,50V,10%,X7R,A  I26  C4G13
   1 PWRGD_PVTT_GHJ_CPU1_R      A @BASEBOARD_FAB2_LIB.BASEBOARD_FAB2(SCH_1):PWRGD_PVTT_GHJ_CPU1_R
   2    GND      B @BASEBOARD_FAB2_LIB.BASEBOARD_FAB2(SCH_1):GND

CAP_A_0603V-47UF,4V,20%,X5R,60A  I28  C2F2
   1 PVTT_GHJ      A @BASEBOARD_FAB2_LIB.BASEBOARD_FAB2(SCH_1):PVTT_GHJ
   2    GND      B @BASEBOARD_FAB2_LIB.BASEBOARD_FAB2(SCH_1):GND

MIC5166_DFN-IC,H55101-001  I37  EU4G2
   7 FM_PVTT_GHJ_EN_R     EN @BASEBOARD_FAB2_LIB.BASEBOARD_FAB2(SCH_1):FM_PVTT_GHJ_EN_R
  10 PVDDQ_GHJ    VIN @BASEBOARD_FAB2_LIB.BASEBOARD_FAB2(SCH_1):PVDDQ_GHJ
   1 VR_PVTT_GHJ_VREF   VREF @BASEBOARD_FAB2_LIB.BASEBOARD_FAB2(SCH_1):VR_PVTT_GHJ_VREF
   2 VR_PVTT_GHJ_BIAS   BIAS @BASEBOARD_FAB2_LIB.BASEBOARD_FAB2(SCH_1):VR_PVTT_GHJ_BIAS
   3    GND   AGND @BASEBOARD_FAB2_LIB.BASEBOARD_FAB2(SCH_1):GND
   5 PWRGD_PVTT_GHJ_CPU1_R     PG @BASEBOARD_FAB2_LIB.BASEBOARD_FAB2(SCH_1):PWRGD_PVTT_GHJ_CPU1_R
   4 VSENSE_PVDDQ_GHJ_VTT   VDDQ @BASEBOARD_FAB2_LIB.BASEBOARD_FAB2(SCH_1):VSENSE_PVDDQ_GHJ_VTT
   6 VR_PVTT_GHJ_SNS    SNS @BASEBOARD_FAB2_LIB.BASEBOARD_FAB2(SCH_1):VR_PVTT_GHJ_SNS
   8    GND   PGND @BASEBOARD_FAB2_LIB.BASEBOARD_FAB2(SCH_1):GND
   9 PVTT_GHJ    VTT @BASEBOARD_FAB2_LIB.BASEBOARD_FAB2(SCH_1):PVTT_GHJ
  11    GND  THPAD @BASEBOARD_FAB2_LIB.BASEBOARD_FAB2(SCH_1):GND

CAP_0603-4.7UF,6.3V,10%,X6S,E1A  I14  C6U11
   1 VSENSE_PVDDQ_GHJ_VTT      A @BASEBOARD_FAB2_LIB.BASEBOARD_FAB2(SCH_1):VSENSE_PVDDQ_GHJ_VTT
   2    GND      B @BASEBOARD_FAB2_LIB.BASEBOARD_FAB2(SCH_1):GND

RES_0402-10.0K,1%,1/16W,CHIP,GA  I24  R4G17
   1   P3V3      A @BASEBOARD_FAB2_LIB.BASEBOARD_FAB2(SCH_1):P3V3
   2 PWRGD_PVTT_GHJ_CPU1_R      B @BASEBOARD_FAB2_LIB.BASEBOARD_FAB2(SCH_1):PWRGD_PVTT_GHJ_CPU1_R

CAP_0805-100UF,4V,20%,X5R,6024A  I41  C8T3
   1 PVTT_GHJ      A @BASEBOARD_FAB2_LIB.BASEBOARD_FAB2(SCH_1):PVTT_GHJ
   2    GND      B @BASEBOARD_FAB2_LIB.BASEBOARD_FAB2(SCH_1):GND

CAP_0805-100UF,4V,20%,X5R,6024A  I42  C8U10
   1 PVTT_GHJ      A @BASEBOARD_FAB2_LIB.BASEBOARD_FAB2(SCH_1):PVTT_GHJ
   2    GND      B @BASEBOARD_FAB2_LIB.BASEBOARD_FAB2(SCH_1):GND

CAP_0805-100UF,4V,20%,X5R,6024A  I43  C6W12
   1 PVTT_GHJ      A @BASEBOARD_FAB2_LIB.BASEBOARD_FAB2(SCH_1):PVTT_GHJ
   2    GND      B @BASEBOARD_FAB2_LIB.BASEBOARD_FAB2(SCH_1):GND


DRAWING: @BASEBOARD_FAB2_LIB.BASEBOARD_FAB2(SCH_1):PAGE231 

CAP_0603LF-10UF,4V,20%,X6S,E15A  I122  C6F6
   1 PVPP_ABC      A @BASEBOARD_FAB2_LIB.BASEBOARD_FAB2(SCH_1):PVPP_ABC
   2    GND      B @BASEBOARD_FAB2_LIB.BASEBOARD_FAB2(SCH_1):GND

CAP_0603LF-10UF,4V,20%,X6S,E15A  I124  C4T6
   1 PVPP_ABC      A @BASEBOARD_FAB2_LIB.BASEBOARD_FAB2(SCH_1):PVPP_ABC
   2    GND      B @BASEBOARD_FAB2_LIB.BASEBOARD_FAB2(SCH_1):GND

CAP_0603LF-10UF,4V,20%,X6S,E15A  I125  C4T5
   1 PVPP_ABC      A @BASEBOARD_FAB2_LIB.BASEBOARD_FAB2(SCH_1):PVPP_ABC
   2    GND      B @BASEBOARD_FAB2_LIB.BASEBOARD_FAB2(SCH_1):GND

CAP_0603LF-10UF,4V,20%,X6S,E15A  I126  C6G1
   1 PVPP_ABC      A @BASEBOARD_FAB2_LIB.BASEBOARD_FAB2(SCH_1):PVPP_ABC
   2    GND      B @BASEBOARD_FAB2_LIB.BASEBOARD_FAB2(SCH_1):GND

CAP_0603LF-10UF,4V,20%,X6S,E15A  I128  C6G2
   1 PVPP_ABC      A @BASEBOARD_FAB2_LIB.BASEBOARD_FAB2(SCH_1):PVPP_ABC
   2    GND      B @BASEBOARD_FAB2_LIB.BASEBOARD_FAB2(SCH_1):GND

CAP_0603LF-10UF,4V,20%,X6S,E15A  I129  C4U2
   1 PVPP_ABC      A @BASEBOARD_FAB2_LIB.BASEBOARD_FAB2(SCH_1):PVPP_ABC
   2    GND      B @BASEBOARD_FAB2_LIB.BASEBOARD_FAB2(SCH_1):GND

CAP_0603LF-10UF,4V,20%,X6S,E15A  I130  C4U1
   1 PVPP_ABC      A @BASEBOARD_FAB2_LIB.BASEBOARD_FAB2(SCH_1):PVPP_ABC
   2    GND      B @BASEBOARD_FAB2_LIB.BASEBOARD_FAB2(SCH_1):GND

CAP_0603LF-10UF,4V,20%,X6S,E15A  I131  C6G4
   1 PVPP_ABC      A @BASEBOARD_FAB2_LIB.BASEBOARD_FAB2(SCH_1):PVPP_ABC
   2    GND      B @BASEBOARD_FAB2_LIB.BASEBOARD_FAB2(SCH_1):GND

RES_0402-7.87K,1.0%,1/16W,CHIPA  I134  R7F15
   1 VR_PVPP_ABC_ISET      A @BASEBOARD_FAB2_LIB.BASEBOARD_FAB2(SCH_1):VR_PVPP_ABC_ISET
   2 AGND_PVPP_ABC      B @BASEBOARD_FAB2_LIB.BASEBOARD_FAB2(SCH_1):AGND_PVPP_ABC

RES_0402-10.0K,1%,1/16W,CHIP,GA  I136  R7F14
   1 FM_PVPP_CPU0_EN      A @BASEBOARD_FAB2_LIB.BASEBOARD_FAB2(SCH_1):FM_PVPP_CPU0_EN
   2    GND      B @BASEBOARD_FAB2_LIB.BASEBOARD_FAB2(SCH_1):GND

CAP_0402LF-1000PF,50V,10%,EMPTA  I140  C7F8
   1 FM_PVPP_CPU0_EN      A @BASEBOARD_FAB2_LIB.BASEBOARD_FAB2(SCH_1):FM_PVPP_CPU0_EN
   2 AGND_PVPP_ABC      B @BASEBOARD_FAB2_LIB.BASEBOARD_FAB2(SCH_1):AGND_PVPP_ABC

CAP_0402LF-1000PF,50V,10%,X7R,A  I142  C7F11
   1 PWRGD_PVPP_ABC_R      A @BASEBOARD_FAB2_LIB.BASEBOARD_FAB2(SCH_1):PWRGD_PVPP_ABC_R
   2    GND      B @BASEBOARD_FAB2_LIB.BASEBOARD_FAB2(SCH_1):GND

RES_0402-1.00K,1%,1/16W,CHIP,GA  I143  R7F19
   1 P3V3_STBY      A @BASEBOARD_FAB2_LIB.BASEBOARD_FAB2(SCH_1):P3V3_STBY
   2 PWRGD_PVPP_ABC_R      B @BASEBOARD_FAB2_LIB.BASEBOARD_FAB2(SCH_1):PWRGD_PVPP_ABC_R

CAP_0603LF-10UF,4V,20%,X6S,E15A  I145  C6G5
   1 PVPP_ABC      A @BASEBOARD_FAB2_LIB.BASEBOARD_FAB2(SCH_1):PVPP_ABC
   2    GND      B @BASEBOARD_FAB2_LIB.BASEBOARD_FAB2(SCH_1):GND

CAP_0603LF-10UF,4V,20%,X6S,E15A  I146  C4U4
   1 PVPP_ABC      A @BASEBOARD_FAB2_LIB.BASEBOARD_FAB2(SCH_1):PVPP_ABC
   2    GND      B @BASEBOARD_FAB2_LIB.BASEBOARD_FAB2(SCH_1):GND

CAP_0603LF-10UF,4V,20%,X6S,E15A  I148  C4U3
   1 PVPP_ABC      A @BASEBOARD_FAB2_LIB.BASEBOARD_FAB2(SCH_1):PVPP_ABC
   2    GND      B @BASEBOARD_FAB2_LIB.BASEBOARD_FAB2(SCH_1):GND

CAP_0603LF-10UF,4V,20%,X6S,E15A  I149  C6F5
   1 PVPP_ABC      A @BASEBOARD_FAB2_LIB.BASEBOARD_FAB2(SCH_1):PVPP_ABC
   2    GND      B @BASEBOARD_FAB2_LIB.BASEBOARD_FAB2(SCH_1):GND

CAP_0603LF-0.1UF,25V,10%,X7R,6A  I159  C7F4
   1 VR_PVPP_ABC_PHASE      A @BASEBOARD_FAB2_LIB.BASEBOARD_FAB2(SCH_1):VR_PVPP_ABC_PHASE
   2 VR_PVPP_ABC_BOOT_R      B @BASEBOARD_FAB2_LIB.BASEBOARD_FAB2(SCH_1):VR_PVPP_ABC_BOOT_R

CAP_0402-1.0UF,16V,10%,X6S,D97A  I161  C3T10
   1 VR_FET_SW_P12V_STBY_PVPP_ABC      A @BASEBOARD_FAB2_LIB.BASEBOARD_FAB2(SCH_1):VR_FET_SW_P12V_STBY_PVPP_ABC
   2    GND      B @BASEBOARD_FAB2_LIB.BASEBOARD_FAB2(SCH_1):GND

FERRITE_SM-22,FB,656554-051  I162  FB7F1
   1 P12V_STBY      A @BASEBOARD_FAB2_LIB.BASEBOARD_FAB2(SCH_1):P12V_STBY
   2 VR_FET_SW_P12V_STBY_PVPP_ABC      B @BASEBOARD_FAB2_LIB.BASEBOARD_FAB2(SCH_1):VR_FET_SW_P12V_STBY_PVPP_ABC

RES_0402-20.0K,1%,1/16W,CHIP,GA  I167  R7F13
   1 VSENSE_PVPP_ABC      A @BASEBOARD_FAB2_LIB.BASEBOARD_FAB2(SCH_1):VSENSE_PVPP_ABC
   2 VR_FB_PVPP_ABC      B @BASEBOARD_FAB2_LIB.BASEBOARD_FAB2(SCH_1):VR_FB_PVPP_ABC

RES_0402-0.0,5%,1/16W,CHIP,G21A  I168  R7F12
   1 PVPP_ABC      A @BASEBOARD_FAB2_LIB.BASEBOARD_FAB2(SCH_1):PVPP_ABC
   2 VSENSE_PVPP_ABC      B @BASEBOARD_FAB2_LIB.BASEBOARD_FAB2(SCH_1):VSENSE_PVPP_ABC

RES_0402-0.0,5%,1/16W,CHIP,G21A  I170  R7F35
   1    GND      A @BASEBOARD_FAB2_LIB.BASEBOARD_FAB2(SCH_1):GND
   2 AGND_PVPP_ABC      B @BASEBOARD_FAB2_LIB.BASEBOARD_FAB2(SCH_1):AGND_PVPP_ABC

RES_0402-2.2,5%,1/16W,EMPTY,G2A  I174  R7F7
   1 VR_PVPP_ABC_SNUB      A @BASEBOARD_FAB2_LIB.BASEBOARD_FAB2(SCH_1):VR_PVPP_ABC_SNUB
   2    GND      B @BASEBOARD_FAB2_LIB.BASEBOARD_FAB2(SCH_1):GND

CAP_0402LF-3300PF,50V,10%,EMPTA  I175  C7F3
   1 VR_PVPP_ABC_PHASE      A @BASEBOARD_FAB2_LIB.BASEBOARD_FAB2(SCH_1):VR_PVPP_ABC_PHASE
   2 VR_PVPP_ABC_SNUB      B @BASEBOARD_FAB2_LIB.BASEBOARD_FAB2(SCH_1):VR_PVPP_ABC_SNUB

RES_0603-120.0,1%,1/10W,CHIP,GA  I177  R7F10
   1 PVPP_ABC      A @BASEBOARD_FAB2_LIB.BASEBOARD_FAB2(SCH_1):PVPP_ABC
   2    GND      B @BASEBOARD_FAB2_LIB.BASEBOARD_FAB2(SCH_1):GND

INDUCTOR_SM-0.47UH,IND,E13358-A  I178  L7F1
   1 VR_PVPP_ABC_PHASE    INA @BASEBOARD_FAB2_LIB.BASEBOARD_FAB2(SCH_1):VR_PVPP_ABC_PHASE
   2 PVPP_ABC    INB @BASEBOARD_FAB2_LIB.BASEBOARD_FAB2(SCH_1):PVPP_ABC

CAPP_7343LF-330UF,6.3V,20%,POSA  I180  C6F4
   1 PVPP_ABC      A @BASEBOARD_FAB2_LIB.BASEBOARD_FAB2(SCH_1):PVPP_ABC
   2    GND      B @BASEBOARD_FAB2_LIB.BASEBOARD_FAB2(SCH_1):GND

CAP_0805-47UF,4V,20%,X6S,C9533A  I184  C3T7
   1 PVPP_ABC      A @BASEBOARD_FAB2_LIB.BASEBOARD_FAB2(SCH_1):PVPP_ABC
   2    GND      B @BASEBOARD_FAB2_LIB.BASEBOARD_FAB2(SCH_1):GND

CAP_0805-47UF,4V,20%,X6S,C9533A  I186  C3T9
   1 PVPP_ABC      A @BASEBOARD_FAB2_LIB.BASEBOARD_FAB2(SCH_1):PVPP_ABC
   2    GND      B @BASEBOARD_FAB2_LIB.BASEBOARD_FAB2(SCH_1):GND

NCP3232L_SM-IC,H86355-001  I193  EU7F1
   5 AGND_PVPP_ABC   AGND @BASEBOARD_FAB2_LIB.BASEBOARD_FAB2(SCH_1):AGND_PVPP_ABC
  36 VR_PVPP_ABC_BOOT    BST @BASEBOARD_FAB2_LIB.BASEBOARD_FAB2(SCH_1):VR_PVPP_ABC_BOOT
   3 VR_COMP_PVPP_ABC_3   COMP @BASEBOARD_FAB2_LIB.BASEBOARD_FAB2(SCH_1):VR_COMP_PVPP_ABC_3
  40 FM_PVPP_PVDDQ_CPU0_EN_ABC     EN @BASEBOARD_FAB2_LIB.BASEBOARD_FAB2(SCH_1):FM_PVPP_PVDDQ_CPU0_EN_ABC
   2 VR_FB_PVPP_ABC     FB @BASEBOARD_FAB2_LIB.BASEBOARD_FAB2(SCH_1):VR_FB_PVPP_ABC
  41    GND    GND @BASEBOARD_FAB2_LIB.BASEBOARD_FAB2(SCH_1):GND
   4 VR_PVPP_ABC_ISET   ISET @BASEBOARD_FAB2_LIB.BASEBOARD_FAB2(SCH_1):VR_PVPP_ABC_ISET
   6 AGND_PVPP_ABC    OTS @BASEBOARD_FAB2_LIB.BASEBOARD_FAB2(SCH_1):AGND_PVPP_ABC
   7 PWRGD_PVPP_ABC_R     PG @BASEBOARD_FAB2_LIB.BASEBOARD_FAB2(SCH_1):PWRGD_PVPP_ABC_R
  37    GND PGND<13> @BASEBOARD_FAB2_LIB.BASEBOARD_FAB2(SCH_1):GND
  28    GND PGND<12> @BASEBOARD_FAB2_LIB.BASEBOARD_FAB2(SCH_1):GND
  27    GND PGND<11> @BASEBOARD_FAB2_LIB.BASEBOARD_FAB2(SCH_1):GND
  26    GND PGND<10> @BASEBOARD_FAB2_LIB.BASEBOARD_FAB2(SCH_1):GND
  25    GND PGND<9> @BASEBOARD_FAB2_LIB.BASEBOARD_FAB2(SCH_1):GND
  24    GND PGND<8> @BASEBOARD_FAB2_LIB.BASEBOARD_FAB2(SCH_1):GND
  23    GND PGND<7> @BASEBOARD_FAB2_LIB.BASEBOARD_FAB2(SCH_1):GND
  22    GND PGND<6> @BASEBOARD_FAB2_LIB.BASEBOARD_FAB2(SCH_1):GND
  21    GND PGND<5> @BASEBOARD_FAB2_LIB.BASEBOARD_FAB2(SCH_1):GND
  20    GND PGND<4> @BASEBOARD_FAB2_LIB.BASEBOARD_FAB2(SCH_1):GND
  19    GND PGND<3> @BASEBOARD_FAB2_LIB.BASEBOARD_FAB2(SCH_1):GND
  18    GND PGND<2> @BASEBOARD_FAB2_LIB.BASEBOARD_FAB2(SCH_1):GND
  17    GND PGND<1> @BASEBOARD_FAB2_LIB.BASEBOARD_FAB2(SCH_1):GND
  16    GND PGND<0> @BASEBOARD_FAB2_LIB.BASEBOARD_FAB2(SCH_1):GND
   1 VR_PVPP_ABC_SS     SS @BASEBOARD_FAB2_LIB.BASEBOARD_FAB2(SCH_1):VR_PVPP_ABC_SS
  38 VR_VB_PVPP_ABC     VB @BASEBOARD_FAB2_LIB.BASEBOARD_FAB2(SCH_1):VR_VB_PVPP_ABC
  39 VR_FET_SW_P12V_STBY_PVPP_ABC    VCC @BASEBOARD_FAB2_LIB.BASEBOARD_FAB2(SCH_1):VR_FET_SW_P12V_STBY_PVPP_ABC
  42 VR_FET_SW_P12V_STBY_PVPP_ABC VIN<7> @BASEBOARD_FAB2_LIB.BASEBOARD_FAB2(SCH_1):VR_FET_SW_P12V_STBY_PVPP_ABC
  14 VR_FET_SW_P12V_STBY_PVPP_ABC VIN<6> @BASEBOARD_FAB2_LIB.BASEBOARD_FAB2(SCH_1):VR_FET_SW_P12V_STBY_PVPP_ABC
  13 VR_FET_SW_P12V_STBY_PVPP_ABC VIN<5> @BASEBOARD_FAB2_LIB.BASEBOARD_FAB2(SCH_1):VR_FET_SW_P12V_STBY_PVPP_ABC
  12 VR_FET_SW_P12V_STBY_PVPP_ABC VIN<4> @BASEBOARD_FAB2_LIB.BASEBOARD_FAB2(SCH_1):VR_FET_SW_P12V_STBY_PVPP_ABC
  11 VR_FET_SW_P12V_STBY_PVPP_ABC VIN<3> @BASEBOARD_FAB2_LIB.BASEBOARD_FAB2(SCH_1):VR_FET_SW_P12V_STBY_PVPP_ABC
  10 VR_FET_SW_P12V_STBY_PVPP_ABC VIN<2> @BASEBOARD_FAB2_LIB.BASEBOARD_FAB2(SCH_1):VR_FET_SW_P12V_STBY_PVPP_ABC
   9 VR_FET_SW_P12V_STBY_PVPP_ABC VIN<1> @BASEBOARD_FAB2_LIB.BASEBOARD_FAB2(SCH_1):VR_FET_SW_P12V_STBY_PVPP_ABC
   8 VR_FET_SW_P12V_STBY_PVPP_ABC VIN<0> @BASEBOARD_FAB2_LIB.BASEBOARD_FAB2(SCH_1):VR_FET_SW_P12V_STBY_PVPP_ABC
  35 VR_PVPP_ABC_PHASE    VSW @BASEBOARD_FAB2_LIB.BASEBOARD_FAB2(SCH_1):VR_PVPP_ABC_PHASE
  43 VR_PVPP_ABC_PHASE VSWH<7> @BASEBOARD_FAB2_LIB.BASEBOARD_FAB2(SCH_1):VR_PVPP_ABC_PHASE
  34 VR_PVPP_ABC_PHASE VSWH<6> @BASEBOARD_FAB2_LIB.BASEBOARD_FAB2(SCH_1):VR_PVPP_ABC_PHASE
  33 VR_PVPP_ABC_PHASE VSWH<5> @BASEBOARD_FAB2_LIB.BASEBOARD_FAB2(SCH_1):VR_PVPP_ABC_PHASE
  32 VR_PVPP_ABC_PHASE VSWH<4> @BASEBOARD_FAB2_LIB.BASEBOARD_FAB2(SCH_1):VR_PVPP_ABC_PHASE
  31 VR_PVPP_ABC_PHASE VSWH<3> @BASEBOARD_FAB2_LIB.BASEBOARD_FAB2(SCH_1):VR_PVPP_ABC_PHASE
  30 VR_PVPP_ABC_PHASE VSWH<2> @BASEBOARD_FAB2_LIB.BASEBOARD_FAB2(SCH_1):VR_PVPP_ABC_PHASE
  29 VR_PVPP_ABC_PHASE VSWH<1> @BASEBOARD_FAB2_LIB.BASEBOARD_FAB2(SCH_1):VR_PVPP_ABC_PHASE
  15 VR_PVPP_ABC_PHASE VSWH<0> @BASEBOARD_FAB2_LIB.BASEBOARD_FAB2(SCH_1):VR_PVPP_ABC_PHASE

CAP_0402-0.027UF,16V,10%,X7R,AA  I194  C7F10
   1 VR_PVPP_ABC_SS      A @BASEBOARD_FAB2_LIB.BASEBOARD_FAB2(SCH_1):VR_PVPP_ABC_SS
   2 AGND_PVPP_ABC      B @BASEBOARD_FAB2_LIB.BASEBOARD_FAB2(SCH_1):AGND_PVPP_ABC

CAP_0402LF-100.0PF,50V,5%,COG,A  I199  C7F9
   1 VR_FB_PVPP_ABC      A @BASEBOARD_FAB2_LIB.BASEBOARD_FAB2(SCH_1):VR_FB_PVPP_ABC
   2 VR_COMP_PVPP_ABC_3      B @BASEBOARD_FAB2_LIB.BASEBOARD_FAB2(SCH_1):VR_COMP_PVPP_ABC_3

CAP_0402LF-2200PF,50V,10%,X7R,A  I200  C7F12
   1 VR_COMP_RC_PVPP_ABC      A @BASEBOARD_FAB2_LIB.BASEBOARD_FAB2(SCH_1):VR_COMP_RC_PVPP_ABC
   2 VR_COMP_PVPP_ABC_3      B @BASEBOARD_FAB2_LIB.BASEBOARD_FAB2(SCH_1):VR_COMP_PVPP_ABC_3

RES_0402-7.87K,1.0%,1/16W,CHIPA  I201  R7F18
   1 VR_COMP_RC_PVPP_ABC      A @BASEBOARD_FAB2_LIB.BASEBOARD_FAB2(SCH_1):VR_COMP_RC_PVPP_ABC
   2 VR_FB_PVPP_ABC      B @BASEBOARD_FAB2_LIB.BASEBOARD_FAB2(SCH_1):VR_FB_PVPP_ABC

CAP_0603-4.7UF,6.3V,10%,X6S,E1A  I202  C3T11
   1 VR_VB_PVPP_ABC      A @BASEBOARD_FAB2_LIB.BASEBOARD_FAB2(SCH_1):VR_VB_PVPP_ABC
   2 AGND_PVPP_ABC      B @BASEBOARD_FAB2_LIB.BASEBOARD_FAB2(SCH_1):AGND_PVPP_ABC

CAP_A_0402V-0.1UF,16V,10%,X7R,A  I205  C7F6
   1 VR_FET_SW_P12V_STBY_PVPP_ABC      A @BASEBOARD_FAB2_LIB.BASEBOARD_FAB2(SCH_1):VR_FET_SW_P12V_STBY_PVPP_ABC
   2    GND      B @BASEBOARD_FAB2_LIB.BASEBOARD_FAB2(SCH_1):GND

RES_0402-22.1,1.0%,1/16W,CHIP,A  I208  R7F16
   1 PWRGD_PVPP_ABC_R      A @BASEBOARD_FAB2_LIB.BASEBOARD_FAB2(SCH_1):PWRGD_PVPP_ABC_R
   2 PWRGD_PVPP_ABC      B @BASEBOARD_FAB2_LIB.BASEBOARD_FAB2(SCH_1):PWRGD_PVPP_ABC

CAP_0805-10UF,16V,10%,X6S,C953A  I209  C7F5
   1 VR_FET_SW_P12V_STBY_PVPP_ABC      A @BASEBOARD_FAB2_LIB.BASEBOARD_FAB2(SCH_1):VR_FET_SW_P12V_STBY_PVPP_ABC
   2    GND      B @BASEBOARD_FAB2_LIB.BASEBOARD_FAB2(SCH_1):GND

CAP_0805-10UF,16V,10%,X6S,C953A  I210  C3T8
   1 VR_FET_SW_P12V_STBY_PVPP_ABC      A @BASEBOARD_FAB2_LIB.BASEBOARD_FAB2(SCH_1):VR_FET_SW_P12V_STBY_PVPP_ABC
   2    GND      B @BASEBOARD_FAB2_LIB.BASEBOARD_FAB2(SCH_1):GND

CAP_0805-10UF,16V,10%,X6S,C953A  I211  C3T14
   1 VR_FET_SW_P12V_STBY_PVPP_ABC      A @BASEBOARD_FAB2_LIB.BASEBOARD_FAB2(SCH_1):VR_FET_SW_P12V_STBY_PVPP_ABC
   2    GND      B @BASEBOARD_FAB2_LIB.BASEBOARD_FAB2(SCH_1):GND

CAP_0805-10UF,16V,10%,X6S,C953A  I215  C3T12
   1 VR_FET_SW_P12V_STBY_PVPP_ABC      A @BASEBOARD_FAB2_LIB.BASEBOARD_FAB2(SCH_1):VR_FET_SW_P12V_STBY_PVPP_ABC
   2    GND      B @BASEBOARD_FAB2_LIB.BASEBOARD_FAB2(SCH_1):GND

CAPP_7343-220UF,4V,20%,POSCAP,A  I217  C4T3
   1 PVPP_ABC      A @BASEBOARD_FAB2_LIB.BASEBOARD_FAB2(SCH_1):PVPP_ABC
   2    GND      B @BASEBOARD_FAB2_LIB.BASEBOARD_FAB2(SCH_1):GND

RES_0402-1.0K,0.1%,1/16W,CHIP,A  I218  R7F17
   1 VSENSE_PVPP_ABC      A @BASEBOARD_FAB2_LIB.BASEBOARD_FAB2(SCH_1):VSENSE_PVPP_ABC
   2 VR_COMP_PVPP_ABC      B @BASEBOARD_FAB2_LIB.BASEBOARD_FAB2(SCH_1):VR_COMP_PVPP_ABC

CAP_0402LF-2200PF,50V,10%,X7R,A  I219  C7F13
   1 VR_COMP_PVPP_ABC      A @BASEBOARD_FAB2_LIB.BASEBOARD_FAB2(SCH_1):VR_COMP_PVPP_ABC
   2 VR_FB_PVPP_ABC      B @BASEBOARD_FAB2_LIB.BASEBOARD_FAB2(SCH_1):VR_FB_PVPP_ABC

RES_0402-0.0,5%,1/16W,CHIP,G21A  I220  R7F9
   1 FM_PVPP_CPU0_EN      A @BASEBOARD_FAB2_LIB.BASEBOARD_FAB2(SCH_1):FM_PVPP_CPU0_EN
   2 FM_PVPP_PVDDQ_CPU0_EN_ABC      B @BASEBOARD_FAB2_LIB.BASEBOARD_FAB2(SCH_1):FM_PVPP_PVDDQ_CPU0_EN_ABC

SC22U16V5MX-4-GP_SMD-BCG5-SC22A  I225  C22W10
   1 VR_FET_SW_P12V_STBY_PVPP_ABC      1 @BASEBOARD_FAB2_LIB.BASEBOARD_FAB2(SCH_1):VR_FET_SW_P12V_STBY_PVPP_ABC
   2    GND      2 @BASEBOARD_FAB2_LIB.BASEBOARD_FAB2(SCH_1):GND

SC22U16V5MX-4-GP_SMD-BCG5-SC22A  I226  C7F7
   1 VR_FET_SW_P12V_STBY_PVPP_ABC      1 @BASEBOARD_FAB2_LIB.BASEBOARD_FAB2(SCH_1):VR_FET_SW_P12V_STBY_PVPP_ABC
   2    GND      2 @BASEBOARD_FAB2_LIB.BASEBOARD_FAB2(SCH_1):GND

RES_0603-0,5.0%,1/10W,CHIP,G22A  I229  R7F8
   1 VR_PVPP_ABC_BOOT      A @BASEBOARD_FAB2_LIB.BASEBOARD_FAB2(SCH_1):VR_PVPP_ABC_BOOT
   2 VR_PVPP_ABC_BOOT_R      B @BASEBOARD_FAB2_LIB.BASEBOARD_FAB2(SCH_1):VR_PVPP_ABC_BOOT_R

RES_0402-6.19K,1%,1/16W,CHIP,GA  I230  R7F11
   1 VR_FB_PVPP_ABC      A @BASEBOARD_FAB2_LIB.BASEBOARD_FAB2(SCH_1):VR_FB_PVPP_ABC
   2 AGND_PVPP_ABC      B @BASEBOARD_FAB2_LIB.BASEBOARD_FAB2(SCH_1):AGND_PVPP_ABC


DRAWING: @BASEBOARD_FAB2_LIB.BASEBOARD_FAB2(SCH_1):PAGE232 

CAP_0603LF-10UF,4V,20%,X6S,E15A  I102  C4L2
   1 PVPP_DEF      A @BASEBOARD_FAB2_LIB.BASEBOARD_FAB2(SCH_1):PVPP_DEF
   2    GND      B @BASEBOARD_FAB2_LIB.BASEBOARD_FAB2(SCH_1):GND

CAP_0603LF-10UF,4V,20%,X6S,E15A  I104  C6A3
   1 PVPP_DEF      A @BASEBOARD_FAB2_LIB.BASEBOARD_FAB2(SCH_1):PVPP_DEF
   2    GND      B @BASEBOARD_FAB2_LIB.BASEBOARD_FAB2(SCH_1):GND

CAP_0603LF-10UF,4V,20%,X6S,E15A  I105  C6A2
   1 PVPP_DEF      A @BASEBOARD_FAB2_LIB.BASEBOARD_FAB2(SCH_1):PVPP_DEF
   2    GND      B @BASEBOARD_FAB2_LIB.BASEBOARD_FAB2(SCH_1):GND

CAP_0603LF-10UF,4V,20%,X6S,E15A  I106  C4L3
   1 PVPP_DEF      A @BASEBOARD_FAB2_LIB.BASEBOARD_FAB2(SCH_1):PVPP_DEF
   2    GND      B @BASEBOARD_FAB2_LIB.BASEBOARD_FAB2(SCH_1):GND

CAP_0603LF-10UF,4V,20%,X6S,E15A  I108  C4L4
   1 PVPP_DEF      A @BASEBOARD_FAB2_LIB.BASEBOARD_FAB2(SCH_1):PVPP_DEF
   2    GND      B @BASEBOARD_FAB2_LIB.BASEBOARD_FAB2(SCH_1):GND

CAP_0603LF-10UF,4V,20%,X6S,E15A  I109  C6A7
   1 PVPP_DEF      A @BASEBOARD_FAB2_LIB.BASEBOARD_FAB2(SCH_1):PVPP_DEF
   2    GND      B @BASEBOARD_FAB2_LIB.BASEBOARD_FAB2(SCH_1):GND

CAP_0603LF-10UF,4V,20%,X6S,E15A  I110  C6A6
   1 PVPP_DEF      A @BASEBOARD_FAB2_LIB.BASEBOARD_FAB2(SCH_1):PVPP_DEF
   2    GND      B @BASEBOARD_FAB2_LIB.BASEBOARD_FAB2(SCH_1):GND

CAP_0603LF-10UF,4V,20%,X6S,E15A  I111  C4M3
   1 PVPP_DEF      A @BASEBOARD_FAB2_LIB.BASEBOARD_FAB2(SCH_1):PVPP_DEF
   2    GND      B @BASEBOARD_FAB2_LIB.BASEBOARD_FAB2(SCH_1):GND

CAP_0603LF-10UF,4V,20%,X6S,E15A  I125  C4M4
   1 PVPP_DEF      A @BASEBOARD_FAB2_LIB.BASEBOARD_FAB2(SCH_1):PVPP_DEF
   2    GND      B @BASEBOARD_FAB2_LIB.BASEBOARD_FAB2(SCH_1):GND

CAP_0603LF-10UF,4V,20%,X6S,E15A  I126  C6B2
   1 PVPP_DEF      A @BASEBOARD_FAB2_LIB.BASEBOARD_FAB2(SCH_1):PVPP_DEF
   2    GND      B @BASEBOARD_FAB2_LIB.BASEBOARD_FAB2(SCH_1):GND

CAP_0603LF-10UF,4V,20%,X6S,E15A  I128  C6B1
   1 PVPP_DEF      A @BASEBOARD_FAB2_LIB.BASEBOARD_FAB2(SCH_1):PVPP_DEF
   2    GND      B @BASEBOARD_FAB2_LIB.BASEBOARD_FAB2(SCH_1):GND

CAP_0603LF-10UF,4V,20%,X6S,E15A  I129  C4L1
   1 PVPP_DEF      A @BASEBOARD_FAB2_LIB.BASEBOARD_FAB2(SCH_1):PVPP_DEF
   2    GND      B @BASEBOARD_FAB2_LIB.BASEBOARD_FAB2(SCH_1):GND

RES_0402-0.0,5%,1/16W,CHIP,G21A  I150  R7B20
   1    GND      A @BASEBOARD_FAB2_LIB.BASEBOARD_FAB2(SCH_1):GND
   2 AGND_PVPP_DEF      B @BASEBOARD_FAB2_LIB.BASEBOARD_FAB2(SCH_1):AGND_PVPP_DEF

CAP_0402LF-1000PF,50V,10%,EMPTA  I185  C7B9
   1 FM_PVPP_CPU0_EN      A @BASEBOARD_FAB2_LIB.BASEBOARD_FAB2(SCH_1):FM_PVPP_CPU0_EN
   2 AGND_PVPP_DEF      B @BASEBOARD_FAB2_LIB.BASEBOARD_FAB2(SCH_1):AGND_PVPP_DEF

CAP_0402-0.027UF,16V,10%,X7R,AA  I197  C7B11
   1 VR_PVPP_DEF_SS      A @BASEBOARD_FAB2_LIB.BASEBOARD_FAB2(SCH_1):VR_PVPP_DEF_SS
   2 AGND_PVPP_DEF      B @BASEBOARD_FAB2_LIB.BASEBOARD_FAB2(SCH_1):AGND_PVPP_DEF

FERRITE_SM-22,FB,656554-051  I200  FB7B1
   1 P12V_STBY      A @BASEBOARD_FAB2_LIB.BASEBOARD_FAB2(SCH_1):P12V_STBY
   2 VR_FET_SW_P12V_STBY_PVPP_DEF      B @BASEBOARD_FAB2_LIB.BASEBOARD_FAB2(SCH_1):VR_FET_SW_P12V_STBY_PVPP_DEF

CAP_0402-1.0UF,16V,10%,X6S,D97A  I207  C3M9
   1 VR_FET_SW_P12V_STBY_PVPP_DEF      A @BASEBOARD_FAB2_LIB.BASEBOARD_FAB2(SCH_1):VR_FET_SW_P12V_STBY_PVPP_DEF
   2    GND      B @BASEBOARD_FAB2_LIB.BASEBOARD_FAB2(SCH_1):GND

CAP_0402LF-1000PF,50V,10%,X7R,A  I209  C7B12
   1 PWRGD_PVPP_DEF_R      A @BASEBOARD_FAB2_LIB.BASEBOARD_FAB2(SCH_1):PWRGD_PVPP_DEF_R
   2    GND      B @BASEBOARD_FAB2_LIB.BASEBOARD_FAB2(SCH_1):GND

RES_0402-1.00K,1%,1/16W,CHIP,GA  I210  R7B17
   1 P3V3_STBY      A @BASEBOARD_FAB2_LIB.BASEBOARD_FAB2(SCH_1):P3V3_STBY
   2 PWRGD_PVPP_DEF_R      B @BASEBOARD_FAB2_LIB.BASEBOARD_FAB2(SCH_1):PWRGD_PVPP_DEF_R

NCP3232L_SM-IC,H86355-001  I214  EU7B1
   5 AGND_PVPP_DEF   AGND @BASEBOARD_FAB2_LIB.BASEBOARD_FAB2(SCH_1):AGND_PVPP_DEF
  36 VR_PVPP_DEF_BOOT    BST @BASEBOARD_FAB2_LIB.BASEBOARD_FAB2(SCH_1):VR_PVPP_DEF_BOOT
   3 VR_COMP_PVPP_DEF_3   COMP @BASEBOARD_FAB2_LIB.BASEBOARD_FAB2(SCH_1):VR_COMP_PVPP_DEF_3
  40 FM_PVPP_PVDDQ_CPU0_EN_DEF     EN @BASEBOARD_FAB2_LIB.BASEBOARD_FAB2(SCH_1):FM_PVPP_PVDDQ_CPU0_EN_DEF
   2 VR_FB_PVPP_DEF     FB @BASEBOARD_FAB2_LIB.BASEBOARD_FAB2(SCH_1):VR_FB_PVPP_DEF
  41    GND    GND @BASEBOARD_FAB2_LIB.BASEBOARD_FAB2(SCH_1):GND
   4 VR_PVPP_DEF_ISET   ISET @BASEBOARD_FAB2_LIB.BASEBOARD_FAB2(SCH_1):VR_PVPP_DEF_ISET
   6 AGND_PVPP_DEF    OTS @BASEBOARD_FAB2_LIB.BASEBOARD_FAB2(SCH_1):AGND_PVPP_DEF
   7 PWRGD_PVPP_DEF_R     PG @BASEBOARD_FAB2_LIB.BASEBOARD_FAB2(SCH_1):PWRGD_PVPP_DEF_R
  37    GND PGND<13> @BASEBOARD_FAB2_LIB.BASEBOARD_FAB2(SCH_1):GND
  28    GND PGND<12> @BASEBOARD_FAB2_LIB.BASEBOARD_FAB2(SCH_1):GND
  27    GND PGND<11> @BASEBOARD_FAB2_LIB.BASEBOARD_FAB2(SCH_1):GND
  26    GND PGND<10> @BASEBOARD_FAB2_LIB.BASEBOARD_FAB2(SCH_1):GND
  25    GND PGND<9> @BASEBOARD_FAB2_LIB.BASEBOARD_FAB2(SCH_1):GND
  24    GND PGND<8> @BASEBOARD_FAB2_LIB.BASEBOARD_FAB2(SCH_1):GND
  23    GND PGND<7> @BASEBOARD_FAB2_LIB.BASEBOARD_FAB2(SCH_1):GND
  22    GND PGND<6> @BASEBOARD_FAB2_LIB.BASEBOARD_FAB2(SCH_1):GND
  21    GND PGND<5> @BASEBOARD_FAB2_LIB.BASEBOARD_FAB2(SCH_1):GND
  20    GND PGND<4> @BASEBOARD_FAB2_LIB.BASEBOARD_FAB2(SCH_1):GND
  19    GND PGND<3> @BASEBOARD_FAB2_LIB.BASEBOARD_FAB2(SCH_1):GND
  18    GND PGND<2> @BASEBOARD_FAB2_LIB.BASEBOARD_FAB2(SCH_1):GND
  17    GND PGND<1> @BASEBOARD_FAB2_LIB.BASEBOARD_FAB2(SCH_1):GND
  16    GND PGND<0> @BASEBOARD_FAB2_LIB.BASEBOARD_FAB2(SCH_1):GND
   1 VR_PVPP_DEF_SS     SS @BASEBOARD_FAB2_LIB.BASEBOARD_FAB2(SCH_1):VR_PVPP_DEF_SS
  38 VR_VB_PVPP_DEF     VB @BASEBOARD_FAB2_LIB.BASEBOARD_FAB2(SCH_1):VR_VB_PVPP_DEF
  39 VR_FET_SW_P12V_STBY_PVPP_DEF    VCC @BASEBOARD_FAB2_LIB.BASEBOARD_FAB2(SCH_1):VR_FET_SW_P12V_STBY_PVPP_DEF
  42 VR_FET_SW_P12V_STBY_PVPP_DEF VIN<7> @BASEBOARD_FAB2_LIB.BASEBOARD_FAB2(SCH_1):VR_FET_SW_P12V_STBY_PVPP_DEF
  14 VR_FET_SW_P12V_STBY_PVPP_DEF VIN<6> @BASEBOARD_FAB2_LIB.BASEBOARD_FAB2(SCH_1):VR_FET_SW_P12V_STBY_PVPP_DEF
  13 VR_FET_SW_P12V_STBY_PVPP_DEF VIN<5> @BASEBOARD_FAB2_LIB.BASEBOARD_FAB2(SCH_1):VR_FET_SW_P12V_STBY_PVPP_DEF
  12 VR_FET_SW_P12V_STBY_PVPP_DEF VIN<4> @BASEBOARD_FAB2_LIB.BASEBOARD_FAB2(SCH_1):VR_FET_SW_P12V_STBY_PVPP_DEF
  11 VR_FET_SW_P12V_STBY_PVPP_DEF VIN<3> @BASEBOARD_FAB2_LIB.BASEBOARD_FAB2(SCH_1):VR_FET_SW_P12V_STBY_PVPP_DEF
  10 VR_FET_SW_P12V_STBY_PVPP_DEF VIN<2> @BASEBOARD_FAB2_LIB.BASEBOARD_FAB2(SCH_1):VR_FET_SW_P12V_STBY_PVPP_DEF
   9 VR_FET_SW_P12V_STBY_PVPP_DEF VIN<1> @BASEBOARD_FAB2_LIB.BASEBOARD_FAB2(SCH_1):VR_FET_SW_P12V_STBY_PVPP_DEF
   8 VR_FET_SW_P12V_STBY_PVPP_DEF VIN<0> @BASEBOARD_FAB2_LIB.BASEBOARD_FAB2(SCH_1):VR_FET_SW_P12V_STBY_PVPP_DEF
  35 VR_PVPP_DEF_PHASE    VSW @BASEBOARD_FAB2_LIB.BASEBOARD_FAB2(SCH_1):VR_PVPP_DEF_PHASE
  43 VR_PVPP_DEF_PHASE VSWH<7> @BASEBOARD_FAB2_LIB.BASEBOARD_FAB2(SCH_1):VR_PVPP_DEF_PHASE
  34 VR_PVPP_DEF_PHASE VSWH<6> @BASEBOARD_FAB2_LIB.BASEBOARD_FAB2(SCH_1):VR_PVPP_DEF_PHASE
  33 VR_PVPP_DEF_PHASE VSWH<5> @BASEBOARD_FAB2_LIB.BASEBOARD_FAB2(SCH_1):VR_PVPP_DEF_PHASE
  32 VR_PVPP_DEF_PHASE VSWH<4> @BASEBOARD_FAB2_LIB.BASEBOARD_FAB2(SCH_1):VR_PVPP_DEF_PHASE
  31 VR_PVPP_DEF_PHASE VSWH<3> @BASEBOARD_FAB2_LIB.BASEBOARD_FAB2(SCH_1):VR_PVPP_DEF_PHASE
  30 VR_PVPP_DEF_PHASE VSWH<2> @BASEBOARD_FAB2_LIB.BASEBOARD_FAB2(SCH_1):VR_PVPP_DEF_PHASE
  29 VR_PVPP_DEF_PHASE VSWH<1> @BASEBOARD_FAB2_LIB.BASEBOARD_FAB2(SCH_1):VR_PVPP_DEF_PHASE
  15 VR_PVPP_DEF_PHASE VSWH<0> @BASEBOARD_FAB2_LIB.BASEBOARD_FAB2(SCH_1):VR_PVPP_DEF_PHASE

RES_0402-2.2,5%,1/16W,EMPTY,G2A  I218  R7A15
   1 VR_PVPP_DEF_SNUB      A @BASEBOARD_FAB2_LIB.BASEBOARD_FAB2(SCH_1):VR_PVPP_DEF_SNUB
   2    GND      B @BASEBOARD_FAB2_LIB.BASEBOARD_FAB2(SCH_1):GND

CAP_0402LF-3300PF,50V,10%,EMPTA  I220  C7A34
   1 VR_PVPP_DEF_PHASE      A @BASEBOARD_FAB2_LIB.BASEBOARD_FAB2(SCH_1):VR_PVPP_DEF_PHASE
   2 VR_PVPP_DEF_SNUB      B @BASEBOARD_FAB2_LIB.BASEBOARD_FAB2(SCH_1):VR_PVPP_DEF_SNUB

RES_0603-120.0,1%,1/10W,CHIP,GA  I227  R7B10
   1 PVPP_DEF      A @BASEBOARD_FAB2_LIB.BASEBOARD_FAB2(SCH_1):PVPP_DEF
   2    GND      B @BASEBOARD_FAB2_LIB.BASEBOARD_FAB2(SCH_1):GND

CAPP_7343LF-330UF,6.3V,20%,POSA  I229  C6B7
   1 PVPP_DEF      A @BASEBOARD_FAB2_LIB.BASEBOARD_FAB2(SCH_1):PVPP_DEF
   2    GND      B @BASEBOARD_FAB2_LIB.BASEBOARD_FAB2(SCH_1):GND

CAP_0805-47UF,4V,20%,X6S,C9533A  I236  C6B3
   1 PVPP_DEF      A @BASEBOARD_FAB2_LIB.BASEBOARD_FAB2(SCH_1):PVPP_DEF
   2    GND      B @BASEBOARD_FAB2_LIB.BASEBOARD_FAB2(SCH_1):GND

CAP_0805-47UF,4V,20%,X6S,C9533A  I238  C7B7
   1 PVPP_DEF      A @BASEBOARD_FAB2_LIB.BASEBOARD_FAB2(SCH_1):PVPP_DEF
   2    GND      B @BASEBOARD_FAB2_LIB.BASEBOARD_FAB2(SCH_1):GND

INDUCTOR_SM-0.47UH,IND,E13358-A  I239  L7B1
   1 VR_PVPP_DEF_PHASE    INA @BASEBOARD_FAB2_LIB.BASEBOARD_FAB2(SCH_1):VR_PVPP_DEF_PHASE
   2 PVPP_DEF    INB @BASEBOARD_FAB2_LIB.BASEBOARD_FAB2(SCH_1):PVPP_DEF

CAP_0603LF-0.1UF,25V,10%,X7R,6A  I241  C7B30
   1 VR_PVPP_DEF_PHASE      A @BASEBOARD_FAB2_LIB.BASEBOARD_FAB2(SCH_1):VR_PVPP_DEF_PHASE
   2 VR_PVPP_DEF_BOOT_R      B @BASEBOARD_FAB2_LIB.BASEBOARD_FAB2(SCH_1):VR_PVPP_DEF_BOOT_R

CAP_A_0402V-0.1UF,16V,10%,X7R,A  I252  C7B6
   1 VR_FET_SW_P12V_STBY_PVPP_DEF      A @BASEBOARD_FAB2_LIB.BASEBOARD_FAB2(SCH_1):VR_FET_SW_P12V_STBY_PVPP_DEF
   2    GND      B @BASEBOARD_FAB2_LIB.BASEBOARD_FAB2(SCH_1):GND

CAP_0603-4.7UF,6.3V,10%,X6S,E1A  I253  C3M10
   1 VR_VB_PVPP_DEF      A @BASEBOARD_FAB2_LIB.BASEBOARD_FAB2(SCH_1):VR_VB_PVPP_DEF
   2 AGND_PVPP_DEF      B @BASEBOARD_FAB2_LIB.BASEBOARD_FAB2(SCH_1):AGND_PVPP_DEF

RES_0402-22.1,1.0%,1/16W,CHIP,A  I257  R7B12
   1 PWRGD_PVPP_DEF_R      A @BASEBOARD_FAB2_LIB.BASEBOARD_FAB2(SCH_1):PWRGD_PVPP_DEF_R
   2 PWRGD_PVPP_DEF      B @BASEBOARD_FAB2_LIB.BASEBOARD_FAB2(SCH_1):PWRGD_PVPP_DEF

CAP_0805-10UF,16V,10%,X6S,C953A  I259  C3M8
   1 VR_FET_SW_P12V_STBY_PVPP_DEF      A @BASEBOARD_FAB2_LIB.BASEBOARD_FAB2(SCH_1):VR_FET_SW_P12V_STBY_PVPP_DEF
   2    GND      B @BASEBOARD_FAB2_LIB.BASEBOARD_FAB2(SCH_1):GND

CAP_0805-10UF,16V,10%,X6S,C953A  I260  C3M15
   1 VR_FET_SW_P12V_STBY_PVPP_DEF      A @BASEBOARD_FAB2_LIB.BASEBOARD_FAB2(SCH_1):VR_FET_SW_P12V_STBY_PVPP_DEF
   2    GND      B @BASEBOARD_FAB2_LIB.BASEBOARD_FAB2(SCH_1):GND

CAP_0805-10UF,16V,10%,X6S,C953A  I261  C3M16
   1 VR_FET_SW_P12V_STBY_PVPP_DEF      A @BASEBOARD_FAB2_LIB.BASEBOARD_FAB2(SCH_1):VR_FET_SW_P12V_STBY_PVPP_DEF
   2    GND      B @BASEBOARD_FAB2_LIB.BASEBOARD_FAB2(SCH_1):GND

CAP_0805-10UF,16V,10%,X6S,C953A  I262  C7B5
   1 VR_FET_SW_P12V_STBY_PVPP_DEF      A @BASEBOARD_FAB2_LIB.BASEBOARD_FAB2(SCH_1):VR_FET_SW_P12V_STBY_PVPP_DEF
   2    GND      B @BASEBOARD_FAB2_LIB.BASEBOARD_FAB2(SCH_1):GND

CAPP_7343-220UF,4V,20%,POSCAP,A  I267  C4M1
   1 PVPP_DEF      A @BASEBOARD_FAB2_LIB.BASEBOARD_FAB2(SCH_1):PVPP_DEF
   2    GND      B @BASEBOARD_FAB2_LIB.BASEBOARD_FAB2(SCH_1):GND

RES_0402-1.0K,0.1%,1/16W,CHIP,A  I298  R7B18
   1 VSENSE_PVPP_DEF      A @BASEBOARD_FAB2_LIB.BASEBOARD_FAB2(SCH_1):VSENSE_PVPP_DEF
   2 VR_COMP_PVPP_DEF      B @BASEBOARD_FAB2_LIB.BASEBOARD_FAB2(SCH_1):VR_COMP_PVPP_DEF

RES_0402-0.0,5%,1/16W,CHIP,G21A  I299  R7B11
   1 PVPP_DEF      A @BASEBOARD_FAB2_LIB.BASEBOARD_FAB2(SCH_1):PVPP_DEF
   2 VSENSE_PVPP_DEF      B @BASEBOARD_FAB2_LIB.BASEBOARD_FAB2(SCH_1):VSENSE_PVPP_DEF

RES_0402-7.87K,1.0%,1/16W,CHIPA  I300  R7B16
   1 VR_COMP_RC_PVPP_DEF      A @BASEBOARD_FAB2_LIB.BASEBOARD_FAB2(SCH_1):VR_COMP_RC_PVPP_DEF
   2 VR_FB_PVPP_DEF      B @BASEBOARD_FAB2_LIB.BASEBOARD_FAB2(SCH_1):VR_FB_PVPP_DEF

CAP_0402LF-100.0PF,50V,5%,COG,A  I301  C7B10
   1 VR_FB_PVPP_DEF      A @BASEBOARD_FAB2_LIB.BASEBOARD_FAB2(SCH_1):VR_FB_PVPP_DEF
   2 VR_COMP_PVPP_DEF_3      B @BASEBOARD_FAB2_LIB.BASEBOARD_FAB2(SCH_1):VR_COMP_PVPP_DEF_3

CAP_0402LF-2200PF,50V,10%,X7R,A  I302  C7B13
   1 VR_COMP_PVPP_DEF      A @BASEBOARD_FAB2_LIB.BASEBOARD_FAB2(SCH_1):VR_COMP_PVPP_DEF
   2 VR_FB_PVPP_DEF      B @BASEBOARD_FAB2_LIB.BASEBOARD_FAB2(SCH_1):VR_FB_PVPP_DEF

RES_0402-20.0K,1%,1/16W,CHIP,GA  I303  R7B15
   1 VSENSE_PVPP_DEF      A @BASEBOARD_FAB2_LIB.BASEBOARD_FAB2(SCH_1):VSENSE_PVPP_DEF
   2 VR_FB_PVPP_DEF      B @BASEBOARD_FAB2_LIB.BASEBOARD_FAB2(SCH_1):VR_FB_PVPP_DEF

CAP_0402LF-2200PF,50V,10%,X7R,A  I306  C7B14
   1 VR_COMP_RC_PVPP_DEF      A @BASEBOARD_FAB2_LIB.BASEBOARD_FAB2(SCH_1):VR_COMP_RC_PVPP_DEF
   2 VR_COMP_PVPP_DEF_3      B @BASEBOARD_FAB2_LIB.BASEBOARD_FAB2(SCH_1):VR_COMP_PVPP_DEF_3

RES_0402-0.0,5%,1/16W,CHIP,G21A  I307  R7B9
   1 FM_PVPP_CPU0_EN      A @BASEBOARD_FAB2_LIB.BASEBOARD_FAB2(SCH_1):FM_PVPP_CPU0_EN
   2 FM_PVPP_PVDDQ_CPU0_EN_DEF      B @BASEBOARD_FAB2_LIB.BASEBOARD_FAB2(SCH_1):FM_PVPP_PVDDQ_CPU0_EN_DEF

SC22U16V5MX-4-GP_SMD-BCG5-SC22A  I309  C7B8
   1 VR_FET_SW_P12V_STBY_PVPP_DEF      1 @BASEBOARD_FAB2_LIB.BASEBOARD_FAB2(SCH_1):VR_FET_SW_P12V_STBY_PVPP_DEF
   2    GND      2 @BASEBOARD_FAB2_LIB.BASEBOARD_FAB2(SCH_1):GND

SC22U16V5MX-4-GP_SMD-BCG5-SC22A  I311  C22W7
   1 VR_FET_SW_P12V_STBY_PVPP_DEF      1 @BASEBOARD_FAB2_LIB.BASEBOARD_FAB2(SCH_1):VR_FET_SW_P12V_STBY_PVPP_DEF
   2    GND      2 @BASEBOARD_FAB2_LIB.BASEBOARD_FAB2(SCH_1):GND

RES_0603-0,5.0%,1/10W,CHIP,G22A  I313  R7B19
   1 VR_PVPP_DEF_BOOT      A @BASEBOARD_FAB2_LIB.BASEBOARD_FAB2(SCH_1):VR_PVPP_DEF_BOOT
   2 VR_PVPP_DEF_BOOT_R      B @BASEBOARD_FAB2_LIB.BASEBOARD_FAB2(SCH_1):VR_PVPP_DEF_BOOT_R

RES_0402-6.19K,1%,1/16W,CHIP,GA  I314  R7B13
   1 VR_FB_PVPP_DEF      A @BASEBOARD_FAB2_LIB.BASEBOARD_FAB2(SCH_1):VR_FB_PVPP_DEF
   2 AGND_PVPP_DEF      B @BASEBOARD_FAB2_LIB.BASEBOARD_FAB2(SCH_1):AGND_PVPP_DEF

RES_0402-7.87K,1.0%,1/16W,CHIPA  I315  R7B14
   1 VR_PVPP_DEF_ISET      A @BASEBOARD_FAB2_LIB.BASEBOARD_FAB2(SCH_1):VR_PVPP_DEF_ISET
   2 AGND_PVPP_DEF      B @BASEBOARD_FAB2_LIB.BASEBOARD_FAB2(SCH_1):AGND_PVPP_DEF


DRAWING: @BASEBOARD_FAB2_LIB.BASEBOARD_FAB2(SCH_1):PAGE233 

CAP_0603LF-10UF,4V,20%,X6S,E15A  I109  C7U4
   1 PVPP_GHJ      A @BASEBOARD_FAB2_LIB.BASEBOARD_FAB2(SCH_1):PVPP_GHJ
   2    GND      B @BASEBOARD_FAB2_LIB.BASEBOARD_FAB2(SCH_1):GND

CAP_0603LF-10UF,4V,20%,X6S,E15A  I111  C7U5
   1 PVPP_GHJ      A @BASEBOARD_FAB2_LIB.BASEBOARD_FAB2(SCH_1):PVPP_GHJ
   2    GND      B @BASEBOARD_FAB2_LIB.BASEBOARD_FAB2(SCH_1):GND

CAP_0603LF-10UF,4V,20%,X6S,E15A  I112  C7T2
   1 PVPP_GHJ      A @BASEBOARD_FAB2_LIB.BASEBOARD_FAB2(SCH_1):PVPP_GHJ
   2    GND      B @BASEBOARD_FAB2_LIB.BASEBOARD_FAB2(SCH_1):GND

CAP_0603LF-10UF,4V,20%,X6S,E15A  I113  C7T3
   1 PVPP_GHJ      A @BASEBOARD_FAB2_LIB.BASEBOARD_FAB2(SCH_1):PVPP_GHJ
   2    GND      B @BASEBOARD_FAB2_LIB.BASEBOARD_FAB2(SCH_1):GND

CAP_0603LF-10UF,4V,20%,X6S,E15A  I115  C7U6
   1 PVPP_GHJ      A @BASEBOARD_FAB2_LIB.BASEBOARD_FAB2(SCH_1):PVPP_GHJ
   2    GND      B @BASEBOARD_FAB2_LIB.BASEBOARD_FAB2(SCH_1):GND

CAP_0603LF-10UF,4V,20%,X6S,E15A  I116  C3F3
   1 PVPP_GHJ      A @BASEBOARD_FAB2_LIB.BASEBOARD_FAB2(SCH_1):PVPP_GHJ
   2    GND      B @BASEBOARD_FAB2_LIB.BASEBOARD_FAB2(SCH_1):GND

CAP_0603LF-10UF,4V,20%,X6S,E15A  I117  C3F4
   1 PVPP_GHJ      A @BASEBOARD_FAB2_LIB.BASEBOARD_FAB2(SCH_1):PVPP_GHJ
   2    GND      B @BASEBOARD_FAB2_LIB.BASEBOARD_FAB2(SCH_1):GND

CAP_0603LF-10UF,4V,20%,X6S,E15A  I118  C3G3
   1 PVPP_GHJ      A @BASEBOARD_FAB2_LIB.BASEBOARD_FAB2(SCH_1):PVPP_GHJ
   2    GND      B @BASEBOARD_FAB2_LIB.BASEBOARD_FAB2(SCH_1):GND

CAP_0603LF-10UF,4V,20%,X6S,E15A  I132  C3G7
   1 PVPP_GHJ      A @BASEBOARD_FAB2_LIB.BASEBOARD_FAB2(SCH_1):PVPP_GHJ
   2    GND      B @BASEBOARD_FAB2_LIB.BASEBOARD_FAB2(SCH_1):GND

CAP_0603LF-10UF,4V,20%,X6S,E15A  I133  C3G4
   1 PVPP_GHJ      A @BASEBOARD_FAB2_LIB.BASEBOARD_FAB2(SCH_1):PVPP_GHJ
   2    GND      B @BASEBOARD_FAB2_LIB.BASEBOARD_FAB2(SCH_1):GND

CAP_0603LF-10UF,4V,20%,X6S,E15A  I135  C3G8
   1 PVPP_GHJ      A @BASEBOARD_FAB2_LIB.BASEBOARD_FAB2(SCH_1):PVPP_GHJ
   2    GND      B @BASEBOARD_FAB2_LIB.BASEBOARD_FAB2(SCH_1):GND

CAP_0603LF-10UF,4V,20%,X6S,E15A  I136  C7U3
   1 PVPP_GHJ      A @BASEBOARD_FAB2_LIB.BASEBOARD_FAB2(SCH_1):PVPP_GHJ
   2    GND      B @BASEBOARD_FAB2_LIB.BASEBOARD_FAB2(SCH_1):GND

RES_0402-0.0,5%,1/16W,CHIP,G21A  I157  R4G25
   1    GND      A @BASEBOARD_FAB2_LIB.BASEBOARD_FAB2(SCH_1):GND
   2 AGND_PVPP_GHJ      B @BASEBOARD_FAB2_LIB.BASEBOARD_FAB2(SCH_1):AGND_PVPP_GHJ

RES_0402-10.0K,1%,1/16W,CHIP,GA  I182  R4G5
   1 FM_PVPP_CPU1_EN      A @BASEBOARD_FAB2_LIB.BASEBOARD_FAB2(SCH_1):FM_PVPP_CPU1_EN
   2    GND      B @BASEBOARD_FAB2_LIB.BASEBOARD_FAB2(SCH_1):GND

CAP_0402LF-1000PF,50V,10%,EMPTA  I183  C4G7
   1 FM_PVPP_CPU1_EN      A @BASEBOARD_FAB2_LIB.BASEBOARD_FAB2(SCH_1):FM_PVPP_CPU1_EN
   2 AGND_PVPP_GHJ      B @BASEBOARD_FAB2_LIB.BASEBOARD_FAB2(SCH_1):AGND_PVPP_GHJ

RES_0402-1.00K,1%,1/16W,CHIP,GA  I185  R4G14
   1 P3V3_STBY      A @BASEBOARD_FAB2_LIB.BASEBOARD_FAB2(SCH_1):P3V3_STBY
   2 PWRGD_PVPP_GHJ_R      B @BASEBOARD_FAB2_LIB.BASEBOARD_FAB2(SCH_1):PWRGD_PVPP_GHJ_R

CAP_0603-4.7UF,6.3V,10%,X6S,E1A  I187  C6U6
   1 VR_VB_PVPP_GHJ      A @BASEBOARD_FAB2_LIB.BASEBOARD_FAB2(SCH_1):VR_VB_PVPP_GHJ
   2 AGND_PVPP_GHJ      B @BASEBOARD_FAB2_LIB.BASEBOARD_FAB2(SCH_1):AGND_PVPP_GHJ

CAP_0402-0.027UF,16V,10%,X7R,AA  I194  C4G8
   1 VR_PVPP_GHJ_SS      A @BASEBOARD_FAB2_LIB.BASEBOARD_FAB2(SCH_1):VR_PVPP_GHJ_SS
   2 AGND_PVPP_GHJ      B @BASEBOARD_FAB2_LIB.BASEBOARD_FAB2(SCH_1):AGND_PVPP_GHJ

CAP_0402-1.0UF,16V,10%,X6S,D97A  I196  C4G4
   1 VR_FET_SW_P12V_STBY_PVPP_GHJ      A @BASEBOARD_FAB2_LIB.BASEBOARD_FAB2(SCH_1):VR_FET_SW_P12V_STBY_PVPP_GHJ
   2    GND      B @BASEBOARD_FAB2_LIB.BASEBOARD_FAB2(SCH_1):GND

FERRITE_SM-22,FB,656554-051  I198  FB4G1
   1 P12V_STBY      A @BASEBOARD_FAB2_LIB.BASEBOARD_FAB2(SCH_1):P12V_STBY
   2 VR_FET_SW_P12V_STBY_PVPP_GHJ      B @BASEBOARD_FAB2_LIB.BASEBOARD_FAB2(SCH_1):VR_FET_SW_P12V_STBY_PVPP_GHJ

CAP_0402LF-1000PF,50V,10%,X7R,A  I201  C4G9
   1 PWRGD_PVPP_GHJ_R      A @BASEBOARD_FAB2_LIB.BASEBOARD_FAB2(SCH_1):PWRGD_PVPP_GHJ_R
   2    GND      B @BASEBOARD_FAB2_LIB.BASEBOARD_FAB2(SCH_1):GND

RES_0402-2.2,5%,1/16W,EMPTY,G2A  I208  R4F6
   1 VR_PVPP_GHJ_SNUB      A @BASEBOARD_FAB2_LIB.BASEBOARD_FAB2(SCH_1):VR_PVPP_GHJ_SNUB
   2    GND      B @BASEBOARD_FAB2_LIB.BASEBOARD_FAB2(SCH_1):GND

CAP_0402LF-3300PF,50V,10%,EMPTA  I209  C4F12
   1 VR_PVPP_GHJ_PHASE      A @BASEBOARD_FAB2_LIB.BASEBOARD_FAB2(SCH_1):VR_PVPP_GHJ_PHASE
   2 VR_PVPP_GHJ_SNUB      B @BASEBOARD_FAB2_LIB.BASEBOARD_FAB2(SCH_1):VR_PVPP_GHJ_SNUB

RES_0603-120.0,1%,1/10W,CHIP,GA  I211  R4G6
   1 PVPP_GHJ      A @BASEBOARD_FAB2_LIB.BASEBOARD_FAB2(SCH_1):PVPP_GHJ
   2    GND      B @BASEBOARD_FAB2_LIB.BASEBOARD_FAB2(SCH_1):GND

CAPP_7343LF-330UF,6.3V,20%,POSA  I217  C4F7
   1 PVPP_GHJ      A @BASEBOARD_FAB2_LIB.BASEBOARD_FAB2(SCH_1):PVPP_GHJ
   2    GND      B @BASEBOARD_FAB2_LIB.BASEBOARD_FAB2(SCH_1):GND

CAP_0805-47UF,4V,20%,X6S,C9533A  I221  C6U3
   1 PVPP_GHJ      A @BASEBOARD_FAB2_LIB.BASEBOARD_FAB2(SCH_1):PVPP_GHJ
   2    GND      B @BASEBOARD_FAB2_LIB.BASEBOARD_FAB2(SCH_1):GND

CAP_0805-47UF,4V,20%,X6S,C9533A  I223  C6U2
   1 PVPP_GHJ      A @BASEBOARD_FAB2_LIB.BASEBOARD_FAB2(SCH_1):PVPP_GHJ
   2    GND      B @BASEBOARD_FAB2_LIB.BASEBOARD_FAB2(SCH_1):GND

CAP_0603LF-0.1UF,25V,10%,X7R,6A  I224  C4G26
   1 VR_PVPP_GHJ_PHASE      A @BASEBOARD_FAB2_LIB.BASEBOARD_FAB2(SCH_1):VR_PVPP_GHJ_PHASE
   2 VR_PVPP_GHJ_BOOT_R      B @BASEBOARD_FAB2_LIB.BASEBOARD_FAB2(SCH_1):VR_PVPP_GHJ_BOOT_R

NCP3232L_SM-IC,H86355-001  I225  EU4G1
   5 AGND_PVPP_GHJ   AGND @BASEBOARD_FAB2_LIB.BASEBOARD_FAB2(SCH_1):AGND_PVPP_GHJ
  36 VR_PVPP_GHJ_BOOT    BST @BASEBOARD_FAB2_LIB.BASEBOARD_FAB2(SCH_1):VR_PVPP_GHJ_BOOT
   3 VR_COMP_PVPP_GHJ_3   COMP @BASEBOARD_FAB2_LIB.BASEBOARD_FAB2(SCH_1):VR_COMP_PVPP_GHJ_3
  40 FM_PVPP_PVDDQ_CPU1_EN_GHJ     EN @BASEBOARD_FAB2_LIB.BASEBOARD_FAB2(SCH_1):FM_PVPP_PVDDQ_CPU1_EN_GHJ
   2 VR_FB_PVPP_GHJ     FB @BASEBOARD_FAB2_LIB.BASEBOARD_FAB2(SCH_1):VR_FB_PVPP_GHJ
  41    GND    GND @BASEBOARD_FAB2_LIB.BASEBOARD_FAB2(SCH_1):GND
   4 VR_PVPP_GHJ_ISET   ISET @BASEBOARD_FAB2_LIB.BASEBOARD_FAB2(SCH_1):VR_PVPP_GHJ_ISET
   6 AGND_PVPP_GHJ    OTS @BASEBOARD_FAB2_LIB.BASEBOARD_FAB2(SCH_1):AGND_PVPP_GHJ
   7 PWRGD_PVPP_GHJ_R     PG @BASEBOARD_FAB2_LIB.BASEBOARD_FAB2(SCH_1):PWRGD_PVPP_GHJ_R
  37    GND PGND<13> @BASEBOARD_FAB2_LIB.BASEBOARD_FAB2(SCH_1):GND
  28    GND PGND<12> @BASEBOARD_FAB2_LIB.BASEBOARD_FAB2(SCH_1):GND
  27    GND PGND<11> @BASEBOARD_FAB2_LIB.BASEBOARD_FAB2(SCH_1):GND
  26    GND PGND<10> @BASEBOARD_FAB2_LIB.BASEBOARD_FAB2(SCH_1):GND
  25    GND PGND<9> @BASEBOARD_FAB2_LIB.BASEBOARD_FAB2(SCH_1):GND
  24    GND PGND<8> @BASEBOARD_FAB2_LIB.BASEBOARD_FAB2(SCH_1):GND
  23    GND PGND<7> @BASEBOARD_FAB2_LIB.BASEBOARD_FAB2(SCH_1):GND
  22    GND PGND<6> @BASEBOARD_FAB2_LIB.BASEBOARD_FAB2(SCH_1):GND
  21    GND PGND<5> @BASEBOARD_FAB2_LIB.BASEBOARD_FAB2(SCH_1):GND
  20    GND PGND<4> @BASEBOARD_FAB2_LIB.BASEBOARD_FAB2(SCH_1):GND
  19    GND PGND<3> @BASEBOARD_FAB2_LIB.BASEBOARD_FAB2(SCH_1):GND
  18    GND PGND<2> @BASEBOARD_FAB2_LIB.BASEBOARD_FAB2(SCH_1):GND
  17    GND PGND<1> @BASEBOARD_FAB2_LIB.BASEBOARD_FAB2(SCH_1):GND
  16    GND PGND<0> @BASEBOARD_FAB2_LIB.BASEBOARD_FAB2(SCH_1):GND
   1 VR_PVPP_GHJ_SS     SS @BASEBOARD_FAB2_LIB.BASEBOARD_FAB2(SCH_1):VR_PVPP_GHJ_SS
  38 VR_VB_PVPP_GHJ     VB @BASEBOARD_FAB2_LIB.BASEBOARD_FAB2(SCH_1):VR_VB_PVPP_GHJ
  39 VR_FET_SW_P12V_STBY_PVPP_GHJ    VCC @BASEBOARD_FAB2_LIB.BASEBOARD_FAB2(SCH_1):VR_FET_SW_P12V_STBY_PVPP_GHJ
  42 VR_FET_SW_P12V_STBY_PVPP_GHJ VIN<7> @BASEBOARD_FAB2_LIB.BASEBOARD_FAB2(SCH_1):VR_FET_SW_P12V_STBY_PVPP_GHJ
  14 VR_FET_SW_P12V_STBY_PVPP_GHJ VIN<6> @BASEBOARD_FAB2_LIB.BASEBOARD_FAB2(SCH_1):VR_FET_SW_P12V_STBY_PVPP_GHJ
  13 VR_FET_SW_P12V_STBY_PVPP_GHJ VIN<5> @BASEBOARD_FAB2_LIB.BASEBOARD_FAB2(SCH_1):VR_FET_SW_P12V_STBY_PVPP_GHJ
  12 VR_FET_SW_P12V_STBY_PVPP_GHJ VIN<4> @BASEBOARD_FAB2_LIB.BASEBOARD_FAB2(SCH_1):VR_FET_SW_P12V_STBY_PVPP_GHJ
  11 VR_FET_SW_P12V_STBY_PVPP_GHJ VIN<3> @BASEBOARD_FAB2_LIB.BASEBOARD_FAB2(SCH_1):VR_FET_SW_P12V_STBY_PVPP_GHJ
  10 VR_FET_SW_P12V_STBY_PVPP_GHJ VIN<2> @BASEBOARD_FAB2_LIB.BASEBOARD_FAB2(SCH_1):VR_FET_SW_P12V_STBY_PVPP_GHJ
   9 VR_FET_SW_P12V_STBY_PVPP_GHJ VIN<1> @BASEBOARD_FAB2_LIB.BASEBOARD_FAB2(SCH_1):VR_FET_SW_P12V_STBY_PVPP_GHJ
   8 VR_FET_SW_P12V_STBY_PVPP_GHJ VIN<0> @BASEBOARD_FAB2_LIB.BASEBOARD_FAB2(SCH_1):VR_FET_SW_P12V_STBY_PVPP_GHJ
  35 VR_PVPP_GHJ_PHASE    VSW @BASEBOARD_FAB2_LIB.BASEBOARD_FAB2(SCH_1):VR_PVPP_GHJ_PHASE
  43 VR_PVPP_GHJ_PHASE VSWH<7> @BASEBOARD_FAB2_LIB.BASEBOARD_FAB2(SCH_1):VR_PVPP_GHJ_PHASE
  34 VR_PVPP_GHJ_PHASE VSWH<6> @BASEBOARD_FAB2_LIB.BASEBOARD_FAB2(SCH_1):VR_PVPP_GHJ_PHASE
  33 VR_PVPP_GHJ_PHASE VSWH<5> @BASEBOARD_FAB2_LIB.BASEBOARD_FAB2(SCH_1):VR_PVPP_GHJ_PHASE
  32 VR_PVPP_GHJ_PHASE VSWH<4> @BASEBOARD_FAB2_LIB.BASEBOARD_FAB2(SCH_1):VR_PVPP_GHJ_PHASE
  31 VR_PVPP_GHJ_PHASE VSWH<3> @BASEBOARD_FAB2_LIB.BASEBOARD_FAB2(SCH_1):VR_PVPP_GHJ_PHASE
  30 VR_PVPP_GHJ_PHASE VSWH<2> @BASEBOARD_FAB2_LIB.BASEBOARD_FAB2(SCH_1):VR_PVPP_GHJ_PHASE
  29 VR_PVPP_GHJ_PHASE VSWH<1> @BASEBOARD_FAB2_LIB.BASEBOARD_FAB2(SCH_1):VR_PVPP_GHJ_PHASE
  15 VR_PVPP_GHJ_PHASE VSWH<0> @BASEBOARD_FAB2_LIB.BASEBOARD_FAB2(SCH_1):VR_PVPP_GHJ_PHASE

CAP_A_0402V-0.1UF,16V,10%,X7R,A  I242  C6U5
   1 VR_FET_SW_P12V_STBY_PVPP_GHJ      A @BASEBOARD_FAB2_LIB.BASEBOARD_FAB2(SCH_1):VR_FET_SW_P12V_STBY_PVPP_GHJ
   2    GND      B @BASEBOARD_FAB2_LIB.BASEBOARD_FAB2(SCH_1):GND

RES_0402-22.1,1.0%,1/16W,CHIP,A  I247  R4G12
   1 PWRGD_PVPP_GHJ_R      A @BASEBOARD_FAB2_LIB.BASEBOARD_FAB2(SCH_1):PWRGD_PVPP_GHJ_R
   2 PWRGD_PVPP_GHJ      B @BASEBOARD_FAB2_LIB.BASEBOARD_FAB2(SCH_1):PWRGD_PVPP_GHJ

CAP_0805-10UF,16V,10%,X6S,C953A  I248  C6U4
   1 VR_FET_SW_P12V_STBY_PVPP_GHJ      A @BASEBOARD_FAB2_LIB.BASEBOARD_FAB2(SCH_1):VR_FET_SW_P12V_STBY_PVPP_GHJ
   2    GND      B @BASEBOARD_FAB2_LIB.BASEBOARD_FAB2(SCH_1):GND

CAP_0805-10UF,16V,10%,X6S,C953A  I253  C4G2
   1 VR_FET_SW_P12V_STBY_PVPP_GHJ      A @BASEBOARD_FAB2_LIB.BASEBOARD_FAB2(SCH_1):VR_FET_SW_P12V_STBY_PVPP_GHJ
   2    GND      B @BASEBOARD_FAB2_LIB.BASEBOARD_FAB2(SCH_1):GND

CAP_0805-10UF,16V,10%,X6S,C953A  I254  C6U7
   1 VR_FET_SW_P12V_STBY_PVPP_GHJ      A @BASEBOARD_FAB2_LIB.BASEBOARD_FAB2(SCH_1):VR_FET_SW_P12V_STBY_PVPP_GHJ
   2    GND      B @BASEBOARD_FAB2_LIB.BASEBOARD_FAB2(SCH_1):GND

CAP_0805-10UF,16V,10%,X6S,C953A  I255  C6U8
   1 VR_FET_SW_P12V_STBY_PVPP_GHJ      A @BASEBOARD_FAB2_LIB.BASEBOARD_FAB2(SCH_1):VR_FET_SW_P12V_STBY_PVPP_GHJ
   2    GND      B @BASEBOARD_FAB2_LIB.BASEBOARD_FAB2(SCH_1):GND

CAPP_7343-220UF,4V,20%,POSCAP,A  I256  C4F11
   1 PVPP_GHJ      A @BASEBOARD_FAB2_LIB.BASEBOARD_FAB2(SCH_1):PVPP_GHJ
   2    GND      B @BASEBOARD_FAB2_LIB.BASEBOARD_FAB2(SCH_1):GND

RES_0402-1.0K,0.1%,1/16W,CHIP,A  I266  R4G10
   1 VSENSE_PVPP_GHJ      A @BASEBOARD_FAB2_LIB.BASEBOARD_FAB2(SCH_1):VSENSE_PVPP_GHJ
   2 VR_COMP_PVPP_GHJ      B @BASEBOARD_FAB2_LIB.BASEBOARD_FAB2(SCH_1):VR_COMP_PVPP_GHJ

CAP_0402LF-2200PF,50V,10%,X7R,A  I267  C4G11
   1 VR_COMP_PVPP_GHJ      A @BASEBOARD_FAB2_LIB.BASEBOARD_FAB2(SCH_1):VR_COMP_PVPP_GHJ
   2 VR_FB_PVPP_GHJ      B @BASEBOARD_FAB2_LIB.BASEBOARD_FAB2(SCH_1):VR_FB_PVPP_GHJ

RES_0402-20.0K,1%,1/16W,CHIP,GA  I270  R4G7
   1 VSENSE_PVPP_GHJ      A @BASEBOARD_FAB2_LIB.BASEBOARD_FAB2(SCH_1):VSENSE_PVPP_GHJ
   2 VR_FB_PVPP_GHJ      B @BASEBOARD_FAB2_LIB.BASEBOARD_FAB2(SCH_1):VR_FB_PVPP_GHJ

RES_0402-0.0,5%,1/16W,CHIP,G21A  I271  R4G8
   1 PVPP_GHJ      A @BASEBOARD_FAB2_LIB.BASEBOARD_FAB2(SCH_1):PVPP_GHJ
   2 VSENSE_PVPP_GHJ      B @BASEBOARD_FAB2_LIB.BASEBOARD_FAB2(SCH_1):VSENSE_PVPP_GHJ

RES_0402-7.87K,1.0%,1/16W,CHIPA  I272  R4G13
   1 VR_COMP_RC_PVPP_GHJ      A @BASEBOARD_FAB2_LIB.BASEBOARD_FAB2(SCH_1):VR_COMP_RC_PVPP_GHJ
   2 VR_FB_PVPP_GHJ      B @BASEBOARD_FAB2_LIB.BASEBOARD_FAB2(SCH_1):VR_FB_PVPP_GHJ

CAP_0402LF-100.0PF,50V,5%,COG,A  I273  C4G6
   1 VR_FB_PVPP_GHJ      A @BASEBOARD_FAB2_LIB.BASEBOARD_FAB2(SCH_1):VR_FB_PVPP_GHJ
   2 VR_COMP_PVPP_GHJ_3      B @BASEBOARD_FAB2_LIB.BASEBOARD_FAB2(SCH_1):VR_COMP_PVPP_GHJ_3

CAP_0402LF-2200PF,50V,10%,X7R,A  I274  C4G10
   1 VR_COMP_RC_PVPP_GHJ      A @BASEBOARD_FAB2_LIB.BASEBOARD_FAB2(SCH_1):VR_COMP_RC_PVPP_GHJ
   2 VR_COMP_PVPP_GHJ_3      B @BASEBOARD_FAB2_LIB.BASEBOARD_FAB2(SCH_1):VR_COMP_PVPP_GHJ_3

RES_0402-0.0,5%,1/16W,CHIP,G21A  I275  R4G4
   1 FM_PVPP_CPU1_EN      A @BASEBOARD_FAB2_LIB.BASEBOARD_FAB2(SCH_1):FM_PVPP_CPU1_EN
   2 FM_PVPP_PVDDQ_CPU1_EN_GHJ      B @BASEBOARD_FAB2_LIB.BASEBOARD_FAB2(SCH_1):FM_PVPP_PVDDQ_CPU1_EN_GHJ

INDUCTOR_SM-0.47UH,IND,E13358-A  I277  L4G1
   1 VR_PVPP_GHJ_PHASE    INA @BASEBOARD_FAB2_LIB.BASEBOARD_FAB2(SCH_1):VR_PVPP_GHJ_PHASE
   2 PVPP_GHJ    INB @BASEBOARD_FAB2_LIB.BASEBOARD_FAB2(SCH_1):PVPP_GHJ

SC22U16V5MX-4-GP_SMD-BCG5-SC22A  I278  C22W6
   1 VR_FET_SW_P12V_STBY_PVPP_GHJ      1 @BASEBOARD_FAB2_LIB.BASEBOARD_FAB2(SCH_1):VR_FET_SW_P12V_STBY_PVPP_GHJ
   2    GND      2 @BASEBOARD_FAB2_LIB.BASEBOARD_FAB2(SCH_1):GND

SC22U16V5MX-4-GP_SMD-BCG5-SC22A  I280  C4G5
   1 VR_FET_SW_P12V_STBY_PVPP_GHJ      1 @BASEBOARD_FAB2_LIB.BASEBOARD_FAB2(SCH_1):VR_FET_SW_P12V_STBY_PVPP_GHJ
   2    GND      2 @BASEBOARD_FAB2_LIB.BASEBOARD_FAB2(SCH_1):GND

RES_0603-0,5.0%,1/10W,CHIP,G22A  I282  R4G24
   1 VR_PVPP_GHJ_BOOT      A @BASEBOARD_FAB2_LIB.BASEBOARD_FAB2(SCH_1):VR_PVPP_GHJ_BOOT
   2 VR_PVPP_GHJ_BOOT_R      B @BASEBOARD_FAB2_LIB.BASEBOARD_FAB2(SCH_1):VR_PVPP_GHJ_BOOT_R

RES_0402-6.19K,1%,1/16W,CHIP,GA  I283  R4G9
   1 VR_FB_PVPP_GHJ      A @BASEBOARD_FAB2_LIB.BASEBOARD_FAB2(SCH_1):VR_FB_PVPP_GHJ
   2 AGND_PVPP_GHJ      B @BASEBOARD_FAB2_LIB.BASEBOARD_FAB2(SCH_1):AGND_PVPP_GHJ

RES_0402-7.87K,1.0%,1/16W,CHIPA  I284  R4G11
   1 VR_PVPP_GHJ_ISET      A @BASEBOARD_FAB2_LIB.BASEBOARD_FAB2(SCH_1):VR_PVPP_GHJ_ISET
   2 AGND_PVPP_GHJ      B @BASEBOARD_FAB2_LIB.BASEBOARD_FAB2(SCH_1):AGND_PVPP_GHJ


DRAWING: @BASEBOARD_FAB2_LIB.BASEBOARD_FAB2(SCH_1):PAGE234 

RES_0402-0.0,5%,1/16W,CHIP,G21A  I29  R4B14
   1    GND      A @BASEBOARD_FAB2_LIB.BASEBOARD_FAB2(SCH_1):GND
   2 AGND_PVPP_KLM      B @BASEBOARD_FAB2_LIB.BASEBOARD_FAB2(SCH_1):AGND_PVPP_KLM

CAP_0603LF-10UF,4V,20%,X6S,E15A  I84  C3B2
   1 PVPP_KLM      A @BASEBOARD_FAB2_LIB.BASEBOARD_FAB2(SCH_1):PVPP_KLM
   2    GND      B @BASEBOARD_FAB2_LIB.BASEBOARD_FAB2(SCH_1):GND

CAP_0603LF-10UF,4V,20%,X6S,E15A  I86  C3A8
   1 PVPP_KLM      A @BASEBOARD_FAB2_LIB.BASEBOARD_FAB2(SCH_1):PVPP_KLM
   2    GND      B @BASEBOARD_FAB2_LIB.BASEBOARD_FAB2(SCH_1):GND

CAP_0603LF-10UF,4V,20%,X6S,E15A  I87  C7L3
   1 PVPP_KLM      A @BASEBOARD_FAB2_LIB.BASEBOARD_FAB2(SCH_1):PVPP_KLM
   2    GND      B @BASEBOARD_FAB2_LIB.BASEBOARD_FAB2(SCH_1):GND

CAP_0603LF-10UF,4V,20%,X6S,E15A  I88  C7L2
   1 PVPP_KLM      A @BASEBOARD_FAB2_LIB.BASEBOARD_FAB2(SCH_1):PVPP_KLM
   2    GND      B @BASEBOARD_FAB2_LIB.BASEBOARD_FAB2(SCH_1):GND

CAP_0603LF-10UF,4V,20%,X6S,E15A  I89  C7L7
   1 PVPP_KLM      A @BASEBOARD_FAB2_LIB.BASEBOARD_FAB2(SCH_1):PVPP_KLM
   2    GND      B @BASEBOARD_FAB2_LIB.BASEBOARD_FAB2(SCH_1):GND

CAP_0603LF-10UF,4V,20%,X6S,E15A  I90  C7L6
   1 PVPP_KLM      A @BASEBOARD_FAB2_LIB.BASEBOARD_FAB2(SCH_1):PVPP_KLM
   2    GND      B @BASEBOARD_FAB2_LIB.BASEBOARD_FAB2(SCH_1):GND

CAP_0603LF-10UF,4V,20%,X6S,E15A  I91  C7M4
   1 PVPP_KLM      A @BASEBOARD_FAB2_LIB.BASEBOARD_FAB2(SCH_1):PVPP_KLM
   2    GND      B @BASEBOARD_FAB2_LIB.BASEBOARD_FAB2(SCH_1):GND

CAP_0603LF-10UF,4V,20%,X6S,E15A  I92  C7M3
   1 PVPP_KLM      A @BASEBOARD_FAB2_LIB.BASEBOARD_FAB2(SCH_1):PVPP_KLM
   2    GND      B @BASEBOARD_FAB2_LIB.BASEBOARD_FAB2(SCH_1):GND

CAP_0603LF-10UF,4V,20%,X6S,E15A  I93  C3A4
   1 PVPP_KLM      A @BASEBOARD_FAB2_LIB.BASEBOARD_FAB2(SCH_1):PVPP_KLM
   2    GND      B @BASEBOARD_FAB2_LIB.BASEBOARD_FAB2(SCH_1):GND

CAP_0603LF-10UF,4V,20%,X6S,E15A  I94  C3B1
   1 PVPP_KLM      A @BASEBOARD_FAB2_LIB.BASEBOARD_FAB2(SCH_1):PVPP_KLM
   2    GND      B @BASEBOARD_FAB2_LIB.BASEBOARD_FAB2(SCH_1):GND

CAP_0603LF-10UF,4V,20%,X6S,E15A  I95  C3A7
   1 PVPP_KLM      A @BASEBOARD_FAB2_LIB.BASEBOARD_FAB2(SCH_1):PVPP_KLM
   2    GND      B @BASEBOARD_FAB2_LIB.BASEBOARD_FAB2(SCH_1):GND

CAP_0603LF-10UF,4V,20%,X6S,E15A  I97  C3A3
   1 PVPP_KLM      A @BASEBOARD_FAB2_LIB.BASEBOARD_FAB2(SCH_1):PVPP_KLM
   2    GND      B @BASEBOARD_FAB2_LIB.BASEBOARD_FAB2(SCH_1):GND

CAP_0402LF-1000PF,50V,10%,EMPTA  I129  C4B5
   1 FM_PVPP_CPU1_EN      A @BASEBOARD_FAB2_LIB.BASEBOARD_FAB2(SCH_1):FM_PVPP_CPU1_EN
   2 AGND_PVPP_KLM      B @BASEBOARD_FAB2_LIB.BASEBOARD_FAB2(SCH_1):AGND_PVPP_KLM

CAP_0402LF-1000PF,50V,10%,X7R,A  I139  C4B8
   1 PWRGD_PVPP_KLM_R      A @BASEBOARD_FAB2_LIB.BASEBOARD_FAB2(SCH_1):PWRGD_PVPP_KLM_R
   2    GND      B @BASEBOARD_FAB2_LIB.BASEBOARD_FAB2(SCH_1):GND

RES_0402-1.00K,1%,1/16W,CHIP,GA  I143  R4B10
   1 P3V3_STBY      A @BASEBOARD_FAB2_LIB.BASEBOARD_FAB2(SCH_1):P3V3_STBY
   2 PWRGD_PVPP_KLM_R      B @BASEBOARD_FAB2_LIB.BASEBOARD_FAB2(SCH_1):PWRGD_PVPP_KLM_R

CAP_0603-4.7UF,6.3V,10%,X6S,E1A  I144  C6L12
   1 VR_VB_PVPP_KLM      A @BASEBOARD_FAB2_LIB.BASEBOARD_FAB2(SCH_1):VR_VB_PVPP_KLM
   2 AGND_PVPP_KLM      B @BASEBOARD_FAB2_LIB.BASEBOARD_FAB2(SCH_1):AGND_PVPP_KLM

CAP_0402-0.027UF,16V,10%,X7R,AA  I146  C4B6
   1 VR_PVPP_KLM_SS      A @BASEBOARD_FAB2_LIB.BASEBOARD_FAB2(SCH_1):VR_PVPP_KLM_SS
   2 AGND_PVPP_KLM      B @BASEBOARD_FAB2_LIB.BASEBOARD_FAB2(SCH_1):AGND_PVPP_KLM

CAP_0402-1.0UF,16V,10%,X6S,D97A  I152  C6L11
   1 VR_FET_SW_P12V_STBY_PVPP_KLM      A @BASEBOARD_FAB2_LIB.BASEBOARD_FAB2(SCH_1):VR_FET_SW_P12V_STBY_PVPP_KLM
   2    GND      B @BASEBOARD_FAB2_LIB.BASEBOARD_FAB2(SCH_1):GND

FERRITE_SM-22,FB,656554-051  I154  FB4A1
   1 P12V_STBY      A @BASEBOARD_FAB2_LIB.BASEBOARD_FAB2(SCH_1):P12V_STBY
   2 VR_FET_SW_P12V_STBY_PVPP_KLM      B @BASEBOARD_FAB2_LIB.BASEBOARD_FAB2(SCH_1):VR_FET_SW_P12V_STBY_PVPP_KLM

RES_0402-2.2,5%,1/16W,EMPTY,G2A  I162  R4A7
   1 VR_PVPP_KLM_SNUB      A @BASEBOARD_FAB2_LIB.BASEBOARD_FAB2(SCH_1):VR_PVPP_KLM_SNUB
   2    GND      B @BASEBOARD_FAB2_LIB.BASEBOARD_FAB2(SCH_1):GND

CAP_0402LF-3300PF,50V,10%,EMPTA  I163  C4A16
   1 VR_PVPP_KLM_PHASE      A @BASEBOARD_FAB2_LIB.BASEBOARD_FAB2(SCH_1):VR_PVPP_KLM_PHASE
   2 VR_PVPP_KLM_SNUB      B @BASEBOARD_FAB2_LIB.BASEBOARD_FAB2(SCH_1):VR_PVPP_KLM_SNUB

INDUCTOR_SM-0.47UH,IND,E13358-A  I164  L4A1
   1 VR_PVPP_KLM_PHASE    INA @BASEBOARD_FAB2_LIB.BASEBOARD_FAB2(SCH_1):VR_PVPP_KLM_PHASE
   2 PVPP_KLM    INB @BASEBOARD_FAB2_LIB.BASEBOARD_FAB2(SCH_1):PVPP_KLM

CAPP_7343LF-330UF,6.3V,20%,POSA  I167  C3B3
   1 PVPP_KLM      A @BASEBOARD_FAB2_LIB.BASEBOARD_FAB2(SCH_1):PVPP_KLM
   2    GND      B @BASEBOARD_FAB2_LIB.BASEBOARD_FAB2(SCH_1):GND

CAP_0805-47UF,4V,20%,X6S,C9533A  I177  C4B3
   1 PVPP_KLM      A @BASEBOARD_FAB2_LIB.BASEBOARD_FAB2(SCH_1):PVPP_KLM
   2    GND      B @BASEBOARD_FAB2_LIB.BASEBOARD_FAB2(SCH_1):GND

CAP_0805-47UF,4V,20%,X6S,C9533A  I180  C4B2
   1 PVPP_KLM      A @BASEBOARD_FAB2_LIB.BASEBOARD_FAB2(SCH_1):PVPP_KLM
   2    GND      B @BASEBOARD_FAB2_LIB.BASEBOARD_FAB2(SCH_1):GND

CAP_0603LF-0.1UF,25V,10%,X7R,6A  I182  C4B15
   1 VR_PVPP_KLM_PHASE      A @BASEBOARD_FAB2_LIB.BASEBOARD_FAB2(SCH_1):VR_PVPP_KLM_PHASE
   2 VR_PVPP_KLM_BOOT_R      B @BASEBOARD_FAB2_LIB.BASEBOARD_FAB2(SCH_1):VR_PVPP_KLM_BOOT_R

RES_0603-120.0,1%,1/10W,CHIP,GA  I183  R4B2
   1 PVPP_KLM      A @BASEBOARD_FAB2_LIB.BASEBOARD_FAB2(SCH_1):PVPP_KLM
   2    GND      B @BASEBOARD_FAB2_LIB.BASEBOARD_FAB2(SCH_1):GND

NCP3232L_SM-IC,H86355-001  I184  EU4A3
   5 AGND_PVPP_KLM   AGND @BASEBOARD_FAB2_LIB.BASEBOARD_FAB2(SCH_1):AGND_PVPP_KLM
  36 VR_PVPP_KLM_BOOT    BST @BASEBOARD_FAB2_LIB.BASEBOARD_FAB2(SCH_1):VR_PVPP_KLM_BOOT
   3 VR_COMP_PVPP_KLM_3   COMP @BASEBOARD_FAB2_LIB.BASEBOARD_FAB2(SCH_1):VR_COMP_PVPP_KLM_3
  40 FM_PVPP_PVDDQ_CPU1_EN_KLM     EN @BASEBOARD_FAB2_LIB.BASEBOARD_FAB2(SCH_1):FM_PVPP_PVDDQ_CPU1_EN_KLM
   2 VR_FB_PVPP_KLM     FB @BASEBOARD_FAB2_LIB.BASEBOARD_FAB2(SCH_1):VR_FB_PVPP_KLM
  41    GND    GND @BASEBOARD_FAB2_LIB.BASEBOARD_FAB2(SCH_1):GND
   4 VR_PVPP_KLM_ISET   ISET @BASEBOARD_FAB2_LIB.BASEBOARD_FAB2(SCH_1):VR_PVPP_KLM_ISET
   6 AGND_PVPP_KLM    OTS @BASEBOARD_FAB2_LIB.BASEBOARD_FAB2(SCH_1):AGND_PVPP_KLM
   7 PWRGD_PVPP_KLM_R     PG @BASEBOARD_FAB2_LIB.BASEBOARD_FAB2(SCH_1):PWRGD_PVPP_KLM_R
  37    GND PGND<13> @BASEBOARD_FAB2_LIB.BASEBOARD_FAB2(SCH_1):GND
  28    GND PGND<12> @BASEBOARD_FAB2_LIB.BASEBOARD_FAB2(SCH_1):GND
  27    GND PGND<11> @BASEBOARD_FAB2_LIB.BASEBOARD_FAB2(SCH_1):GND
  26    GND PGND<10> @BASEBOARD_FAB2_LIB.BASEBOARD_FAB2(SCH_1):GND
  25    GND PGND<9> @BASEBOARD_FAB2_LIB.BASEBOARD_FAB2(SCH_1):GND
  24    GND PGND<8> @BASEBOARD_FAB2_LIB.BASEBOARD_FAB2(SCH_1):GND
  23    GND PGND<7> @BASEBOARD_FAB2_LIB.BASEBOARD_FAB2(SCH_1):GND
  22    GND PGND<6> @BASEBOARD_FAB2_LIB.BASEBOARD_FAB2(SCH_1):GND
  21    GND PGND<5> @BASEBOARD_FAB2_LIB.BASEBOARD_FAB2(SCH_1):GND
  20    GND PGND<4> @BASEBOARD_FAB2_LIB.BASEBOARD_FAB2(SCH_1):GND
  19    GND PGND<3> @BASEBOARD_FAB2_LIB.BASEBOARD_FAB2(SCH_1):GND
  18    GND PGND<2> @BASEBOARD_FAB2_LIB.BASEBOARD_FAB2(SCH_1):GND
  17    GND PGND<1> @BASEBOARD_FAB2_LIB.BASEBOARD_FAB2(SCH_1):GND
  16    GND PGND<0> @BASEBOARD_FAB2_LIB.BASEBOARD_FAB2(SCH_1):GND
   1 VR_PVPP_KLM_SS     SS @BASEBOARD_FAB2_LIB.BASEBOARD_FAB2(SCH_1):VR_PVPP_KLM_SS
  38 VR_VB_PVPP_KLM     VB @BASEBOARD_FAB2_LIB.BASEBOARD_FAB2(SCH_1):VR_VB_PVPP_KLM
  39 VR_FET_SW_P12V_STBY_PVPP_KLM    VCC @BASEBOARD_FAB2_LIB.BASEBOARD_FAB2(SCH_1):VR_FET_SW_P12V_STBY_PVPP_KLM
  42 VR_FET_SW_P12V_STBY_PVPP_KLM VIN<7> @BASEBOARD_FAB2_LIB.BASEBOARD_FAB2(SCH_1):VR_FET_SW_P12V_STBY_PVPP_KLM
  14 VR_FET_SW_P12V_STBY_PVPP_KLM VIN<6> @BASEBOARD_FAB2_LIB.BASEBOARD_FAB2(SCH_1):VR_FET_SW_P12V_STBY_PVPP_KLM
  13 VR_FET_SW_P12V_STBY_PVPP_KLM VIN<5> @BASEBOARD_FAB2_LIB.BASEBOARD_FAB2(SCH_1):VR_FET_SW_P12V_STBY_PVPP_KLM
  12 VR_FET_SW_P12V_STBY_PVPP_KLM VIN<4> @BASEBOARD_FAB2_LIB.BASEBOARD_FAB2(SCH_1):VR_FET_SW_P12V_STBY_PVPP_KLM
  11 VR_FET_SW_P12V_STBY_PVPP_KLM VIN<3> @BASEBOARD_FAB2_LIB.BASEBOARD_FAB2(SCH_1):VR_FET_SW_P12V_STBY_PVPP_KLM
  10 VR_FET_SW_P12V_STBY_PVPP_KLM VIN<2> @BASEBOARD_FAB2_LIB.BASEBOARD_FAB2(SCH_1):VR_FET_SW_P12V_STBY_PVPP_KLM
   9 VR_FET_SW_P12V_STBY_PVPP_KLM VIN<1> @BASEBOARD_FAB2_LIB.BASEBOARD_FAB2(SCH_1):VR_FET_SW_P12V_STBY_PVPP_KLM
   8 VR_FET_SW_P12V_STBY_PVPP_KLM VIN<0> @BASEBOARD_FAB2_LIB.BASEBOARD_FAB2(SCH_1):VR_FET_SW_P12V_STBY_PVPP_KLM
  35 VR_PVPP_KLM_PHASE    VSW @BASEBOARD_FAB2_LIB.BASEBOARD_FAB2(SCH_1):VR_PVPP_KLM_PHASE
  43 VR_PVPP_KLM_PHASE VSWH<7> @BASEBOARD_FAB2_LIB.BASEBOARD_FAB2(SCH_1):VR_PVPP_KLM_PHASE
  34 VR_PVPP_KLM_PHASE VSWH<6> @BASEBOARD_FAB2_LIB.BASEBOARD_FAB2(SCH_1):VR_PVPP_KLM_PHASE
  33 VR_PVPP_KLM_PHASE VSWH<5> @BASEBOARD_FAB2_LIB.BASEBOARD_FAB2(SCH_1):VR_PVPP_KLM_PHASE
  32 VR_PVPP_KLM_PHASE VSWH<4> @BASEBOARD_FAB2_LIB.BASEBOARD_FAB2(SCH_1):VR_PVPP_KLM_PHASE
  31 VR_PVPP_KLM_PHASE VSWH<3> @BASEBOARD_FAB2_LIB.BASEBOARD_FAB2(SCH_1):VR_PVPP_KLM_PHASE
  30 VR_PVPP_KLM_PHASE VSWH<2> @BASEBOARD_FAB2_LIB.BASEBOARD_FAB2(SCH_1):VR_PVPP_KLM_PHASE
  29 VR_PVPP_KLM_PHASE VSWH<1> @BASEBOARD_FAB2_LIB.BASEBOARD_FAB2(SCH_1):VR_PVPP_KLM_PHASE
  15 VR_PVPP_KLM_PHASE VSWH<0> @BASEBOARD_FAB2_LIB.BASEBOARD_FAB2(SCH_1):VR_PVPP_KLM_PHASE

CAP_A_0402V-0.1UF,16V,10%,X7R,A  I199  C4A20
   1 VR_FET_SW_P12V_STBY_PVPP_KLM      A @BASEBOARD_FAB2_LIB.BASEBOARD_FAB2(SCH_1):VR_FET_SW_P12V_STBY_PVPP_KLM
   2    GND      B @BASEBOARD_FAB2_LIB.BASEBOARD_FAB2(SCH_1):GND

RES_0402-22.1,1.0%,1/16W,CHIP,A  I201  R4B7
   1 PWRGD_PVPP_KLM_R      A @BASEBOARD_FAB2_LIB.BASEBOARD_FAB2(SCH_1):PWRGD_PVPP_KLM_R
   2 PWRGD_PVPP_KLM      B @BASEBOARD_FAB2_LIB.BASEBOARD_FAB2(SCH_1):PWRGD_PVPP_KLM

CAP_0805-10UF,16V,10%,X6S,C953A  I202  C6L10
   1 VR_FET_SW_P12V_STBY_PVPP_KLM      A @BASEBOARD_FAB2_LIB.BASEBOARD_FAB2(SCH_1):VR_FET_SW_P12V_STBY_PVPP_KLM
   2    GND      B @BASEBOARD_FAB2_LIB.BASEBOARD_FAB2(SCH_1):GND

CAP_0805-10UF,16V,10%,X6S,C953A  I203  C6M3
   1 VR_FET_SW_P12V_STBY_PVPP_KLM      A @BASEBOARD_FAB2_LIB.BASEBOARD_FAB2(SCH_1):VR_FET_SW_P12V_STBY_PVPP_KLM
   2    GND      B @BASEBOARD_FAB2_LIB.BASEBOARD_FAB2(SCH_1):GND

CAP_0805-10UF,16V,10%,X6S,C953A  I204  C6M5
   1 VR_FET_SW_P12V_STBY_PVPP_KLM      A @BASEBOARD_FAB2_LIB.BASEBOARD_FAB2(SCH_1):VR_FET_SW_P12V_STBY_PVPP_KLM
   2    GND      B @BASEBOARD_FAB2_LIB.BASEBOARD_FAB2(SCH_1):GND

CAP_0805-10UF,16V,10%,X6S,C953A  I205  C4A19
   1 VR_FET_SW_P12V_STBY_PVPP_KLM      A @BASEBOARD_FAB2_LIB.BASEBOARD_FAB2(SCH_1):VR_FET_SW_P12V_STBY_PVPP_KLM
   2    GND      B @BASEBOARD_FAB2_LIB.BASEBOARD_FAB2(SCH_1):GND

CAPP_7343-220UF,4V,20%,POSCAP,A  I210  C6L8
   1 PVPP_KLM      A @BASEBOARD_FAB2_LIB.BASEBOARD_FAB2(SCH_1):PVPP_KLM
   2    GND      B @BASEBOARD_FAB2_LIB.BASEBOARD_FAB2(SCH_1):GND

CAP_0402LF-2200PF,50V,10%,X7R,A  I211  C4B9
   1 VR_COMP_RC_PVPP_KLM      A @BASEBOARD_FAB2_LIB.BASEBOARD_FAB2(SCH_1):VR_COMP_RC_PVPP_KLM
   2 VR_COMP_PVPP_KLM_3      B @BASEBOARD_FAB2_LIB.BASEBOARD_FAB2(SCH_1):VR_COMP_PVPP_KLM_3

CAP_0402LF-100.0PF,50V,5%,COG,A  I212  C4B4
   1 VR_FB_PVPP_KLM      A @BASEBOARD_FAB2_LIB.BASEBOARD_FAB2(SCH_1):VR_FB_PVPP_KLM
   2 VR_COMP_PVPP_KLM_3      B @BASEBOARD_FAB2_LIB.BASEBOARD_FAB2(SCH_1):VR_COMP_PVPP_KLM_3

RES_0402-7.87K,1.0%,1/16W,CHIPA  I213  R4B8
   1 VR_COMP_RC_PVPP_KLM      A @BASEBOARD_FAB2_LIB.BASEBOARD_FAB2(SCH_1):VR_COMP_RC_PVPP_KLM
   2 VR_FB_PVPP_KLM      B @BASEBOARD_FAB2_LIB.BASEBOARD_FAB2(SCH_1):VR_FB_PVPP_KLM

RES_0402-0.0,5%,1/16W,CHIP,G21A  I214  R4B3
   1 PVPP_KLM      A @BASEBOARD_FAB2_LIB.BASEBOARD_FAB2(SCH_1):PVPP_KLM
   2 VSENSE_PVPP_KLM      B @BASEBOARD_FAB2_LIB.BASEBOARD_FAB2(SCH_1):VSENSE_PVPP_KLM

RES_0402-20.0K,1%,1/16W,CHIP,GA  I215  R4B5
   1 VSENSE_PVPP_KLM      A @BASEBOARD_FAB2_LIB.BASEBOARD_FAB2(SCH_1):VSENSE_PVPP_KLM
   2 VR_FB_PVPP_KLM      B @BASEBOARD_FAB2_LIB.BASEBOARD_FAB2(SCH_1):VR_FB_PVPP_KLM

CAP_0402LF-2200PF,50V,10%,X7R,A  I218  C4B7
   1 VR_COMP_PVPP_KLM      A @BASEBOARD_FAB2_LIB.BASEBOARD_FAB2(SCH_1):VR_COMP_PVPP_KLM
   2 VR_FB_PVPP_KLM      B @BASEBOARD_FAB2_LIB.BASEBOARD_FAB2(SCH_1):VR_FB_PVPP_KLM

RES_0402-1.0K,0.1%,1/16W,CHIP,A  I219  R4B9
   1 VSENSE_PVPP_KLM      A @BASEBOARD_FAB2_LIB.BASEBOARD_FAB2(SCH_1):VSENSE_PVPP_KLM
   2 VR_COMP_PVPP_KLM      B @BASEBOARD_FAB2_LIB.BASEBOARD_FAB2(SCH_1):VR_COMP_PVPP_KLM

RES_0402-0.0,5%,1/16W,CHIP,G21A  I220  R4B1
   1 FM_PVPP_CPU1_EN      A @BASEBOARD_FAB2_LIB.BASEBOARD_FAB2(SCH_1):FM_PVPP_CPU1_EN
   2 FM_PVPP_PVDDQ_CPU1_EN_KLM      B @BASEBOARD_FAB2_LIB.BASEBOARD_FAB2(SCH_1):FM_PVPP_PVDDQ_CPU1_EN_KLM

SC22U16V5MX-4-GP_SMD-BCG5-SC22A  I222  C22W5
   1 VR_FET_SW_P12V_STBY_PVPP_KLM      1 @BASEBOARD_FAB2_LIB.BASEBOARD_FAB2(SCH_1):VR_FET_SW_P12V_STBY_PVPP_KLM
   2    GND      2 @BASEBOARD_FAB2_LIB.BASEBOARD_FAB2(SCH_1):GND

SC22U16V5MX-4-GP_SMD-BCG5-SC22A  I223  C4B1
   1 VR_FET_SW_P12V_STBY_PVPP_KLM      1 @BASEBOARD_FAB2_LIB.BASEBOARD_FAB2(SCH_1):VR_FET_SW_P12V_STBY_PVPP_KLM
   2    GND      2 @BASEBOARD_FAB2_LIB.BASEBOARD_FAB2(SCH_1):GND

RES_0603-0,5.0%,1/10W,CHIP,G22A  I226  R4B13
   1 VR_PVPP_KLM_BOOT      A @BASEBOARD_FAB2_LIB.BASEBOARD_FAB2(SCH_1):VR_PVPP_KLM_BOOT
   2 VR_PVPP_KLM_BOOT_R      B @BASEBOARD_FAB2_LIB.BASEBOARD_FAB2(SCH_1):VR_PVPP_KLM_BOOT_R

RES_0402-6.19K,1%,1/16W,CHIP,GA  I227  R4B4
   1 VR_FB_PVPP_KLM      A @BASEBOARD_FAB2_LIB.BASEBOARD_FAB2(SCH_1):VR_FB_PVPP_KLM
   2 AGND_PVPP_KLM      B @BASEBOARD_FAB2_LIB.BASEBOARD_FAB2(SCH_1):AGND_PVPP_KLM

RES_0402-7.87K,1.0%,1/16W,CHIPA  I228  R4B6
   1 VR_PVPP_KLM_ISET      A @BASEBOARD_FAB2_LIB.BASEBOARD_FAB2(SCH_1):VR_PVPP_KLM_ISET
   2 AGND_PVPP_KLM      B @BASEBOARD_FAB2_LIB.BASEBOARD_FAB2(SCH_1):AGND_PVPP_KLM


DRAWING: @BASEBOARD_FAB2_LIB.BASEBOARD_FAB2(SCH_1):PAGE235 

CAP_A_0402V-1.0UF,6.3V,10%,X6SA  I143  C8A7
   1 VR_PVNN_P1V05_PCH_VD12      A @BASEBOARD_FAB2_LIB.BASEBOARD_FAB2(SCH_1):VR_PVNN_P1V05_PCH_VD12
   2    GND      B @BASEBOARD_FAB2_LIB.BASEBOARD_FAB2(SCH_1):GND

CAP_A_0402V-0.1UF,16V,10%,X7R,A  I145  C8A8
   1 VR_PVNN_P1V05_PCH_VD12      A @BASEBOARD_FAB2_LIB.BASEBOARD_FAB2(SCH_1):VR_PVNN_P1V05_PCH_VD12
   2    GND      B @BASEBOARD_FAB2_LIB.BASEBOARD_FAB2(SCH_1):GND

RES_0402-22.1,1.0%,1/16W,CHIP,A  I147  R2L16
   1 PWRGD_PVNN_PCH_R      A @BASEBOARD_FAB2_LIB.BASEBOARD_FAB2(SCH_1):PWRGD_PVNN_PCH_R
   2 PWRGD_PVNN_P1V05_PCH      B @BASEBOARD_FAB2_LIB.BASEBOARD_FAB2(SCH_1):PWRGD_PVNN_P1V05_PCH

RES_0402-2.26K,1.0%,1/16W,EMPTA  I148  R2L24
   1 P3V3_STBY      A @BASEBOARD_FAB2_LIB.BASEBOARD_FAB2(SCH_1):P3V3_STBY
   2 PU_VR_PVNN_PCH_FAULT1      B @BASEBOARD_FAB2_LIB.BASEBOARD_FAB2(SCH_1):PU_VR_PVNN_PCH_FAULT1

RES_0402-1.00K,1%,1/16W,CHIP,GA  I149  R8A6
   1 P3V3_STBY      A @BASEBOARD_FAB2_LIB.BASEBOARD_FAB2(SCH_1):P3V3_STBY
   2 PWRGD_PVNN_PCH_R      B @BASEBOARD_FAB2_LIB.BASEBOARD_FAB2(SCH_1):PWRGD_PVNN_PCH_R

CAP_A_0402V-1.0UF,6.3V,10%,X6SA  I151  C2L8
   1 VR_PVNN_PCH_VDD      A @BASEBOARD_FAB2_LIB.BASEBOARD_FAB2(SCH_1):VR_PVNN_PCH_VDD
   2    GND      B @BASEBOARD_FAB2_LIB.BASEBOARD_FAB2(SCH_1):GND

CAP_0402LF-220PF,50V,10%,X7R,AA  I153  C2L2
   1 VR_P1V05_PCH_STBY_AVSP      A @BASEBOARD_FAB2_LIB.BASEBOARD_FAB2(SCH_1):VR_P1V05_PCH_STBY_AVSP
   2 VSENSE_P1V05_PCH_STBY_AVSN      B @BASEBOARD_FAB2_LIB.BASEBOARD_FAB2(SCH_1):VSENSE_P1V05_PCH_STBY_AVSN

RES_0603-10.0,1%,1/10W,CHIP,G2A  I154  R2L8
   1 VSENSE_P1V05_PCH_STBY_AVSP      A @BASEBOARD_FAB2_LIB.BASEBOARD_FAB2(SCH_1):VSENSE_P1V05_PCH_STBY_AVSP
   2 VR_P1V05_PCH_STBY_AVSP      B @BASEBOARD_FAB2_LIB.BASEBOARD_FAB2(SCH_1):VR_P1V05_PCH_STBY_AVSP

RES_0402-0.0,5%,1/16W,CHIP,G21A  I159  R2L14
   1 P3V3_STBY      A @BASEBOARD_FAB2_LIB.BASEBOARD_FAB2(SCH_1):P3V3_STBY
   2 VR_PVNN_PCH_VDD      B @BASEBOARD_FAB2_LIB.BASEBOARD_FAB2(SCH_1):VR_PVNN_PCH_VDD

RES_0402-100.0K,1%,1/16W,CHIP,B  I165  R8A4
   1 VR_FET_SW_P12V_STBY_PVDDQ_DEF      A @BASEBOARD_FAB2_LIB.BASEBOARD_FAB2(SCH_1):VR_FET_SW_P12V_STBY_PVDDQ_DEF
   2 VR_PVNN_PCH_VINSEN      B @BASEBOARD_FAB2_LIB.BASEBOARD_FAB2(SCH_1):VR_PVNN_PCH_VINSEN

RES_0402-1.5K,1%,1/16W,CHIP,G2A  I166  R2L10
   1 VR_PVNN_PCH_VINSEN      A @BASEBOARD_FAB2_LIB.BASEBOARD_FAB2(SCH_1):VR_PVNN_PCH_VINSEN
   2    GND      B @BASEBOARD_FAB2_LIB.BASEBOARD_FAB2(SCH_1):GND

CAP_A_0402V-0.1UF,16V,10%,X7R,A  I169  C2L11
   1 VR_PVNN_PCH_VDD      A @BASEBOARD_FAB2_LIB.BASEBOARD_FAB2(SCH_1):VR_PVNN_PCH_VDD
   2    GND      B @BASEBOARD_FAB2_LIB.BASEBOARD_FAB2(SCH_1):GND

CAP_0402LF-220PF,50V,10%,X7R,AA  I209  C8A2
   1 VR_PVNN_PCH_AVSP      A @BASEBOARD_FAB2_LIB.BASEBOARD_FAB2(SCH_1):VR_PVNN_PCH_AVSP
   2 VSENSE_PVNN_PCH_STBY_AVSN      B @BASEBOARD_FAB2_LIB.BASEBOARD_FAB2(SCH_1):VSENSE_PVNN_PCH_STBY_AVSN

RES_0402-10.0,1%,1/16W,CHIP,G2A  I210  R8A1
   1 VSENSE_PVNN_PCH_STBY_AVSP      A @BASEBOARD_FAB2_LIB.BASEBOARD_FAB2(SCH_1):VSENSE_PVNN_PCH_STBY_AVSP
   2 VR_PVNN_PCH_AVSP      B @BASEBOARD_FAB2_LIB.BASEBOARD_FAB2(SCH_1):VR_PVNN_PCH_AVSP

RES_0402-1.00K,1%,1/16W,CHIP,GA  I216  R8A5
   1 P3V3_STBY      A @BASEBOARD_FAB2_LIB.BASEBOARD_FAB2(SCH_1):P3V3_STBY
   2 IRQ_PVNN_PCH_VRHOT_N      B @BASEBOARD_FAB2_LIB.BASEBOARD_FAB2(SCH_1):IRQ_PVNN_PCH_VRHOT_N

RES_0402-2.67K,1%,1/16W,CHIP,GA  I217  R8A2
   1 VR_PVNN_PCH_XADDR2      A @BASEBOARD_FAB2_LIB.BASEBOARD_FAB2(SCH_1):VR_PVNN_PCH_XADDR2
   2    GND      B @BASEBOARD_FAB2_LIB.BASEBOARD_FAB2(SCH_1):GND

CAP_0402LF-1000PF,50V,10%,X7R,A  I218  C8A9
   1 PWRGD_PVNN_PCH_R      A @BASEBOARD_FAB2_LIB.BASEBOARD_FAB2(SCH_1):PWRGD_PVNN_PCH_R
   2    GND      B @BASEBOARD_FAB2_LIB.BASEBOARD_FAB2(SCH_1):GND

RES_0402-0.0,5%,1/16W,CHIP,G21A  I221  R2L17
   1 PWRGD_P1V8_PCH_STBY      A @BASEBOARD_FAB2_LIB.BASEBOARD_FAB2(SCH_1):PWRGD_P1V8_PCH_STBY
   2 VR_PVNN_PCH_VREN      B @BASEBOARD_FAB2_LIB.BASEBOARD_FAB2(SCH_1):VR_PVNN_PCH_VREN

RES_0402-100.0K,1%,1/16W,EMPTYA  I222  R8A7
   1 P3V3_STBY      A @BASEBOARD_FAB2_LIB.BASEBOARD_FAB2(SCH_1):P3V3_STBY
   2 VR_PVNN_PCH_VREN      B @BASEBOARD_FAB2_LIB.BASEBOARD_FAB2(SCH_1):VR_PVNN_PCH_VREN

PXE1110B_QFN-IC,H89187-001  I229  EU8A1
   1     NC DNC<0>     NC
   2     NC DNC<1>     NC
   3 VR_P1V05_PCH_STBY_PWM1  BPWM1 @BASEBOARD_FAB2_LIB.BASEBOARD_FAB2(SCH_1):VR_P1V05_PCH_STBY_PWM1
   4     NC DNC<2>     NC
   5 VR_PVNN_PCH_PWM1  APWM1 @BASEBOARD_FAB2_LIB.BASEBOARD_FAB2(SCH_1):VR_PVNN_PCH_PWM1
   6 SMB_VR_STBY_LVC3_SDA    SDA @BASEBOARD_FAB2_LIB.BASEBOARD_FAB2(SCH_1):SMB_VR_STBY_LVC3_SDA
   7 SMB_VR_STBY_LVC3_SCL    SCL @BASEBOARD_FAB2_LIB.BASEBOARD_FAB2(SCH_1):SMB_VR_STBY_LVC3_SCL
   8     NC RESET_N     NC
   9 PWRGD_PVNN_PCH_R AVRRDY @BASEBOARD_FAB2_LIB.BASEBOARD_FAB2(SCH_1):PWRGD_PVNN_PCH_R
  10 VR_PVNN_PCH_VREN  AVREN @BASEBOARD_FAB2_LIB.BASEBOARD_FAB2(SCH_1):VR_PVNN_PCH_VREN
  11 IRQ_PVNN_PCH_VRHOT_N VRHOT_N @BASEBOARD_FAB2_LIB.BASEBOARD_FAB2(SCH_1):IRQ_PVNN_PCH_VRHOT_N
  12 PU_PVNN_PCH_PINALRT_N PINALRT_N @BASEBOARD_FAB2_LIB.BASEBOARD_FAB2(SCH_1):PU_PVNN_PCH_PINALRT_N
  13 VID_PCH_CORE_PVNN_AUX_VID_0    MP0 @BASEBOARD_FAB2_LIB.BASEBOARD_FAB2(SCH_1):VID_PCH_CORE_PVNN_AUX_VID_0
  14 VID_PCH_CORE_PVNN_AUX_VID_1    MP1 @BASEBOARD_FAB2_LIB.BASEBOARD_FAB2(SCH_1):VID_PCH_CORE_PVNN_AUX_VID_1
  15 PU_PVNN_PCH_VCLK   VCLK @BASEBOARD_FAB2_LIB.BASEBOARD_FAB2(SCH_1):PU_PVNN_PCH_VCLK
  16 PU_PVNN_PCH_VDIO   VDIO @BASEBOARD_FAB2_LIB.BASEBOARD_FAB2(SCH_1):PU_PVNN_PCH_VDIO
  17     NC VALRT_N     NC
  18     NC    MP2     NC
  19 VR_PVNN_PCH_AVSP  AVSEN @BASEBOARD_FAB2_LIB.BASEBOARD_FAB2(SCH_1):VR_PVNN_PCH_AVSP
  20 VSENSE_PVNN_PCH_STBY_AVSN  AVREF @BASEBOARD_FAB2_LIB.BASEBOARD_FAB2(SCH_1):VSENSE_PVNN_PCH_STBY_AVSN
  21 VR_PVNN_PCH_AIREF1 AIREF1 @BASEBOARD_FAB2_LIB.BASEBOARD_FAB2(SCH_1):VR_PVNN_PCH_AIREF1
  22 ISENSE_PVNN_PCH_PH1_IMON AISEN1 @BASEBOARD_FAB2_LIB.BASEBOARD_FAB2(SCH_1):ISENSE_PVNN_PCH_PH1_IMON
  23    GND GND<1> @BASEBOARD_FAB2_LIB.BASEBOARD_FAB2(SCH_1):GND
  24     NC DNC<3>     NC
  25 VR_P1V05_PCH_BIREF1 BIREF1 @BASEBOARD_FAB2_LIB.BASEBOARD_FAB2(SCH_1):VR_P1V05_PCH_BIREF1
  26 ISENSE_P1V05_PCH_STBY_PH1_IMON BISEN1 @BASEBOARD_FAB2_LIB.BASEBOARD_FAB2(SCH_1):ISENSE_P1V05_PCH_STBY_PH1_IMON
  27    GND GND<0> @BASEBOARD_FAB2_LIB.BASEBOARD_FAB2(SCH_1):GND
  28     NC DNC<4>     NC
  29 VR_P1V05_PCH_STBY_AVSP  BVSEN @BASEBOARD_FAB2_LIB.BASEBOARD_FAB2(SCH_1):VR_P1V05_PCH_STBY_AVSP
  30 VSENSE_P1V05_PCH_STBY_AVSN  BVREF @BASEBOARD_FAB2_LIB.BASEBOARD_FAB2(SCH_1):VSENSE_P1V05_PCH_STBY_AVSN
  31     NC    MP3     NC
  32 PU_VR_PVNN_PCH_FAULT1    MP4 @BASEBOARD_FAB2_LIB.BASEBOARD_FAB2(SCH_1):PU_VR_PVNN_PCH_FAULT1
  33 VR_PVNN_PCH_XADDR2 XADDR2 @BASEBOARD_FAB2_LIB.BASEBOARD_FAB2(SCH_1):VR_PVNN_PCH_XADDR2
  34 A_TSENSE_P1V05_PCH_STBY_TMON  BTSEN @BASEBOARD_FAB2_LIB.BASEBOARD_FAB2(SCH_1):A_TSENSE_P1V05_PCH_STBY_TMON
  35 A_TSENSE_PVNN_PCH_TMON  ATSEN @BASEBOARD_FAB2_LIB.BASEBOARD_FAB2(SCH_1):A_TSENSE_PVNN_PCH_TMON
  36 VR_PVNN_PCH_XADDR1 XADDR1 @BASEBOARD_FAB2_LIB.BASEBOARD_FAB2(SCH_1):VR_PVNN_PCH_XADDR1
  37 VR_PVNN_PCH_VINSEN VINSEN @BASEBOARD_FAB2_LIB.BASEBOARD_FAB2(SCH_1):VR_PVNN_PCH_VINSEN
  38     NC IINSEN     NC
  39 VR_PVNN_PCH_VDD    VDD @BASEBOARD_FAB2_LIB.BASEBOARD_FAB2(SCH_1):VR_PVNN_PCH_VDD
  40 VR_PVNN_P1V05_PCH_VD12   VD12 @BASEBOARD_FAB2_LIB.BASEBOARD_FAB2(SCH_1):VR_PVNN_P1V05_PCH_VD12
  41    GND  THPAD @BASEBOARD_FAB2_LIB.BASEBOARD_FAB2(SCH_1):GND

SC22P50V2JN-4GP_SMD-BCG-SC22P5A  I239  CF23
   1 VR_PVNN_PCH_AIREF1      1 @BASEBOARD_FAB2_LIB.BASEBOARD_FAB2(SCH_1):VR_PVNN_PCH_AIREF1
   2 ISENSE_PVNN_PCH_PH1_IMON      2 @BASEBOARD_FAB2_LIB.BASEBOARD_FAB2(SCH_1):ISENSE_PVNN_PCH_PH1_IMON

SC22P50V2JN-4GP_SMD-BCG-SC22P5A  I240  CF24
   1 VR_P1V05_PCH_BIREF1      1 @BASEBOARD_FAB2_LIB.BASEBOARD_FAB2(SCH_1):VR_P1V05_PCH_BIREF1
   2 ISENSE_P1V05_PCH_STBY_PH1_IMON      2 @BASEBOARD_FAB2_LIB.BASEBOARD_FAB2(SCH_1):ISENSE_P1V05_PCH_STBY_PH1_IMON

RES_0402-1.0K,0.1%,1/16W,CHIP,A  I241  RF23
   1 VR_PVNN_PCH_AIREF1      A @BASEBOARD_FAB2_LIB.BASEBOARD_FAB2(SCH_1):VR_PVNN_PCH_AIREF1
   2 ISENSE_PVNN_PCH_PH1_IMON      B @BASEBOARD_FAB2_LIB.BASEBOARD_FAB2(SCH_1):ISENSE_PVNN_PCH_PH1_IMON

RES_0402-1.0K,0.1%,1/16W,CHIP,A  I242  RF24
   1 VR_P1V05_PCH_BIREF1      A @BASEBOARD_FAB2_LIB.BASEBOARD_FAB2(SCH_1):VR_P1V05_PCH_BIREF1
   2 ISENSE_P1V05_PCH_STBY_PH1_IMON      B @BASEBOARD_FAB2_LIB.BASEBOARD_FAB2(SCH_1):ISENSE_P1V05_PCH_STBY_PH1_IMON

CAP_0402LF-220PF,50V,10%,X7R,AA  I244  C4W3
   1 A_TSENSE_PVNN_PCH_TMON      A @BASEBOARD_FAB2_LIB.BASEBOARD_FAB2(SCH_1):A_TSENSE_PVNN_PCH_TMON
   2    GND      B @BASEBOARD_FAB2_LIB.BASEBOARD_FAB2(SCH_1):GND

CAP_0402LF-220PF,50V,10%,X7R,AA  I246  C4W4
   1 A_TSENSE_P1V05_PCH_STBY_TMON      A @BASEBOARD_FAB2_LIB.BASEBOARD_FAB2(SCH_1):A_TSENSE_P1V05_PCH_STBY_TMON
   2    GND      B @BASEBOARD_FAB2_LIB.BASEBOARD_FAB2(SCH_1):GND

RES_0402-1.00K,1%,1/16W,CHIP,GA  I247  R8W2
   1 PU_PVNN_PCH_VCLK      A @BASEBOARD_FAB2_LIB.BASEBOARD_FAB2(SCH_1):PU_PVNN_PCH_VCLK
   2 VR_PVNN_P1V05_PCH_VD12      B @BASEBOARD_FAB2_LIB.BASEBOARD_FAB2(SCH_1):VR_PVNN_P1V05_PCH_VD12

RES_0402-1.00K,1%,1/16W,CHIP,GA  I248  R8W3
   1 VR_PVNN_P1V05_PCH_VD12      A @BASEBOARD_FAB2_LIB.BASEBOARD_FAB2(SCH_1):VR_PVNN_P1V05_PCH_VD12
   2 PU_PVNN_PCH_VDIO      B @BASEBOARD_FAB2_LIB.BASEBOARD_FAB2(SCH_1):PU_PVNN_PCH_VDIO

RES_0402-1.00K,1%,1/16W,CHIP,GA  I249  R8W8
   1 P3V3_STBY      A @BASEBOARD_FAB2_LIB.BASEBOARD_FAB2(SCH_1):P3V3_STBY
   2 PU_PVNN_PCH_PINALRT_N      B @BASEBOARD_FAB2_LIB.BASEBOARD_FAB2(SCH_1):PU_PVNN_PCH_PINALRT_N

RES_0402-100.0K,1%,1/16W,CHIP,A  I252  R2L25
   1 P3V3_STBY      A @BASEBOARD_FAB2_LIB.BASEBOARD_FAB2(SCH_1):P3V3_STBY
   2 VID_PCH_CORE_PVNN_AUX_VID_1      B @BASEBOARD_FAB2_LIB.BASEBOARD_FAB2(SCH_1):VID_PCH_CORE_PVNN_AUX_VID_1

RES_0402-100.0K,1%,1/16W,CHIP,A  I253  R2L26
   1 P3V3_STBY      A @BASEBOARD_FAB2_LIB.BASEBOARD_FAB2(SCH_1):P3V3_STBY
   2 VID_PCH_CORE_PVNN_AUX_VID_0      B @BASEBOARD_FAB2_LIB.BASEBOARD_FAB2(SCH_1):VID_PCH_CORE_PVNN_AUX_VID_0

RES_0402-4.02K,1%,1/16W,CHIP,GA  I254  R2L9
   1 VR_PVNN_PCH_XADDR1      A @BASEBOARD_FAB2_LIB.BASEBOARD_FAB2(SCH_1):VR_PVNN_PCH_XADDR1
   2    GND      B @BASEBOARD_FAB2_LIB.BASEBOARD_FAB2(SCH_1):GND

CAP_A_0402V-0.1UF,16V,10%,X7R,A  I255  C8A3
   1 VR_PVNN_PCH_VINSEN      A @BASEBOARD_FAB2_LIB.BASEBOARD_FAB2(SCH_1):VR_PVNN_PCH_VINSEN
   2    GND      B @BASEBOARD_FAB2_LIB.BASEBOARD_FAB2(SCH_1):GND


DRAWING: @BASEBOARD_FAB2_LIB.BASEBOARD_FAB2(SCH_1):PAGE236 

CAP_0805LF-22UF,4V,20%,X6S,C95A  I9  C7A30
   1 PVNN_PCH_STBY      A @BASEBOARD_FAB2_LIB.BASEBOARD_FAB2(SCH_1):PVNN_PCH_STBY
   2    GND      B @BASEBOARD_FAB2_LIB.BASEBOARD_FAB2(SCH_1):GND

CAP_0402-0.22UF,16V,10%,X7R,A3A  I16  C7A8
   1 P5V_STBY      A @BASEBOARD_FAB2_LIB.BASEBOARD_FAB2(SCH_1):P5V_STBY
   2    GND      B @BASEBOARD_FAB2_LIB.BASEBOARD_FAB2(SCH_1):GND

CAP_0402-1.0UF,16V,10%,X6S,D97A  I19  C7A6
   1 VR_PVNN_PCH_PH1_VCIN      A @BASEBOARD_FAB2_LIB.BASEBOARD_FAB2(SCH_1):VR_PVNN_PCH_PH1_VCIN
   2    GND      B @BASEBOARD_FAB2_LIB.BASEBOARD_FAB2(SCH_1):GND

CAP_A_0402V-0.1UF,16V,10%,X7R,A  I20  C7A39
   1 VR_FET_SW_P12V_STBY_PVDDQ_DEF      A @BASEBOARD_FAB2_LIB.BASEBOARD_FAB2(SCH_1):VR_FET_SW_P12V_STBY_PVDDQ_DEF
   2    GND      B @BASEBOARD_FAB2_LIB.BASEBOARD_FAB2(SCH_1):GND

CAP_0402-0.220UF,16V,10%,X7R,AA  I21  C7A43
   1 VR_PVNN_PCH_PH1_BOOT      A @BASEBOARD_FAB2_LIB.BASEBOARD_FAB2(SCH_1):VR_PVNN_PCH_PH1_BOOT
   2 VR_PVNN_PCH_PH1_PHASE      B @BASEBOARD_FAB2_LIB.BASEBOARD_FAB2(SCH_1):VR_PVNN_PCH_PH1_PHASE

CAP_0402-1.0UF,16V,10%,X6S,D97A  I22  C7A7
   1 VR_FET_SW_P12V_STBY_PVDDQ_DEF      A @BASEBOARD_FAB2_LIB.BASEBOARD_FAB2(SCH_1):VR_FET_SW_P12V_STBY_PVDDQ_DEF
   2    GND      B @BASEBOARD_FAB2_LIB.BASEBOARD_FAB2(SCH_1):GND

CAP_0805-10UF,16V,10%,X6S,C953A  I23  C3L12
   1 VR_FET_SW_P12V_STBY_PVDDQ_DEF      A @BASEBOARD_FAB2_LIB.BASEBOARD_FAB2(SCH_1):VR_FET_SW_P12V_STBY_PVDDQ_DEF
   2    GND      B @BASEBOARD_FAB2_LIB.BASEBOARD_FAB2(SCH_1):GND

CAP_0805-10UF,16V,10%,X6S,C953A  I24  C3L11
   1 VR_FET_SW_P12V_STBY_PVDDQ_DEF      A @BASEBOARD_FAB2_LIB.BASEBOARD_FAB2(SCH_1):VR_FET_SW_P12V_STBY_PVDDQ_DEF
   2    GND      B @BASEBOARD_FAB2_LIB.BASEBOARD_FAB2(SCH_1):GND

CAP_0805-10UF,16V,10%,X6S,C953A  I26  C3L8
   1 VR_FET_SW_P12V_STBY_PVDDQ_DEF      A @BASEBOARD_FAB2_LIB.BASEBOARD_FAB2(SCH_1):VR_FET_SW_P12V_STBY_PVDDQ_DEF
   2    GND      B @BASEBOARD_FAB2_LIB.BASEBOARD_FAB2(SCH_1):GND

CAP_0805-10UF,16V,10%,X6S,C953A  I29  C3L9
   1 VR_FET_SW_P12V_STBY_PVDDQ_DEF      A @BASEBOARD_FAB2_LIB.BASEBOARD_FAB2(SCH_1):VR_FET_SW_P12V_STBY_PVDDQ_DEF
   2    GND      B @BASEBOARD_FAB2_LIB.BASEBOARD_FAB2(SCH_1):GND

CAP_0805-10UF,16V,10%,X6S,C953A  I31  C3L7
   1 VR_FET_SW_P12V_STBY_PVDDQ_DEF      A @BASEBOARD_FAB2_LIB.BASEBOARD_FAB2(SCH_1):VR_FET_SW_P12V_STBY_PVDDQ_DEF
   2    GND      B @BASEBOARD_FAB2_LIB.BASEBOARD_FAB2(SCH_1):GND

CAP_0805-10UF,16V,10%,X6S,C953A  I32  C3L10
   1 VR_FET_SW_P12V_STBY_PVDDQ_DEF      A @BASEBOARD_FAB2_LIB.BASEBOARD_FAB2(SCH_1):VR_FET_SW_P12V_STBY_PVDDQ_DEF
   2    GND      B @BASEBOARD_FAB2_LIB.BASEBOARD_FAB2(SCH_1):GND

CAP_0402-1.0UF,16V,10%,X6S,D97A  I33  C7A9
   1 VR_FET_SW_P12V_STBY_PVDDQ_DEF      A @BASEBOARD_FAB2_LIB.BASEBOARD_FAB2(SCH_1):VR_FET_SW_P12V_STBY_PVDDQ_DEF
   2    GND      B @BASEBOARD_FAB2_LIB.BASEBOARD_FAB2(SCH_1):GND

CAP_0402-0.220UF,16V,10%,X7R,AA  I34  C7A44
   1 VR_P1V05_PCH_STBY_PH1_BOOT      A @BASEBOARD_FAB2_LIB.BASEBOARD_FAB2(SCH_1):VR_P1V05_PCH_STBY_PH1_BOOT
   2 VR_P1V05_PCH_STBY_PH1_PHASE      B @BASEBOARD_FAB2_LIB.BASEBOARD_FAB2(SCH_1):VR_P1V05_PCH_STBY_PH1_PHASE

CAP_A_0402V-0.1UF,16V,10%,X7R,A  I35  C7A40
   1 VR_FET_SW_P12V_STBY_PVDDQ_DEF      A @BASEBOARD_FAB2_LIB.BASEBOARD_FAB2(SCH_1):VR_FET_SW_P12V_STBY_PVDDQ_DEF
   2    GND      B @BASEBOARD_FAB2_LIB.BASEBOARD_FAB2(SCH_1):GND

CAP_0402-1.0UF,16V,10%,X6S,D97A  I36  C7A10
   1 VR_P1V05_PCH_STBY_PH1_VCIN      A @BASEBOARD_FAB2_LIB.BASEBOARD_FAB2(SCH_1):VR_P1V05_PCH_STBY_PH1_VCIN
   2    GND      B @BASEBOARD_FAB2_LIB.BASEBOARD_FAB2(SCH_1):GND

CAP_0402-0.22UF,16V,10%,X7R,A3A  I39  C7A41
   1 P5V_STBY      A @BASEBOARD_FAB2_LIB.BASEBOARD_FAB2(SCH_1):P5V_STBY
   2    GND      B @BASEBOARD_FAB2_LIB.BASEBOARD_FAB2(SCH_1):GND

CAP_0805LF-22UF,4V,20%,X6S,C95A  I46  C7A42
   1 P1V05_PCH_STBY      A @BASEBOARD_FAB2_LIB.BASEBOARD_FAB2(SCH_1):P1V05_PCH_STBY
   2    GND      B @BASEBOARD_FAB2_LIB.BASEBOARD_FAB2(SCH_1):GND

RES_0402-0.0,5%,1/16W,CHIP,G21A  I56  R8B14
   1 VSENSE_P1V05_PCH_STBY_AVSP      A @BASEBOARD_FAB2_LIB.BASEBOARD_FAB2(SCH_1):VSENSE_P1V05_PCH_STBY_AVSP
   2 P1V05_PCH_STBY      B @BASEBOARD_FAB2_LIB.BASEBOARD_FAB2(SCH_1):P1V05_PCH_STBY

RES_0402-100.0,1%,1/16W,EMPTY,A  I57  R8B15
   1 VSENSE_P1V05_PCH_STBY_AVSP      A @BASEBOARD_FAB2_LIB.BASEBOARD_FAB2(SCH_1):VSENSE_P1V05_PCH_STBY_AVSP
   2 VSENSE_P1V05_PCH_STBY_AVSN      B @BASEBOARD_FAB2_LIB.BASEBOARD_FAB2(SCH_1):VSENSE_P1V05_PCH_STBY_AVSN

RES_0402-0.0,5%,1/16W,CHIP,G21A  I59  R8B12
   1 VSENSE_P1V05_PCH_STBY_AVSN      A @BASEBOARD_FAB2_LIB.BASEBOARD_FAB2(SCH_1):VSENSE_P1V05_PCH_STBY_AVSN
   2    GND      B @BASEBOARD_FAB2_LIB.BASEBOARD_FAB2(SCH_1):GND

CAPP_SM-470UF,2V,20%,ALUM,6990A  I71  C3L18
   1 PVNN_PCH_STBY      A @BASEBOARD_FAB2_LIB.BASEBOARD_FAB2(SCH_1):PVNN_PCH_STBY
   2    GND      B @BASEBOARD_FAB2_LIB.BASEBOARD_FAB2(SCH_1):GND

CAPP_SM-470UF,2V,20%,ALUM,6990A  I73  C3L20
   1 PVNN_PCH_STBY      A @BASEBOARD_FAB2_LIB.BASEBOARD_FAB2(SCH_1):PVNN_PCH_STBY
   2    GND      B @BASEBOARD_FAB2_LIB.BASEBOARD_FAB2(SCH_1):GND

CAPP_SM-470UF,2V,20%,ALUM,6990A  I74  C3L21
   1 PVNN_PCH_STBY      A @BASEBOARD_FAB2_LIB.BASEBOARD_FAB2(SCH_1):PVNN_PCH_STBY
   2    GND      B @BASEBOARD_FAB2_LIB.BASEBOARD_FAB2(SCH_1):GND

CAPP_SM-470UF,2V,20%,ALUM,6990A  I75  C7A27
   1 PVNN_PCH_STBY      A @BASEBOARD_FAB2_LIB.BASEBOARD_FAB2(SCH_1):PVNN_PCH_STBY
   2    GND      B @BASEBOARD_FAB2_LIB.BASEBOARD_FAB2(SCH_1):GND

CAPP_SM-470UF,2V,20%,ALUM,6990A  I76  C3L19
   1 P1V05_PCH_STBY      A @BASEBOARD_FAB2_LIB.BASEBOARD_FAB2(SCH_1):P1V05_PCH_STBY
   2    GND      B @BASEBOARD_FAB2_LIB.BASEBOARD_FAB2(SCH_1):GND

CAPP_SM-470UF,2V,20%,ALUM,6990A  I77  C2L46
   1 P1V05_PCH_STBY      A @BASEBOARD_FAB2_LIB.BASEBOARD_FAB2(SCH_1):P1V05_PCH_STBY
   2    GND      B @BASEBOARD_FAB2_LIB.BASEBOARD_FAB2(SCH_1):GND

CAPP_SM-470UF,2V,20%,ALUM,6990A  I78  C8A15
   1 P1V05_PCH_STBY      A @BASEBOARD_FAB2_LIB.BASEBOARD_FAB2(SCH_1):P1V05_PCH_STBY
   2    GND      B @BASEBOARD_FAB2_LIB.BASEBOARD_FAB2(SCH_1):GND

CAPP_SM-470UF,2V,20%,ALUM,6990A  I79  C2L25
   1 P1V05_PCH_STBY      A @BASEBOARD_FAB2_LIB.BASEBOARD_FAB2(SCH_1):P1V05_PCH_STBY
   2    GND      B @BASEBOARD_FAB2_LIB.BASEBOARD_FAB2(SCH_1):GND

RES_0402-100.0,1%,1/16W,CHIP,GA  I90  R7A13
   1 VSENSE_PVNN_PCH_STBY_AVSP      A @BASEBOARD_FAB2_LIB.BASEBOARD_FAB2(SCH_1):VSENSE_PVNN_PCH_STBY_AVSP
   2 PVNN_PCH_STBY      B @BASEBOARD_FAB2_LIB.BASEBOARD_FAB2(SCH_1):PVNN_PCH_STBY

RES_0402-0.0,5%,1/16W,CHIP,G21A  I92  R7A18
   1    GND      A @BASEBOARD_FAB2_LIB.BASEBOARD_FAB2(SCH_1):GND
   2 VSENSE_PVNN_PCH_STBY_AVSN      B @BASEBOARD_FAB2_LIB.BASEBOARD_FAB2(SCH_1):VSENSE_PVNN_PCH_STBY_AVSN

RES_0402-10.0,1%,1/16W,CHIP,G2A  I93  R7A19
   1 VSENSE_PVNN_PCH_STBY_QAT      A @BASEBOARD_FAB2_LIB.BASEBOARD_FAB2(SCH_1):VSENSE_PVNN_PCH_STBY_QAT
   2 VSENSE_PVNN_PCH_STBY_AVSP      B @BASEBOARD_FAB2_LIB.BASEBOARD_FAB2(SCH_1):VSENSE_PVNN_PCH_STBY_AVSP

RES_0402-10.0,1%,1/16W,CHIP,G2A  I94  R7A14
   1 VSENSE_PVNN_PCH_STBY_FPK      A @BASEBOARD_FAB2_LIB.BASEBOARD_FAB2(SCH_1):VSENSE_PVNN_PCH_STBY_FPK
   2 VSENSE_PVNN_PCH_STBY_AVSP      B @BASEBOARD_FAB2_LIB.BASEBOARD_FAB2(SCH_1):VSENSE_PVNN_PCH_STBY_AVSP

IR354XX_SM-IR35412,IC,H73684-0A  I116  EU7A3
  33 VR_PVNN_PCH_PH1_BOOT_R  BOOST @BASEBOARD_FAB2_LIB.BASEBOARD_FAB2(SCH_1):VR_PVNN_PCH_PH1_BOOT_R
  35 P5V_STBY     EN @BASEBOARD_FAB2_LIB.BASEBOARD_FAB2(SCH_1):P5V_STBY
  41 TP_PVNN_PCH_GL_1  GL<1> @BASEBOARD_FAB2_LIB.BASEBOARD_FAB2(SCH_1):TP_PVNN_PCH_GL_1
   6 TP_PVNN_PCH_GL_0  GL<0> @BASEBOARD_FAB2_LIB.BASEBOARD_FAB2(SCH_1):TP_PVNN_PCH_GL_0
  38 ISENSE_PVNN_PCH_PH1_IMON   IOUT @BASEBOARD_FAB2_LIB.BASEBOARD_FAB2(SCH_1):ISENSE_PVNN_PCH_PH1_IMON
   2    GND   LGND @BASEBOARD_FAB2_LIB.BASEBOARD_FAB2(SCH_1):GND
  31     NC     NC     NC
  37 VR_PVNN_PCH_STBY_OCSET  OCSET @BASEBOARD_FAB2_LIB.BASEBOARD_FAB2(SCH_1):VR_PVNN_PCH_STBY_OCSET
  40    GND PGND<2> @BASEBOARD_FAB2_LIB.BASEBOARD_FAB2(SCH_1):GND
   7    GND PGND<1> @BASEBOARD_FAB2_LIB.BASEBOARD_FAB2(SCH_1):GND
   5    GND PGND<0> @BASEBOARD_FAB2_LIB.BASEBOARD_FAB2(SCH_1):GND
  32 VR_PVNN_PCH_PH1_PHASE  PHASE @BASEBOARD_FAB2_LIB.BASEBOARD_FAB2(SCH_1):VR_PVNN_PCH_PH1_PHASE
  34 VR_PVNN_PCH_PWM1    PWM @BASEBOARD_FAB2_LIB.BASEBOARD_FAB2(SCH_1):VR_PVNN_PCH_PWM1
  39 VR_PVNN_PCH_AIREF1  REFIN @BASEBOARD_FAB2_LIB.BASEBOARD_FAB2(SCH_1):VR_PVNN_PCH_AIREF1
  10 VR_PVNN_PCH_PH1_PHASE_SW     SW @BASEBOARD_FAB2_LIB.BASEBOARD_FAB2(SCH_1):VR_PVNN_PCH_PH1_PHASE_SW
  36 A_TSENSE_PVNN_PCH_TMON TOUT_FLT @BASEBOARD_FAB2_LIB.BASEBOARD_FAB2(SCH_1):A_TSENSE_PVNN_PCH_TMON
   3 VR_PVNN_PCH_PH1_VCIN    VCC @BASEBOARD_FAB2_LIB.BASEBOARD_FAB2(SCH_1):VR_PVNN_PCH_PH1_VCIN
   4 P5V_STBY   VDRV @BASEBOARD_FAB2_LIB.BASEBOARD_FAB2(SCH_1):P5V_STBY
  30 VR_FET_SW_P12V_STBY_PVDDQ_DEF VIN<1> @BASEBOARD_FAB2_LIB.BASEBOARD_FAB2(SCH_1):VR_FET_SW_P12V_STBY_PVDDQ_DEF
  25 VR_FET_SW_P12V_STBY_PVDDQ_DEF VIN<0> @BASEBOARD_FAB2_LIB.BASEBOARD_FAB2(SCH_1):VR_FET_SW_P12V_STBY_PVDDQ_DEF
   1 PVNN_PCH_STBY    VOS @BASEBOARD_FAB2_LIB.BASEBOARD_FAB2(SCH_1):PVNN_PCH_STBY

IR354XX_SM-IR35412,IC,H73684-0A  I117  EU7A2
  33 VR_P1V05_PCH_STBY_PH1_BOOT_R  BOOST @BASEBOARD_FAB2_LIB.BASEBOARD_FAB2(SCH_1):VR_P1V05_PCH_STBY_PH1_BOOT_R
  35 P5V_STBY     EN @BASEBOARD_FAB2_LIB.BASEBOARD_FAB2(SCH_1):P5V_STBY
  41 TP_P1V05_PCH_GL_1  GL<1> @BASEBOARD_FAB2_LIB.BASEBOARD_FAB2(SCH_1):TP_P1V05_PCH_GL_1
   6 TP_P1V05_PCH_GL_0  GL<0> @BASEBOARD_FAB2_LIB.BASEBOARD_FAB2(SCH_1):TP_P1V05_PCH_GL_0
  38 ISENSE_P1V05_PCH_STBY_PH1_IMON   IOUT @BASEBOARD_FAB2_LIB.BASEBOARD_FAB2(SCH_1):ISENSE_P1V05_PCH_STBY_PH1_IMON
   2    GND   LGND @BASEBOARD_FAB2_LIB.BASEBOARD_FAB2(SCH_1):GND
  31     NC     NC     NC
  37 VR_P1V05_PCH_STBY_OCSET  OCSET @BASEBOARD_FAB2_LIB.BASEBOARD_FAB2(SCH_1):VR_P1V05_PCH_STBY_OCSET
  40    GND PGND<2> @BASEBOARD_FAB2_LIB.BASEBOARD_FAB2(SCH_1):GND
   7    GND PGND<1> @BASEBOARD_FAB2_LIB.BASEBOARD_FAB2(SCH_1):GND
   5    GND PGND<0> @BASEBOARD_FAB2_LIB.BASEBOARD_FAB2(SCH_1):GND
  32 VR_P1V05_PCH_STBY_PH1_PHASE  PHASE @BASEBOARD_FAB2_LIB.BASEBOARD_FAB2(SCH_1):VR_P1V05_PCH_STBY_PH1_PHASE
  34 VR_P1V05_PCH_STBY_PWM1    PWM @BASEBOARD_FAB2_LIB.BASEBOARD_FAB2(SCH_1):VR_P1V05_PCH_STBY_PWM1
  39 VR_P1V05_PCH_BIREF1  REFIN @BASEBOARD_FAB2_LIB.BASEBOARD_FAB2(SCH_1):VR_P1V05_PCH_BIREF1
  10 VR_P1V05_PCH_STBY_PH1_PHASE_SW     SW @BASEBOARD_FAB2_LIB.BASEBOARD_FAB2(SCH_1):VR_P1V05_PCH_STBY_PH1_PHASE_SW
  36 A_TSENSE_P1V05_PCH_STBY_TMON TOUT_FLT @BASEBOARD_FAB2_LIB.BASEBOARD_FAB2(SCH_1):A_TSENSE_P1V05_PCH_STBY_TMON
   3 VR_P1V05_PCH_STBY_PH1_VCIN    VCC @BASEBOARD_FAB2_LIB.BASEBOARD_FAB2(SCH_1):VR_P1V05_PCH_STBY_PH1_VCIN
   4 P5V_STBY   VDRV @BASEBOARD_FAB2_LIB.BASEBOARD_FAB2(SCH_1):P5V_STBY
  30 VR_FET_SW_P12V_STBY_PVDDQ_DEF VIN<1> @BASEBOARD_FAB2_LIB.BASEBOARD_FAB2(SCH_1):VR_FET_SW_P12V_STBY_PVDDQ_DEF
  25 VR_FET_SW_P12V_STBY_PVDDQ_DEF VIN<0> @BASEBOARD_FAB2_LIB.BASEBOARD_FAB2(SCH_1):VR_FET_SW_P12V_STBY_PVDDQ_DEF
   1 P1V05_PCH_STBY    VOS @BASEBOARD_FAB2_LIB.BASEBOARD_FAB2(SCH_1):P1V05_PCH_STBY

RES_0402-68.1K,1%,1/16W,EMPTY,A  I118  R3L15
   1 VR_PVNN_PCH_STBY_OCSET      A @BASEBOARD_FAB2_LIB.BASEBOARD_FAB2(SCH_1):VR_PVNN_PCH_STBY_OCSET
   2    GND      B @BASEBOARD_FAB2_LIB.BASEBOARD_FAB2(SCH_1):GND

RES_0402-68.1K,1%,1/16W,EMPTY,A  I120  R3L14
   1 VR_P1V05_PCH_STBY_OCSET      A @BASEBOARD_FAB2_LIB.BASEBOARD_FAB2(SCH_1):VR_P1V05_PCH_STBY_OCSET
   2    GND      B @BASEBOARD_FAB2_LIB.BASEBOARD_FAB2(SCH_1):GND

CAP_A_0402V-0.1UF,16V,10%,X7R,A  I124  CT67
   1 VR_P1V05_PCH_BIREF1      A @BASEBOARD_FAB2_LIB.BASEBOARD_FAB2(SCH_1):VR_P1V05_PCH_BIREF1
   2    GND      B @BASEBOARD_FAB2_LIB.BASEBOARD_FAB2(SCH_1):GND

CAP_A_0402V-0.1UF,16V,10%,X7R,A  I127  CT66
   1 VR_PVNN_PCH_AIREF1      A @BASEBOARD_FAB2_LIB.BASEBOARD_FAB2(SCH_1):VR_PVNN_PCH_AIREF1
   2    GND      B @BASEBOARD_FAB2_LIB.BASEBOARD_FAB2(SCH_1):GND

CAP_0402LF-1000PF,50V,10%,X7R,A  I134  CT69
   1 A_TSENSE_P1V05_PCH_STBY_TMON      A @BASEBOARD_FAB2_LIB.BASEBOARD_FAB2(SCH_1):A_TSENSE_P1V05_PCH_STBY_TMON
   2    GND      B @BASEBOARD_FAB2_LIB.BASEBOARD_FAB2(SCH_1):GND

CAP_0402LF-1000PF,50V,10%,X7R,A  I136  CT64
   1 A_TSENSE_PVNN_PCH_TMON      A @BASEBOARD_FAB2_LIB.BASEBOARD_FAB2(SCH_1):A_TSENSE_PVNN_PCH_TMON
   2    GND      B @BASEBOARD_FAB2_LIB.BASEBOARD_FAB2(SCH_1):GND

CAP_0402LF-1000PF,50V,10%,X7R,A  I149  CT65
   1 VR_PVNN_PCH_PH1_PHASE_SW      A @BASEBOARD_FAB2_LIB.BASEBOARD_FAB2(SCH_1):VR_PVNN_PCH_PH1_PHASE_SW
   2 VR_PVNN_PCH_PH1_PHASE_SW_RC      B @BASEBOARD_FAB2_LIB.BASEBOARD_FAB2(SCH_1):VR_PVNN_PCH_PH1_PHASE_SW_RC

CAP_0402LF-1000PF,50V,10%,X7R,A  I150  CT68
   1 VR_P1V05_PCH_STBY_PH1_PHASE_SW      A @BASEBOARD_FAB2_LIB.BASEBOARD_FAB2(SCH_1):VR_P1V05_PCH_STBY_PH1_PHASE_SW
   2 VR_P1V05_PCH_STBY_PH1_SW_RC      B @BASEBOARD_FAB2_LIB.BASEBOARD_FAB2(SCH_1):VR_P1V05_PCH_STBY_PH1_SW_RC

RES_0603-0,5.0%,1/10W,CHIP,G22A  I153  RT44
   1 VR_PVNN_PCH_PH1_BOOT      A @BASEBOARD_FAB2_LIB.BASEBOARD_FAB2(SCH_1):VR_PVNN_PCH_PH1_BOOT
   2 VR_PVNN_PCH_PH1_BOOT_R      B @BASEBOARD_FAB2_LIB.BASEBOARD_FAB2(SCH_1):VR_PVNN_PCH_PH1_BOOT_R

RES_0603-0,5.0%,1/10W,CHIP,G22A  I154  RT46
   1 VR_P1V05_PCH_STBY_PH1_BOOT      A @BASEBOARD_FAB2_LIB.BASEBOARD_FAB2(SCH_1):VR_P1V05_PCH_STBY_PH1_BOOT
   2 VR_P1V05_PCH_STBY_PH1_BOOT_R      B @BASEBOARD_FAB2_LIB.BASEBOARD_FAB2(SCH_1):VR_P1V05_PCH_STBY_PH1_BOOT_R

SC22U16V5MX-4-GP_SMD-BCG5-SC22A  I159  C22W23
   1 VR_FET_SW_P12V_STBY_PVDDQ_DEF      1 @BASEBOARD_FAB2_LIB.BASEBOARD_FAB2(SCH_1):VR_FET_SW_P12V_STBY_PVDDQ_DEF
   2    GND      2 @BASEBOARD_FAB2_LIB.BASEBOARD_FAB2(SCH_1):GND

SC22U16V5MX-4-GP_SMD-BCG5-SC22A  I160  C22W24
   1 VR_FET_SW_P12V_STBY_PVDDQ_DEF      1 @BASEBOARD_FAB2_LIB.BASEBOARD_FAB2(SCH_1):VR_FET_SW_P12V_STBY_PVDDQ_DEF
   2    GND      2 @BASEBOARD_FAB2_LIB.BASEBOARD_FAB2(SCH_1):GND

SC22U16V5MX-4-GP_SMD-BCG5-SC22A  I161  C7A13
   1 VR_FET_SW_P12V_STBY_PVDDQ_DEF      1 @BASEBOARD_FAB2_LIB.BASEBOARD_FAB2(SCH_1):VR_FET_SW_P12V_STBY_PVDDQ_DEF
   2    GND      2 @BASEBOARD_FAB2_LIB.BASEBOARD_FAB2(SCH_1):GND

SC22U16V5MX-4-GP_SMD-BCG5-SC22A  I162  C22W25
   1 VR_FET_SW_P12V_STBY_PVDDQ_DEF      1 @BASEBOARD_FAB2_LIB.BASEBOARD_FAB2(SCH_1):VR_FET_SW_P12V_STBY_PVDDQ_DEF
   2    GND      2 @BASEBOARD_FAB2_LIB.BASEBOARD_FAB2(SCH_1):GND

SC22U16V5MX-4-GP_SMD-BCG5-SC22A  I163  C22W27
   1 VR_FET_SW_P12V_STBY_PVDDQ_DEF      1 @BASEBOARD_FAB2_LIB.BASEBOARD_FAB2(SCH_1):VR_FET_SW_P12V_STBY_PVDDQ_DEF
   2    GND      2 @BASEBOARD_FAB2_LIB.BASEBOARD_FAB2(SCH_1):GND

SC22U16V5MX-4-GP_SMD-BCG5-SC22A  I165  C22W26
   1 VR_FET_SW_P12V_STBY_PVDDQ_DEF      1 @BASEBOARD_FAB2_LIB.BASEBOARD_FAB2(SCH_1):VR_FET_SW_P12V_STBY_PVDDQ_DEF
   2    GND      2 @BASEBOARD_FAB2_LIB.BASEBOARD_FAB2(SCH_1):GND

SC22U16V5MX-4-GP_SMD-BCG5-SC22A  I171  C22W22
   1 VR_FET_SW_P12V_STBY_PVDDQ_DEF      1 @BASEBOARD_FAB2_LIB.BASEBOARD_FAB2(SCH_1):VR_FET_SW_P12V_STBY_PVDDQ_DEF
   2    GND      2 @BASEBOARD_FAB2_LIB.BASEBOARD_FAB2(SCH_1):GND

SC22U16V5MX-4-GP_SMD-BCG5-SC22A  I172  C7A14
   1 VR_FET_SW_P12V_STBY_PVDDQ_DEF      1 @BASEBOARD_FAB2_LIB.BASEBOARD_FAB2(SCH_1):VR_FET_SW_P12V_STBY_PVDDQ_DEF
   2    GND      2 @BASEBOARD_FAB2_LIB.BASEBOARD_FAB2(SCH_1):GND

RES_0402-0.0,5%,1/16W,CHIP,G21A  I175  R3L1
   1 VR_PVNN_PCH_PH1_VCIN      A @BASEBOARD_FAB2_LIB.BASEBOARD_FAB2(SCH_1):VR_PVNN_PCH_PH1_VCIN
   2 P5V_STBY      B @BASEBOARD_FAB2_LIB.BASEBOARD_FAB2(SCH_1):P5V_STBY

RES_0402-0.0,5%,1/16W,CHIP,G21A  I177  R3L4
   1 VR_P1V05_PCH_STBY_PH1_VCIN      A @BASEBOARD_FAB2_LIB.BASEBOARD_FAB2(SCH_1):VR_P1V05_PCH_STBY_PH1_VCIN
   2 P5V_STBY      B @BASEBOARD_FAB2_LIB.BASEBOARD_FAB2(SCH_1):P5V_STBY

IND-300NH-20-GP_DISCRET-GB1-INA  I178  L7A2
   1 VR_PVNN_PCH_PH1_PHASE_SW      S @BASEBOARD_FAB2_LIB.BASEBOARD_FAB2(SCH_1):VR_PVNN_PCH_PH1_PHASE_SW
   2 PVNN_PCH_STBY      F @BASEBOARD_FAB2_LIB.BASEBOARD_FAB2(SCH_1):PVNN_PCH_STBY

IND-300NH-20-GP_DISCRET-GB1-INA  I179  L7A4
   1 VR_P1V05_PCH_STBY_PH1_PHASE_SW      S @BASEBOARD_FAB2_LIB.BASEBOARD_FAB2(SCH_1):VR_P1V05_PCH_STBY_PH1_PHASE_SW
   2 P1V05_PCH_STBY      F @BASEBOARD_FAB2_LIB.BASEBOARD_FAB2(SCH_1):P1V05_PCH_STBY

SC1U10V2KX-4-GP_SMD-BCG6-SC1U1A  I180  C3L1
   1 P5V_STBY      1 @BASEBOARD_FAB2_LIB.BASEBOARD_FAB2(SCH_1):P5V_STBY
   2    GND      2 @BASEBOARD_FAB2_LIB.BASEBOARD_FAB2(SCH_1):GND

SC1U10V2KX-4-GP_SMD-BCG6-SC1U1A  I181  C3L29
   1 P5V_STBY      1 @BASEBOARD_FAB2_LIB.BASEBOARD_FAB2(SCH_1):P5V_STBY
   2    GND      2 @BASEBOARD_FAB2_LIB.BASEBOARD_FAB2(SCH_1):GND

1R3F-GP_RCL_GP-1R3F-GP,64.1R00A  I182  RT43
   1 VR_PVNN_PCH_PH1_PHASE_SW_RC      1 @BASEBOARD_FAB2_LIB.BASEBOARD_FAB2(SCH_1):VR_PVNN_PCH_PH1_PHASE_SW_RC
   2    GND      2 @BASEBOARD_FAB2_LIB.BASEBOARD_FAB2(SCH_1):GND

1R3F-GP_RCL_GP-1R3F-GP,64.1R00A  I183  RT45
   1 VR_P1V05_PCH_STBY_PH1_SW_RC      1 @BASEBOARD_FAB2_LIB.BASEBOARD_FAB2(SCH_1):VR_P1V05_PCH_STBY_PH1_SW_RC
   2    GND      2 @BASEBOARD_FAB2_LIB.BASEBOARD_FAB2(SCH_1):GND


DRAWING: @BASEBOARD_FAB2_LIB.BASEBOARD_FAB2(SCH_1):PAGE237 

RES_0402-5.11K,1%,1/16W,CHIP,GA  I3  R8A10
   1 P3V3_STBY      A @BASEBOARD_FAB2_LIB.BASEBOARD_FAB2(SCH_1):P3V3_STBY
   2 PWRGD_P1V8_PCH_STBY_R      B @BASEBOARD_FAB2_LIB.BASEBOARD_FAB2(SCH_1):PWRGD_P1V8_PCH_STBY_R

CAP_0402LF-1000PF,50V,10%,X7R,A  I5  C8A11
   1 PWRGD_P1V8_PCH_STBY_R      A @BASEBOARD_FAB2_LIB.BASEBOARD_FAB2(SCH_1):PWRGD_P1V8_PCH_STBY_R
   2    GND      B @BASEBOARD_FAB2_LIB.BASEBOARD_FAB2(SCH_1):GND

CAP_0805-22UF,6.3V,20%,X6S,C95A  I12  C2L45
   1 P1V8_PCH_STBY      A @BASEBOARD_FAB2_LIB.BASEBOARD_FAB2(SCH_1):P1V8_PCH_STBY
   2    GND      B @BASEBOARD_FAB2_LIB.BASEBOARD_FAB2(SCH_1):GND

CAP_0805-22UF,6.3V,20%,X6S,C95A  I13  C8A14
   1 P1V8_PCH_STBY      A @BASEBOARD_FAB2_LIB.BASEBOARD_FAB2(SCH_1):P1V8_PCH_STBY
   2    GND      B @BASEBOARD_FAB2_LIB.BASEBOARD_FAB2(SCH_1):GND

RES_0603-475.0,1%,1/10W,CHIP,GA  I15  R8A12
   1 P1V8_PCH_STBY      A @BASEBOARD_FAB2_LIB.BASEBOARD_FAB2(SCH_1):P1V8_PCH_STBY
   2    GND      B @BASEBOARD_FAB2_LIB.BASEBOARD_FAB2(SCH_1):GND

CAP_0603-10UF,6.3V,20%,X6S,E15A  I29  C8A6
   1 P3V3_STBY      A @BASEBOARD_FAB2_LIB.BASEBOARD_FAB2(SCH_1):P3V3_STBY
   2    GND      B @BASEBOARD_FAB2_LIB.BASEBOARD_FAB2(SCH_1):GND

CAP_0603LF-0.1UF,25V,10%,X7R,6A  I31  C8A4
   1 P3V3_STBY      A @BASEBOARD_FAB2_LIB.BASEBOARD_FAB2(SCH_1):P3V3_STBY
   2    GND      B @BASEBOARD_FAB2_LIB.BASEBOARD_FAB2(SCH_1):GND

CAP_0402LF-1000PF,50V,10%,EMPTA  I55  C8A10
   1 PWRGD_P3V3_STBY      A @BASEBOARD_FAB2_LIB.BASEBOARD_FAB2(SCH_1):PWRGD_P3V3_STBY
   2    GND      B @BASEBOARD_FAB2_LIB.BASEBOARD_FAB2(SCH_1):GND

CAP_0805-47UF,4V,20%,X6S,C9533A  I77  C8A12
   1 P1V8_PCH_STBY      A @BASEBOARD_FAB2_LIB.BASEBOARD_FAB2(SCH_1):P1V8_PCH_STBY
   2    GND      B @BASEBOARD_FAB2_LIB.BASEBOARD_FAB2(SCH_1):GND

CAP_0805-47UF,4V,20%,X6S,C9533A  I79  C2L32
   1 P1V8_PCH_STBY      A @BASEBOARD_FAB2_LIB.BASEBOARD_FAB2(SCH_1):P1V8_PCH_STBY
   2    GND      B @BASEBOARD_FAB2_LIB.BASEBOARD_FAB2(SCH_1):GND

RES_0402-49.9K,1%,1/16W,CHIP,GA  I80  R2L19
   1 VR_P1V8_PCH_STBY_FB      A @BASEBOARD_FAB2_LIB.BASEBOARD_FAB2(SCH_1):VR_P1V8_PCH_STBY_FB
   2    GND      B @BASEBOARD_FAB2_LIB.BASEBOARD_FAB2(SCH_1):GND

RES_0402-63.4K,1.0%,1/16W,CHIPA  I81  R2L20
   1 P1V8_PCH_STBY      A @BASEBOARD_FAB2_LIB.BASEBOARD_FAB2(SCH_1):P1V8_PCH_STBY
   2 VR_P1V8_PCH_STBY_FB      B @BASEBOARD_FAB2_LIB.BASEBOARD_FAB2(SCH_1):VR_P1V8_PCH_STBY_FB

RT9059_DFN-IC,H65765-001  I86  EU8A2
   4 VR_P1V8_PCH_STBY_FB ADJ_NC @BASEBOARD_FAB2_LIB.BASEBOARD_FAB2(SCH_1):VR_P1V8_PCH_STBY_FB
   6 PWRGD_P3V3_STBY     EN @BASEBOARD_FAB2_LIB.BASEBOARD_FAB2(SCH_1):PWRGD_P3V3_STBY
  11    GND    GND @BASEBOARD_FAB2_LIB.BASEBOARD_FAB2(SCH_1):GND
   5 PWRGD_P1V8_PCH_STBY_R  PGOOD @BASEBOARD_FAB2_LIB.BASEBOARD_FAB2(SCH_1):PWRGD_P1V8_PCH_STBY_R
  10 P3V3_STBY    VDD @BASEBOARD_FAB2_LIB.BASEBOARD_FAB2(SCH_1):P3V3_STBY
   9 P3V3_STBY VIN<2> @BASEBOARD_FAB2_LIB.BASEBOARD_FAB2(SCH_1):P3V3_STBY
   8 P3V3_STBY VIN<1> @BASEBOARD_FAB2_LIB.BASEBOARD_FAB2(SCH_1):P3V3_STBY
   7 P3V3_STBY VIN<0> @BASEBOARD_FAB2_LIB.BASEBOARD_FAB2(SCH_1):P3V3_STBY
   3 P1V8_PCH_STBY VOUT<2> @BASEBOARD_FAB2_LIB.BASEBOARD_FAB2(SCH_1):P1V8_PCH_STBY
   2 P1V8_PCH_STBY VOUT<1> @BASEBOARD_FAB2_LIB.BASEBOARD_FAB2(SCH_1):P1V8_PCH_STBY
   1 P1V8_PCH_STBY VOUT<0> @BASEBOARD_FAB2_LIB.BASEBOARD_FAB2(SCH_1):P1V8_PCH_STBY

RES_0402-22.1,1.0%,1/16W,CHIP,A  I90  R8A11
   1 PWRGD_P1V8_PCH_STBY_R      A @BASEBOARD_FAB2_LIB.BASEBOARD_FAB2(SCH_1):PWRGD_P1V8_PCH_STBY_R
   2 PWRGD_P1V8_PCH_STBY      B @BASEBOARD_FAB2_LIB.BASEBOARD_FAB2(SCH_1):PWRGD_P1V8_PCH_STBY


DRAWING: @BASEBOARD_FAB2_LIB.BASEBOARD_FAB2(SCH_1):PAGE238 

CAP_0402LF-1000PF,50V,10%,EMPTA  I5  C9F9
   1 PWRGD_P1V2_BMC_STBY      A @BASEBOARD_FAB2_LIB.BASEBOARD_FAB2(SCH_1):PWRGD_P1V2_BMC_STBY
   2    GND      B @BASEBOARD_FAB2_LIB.BASEBOARD_FAB2(SCH_1):GND

CAP_0603-10UF,6.3V,20%,X6S,E15A  I7  C9F3
   1 P3V3_STBY      A @BASEBOARD_FAB2_LIB.BASEBOARD_FAB2(SCH_1):P3V3_STBY
   2    GND      B @BASEBOARD_FAB2_LIB.BASEBOARD_FAB2(SCH_1):GND

RES_0402-10.0K,1%,1/16W,CHIP,GA  I14  R9F8
   1    GND      A @BASEBOARD_FAB2_LIB.BASEBOARD_FAB2(SCH_1):GND
   2 VR_P1V15_BMC_STBY_FB      B @BASEBOARD_FAB2_LIB.BASEBOARD_FAB2(SCH_1):VR_P1V15_BMC_STBY_FB

CAP_0402LF-1000PF,50V,10%,X7R,A  I19  C9F8
   1 PWRGD_P1V15_BMC_STBY_R      A @BASEBOARD_FAB2_LIB.BASEBOARD_FAB2(SCH_1):PWRGD_P1V15_BMC_STBY_R
   2    GND      B @BASEBOARD_FAB2_LIB.BASEBOARD_FAB2(SCH_1):GND

RES_0402-10.0K,1%,1/16W,CHIP,GA  I21  R9F13
   1 P3V3_STBY      A @BASEBOARD_FAB2_LIB.BASEBOARD_FAB2(SCH_1):P3V3_STBY
   2 PWRGD_P1V15_BMC_STBY_R      B @BASEBOARD_FAB2_LIB.BASEBOARD_FAB2(SCH_1):PWRGD_P1V15_BMC_STBY_R

CAP_0603-10UF,6.3V,20%,X6S,E15A  I23  C9E10
   1 P1V15_AUX_BMC      A @BASEBOARD_FAB2_LIB.BASEBOARD_FAB2(SCH_1):P1V15_AUX_BMC
   2    GND      B @BASEBOARD_FAB2_LIB.BASEBOARD_FAB2(SCH_1):GND

CAP_0805LF-22UF,4V,20%,X6S,C95A  I30  C9F4
   1 P1V15_AUX_BMC      A @BASEBOARD_FAB2_LIB.BASEBOARD_FAB2(SCH_1):P1V15_AUX_BMC
   2    GND      B @BASEBOARD_FAB2_LIB.BASEBOARD_FAB2(SCH_1):GND

CAP_0402-1.0UF,16V,10%,X6S,D97A  I39  C9E11
   1 P3V3_STBY      A @BASEBOARD_FAB2_LIB.BASEBOARD_FAB2(SCH_1):P3V3_STBY
   2    GND      B @BASEBOARD_FAB2_LIB.BASEBOARD_FAB2(SCH_1):GND

RT9059_DFN-IC,H65765-001  I40  EU9F1
   4 VR_P1V15_BMC_STBY_FB ADJ_NC @BASEBOARD_FAB2_LIB.BASEBOARD_FAB2(SCH_1):VR_P1V15_BMC_STBY_FB
   6 PWRGD_P1V2_BMC_STBY     EN @BASEBOARD_FAB2_LIB.BASEBOARD_FAB2(SCH_1):PWRGD_P1V2_BMC_STBY
  11    GND    GND @BASEBOARD_FAB2_LIB.BASEBOARD_FAB2(SCH_1):GND
   5 PWRGD_P1V15_BMC_STBY_R  PGOOD @BASEBOARD_FAB2_LIB.BASEBOARD_FAB2(SCH_1):PWRGD_P1V15_BMC_STBY_R
  10 P3V3_STBY    VDD @BASEBOARD_FAB2_LIB.BASEBOARD_FAB2(SCH_1):P3V3_STBY
   9 P3V3_STBY VIN<2> @BASEBOARD_FAB2_LIB.BASEBOARD_FAB2(SCH_1):P3V3_STBY
   8 P3V3_STBY VIN<1> @BASEBOARD_FAB2_LIB.BASEBOARD_FAB2(SCH_1):P3V3_STBY
   7 P3V3_STBY VIN<0> @BASEBOARD_FAB2_LIB.BASEBOARD_FAB2(SCH_1):P3V3_STBY
   3 P1V15_AUX_BMC VOUT<2> @BASEBOARD_FAB2_LIB.BASEBOARD_FAB2(SCH_1):P1V15_AUX_BMC
   2 P1V15_AUX_BMC VOUT<1> @BASEBOARD_FAB2_LIB.BASEBOARD_FAB2(SCH_1):P1V15_AUX_BMC
   1 P1V15_AUX_BMC VOUT<0> @BASEBOARD_FAB2_LIB.BASEBOARD_FAB2(SCH_1):P1V15_AUX_BMC

RES_0402-22.1,1.0%,1/16W,CHIP,A  I41  R9F11
   1 PWRGD_P1V15_BMC_STBY_R      A @BASEBOARD_FAB2_LIB.BASEBOARD_FAB2(SCH_1):PWRGD_P1V15_BMC_STBY_R
   2 PWRGD_P1V15_BMC_STBY      B @BASEBOARD_FAB2_LIB.BASEBOARD_FAB2(SCH_1):PWRGD_P1V15_BMC_STBY

4K42R2F-GP_SMD-RG-4K42R2F-GP,6A  I45  R9F6
   1 P1V15_AUX_BMC      1 @BASEBOARD_FAB2_LIB.BASEBOARD_FAB2(SCH_1):P1V15_AUX_BMC
   2 VR_P1V15_BMC_STBY_FB      2 @BASEBOARD_FAB2_LIB.BASEBOARD_FAB2(SCH_1):VR_P1V15_BMC_STBY_FB

CAP_0603-10UF,6.3V,20%,X6S,E15A  I46  C9W14
   1 P3V3_STBY      A @BASEBOARD_FAB2_LIB.BASEBOARD_FAB2(SCH_1):P3V3_STBY
   2    GND      B @BASEBOARD_FAB2_LIB.BASEBOARD_FAB2(SCH_1):GND

CAP_A_0603V-22.0UF,4V,20%,X6S,A  I50  C9W16
   1 P1V15_AUX_BMC      A @BASEBOARD_FAB2_LIB.BASEBOARD_FAB2(SCH_1):P1V15_AUX_BMC
   2    GND      B @BASEBOARD_FAB2_LIB.BASEBOARD_FAB2(SCH_1):GND


DRAWING: @BASEBOARD_FAB2_LIB.BASEBOARD_FAB2(SCH_1):PAGE239 

CAP_0402LF-1000PF,50V,10%,X7R,A  I4  C9F10
   1 PWRGD_P1V2_BMC_STBY_R      A @BASEBOARD_FAB2_LIB.BASEBOARD_FAB2(SCH_1):PWRGD_P1V2_BMC_STBY_R
   2    GND      B @BASEBOARD_FAB2_LIB.BASEBOARD_FAB2(SCH_1):GND

RES_0402-10.0K,1%,1/16W,CHIP,GA  I6  R9F12
   1 P3V3_STBY      A @BASEBOARD_FAB2_LIB.BASEBOARD_FAB2(SCH_1):P3V3_STBY
   2 PWRGD_P1V2_BMC_STBY_R      B @BASEBOARD_FAB2_LIB.BASEBOARD_FAB2(SCH_1):PWRGD_P1V2_BMC_STBY_R

CAP_0805LF-22UF,4V,20%,X6S,C95A  I7  C9F13
   1 P1V2_AUX_BMC      A @BASEBOARD_FAB2_LIB.BASEBOARD_FAB2(SCH_1):P1V2_AUX_BMC
   2    GND      B @BASEBOARD_FAB2_LIB.BASEBOARD_FAB2(SCH_1):GND

CAP_0603-10UF,6.3V,20%,X6S,E15A  I12  C1T15
   1 P1V2_AUX_BMC      A @BASEBOARD_FAB2_LIB.BASEBOARD_FAB2(SCH_1):P1V2_AUX_BMC
   2    GND      B @BASEBOARD_FAB2_LIB.BASEBOARD_FAB2(SCH_1):GND

CAP_0603-10UF,6.3V,20%,X6S,E15A  I22  C1T7
   1 P3V3_STBY      A @BASEBOARD_FAB2_LIB.BASEBOARD_FAB2(SCH_1):P3V3_STBY
   2    GND      B @BASEBOARD_FAB2_LIB.BASEBOARD_FAB2(SCH_1):GND

CAP_0402LF-1000PF,50V,10%,EMPTA  I30  C9F6
   1 PWRGD_P2V5_BMC_STBY      A @BASEBOARD_FAB2_LIB.BASEBOARD_FAB2(SCH_1):PWRGD_P2V5_BMC_STBY
   2    GND      B @BASEBOARD_FAB2_LIB.BASEBOARD_FAB2(SCH_1):GND

RT9059_DFN-IC,H65765-001  I70  EU9F2
   4 VR_P1V2_BMC_STBY_FB ADJ_NC @BASEBOARD_FAB2_LIB.BASEBOARD_FAB2(SCH_1):VR_P1V2_BMC_STBY_FB
   6 PWRGD_P2V5_BMC_STBY     EN @BASEBOARD_FAB2_LIB.BASEBOARD_FAB2(SCH_1):PWRGD_P2V5_BMC_STBY
  11    GND    GND @BASEBOARD_FAB2_LIB.BASEBOARD_FAB2(SCH_1):GND
   5 PWRGD_P1V2_BMC_STBY_R  PGOOD @BASEBOARD_FAB2_LIB.BASEBOARD_FAB2(SCH_1):PWRGD_P1V2_BMC_STBY_R
  10 P3V3_STBY    VDD @BASEBOARD_FAB2_LIB.BASEBOARD_FAB2(SCH_1):P3V3_STBY
   9 P3V3_STBY VIN<2> @BASEBOARD_FAB2_LIB.BASEBOARD_FAB2(SCH_1):P3V3_STBY
   8 P3V3_STBY VIN<1> @BASEBOARD_FAB2_LIB.BASEBOARD_FAB2(SCH_1):P3V3_STBY
   7 P3V3_STBY VIN<0> @BASEBOARD_FAB2_LIB.BASEBOARD_FAB2(SCH_1):P3V3_STBY
   3 P1V2_AUX_BMC VOUT<2> @BASEBOARD_FAB2_LIB.BASEBOARD_FAB2(SCH_1):P1V2_AUX_BMC
   2 P1V2_AUX_BMC VOUT<1> @BASEBOARD_FAB2_LIB.BASEBOARD_FAB2(SCH_1):P1V2_AUX_BMC
   1 P1V2_AUX_BMC VOUT<0> @BASEBOARD_FAB2_LIB.BASEBOARD_FAB2(SCH_1):P1V2_AUX_BMC

CAP_A_0402V-0.1UF,16V,10%,X7R,A  I71  C9F5
   1 P3V3_STBY      A @BASEBOARD_FAB2_LIB.BASEBOARD_FAB2(SCH_1):P3V3_STBY
   2    GND      B @BASEBOARD_FAB2_LIB.BASEBOARD_FAB2(SCH_1):GND

RES_0402-22.1,1.0%,1/16W,CHIP,A  I72  R1T9
   1 PWRGD_P1V2_BMC_STBY_R      A @BASEBOARD_FAB2_LIB.BASEBOARD_FAB2(SCH_1):PWRGD_P1V2_BMC_STBY_R
   2 PWRGD_P1V2_BMC_STBY      B @BASEBOARD_FAB2_LIB.BASEBOARD_FAB2(SCH_1):PWRGD_P1V2_BMC_STBY

RT9059_DFN-IC,H65765-001  I73  EU25F2
   4 VR_P2V5_BMC_STBY_FB ADJ_NC @BASEBOARD_FAB2_LIB.BASEBOARD_FAB2(SCH_1):VR_P2V5_BMC_STBY_FB
   6 PWRGD_P3V3_STBY     EN @BASEBOARD_FAB2_LIB.BASEBOARD_FAB2(SCH_1):PWRGD_P3V3_STBY
  11    GND    GND @BASEBOARD_FAB2_LIB.BASEBOARD_FAB2(SCH_1):GND
   5 PWRGD_P2V5_BMC_STBY_R  PGOOD @BASEBOARD_FAB2_LIB.BASEBOARD_FAB2(SCH_1):PWRGD_P2V5_BMC_STBY_R
  10 P3V3_STBY    VDD @BASEBOARD_FAB2_LIB.BASEBOARD_FAB2(SCH_1):P3V3_STBY
   9 P3V3_STBY VIN<2> @BASEBOARD_FAB2_LIB.BASEBOARD_FAB2(SCH_1):P3V3_STBY
   8 P3V3_STBY VIN<1> @BASEBOARD_FAB2_LIB.BASEBOARD_FAB2(SCH_1):P3V3_STBY
   7 P3V3_STBY VIN<0> @BASEBOARD_FAB2_LIB.BASEBOARD_FAB2(SCH_1):P3V3_STBY
   3 P2V5_AUX_BMC VOUT<2> @BASEBOARD_FAB2_LIB.BASEBOARD_FAB2(SCH_1):P2V5_AUX_BMC
   2 P2V5_AUX_BMC VOUT<1> @BASEBOARD_FAB2_LIB.BASEBOARD_FAB2(SCH_1):P2V5_AUX_BMC
   1 P2V5_AUX_BMC VOUT<0> @BASEBOARD_FAB2_LIB.BASEBOARD_FAB2(SCH_1):P2V5_AUX_BMC

RES_0402-22.1,1.0%,1/16W,CHIP,A  I77  R1W9
   1 PWRGD_P2V5_BMC_STBY_R      A @BASEBOARD_FAB2_LIB.BASEBOARD_FAB2(SCH_1):PWRGD_P2V5_BMC_STBY_R
   2 PWRGD_P2V5_BMC_STBY      B @BASEBOARD_FAB2_LIB.BASEBOARD_FAB2(SCH_1):PWRGD_P2V5_BMC_STBY

RES_0402-10.0K,1%,1/16W,CHIP,GA  I79  R9W12
   1 P3V3_STBY      A @BASEBOARD_FAB2_LIB.BASEBOARD_FAB2(SCH_1):P3V3_STBY
   2 PWRGD_P2V5_BMC_STBY_R      B @BASEBOARD_FAB2_LIB.BASEBOARD_FAB2(SCH_1):PWRGD_P2V5_BMC_STBY_R

CAP_0805LF-22UF,4V,20%,X6S,C95A  I81  C9W13
   1 P2V5_AUX_BMC      A @BASEBOARD_FAB2_LIB.BASEBOARD_FAB2(SCH_1):P2V5_AUX_BMC
   2    GND      B @BASEBOARD_FAB2_LIB.BASEBOARD_FAB2(SCH_1):GND

CAP_0603-10UF,6.3V,20%,X6S,E15A  I83  C1W15
   1 P2V5_AUX_BMC      A @BASEBOARD_FAB2_LIB.BASEBOARD_FAB2(SCH_1):P2V5_AUX_BMC
   2    GND      B @BASEBOARD_FAB2_LIB.BASEBOARD_FAB2(SCH_1):GND

CAP_0402LF-1000PF,50V,10%,X7R,A  I84  C9W10
   1 PWRGD_P2V5_BMC_STBY_R      A @BASEBOARD_FAB2_LIB.BASEBOARD_FAB2(SCH_1):PWRGD_P2V5_BMC_STBY_R
   2    GND      B @BASEBOARD_FAB2_LIB.BASEBOARD_FAB2(SCH_1):GND

CAP_A_0402V-0.1UF,16V,10%,X7R,A  I90  C9W5
   1 P3V3_STBY      A @BASEBOARD_FAB2_LIB.BASEBOARD_FAB2(SCH_1):P3V3_STBY
   2    GND      B @BASEBOARD_FAB2_LIB.BASEBOARD_FAB2(SCH_1):GND

CAP_0402LF-1000PF,50V,10%,EMPTA  I91  C9W6
   1 PWRGD_P3V3_STBY      A @BASEBOARD_FAB2_LIB.BASEBOARD_FAB2(SCH_1):PWRGD_P3V3_STBY
   2    GND      B @BASEBOARD_FAB2_LIB.BASEBOARD_FAB2(SCH_1):GND

CAP_0603-10UF,6.3V,20%,X6S,E15A  I92  C1W7
   1 P3V3_STBY      A @BASEBOARD_FAB2_LIB.BASEBOARD_FAB2(SCH_1):P3V3_STBY
   2    GND      B @BASEBOARD_FAB2_LIB.BASEBOARD_FAB2(SCH_1):GND

5K1R2F-2-GP_SMD-RG-5K1R2F-2-GPA  I98  R9F31
   1 P1V2_AUX_BMC      1 @BASEBOARD_FAB2_LIB.BASEBOARD_FAB2(SCH_1):P1V2_AUX_BMC
   2 VR_P1V2_BMC_STBY_FB      2 @BASEBOARD_FAB2_LIB.BASEBOARD_FAB2(SCH_1):VR_P1V2_BMC_STBY_FB

RES_0402-10.0K,1%,1/16W,CHIP,GA  I100  R9F32
   1 VR_P1V2_BMC_STBY_FB      A @BASEBOARD_FAB2_LIB.BASEBOARD_FAB2(SCH_1):VR_P1V2_BMC_STBY_FB
   2    GND      B @BASEBOARD_FAB2_LIB.BASEBOARD_FAB2(SCH_1):GND

RES_0402-10.0K,1%,1/16W,CHIP,GA  I101  R9W32
   1 VR_P2V5_BMC_STBY_FB      A @BASEBOARD_FAB2_LIB.BASEBOARD_FAB2(SCH_1):VR_P2V5_BMC_STBY_FB
   2    GND      B @BASEBOARD_FAB2_LIB.BASEBOARD_FAB2(SCH_1):GND

21K5R2F-GP_RCL_GP-21K5R2F-GP,6A  I102  R9W31
   1 P2V5_AUX_BMC      1 @BASEBOARD_FAB2_LIB.BASEBOARD_FAB2(SCH_1):P2V5_AUX_BMC
   2 VR_P2V5_BMC_STBY_FB      2 @BASEBOARD_FAB2_LIB.BASEBOARD_FAB2(SCH_1):VR_P2V5_BMC_STBY_FB

CAP_0603-10UF,6.3V,20%,X6S,E15A  I104  C9W17
   1 P3V3_STBY      A @BASEBOARD_FAB2_LIB.BASEBOARD_FAB2(SCH_1):P3V3_STBY
   2    GND      B @BASEBOARD_FAB2_LIB.BASEBOARD_FAB2(SCH_1):GND

CAP_A_0603V-22.0UF,4V,20%,X6S,A  I111  C9W19
   1 P1V2_AUX_BMC      A @BASEBOARD_FAB2_LIB.BASEBOARD_FAB2(SCH_1):P1V2_AUX_BMC
   2    GND      B @BASEBOARD_FAB2_LIB.BASEBOARD_FAB2(SCH_1):GND


DRAWING: @BASEBOARD_FAB2_LIB.BASEBOARD_FAB2(SCH_1):PAGE240 

RES_0402-10.0K,1%,1/16W,EMPTY,A  I111  R8F1
   1 PWRGD_P5V_STBY      A @BASEBOARD_FAB2_LIB.BASEBOARD_FAB2(SCH_1):PWRGD_P5V_STBY
   2    GND      B @BASEBOARD_FAB2_LIB.BASEBOARD_FAB2(SCH_1):GND

CAP_0402LF-1000PF,50V,10%,EMPTA  I113  C8E17
   1 PWRGD_P5V_STBY      A @BASEBOARD_FAB2_LIB.BASEBOARD_FAB2(SCH_1):PWRGD_P5V_STBY
   2 AGND_P3V3_STBY      B @BASEBOARD_FAB2_LIB.BASEBOARD_FAB2(SCH_1):AGND_P3V3_STBY

CAP_0402LF-1000PF,50V,10%,X7R,A  I116  C8F2
   1 PWRGD_P3V3_STBY_R      A @BASEBOARD_FAB2_LIB.BASEBOARD_FAB2(SCH_1):PWRGD_P3V3_STBY_R
   2    GND      B @BASEBOARD_FAB2_LIB.BASEBOARD_FAB2(SCH_1):GND

RES_0402-1.00K,1%,1/16W,CHIP,GA  I117  R8F5
   1 P3V3_STBY      A @BASEBOARD_FAB2_LIB.BASEBOARD_FAB2(SCH_1):P3V3_STBY
   2 PWRGD_P3V3_STBY_R      B @BASEBOARD_FAB2_LIB.BASEBOARD_FAB2(SCH_1):PWRGD_P3V3_STBY_R

RT8240_QFN-IC,H66262-001  I125  EU8F1
   4 VR_P3V3_STBY_BOOT   BOOT @BASEBOARD_FAB2_LIB.BASEBOARD_FAB2(SCH_1):VR_P3V3_STBY_BOOT
  10 VR_P3V3_STBY_OCSELECT     CS @BASEBOARD_FAB2_LIB.BASEBOARD_FAB2(SCH_1):VR_P3V3_STBY_OCSELECT
   8 VR_P3V3_STBY_EN     EN @BASEBOARD_FAB2_LIB.BASEBOARD_FAB2(SCH_1):VR_P3V3_STBY_EN
  11 AGND_P3V3_STBY     G0 @BASEBOARD_FAB2_LIB.BASEBOARD_FAB2(SCH_1):AGND_P3V3_STBY
  13 AGND_P3V3_STBY GND<1> @BASEBOARD_FAB2_LIB.BASEBOARD_FAB2(SCH_1):AGND_P3V3_STBY
  12 AGND_P3V3_STBY GND<0> @BASEBOARD_FAB2_LIB.BASEBOARD_FAB2(SCH_1):AGND_P3V3_STBY
   1 VR_P3V3_STBY_LGATE  LGATE @BASEBOARD_FAB2_LIB.BASEBOARD_FAB2(SCH_1):VR_P3V3_STBY_LGATE
   9 PWRGD_P3V3_STBY_R  PGOOD @BASEBOARD_FAB2_LIB.BASEBOARD_FAB2(SCH_1):PWRGD_P3V3_STBY_R
   2 VR_P3V3_STBY_PHASE  PHASE @BASEBOARD_FAB2_LIB.BASEBOARD_FAB2(SCH_1):VR_P3V3_STBY_PHASE
   7 VSENSE_RGND_P3V3_STBY   RGND @BASEBOARD_FAB2_LIB.BASEBOARD_FAB2(SCH_1):VSENSE_RGND_P3V3_STBY
   3 VR_P3V3_STBY_UGATE  UGATE @BASEBOARD_FAB2_LIB.BASEBOARD_FAB2(SCH_1):VR_P3V3_STBY_UGATE
   5 P5V_STBY    VCC @BASEBOARD_FAB2_LIB.BASEBOARD_FAB2(SCH_1):P5V_STBY
   6 VSENSE_VOUT_P3V3_STBY   VOUT @BASEBOARD_FAB2_LIB.BASEBOARD_FAB2(SCH_1):VSENSE_VOUT_P3V3_STBY

RES_0402-0.0,5%,1/16W,CHIP,G21A  I127  R8E35
   1 VR_P3V3_STBY_BOOT      A @BASEBOARD_FAB2_LIB.BASEBOARD_FAB2(SCH_1):VR_P3V3_STBY_BOOT
   2 VR_P3V3_STBY_BOOT_R      B @BASEBOARD_FAB2_LIB.BASEBOARD_FAB2(SCH_1):VR_P3V3_STBY_BOOT_R

CAP_0603LF-0.1UF,25V,10%,X7R,6A  I129  C8E12
   1 VR_P3V3_STBY_PHASE      A @BASEBOARD_FAB2_LIB.BASEBOARD_FAB2(SCH_1):VR_P3V3_STBY_PHASE
   2 VR_P3V3_STBY_BOOT_R      B @BASEBOARD_FAB2_LIB.BASEBOARD_FAB2(SCH_1):VR_P3V3_STBY_BOOT_R

CAP_1206LF-22UF,16V,10%,X6S,D3A  I137  C8E10
   1 VR_FET_SW_P12V_STBY_P3V3_STBY      A @BASEBOARD_FAB2_LIB.BASEBOARD_FAB2(SCH_1):VR_FET_SW_P12V_STBY_P3V3_STBY
   2    GND      B @BASEBOARD_FAB2_LIB.BASEBOARD_FAB2(SCH_1):GND

CAP_0402-1.0UF,16V,10%,X6S,D97A  I139  C8E14
   1 VR_FET_SW_P12V_STBY_P3V3_STBY      A @BASEBOARD_FAB2_LIB.BASEBOARD_FAB2(SCH_1):VR_FET_SW_P12V_STBY_P3V3_STBY
   2    GND      B @BASEBOARD_FAB2_LIB.BASEBOARD_FAB2(SCH_1):GND

RES_0402-0.0,5%,1/16W,CHIP,G21A  I140  R8E38
   1 VSENSE_RGND_P3V3_STBY      A @BASEBOARD_FAB2_LIB.BASEBOARD_FAB2(SCH_1):VSENSE_RGND_P3V3_STBY
   2 AGND_P3V3_STBY      B @BASEBOARD_FAB2_LIB.BASEBOARD_FAB2(SCH_1):AGND_P3V3_STBY

RES_0402-10.0K,1%,1/16W,CHIP,GA  I142  R8E34
   1 VSENSE_VOUT_P3V3_STBY      A @BASEBOARD_FAB2_LIB.BASEBOARD_FAB2(SCH_1):VSENSE_VOUT_P3V3_STBY
   2 AGND_P3V3_STBY      B @BASEBOARD_FAB2_LIB.BASEBOARD_FAB2(SCH_1):AGND_P3V3_STBY

RES_0402-23.2K,1%,1/16W,CHIP,GA  I143  R8E31
   1 VSENSE_P3V3_STBY      A @BASEBOARD_FAB2_LIB.BASEBOARD_FAB2(SCH_1):VSENSE_P3V3_STBY
   2 VSENSE_VOUT_P3V3_STBY      B @BASEBOARD_FAB2_LIB.BASEBOARD_FAB2(SCH_1):VSENSE_VOUT_P3V3_STBY

RES_0402-0.0,5%,1/16W,CHIP,G21A  I144  R8E25
   1 P3V3_STBY      A @BASEBOARD_FAB2_LIB.BASEBOARD_FAB2(SCH_1):P3V3_STBY
   2 VSENSE_P3V3_STBY      B @BASEBOARD_FAB2_LIB.BASEBOARD_FAB2(SCH_1):VSENSE_P3V3_STBY

RES_0402-0.0,5%,1/16W,CHIP,G21A  I146  R8F11
   1    GND      A @BASEBOARD_FAB2_LIB.BASEBOARD_FAB2(SCH_1):GND
   2 AGND_P3V3_STBY      B @BASEBOARD_FAB2_LIB.BASEBOARD_FAB2(SCH_1):AGND_P3V3_STBY

RES_0402-2.2,5%,1/16W,EMPTY,G2A  I148  R8F3
   1 VR_P3V3_STBY_SNUB      A @BASEBOARD_FAB2_LIB.BASEBOARD_FAB2(SCH_1):VR_P3V3_STBY_SNUB
   2    GND      B @BASEBOARD_FAB2_LIB.BASEBOARD_FAB2(SCH_1):GND

RES_0402-1.0K,0.1%,1/16W,CHIP,A  I152  R2T4
   1 P3V3_STBY      A @BASEBOARD_FAB2_LIB.BASEBOARD_FAB2(SCH_1):P3V3_STBY
   2    GND      B @BASEBOARD_FAB2_LIB.BASEBOARD_FAB2(SCH_1):GND

CAP_0805-22UF,6.3V,20%,X6S,C95A  I158  C2T7
   1 P3V3_STBY      A @BASEBOARD_FAB2_LIB.BASEBOARD_FAB2(SCH_1):P3V3_STBY
   2    GND      B @BASEBOARD_FAB2_LIB.BASEBOARD_FAB2(SCH_1):GND

CAP_0805-22UF,6.3V,20%,X6S,C95A  I160  C2T6
   1 P3V3_STBY      A @BASEBOARD_FAB2_LIB.BASEBOARD_FAB2(SCH_1):P3V3_STBY
   2    GND      B @BASEBOARD_FAB2_LIB.BASEBOARD_FAB2(SCH_1):GND

CAP_0402LF-3300PF,50V,10%,EMPTA  I163  C8F3
   1 VR_P3V3_STBY_PHASE      A @BASEBOARD_FAB2_LIB.BASEBOARD_FAB2(SCH_1):VR_P3V3_STBY_PHASE
   2 VR_P3V3_STBY_SNUB      B @BASEBOARD_FAB2_LIB.BASEBOARD_FAB2(SCH_1):VR_P3V3_STBY_SNUB

CSD87384M_SM-IC,H66258-001  I170  EU8E1
   4 VR_P3V3_STBY_LGATE     BG @BASEBOARD_FAB2_LIB.BASEBOARD_FAB2(SCH_1):VR_P3V3_STBY_LGATE
   3    GND   PGND @BASEBOARD_FAB2_LIB.BASEBOARD_FAB2(SCH_1):GND
   1 VR_P3V3_STBY_UGATE     TG @BASEBOARD_FAB2_LIB.BASEBOARD_FAB2(SCH_1):VR_P3V3_STBY_UGATE
   2 VR_FET_SW_P12V_STBY_P3V3_STBY    VIN @BASEBOARD_FAB2_LIB.BASEBOARD_FAB2(SCH_1):VR_FET_SW_P12V_STBY_P3V3_STBY
   5 VR_P3V3_STBY_PHASE    VSW @BASEBOARD_FAB2_LIB.BASEBOARD_FAB2(SCH_1):VR_P3V3_STBY_PHASE

RES_0402-22.1,1.0%,1/16W,CHIP,A  I171  R8F10
   1 PWRGD_P3V3_STBY_R      A @BASEBOARD_FAB2_LIB.BASEBOARD_FAB2(SCH_1):PWRGD_P3V3_STBY_R
   2 PWRGD_P3V3_STBY      B @BASEBOARD_FAB2_LIB.BASEBOARD_FAB2(SCH_1):PWRGD_P3V3_STBY

CAP_0805-22UF,6.3V,20%,X6S,C95A  I174  C2T9
   1 P3V3_STBY      A @BASEBOARD_FAB2_LIB.BASEBOARD_FAB2(SCH_1):P3V3_STBY
   2    GND      B @BASEBOARD_FAB2_LIB.BASEBOARD_FAB2(SCH_1):GND

RES_0402-0.0,5%,1/16W,CHIP,G21A  I176  R8F2
   1 PWRGD_P5V_STBY      A @BASEBOARD_FAB2_LIB.BASEBOARD_FAB2(SCH_1):PWRGD_P5V_STBY
   2 VR_P3V3_STBY_EN      B @BASEBOARD_FAB2_LIB.BASEBOARD_FAB2(SCH_1):VR_P3V3_STBY_EN

RES_0402-100.0K,1%,1/16W,EMPTYA  I177  R8E40
   1 P3V3_STBY      A @BASEBOARD_FAB2_LIB.BASEBOARD_FAB2(SCH_1):P3V3_STBY
   2 VR_P3V3_STBY_EN      B @BASEBOARD_FAB2_LIB.BASEBOARD_FAB2(SCH_1):VR_P3V3_STBY_EN

SC22U16V5MX-4-GP_SMD-BCG5-SC22A  I181  C9F1
   1 VR_FET_SW_P12V_STBY_P3V3_STBY      1 @BASEBOARD_FAB2_LIB.BASEBOARD_FAB2(SCH_1):VR_FET_SW_P12V_STBY_P3V3_STBY
   2    GND      2 @BASEBOARD_FAB2_LIB.BASEBOARD_FAB2(SCH_1):GND

SC22U16V5MX-4-GP_SMD-BCG5-SC22A  I182  C22W11
   1 VR_FET_SW_P12V_STBY_P3V3_STBY      1 @BASEBOARD_FAB2_LIB.BASEBOARD_FAB2(SCH_1):VR_FET_SW_P12V_STBY_P3V3_STBY
   2    GND      2 @BASEBOARD_FAB2_LIB.BASEBOARD_FAB2(SCH_1):GND

SC22U16V5MX-4-GP_SMD-BCG5-SC22A  I183  C8E11
   1 VR_FET_SW_P12V_STBY_P3V3_STBY      1 @BASEBOARD_FAB2_LIB.BASEBOARD_FAB2(SCH_1):VR_FET_SW_P12V_STBY_P3V3_STBY
   2    GND      2 @BASEBOARD_FAB2_LIB.BASEBOARD_FAB2(SCH_1):GND

SC22U16V5MX-4-GP_SMD-BCG5-SC22A  I186  C22W12
   1 VR_FET_SW_P12V_STBY_P3V3_STBY      1 @BASEBOARD_FAB2_LIB.BASEBOARD_FAB2(SCH_1):VR_FET_SW_P12V_STBY_P3V3_STBY
   2    GND      2 @BASEBOARD_FAB2_LIB.BASEBOARD_FAB2(SCH_1):GND

IND-1UH-361-GP_DISCRET-GC1-INDA  I188  L8F1
   1 VR_P3V3_STBY_PHASE      1 @BASEBOARD_FAB2_LIB.BASEBOARD_FAB2(SCH_1):VR_P3V3_STBY_PHASE
   2 P3V3_STBY      2 @BASEBOARD_FAB2_LIB.BASEBOARD_FAB2(SCH_1):P3V3_STBY

ST470U6D3VDM-7-GP_SMD-TCG4-ST4A  I189  C8F14
   1 P3V3_STBY      1 @BASEBOARD_FAB2_LIB.BASEBOARD_FAB2(SCH_1):P3V3_STBY
   2    GND      2 @BASEBOARD_FAB2_LIB.BASEBOARD_FAB2(SCH_1):GND

ST470U6D3VDM-7-GP_SMD-TCG4-ST4A  I190  C8F8
   1 P3V3_STBY      1 @BASEBOARD_FAB2_LIB.BASEBOARD_FAB2(SCH_1):P3V3_STBY
   2    GND      2 @BASEBOARD_FAB2_LIB.BASEBOARD_FAB2(SCH_1):GND

SC4D7U16V3KX-GP_SMD-BCG5-SC4D7A  I191  C2R11
   1 P5V_STBY      1 @BASEBOARD_FAB2_LIB.BASEBOARD_FAB2(SCH_1):P5V_STBY
   2 AGND_P3V3_STBY      2 @BASEBOARD_FAB2_LIB.BASEBOARD_FAB2(SCH_1):AGND_P3V3_STBY

BLM31SN500SN1L-GP_DISCRET-GB1-A  I193  FB9E1
   1 P12V_STBY      1 @BASEBOARD_FAB2_LIB.BASEBOARD_FAB2(SCH_1):P12V_STBY
   2 VR_FET_SW_P12V_STBY_P3V3_STBY      2 @BASEBOARD_FAB2_LIB.BASEBOARD_FAB2(SCH_1):VR_FET_SW_P12V_STBY_P3V3_STBY

RES_0402-49.9K,1%,1/16W,CHIP,GA  I195  R8F9
   1 VR_P3V3_STBY_OCSELECT      A @BASEBOARD_FAB2_LIB.BASEBOARD_FAB2(SCH_1):VR_P3V3_STBY_OCSELECT
   2 AGND_P3V3_STBY      B @BASEBOARD_FAB2_LIB.BASEBOARD_FAB2(SCH_1):AGND_P3V3_STBY


DRAWING: @BASEBOARD_FAB2_LIB.BASEBOARD_FAB2(SCH_1):PAGE241 

RES_0402-1.0K,0.1%,1/16W,CHIP,A  I9  R8E18
   1 P5V_STBY      A @BASEBOARD_FAB2_LIB.BASEBOARD_FAB2(SCH_1):P5V_STBY
   2    GND      B @BASEBOARD_FAB2_LIB.BASEBOARD_FAB2(SCH_1):GND

RES_0402-1.00K,1%,1/16W,CHIP,GA  I11  R7E12
   1 P5V_STBY      A @BASEBOARD_FAB2_LIB.BASEBOARD_FAB2(SCH_1):P5V_STBY
   2 PWRGD_P5V_STBY_R      B @BASEBOARD_FAB2_LIB.BASEBOARD_FAB2(SCH_1):PWRGD_P5V_STBY_R

CAP_0603LF-0.1UF,25V,10%,X7R,6A  I12  C8E6
   1 VR_P5V_STBY_BOOT      A @BASEBOARD_FAB2_LIB.BASEBOARD_FAB2(SCH_1):VR_P5V_STBY_BOOT
   2 VR_P5V_STBY_PHASE      B @BASEBOARD_FAB2_LIB.BASEBOARD_FAB2(SCH_1):VR_P5V_STBY_PHASE

CAP_0402LF-1000PF,50V,10%,X7R,A  I14  C7E10
   1 PWRGD_P5V_STBY_R      A @BASEBOARD_FAB2_LIB.BASEBOARD_FAB2(SCH_1):PWRGD_P5V_STBY_R
   2    GND      B @BASEBOARD_FAB2_LIB.BASEBOARD_FAB2(SCH_1):GND

RES_0402-75K,1%,1/16W,CHIP,G21A  I18  R7E14
   1 VR_P5V_STBY_RT      A @BASEBOARD_FAB2_LIB.BASEBOARD_FAB2(SCH_1):VR_P5V_STBY_RT
   2 AGND_P5V_STBY      B @BASEBOARD_FAB2_LIB.BASEBOARD_FAB2(SCH_1):AGND_P5V_STBY

CAP_0402-1.0UF,16V,10%,X6S,D97A  I30  C7E14
   1 VR_P5V_STBY_VIN      A @BASEBOARD_FAB2_LIB.BASEBOARD_FAB2(SCH_1):VR_P5V_STBY_VIN
   2    GND      B @BASEBOARD_FAB2_LIB.BASEBOARD_FAB2(SCH_1):GND

RES_0402-0.0,5%,1/16W,CHIP,G21A  I37  R7E17
   1 VR_FET_SW_P5V_STBY_PVIN      A @BASEBOARD_FAB2_LIB.BASEBOARD_FAB2(SCH_1):VR_FET_SW_P5V_STBY_PVIN
   2 VR_P5V_STBY_VIN      B @BASEBOARD_FAB2_LIB.BASEBOARD_FAB2(SCH_1):VR_P5V_STBY_VIN

CAP_1206LF-22UF,16V,10%,X6S,D3A  I39  C7E11
   1 VR_FET_SW_P5V_STBY_PVIN      A @BASEBOARD_FAB2_LIB.BASEBOARD_FAB2(SCH_1):VR_FET_SW_P5V_STBY_PVIN
   2    GND      B @BASEBOARD_FAB2_LIB.BASEBOARD_FAB2(SCH_1):GND

CAP_0402LF-1000PF,50V,10%,EMPTA  I41  C8E13
   1 PWRGD_P12V_HSC_DLY      A @BASEBOARD_FAB2_LIB.BASEBOARD_FAB2(SCH_1):PWRGD_P12V_HSC_DLY
   2 AGND_P5V_STBY      B @BASEBOARD_FAB2_LIB.BASEBOARD_FAB2(SCH_1):AGND_P5V_STBY

RES_0402-10.0K,1%,1/16W,CHIP,GA  I50  R7F1
   1 VR_P5V_STBY_VSENSE_R      A @BASEBOARD_FAB2_LIB.BASEBOARD_FAB2(SCH_1):VR_P5V_STBY_VSENSE_R
   2 VR_P5V_STBY_VSENSE      B @BASEBOARD_FAB2_LIB.BASEBOARD_FAB2(SCH_1):VR_P5V_STBY_VSENSE

RES_0402-1.37K,1%,1/16W,CHIP,GA  I51  R7E16
   1 VR_P5V_STBY_VSENSE      A @BASEBOARD_FAB2_LIB.BASEBOARD_FAB2(SCH_1):VR_P5V_STBY_VSENSE
   2 AGND_P5V_STBY      B @BASEBOARD_FAB2_LIB.BASEBOARD_FAB2(SCH_1):AGND_P5V_STBY

CAP_0402LF-270PF,50V,10%,X7R,AA  I53  C8E16
   1 VR_P5V_STBY_COMP      A @BASEBOARD_FAB2_LIB.BASEBOARD_FAB2(SCH_1):VR_P5V_STBY_COMP
   2 AGND_P5V_STBY      B @BASEBOARD_FAB2_LIB.BASEBOARD_FAB2(SCH_1):AGND_P5V_STBY

RES_0402-24.9K,1%,1/16W,CHIP,GA  I54  R8E39
   1 VR_P5V_STBY_COMP      A @BASEBOARD_FAB2_LIB.BASEBOARD_FAB2(SCH_1):VR_P5V_STBY_COMP
   2 VR_P5V_STBY_RC_COMP      B @BASEBOARD_FAB2_LIB.BASEBOARD_FAB2(SCH_1):VR_P5V_STBY_RC_COMP

CAP_0402LF-2200PF,50V,10%,X7R,A  I57  C8F1
   1 VR_P5V_STBY_RC_COMP      A @BASEBOARD_FAB2_LIB.BASEBOARD_FAB2(SCH_1):VR_P5V_STBY_RC_COMP
   2 AGND_P5V_STBY      B @BASEBOARD_FAB2_LIB.BASEBOARD_FAB2(SCH_1):AGND_P5V_STBY

RES_0402-0.0,5%,1/16W,CHIP,G21A  I58  R7E13
   1    GND      A @BASEBOARD_FAB2_LIB.BASEBOARD_FAB2(SCH_1):GND
   2 AGND_P5V_STBY      B @BASEBOARD_FAB2_LIB.BASEBOARD_FAB2(SCH_1):AGND_P5V_STBY

CAP_0402LF-0.022UF,16V,10%,X7RA  I63  C8E15
   1 VR_P5V_STBY_SS      A @BASEBOARD_FAB2_LIB.BASEBOARD_FAB2(SCH_1):VR_P5V_STBY_SS
   2 AGND_P5V_STBY      B @BASEBOARD_FAB2_LIB.BASEBOARD_FAB2(SCH_1):AGND_P5V_STBY

RES_0402-0.0,5%,1/16W,CHIP,G21A  I78  R8E37
   1 VR_P5V_STBY_VSENSE_R      A @BASEBOARD_FAB2_LIB.BASEBOARD_FAB2(SCH_1):VR_P5V_STBY_VSENSE_R
   2 P5V_STBY      B @BASEBOARD_FAB2_LIB.BASEBOARD_FAB2(SCH_1):P5V_STBY

FERRITE_SM-22,FB,656554-051  I82  FB7E1
   1 P12V_STBY      A @BASEBOARD_FAB2_LIB.BASEBOARD_FAB2(SCH_1):P12V_STBY
   2 VR_FET_SW_P5V_STBY_PVIN      B @BASEBOARD_FAB2_LIB.BASEBOARD_FAB2(SCH_1):VR_FET_SW_P5V_STBY_PVIN

TPS54821_LCC-IC,H63269-001  I83  EU7E2
  13 VR_P5V_STBY_BOOT   BOOT @BASEBOARD_FAB2_LIB.BASEBOARD_FAB2(SCH_1):VR_P5V_STBY_BOOT
   8 VR_P5V_STBY_COMP   COMP @BASEBOARD_FAB2_LIB.BASEBOARD_FAB2(SCH_1):VR_P5V_STBY_COMP
  10 VR_P5V_STBY_EN     EN @BASEBOARD_FAB2_LIB.BASEBOARD_FAB2(SCH_1):VR_P5V_STBY_EN
   3    GND GND<1> @BASEBOARD_FAB2_LIB.BASEBOARD_FAB2(SCH_1):GND
   2    GND GND<0> @BASEBOARD_FAB2_LIB.BASEBOARD_FAB2(SCH_1):GND
  12 VR_P5V_STBY_PHASE  PH<1> @BASEBOARD_FAB2_LIB.BASEBOARD_FAB2(SCH_1):VR_P5V_STBY_PHASE
  11 VR_P5V_STBY_PHASE  PH<0> @BASEBOARD_FAB2_LIB.BASEBOARD_FAB2(SCH_1):VR_P5V_STBY_PHASE
   5 VR_FET_SW_P5V_STBY_PVIN PVIN<1> @BASEBOARD_FAB2_LIB.BASEBOARD_FAB2(SCH_1):VR_FET_SW_P5V_STBY_PVIN
   4 VR_FET_SW_P5V_STBY_PVIN PVIN<0> @BASEBOARD_FAB2_LIB.BASEBOARD_FAB2(SCH_1):VR_FET_SW_P5V_STBY_PVIN
  14 PWRGD_P5V_STBY_R  PWRGD @BASEBOARD_FAB2_LIB.BASEBOARD_FAB2(SCH_1):PWRGD_P5V_STBY_R
   1 VR_P5V_STBY_RT RT_CLK @BASEBOARD_FAB2_LIB.BASEBOARD_FAB2(SCH_1):VR_P5V_STBY_RT
   9 VR_P5V_STBY_SS  SS_TR @BASEBOARD_FAB2_LIB.BASEBOARD_FAB2(SCH_1):VR_P5V_STBY_SS
  15    GND  THPAD @BASEBOARD_FAB2_LIB.BASEBOARD_FAB2(SCH_1):GND
   6 VR_P5V_STBY_VIN    VIN @BASEBOARD_FAB2_LIB.BASEBOARD_FAB2(SCH_1):VR_P5V_STBY_VIN
   7 VR_P5V_STBY_VSENSE VSENSE @BASEBOARD_FAB2_LIB.BASEBOARD_FAB2(SCH_1):VR_P5V_STBY_VSENSE

RES_0402-22.1,1.0%,1/16W,CHIP,A  I89  R7E15
   1 PWRGD_P5V_STBY_R      A @BASEBOARD_FAB2_LIB.BASEBOARD_FAB2(SCH_1):PWRGD_P5V_STBY_R
   2 PWRGD_P5V_STBY      B @BASEBOARD_FAB2_LIB.BASEBOARD_FAB2(SCH_1):PWRGD_P5V_STBY

INDUCTOR_SM-2.2UH,IND,E98761-0A  I90  L8E1
   1 VR_P5V_STBY_PHASE    INA @BASEBOARD_FAB2_LIB.BASEBOARD_FAB2(SCH_1):VR_P5V_STBY_PHASE
   2 P5V_STBY    INB @BASEBOARD_FAB2_LIB.BASEBOARD_FAB2(SCH_1):P5V_STBY

RES_0402-0.0,5%,1/16W,CHIP,G21A  I91  R8E33
   1 PWRGD_P12V_HSC_DLY      A @BASEBOARD_FAB2_LIB.BASEBOARD_FAB2(SCH_1):PWRGD_P12V_HSC_DLY
   2 VR_P5V_STBY_EN      B @BASEBOARD_FAB2_LIB.BASEBOARD_FAB2(SCH_1):VR_P5V_STBY_EN

SC22U16V5MX-4-GP_SMD-BCG5-SC22A  I92  C7E13
   1 VR_FET_SW_P5V_STBY_PVIN      1 @BASEBOARD_FAB2_LIB.BASEBOARD_FAB2(SCH_1):VR_FET_SW_P5V_STBY_PVIN
   2    GND      2 @BASEBOARD_FAB2_LIB.BASEBOARD_FAB2(SCH_1):GND

SC22U16V5MX-4-GP_SMD-BCG5-SC22A  I95  C22W9
   1 VR_FET_SW_P5V_STBY_PVIN      1 @BASEBOARD_FAB2_LIB.BASEBOARD_FAB2(SCH_1):VR_FET_SW_P5V_STBY_PVIN
   2    GND      2 @BASEBOARD_FAB2_LIB.BASEBOARD_FAB2(SCH_1):GND

SC22U16V5MX-4-GP_SMD-BCG5-SC22A  I96  C22W8
   1 VR_FET_SW_P5V_STBY_PVIN      1 @BASEBOARD_FAB2_LIB.BASEBOARD_FAB2(SCH_1):VR_FET_SW_P5V_STBY_PVIN
   2    GND      2 @BASEBOARD_FAB2_LIB.BASEBOARD_FAB2(SCH_1):GND

SC22U16V5MX-4-GP_SMD-BCG5-SC22A  I98  C7E12
   1 VR_FET_SW_P5V_STBY_PVIN      1 @BASEBOARD_FAB2_LIB.BASEBOARD_FAB2(SCH_1):VR_FET_SW_P5V_STBY_PVIN
   2    GND      2 @BASEBOARD_FAB2_LIB.BASEBOARD_FAB2(SCH_1):GND

ST220U10VDM-LGP_SMD-TCG-ST220UA  I100  C8E4
   1 P5V_STBY      1 @BASEBOARD_FAB2_LIB.BASEBOARD_FAB2(SCH_1):P5V_STBY
   2    GND      2 @BASEBOARD_FAB2_LIB.BASEBOARD_FAB2(SCH_1):GND

SC22U16V5MX-4-GP_SMD-BCG5-SC22A  I103  C8E7
   1 P5V_STBY      1 @BASEBOARD_FAB2_LIB.BASEBOARD_FAB2(SCH_1):P5V_STBY
   2    GND      2 @BASEBOARD_FAB2_LIB.BASEBOARD_FAB2(SCH_1):GND

SC22U16V5MX-4-GP_SMD-BCG5-SC22A  I104  C8E9
   1 P5V_STBY      1 @BASEBOARD_FAB2_LIB.BASEBOARD_FAB2(SCH_1):P5V_STBY
   2    GND      2 @BASEBOARD_FAB2_LIB.BASEBOARD_FAB2(SCH_1):GND


DRAWING: @BASEBOARD_FAB2_LIB.BASEBOARD_FAB2(SCH_1):PAGE242 

CAP_A_0603V-22.0UF,4V,20%,X6S,A  I53  C5G41
   1 PVDDQ_ABC      A @BASEBOARD_FAB2_LIB.BASEBOARD_FAB2(SCH_1):PVDDQ_ABC
   2    GND      B @BASEBOARD_FAB2_LIB.BASEBOARD_FAB2(SCH_1):GND

CAP_A_0603V-22.0UF,4V,20%,X6S,A  I54  C5G42
   1 PVDDQ_ABC      A @BASEBOARD_FAB2_LIB.BASEBOARD_FAB2(SCH_1):PVDDQ_ABC
   2    GND      B @BASEBOARD_FAB2_LIB.BASEBOARD_FAB2(SCH_1):GND

CAP_A_0603V-22.0UF,4V,20%,X6S,A  I55  C5G44
   1 PVDDQ_ABC      A @BASEBOARD_FAB2_LIB.BASEBOARD_FAB2(SCH_1):PVDDQ_ABC
   2    GND      B @BASEBOARD_FAB2_LIB.BASEBOARD_FAB2(SCH_1):GND

CAP_A_0603V-22.0UF,4V,20%,X6S,A  I56  C5G43
   1 PVDDQ_ABC      A @BASEBOARD_FAB2_LIB.BASEBOARD_FAB2(SCH_1):PVDDQ_ABC
   2    GND      B @BASEBOARD_FAB2_LIB.BASEBOARD_FAB2(SCH_1):GND

CAP_A_0603V-22.0UF,4V,20%,X6S,A  I57  C5G48
   1 PVDDQ_ABC      A @BASEBOARD_FAB2_LIB.BASEBOARD_FAB2(SCH_1):PVDDQ_ABC
   2    GND      B @BASEBOARD_FAB2_LIB.BASEBOARD_FAB2(SCH_1):GND

CAP_A_0603V-22.0UF,4V,20%,X6S,A  I58  C5G47
   1 PVDDQ_ABC      A @BASEBOARD_FAB2_LIB.BASEBOARD_FAB2(SCH_1):PVDDQ_ABC
   2    GND      B @BASEBOARD_FAB2_LIB.BASEBOARD_FAB2(SCH_1):GND

CAP_A_0603V-22.0UF,4V,20%,X6S,A  I59  C5G46
   1 PVDDQ_ABC      A @BASEBOARD_FAB2_LIB.BASEBOARD_FAB2(SCH_1):PVDDQ_ABC
   2    GND      B @BASEBOARD_FAB2_LIB.BASEBOARD_FAB2(SCH_1):GND

CAP_A_0603V-22.0UF,4V,20%,X6S,A  I60  C5G45
   1 PVDDQ_ABC      A @BASEBOARD_FAB2_LIB.BASEBOARD_FAB2(SCH_1):PVDDQ_ABC
   2    GND      B @BASEBOARD_FAB2_LIB.BASEBOARD_FAB2(SCH_1):GND

CAP_A_0603V-22.0UF,4V,20%,X6S,A  I61  C5G49
   1 PVDDQ_ABC      A @BASEBOARD_FAB2_LIB.BASEBOARD_FAB2(SCH_1):PVDDQ_ABC
   2    GND      B @BASEBOARD_FAB2_LIB.BASEBOARD_FAB2(SCH_1):GND

CAP_A_0603V-22.0UF,4V,20%,X6S,A  I62  C5G54
   1 PVDDQ_ABC      A @BASEBOARD_FAB2_LIB.BASEBOARD_FAB2(SCH_1):PVDDQ_ABC
   2    GND      B @BASEBOARD_FAB2_LIB.BASEBOARD_FAB2(SCH_1):GND

CAP_A_0603V-22.0UF,4V,20%,X6S,A  I63  C5G58
   1 PVDDQ_ABC      A @BASEBOARD_FAB2_LIB.BASEBOARD_FAB2(SCH_1):PVDDQ_ABC
   2    GND      B @BASEBOARD_FAB2_LIB.BASEBOARD_FAB2(SCH_1):GND

CAP_A_0603V-22.0UF,4V,20%,X6S,A  I64  C5G57
   1 PVDDQ_ABC      A @BASEBOARD_FAB2_LIB.BASEBOARD_FAB2(SCH_1):PVDDQ_ABC
   2    GND      B @BASEBOARD_FAB2_LIB.BASEBOARD_FAB2(SCH_1):GND

CAP_A_0603V-22.0UF,4V,20%,X6S,A  I65  C5G56
   1 PVDDQ_ABC      A @BASEBOARD_FAB2_LIB.BASEBOARD_FAB2(SCH_1):PVDDQ_ABC
   2    GND      B @BASEBOARD_FAB2_LIB.BASEBOARD_FAB2(SCH_1):GND

CAP_A_0603V-22.0UF,4V,20%,X6S,A  I66  C5G55
   1 PVDDQ_ABC      A @BASEBOARD_FAB2_LIB.BASEBOARD_FAB2(SCH_1):PVDDQ_ABC
   2    GND      B @BASEBOARD_FAB2_LIB.BASEBOARD_FAB2(SCH_1):GND

CAP_A_0603V-22.0UF,4V,20%,X6S,A  I67  C5G53
   1 PVDDQ_ABC      A @BASEBOARD_FAB2_LIB.BASEBOARD_FAB2(SCH_1):PVDDQ_ABC
   2    GND      B @BASEBOARD_FAB2_LIB.BASEBOARD_FAB2(SCH_1):GND

CAP_A_0603V-22.0UF,4V,20%,X6S,A  I68  C5G52
   1 PVDDQ_ABC      A @BASEBOARD_FAB2_LIB.BASEBOARD_FAB2(SCH_1):PVDDQ_ABC
   2    GND      B @BASEBOARD_FAB2_LIB.BASEBOARD_FAB2(SCH_1):GND

CAP_A_0603V-22.0UF,4V,20%,X6S,A  I69  C5G51
   1 PVDDQ_ABC      A @BASEBOARD_FAB2_LIB.BASEBOARD_FAB2(SCH_1):PVDDQ_ABC
   2    GND      B @BASEBOARD_FAB2_LIB.BASEBOARD_FAB2(SCH_1):GND

CAP_A_0603V-22.0UF,4V,20%,X6S,A  I70  C5G50
   1 PVDDQ_ABC      A @BASEBOARD_FAB2_LIB.BASEBOARD_FAB2(SCH_1):PVDDQ_ABC
   2    GND      B @BASEBOARD_FAB2_LIB.BASEBOARD_FAB2(SCH_1):GND

CAP_A_0603V-22.0UF,4V,20%,X6S,A  I71  C5G67
   1 PVDDQ_DEF      A @BASEBOARD_FAB2_LIB.BASEBOARD_FAB2(SCH_1):PVDDQ_DEF
   2    GND      B @BASEBOARD_FAB2_LIB.BASEBOARD_FAB2(SCH_1):GND

CAP_A_0603V-22.0UF,4V,20%,X6S,A  I72  C5G66
   1 PVDDQ_DEF      A @BASEBOARD_FAB2_LIB.BASEBOARD_FAB2(SCH_1):PVDDQ_DEF
   2    GND      B @BASEBOARD_FAB2_LIB.BASEBOARD_FAB2(SCH_1):GND

CAP_A_0603V-22.0UF,4V,20%,X6S,A  I73  C5G65
   1 PVDDQ_DEF      A @BASEBOARD_FAB2_LIB.BASEBOARD_FAB2(SCH_1):PVDDQ_DEF
   2    GND      B @BASEBOARD_FAB2_LIB.BASEBOARD_FAB2(SCH_1):GND

CAP_A_0603V-22.0UF,4V,20%,X6S,A  I74  C5G64
   1 PVDDQ_DEF      A @BASEBOARD_FAB2_LIB.BASEBOARD_FAB2(SCH_1):PVDDQ_DEF
   2    GND      B @BASEBOARD_FAB2_LIB.BASEBOARD_FAB2(SCH_1):GND

CAP_A_0603V-22.0UF,4V,20%,X6S,A  I75  C5G63
   1 PVDDQ_DEF      A @BASEBOARD_FAB2_LIB.BASEBOARD_FAB2(SCH_1):PVDDQ_DEF
   2    GND      B @BASEBOARD_FAB2_LIB.BASEBOARD_FAB2(SCH_1):GND

CAP_A_0603V-22.0UF,4V,20%,X6S,A  I76  C5G62
   1 PVDDQ_DEF      A @BASEBOARD_FAB2_LIB.BASEBOARD_FAB2(SCH_1):PVDDQ_DEF
   2    GND      B @BASEBOARD_FAB2_LIB.BASEBOARD_FAB2(SCH_1):GND

CAP_A_0603V-22.0UF,4V,20%,X6S,A  I77  C5G61
   1 PVDDQ_DEF      A @BASEBOARD_FAB2_LIB.BASEBOARD_FAB2(SCH_1):PVDDQ_DEF
   2    GND      B @BASEBOARD_FAB2_LIB.BASEBOARD_FAB2(SCH_1):GND

CAP_A_0603V-22.0UF,4V,20%,X6S,A  I78  C5G60
   1 PVDDQ_DEF      A @BASEBOARD_FAB2_LIB.BASEBOARD_FAB2(SCH_1):PVDDQ_DEF
   2    GND      B @BASEBOARD_FAB2_LIB.BASEBOARD_FAB2(SCH_1):GND

CAP_A_0603V-22.0UF,4V,20%,X6S,A  I79  C5G59
   1 PVDDQ_DEF      A @BASEBOARD_FAB2_LIB.BASEBOARD_FAB2(SCH_1):PVDDQ_DEF
   2    GND      B @BASEBOARD_FAB2_LIB.BASEBOARD_FAB2(SCH_1):GND

CAP_A_0603V-22.0UF,4V,20%,X6S,A  I80  C5G76
   1 PVDDQ_DEF      A @BASEBOARD_FAB2_LIB.BASEBOARD_FAB2(SCH_1):PVDDQ_DEF
   2    GND      B @BASEBOARD_FAB2_LIB.BASEBOARD_FAB2(SCH_1):GND

CAP_A_0603V-22.0UF,4V,20%,X6S,A  I81  C5G75
   1 PVDDQ_DEF      A @BASEBOARD_FAB2_LIB.BASEBOARD_FAB2(SCH_1):PVDDQ_DEF
   2    GND      B @BASEBOARD_FAB2_LIB.BASEBOARD_FAB2(SCH_1):GND

CAP_A_0603V-22.0UF,4V,20%,X6S,A  I82  C5G74
   1 PVDDQ_DEF      A @BASEBOARD_FAB2_LIB.BASEBOARD_FAB2(SCH_1):PVDDQ_DEF
   2    GND      B @BASEBOARD_FAB2_LIB.BASEBOARD_FAB2(SCH_1):GND

CAP_A_0603V-22.0UF,4V,20%,X6S,A  I83  C5G73
   1 PVDDQ_DEF      A @BASEBOARD_FAB2_LIB.BASEBOARD_FAB2(SCH_1):PVDDQ_DEF
   2    GND      B @BASEBOARD_FAB2_LIB.BASEBOARD_FAB2(SCH_1):GND

CAP_A_0603V-22.0UF,4V,20%,X6S,A  I84  C5G72
   1 PVDDQ_DEF      A @BASEBOARD_FAB2_LIB.BASEBOARD_FAB2(SCH_1):PVDDQ_DEF
   2    GND      B @BASEBOARD_FAB2_LIB.BASEBOARD_FAB2(SCH_1):GND

CAP_A_0603V-22.0UF,4V,20%,X6S,A  I85  C5G71
   1 PVDDQ_DEF      A @BASEBOARD_FAB2_LIB.BASEBOARD_FAB2(SCH_1):PVDDQ_DEF
   2    GND      B @BASEBOARD_FAB2_LIB.BASEBOARD_FAB2(SCH_1):GND

CAP_A_0603V-22.0UF,4V,20%,X6S,A  I86  C5G70
   1 PVDDQ_DEF      A @BASEBOARD_FAB2_LIB.BASEBOARD_FAB2(SCH_1):PVDDQ_DEF
   2    GND      B @BASEBOARD_FAB2_LIB.BASEBOARD_FAB2(SCH_1):GND

CAP_A_0603V-22.0UF,4V,20%,X6S,A  I87  C5G69
   1 PVDDQ_DEF      A @BASEBOARD_FAB2_LIB.BASEBOARD_FAB2(SCH_1):PVDDQ_DEF
   2    GND      B @BASEBOARD_FAB2_LIB.BASEBOARD_FAB2(SCH_1):GND

CAP_A_0603V-22.0UF,4V,20%,X6S,A  I88  C5G68
   1 PVDDQ_DEF      A @BASEBOARD_FAB2_LIB.BASEBOARD_FAB2(SCH_1):PVDDQ_DEF
   2    GND      B @BASEBOARD_FAB2_LIB.BASEBOARD_FAB2(SCH_1):GND

CAP_0805-47UF,4V,20%,X6S,C9533A  I89  C5G77
   1 PVDDQ_DEF      A @BASEBOARD_FAB2_LIB.BASEBOARD_FAB2(SCH_1):PVDDQ_DEF
   2    GND      B @BASEBOARD_FAB2_LIB.BASEBOARD_FAB2(SCH_1):GND

CAP_0805-47UF,4V,20%,X6S,C9533A  I90  C5G22
   1 PVDDQ_ABC      A @BASEBOARD_FAB2_LIB.BASEBOARD_FAB2(SCH_1):PVDDQ_ABC
   2    GND      B @BASEBOARD_FAB2_LIB.BASEBOARD_FAB2(SCH_1):GND

CAP_0805-47UF,4V,20%,X6S,C9533A  I91  C5G78
   1 PVDDQ_DEF      A @BASEBOARD_FAB2_LIB.BASEBOARD_FAB2(SCH_1):PVDDQ_DEF
   2    GND      B @BASEBOARD_FAB2_LIB.BASEBOARD_FAB2(SCH_1):GND

CAP_0805-47UF,4V,20%,X6S,C9533A  I92  C5G21
   1 PVDDQ_ABC      A @BASEBOARD_FAB2_LIB.BASEBOARD_FAB2(SCH_1):PVDDQ_ABC
   2    GND      B @BASEBOARD_FAB2_LIB.BASEBOARD_FAB2(SCH_1):GND


DRAWING: @BASEBOARD_FAB2_LIB.BASEBOARD_FAB2(SCH_1):PAGE243 

CAP_A_0603V-22.0UF,4V,20%,X6S,A  I53  C5G79
   1 PVDDQ_GHJ      A @BASEBOARD_FAB2_LIB.BASEBOARD_FAB2(SCH_1):PVDDQ_GHJ
   2    GND      B @BASEBOARD_FAB2_LIB.BASEBOARD_FAB2(SCH_1):GND

CAP_A_0603V-22.0UF,4V,20%,X6S,A  I54  C5G87
   1 PVDDQ_GHJ      A @BASEBOARD_FAB2_LIB.BASEBOARD_FAB2(SCH_1):PVDDQ_GHJ
   2    GND      B @BASEBOARD_FAB2_LIB.BASEBOARD_FAB2(SCH_1):GND

CAP_A_0603V-22.0UF,4V,20%,X6S,A  I55  C5G86
   1 PVDDQ_GHJ      A @BASEBOARD_FAB2_LIB.BASEBOARD_FAB2(SCH_1):PVDDQ_GHJ
   2    GND      B @BASEBOARD_FAB2_LIB.BASEBOARD_FAB2(SCH_1):GND

CAP_A_0603V-22.0UF,4V,20%,X6S,A  I56  C5G85
   1 PVDDQ_GHJ      A @BASEBOARD_FAB2_LIB.BASEBOARD_FAB2(SCH_1):PVDDQ_GHJ
   2    GND      B @BASEBOARD_FAB2_LIB.BASEBOARD_FAB2(SCH_1):GND

CAP_A_0603V-22.0UF,4V,20%,X6S,A  I57  C5G84
   1 PVDDQ_GHJ      A @BASEBOARD_FAB2_LIB.BASEBOARD_FAB2(SCH_1):PVDDQ_GHJ
   2    GND      B @BASEBOARD_FAB2_LIB.BASEBOARD_FAB2(SCH_1):GND

CAP_A_0603V-22.0UF,4V,20%,X6S,A  I58  C5G83
   1 PVDDQ_GHJ      A @BASEBOARD_FAB2_LIB.BASEBOARD_FAB2(SCH_1):PVDDQ_GHJ
   2    GND      B @BASEBOARD_FAB2_LIB.BASEBOARD_FAB2(SCH_1):GND

CAP_A_0603V-22.0UF,4V,20%,X6S,A  I59  C5G82
   1 PVDDQ_GHJ      A @BASEBOARD_FAB2_LIB.BASEBOARD_FAB2(SCH_1):PVDDQ_GHJ
   2    GND      B @BASEBOARD_FAB2_LIB.BASEBOARD_FAB2(SCH_1):GND

CAP_A_0603V-22.0UF,4V,20%,X6S,A  I60  C5G81
   1 PVDDQ_GHJ      A @BASEBOARD_FAB2_LIB.BASEBOARD_FAB2(SCH_1):PVDDQ_GHJ
   2    GND      B @BASEBOARD_FAB2_LIB.BASEBOARD_FAB2(SCH_1):GND

CAP_A_0603V-22.0UF,4V,20%,X6S,A  I61  C5G80
   1 PVDDQ_GHJ      A @BASEBOARD_FAB2_LIB.BASEBOARD_FAB2(SCH_1):PVDDQ_GHJ
   2    GND      B @BASEBOARD_FAB2_LIB.BASEBOARD_FAB2(SCH_1):GND

CAP_A_0603V-22.0UF,4V,20%,X6S,A  I62  C5G96
   1 PVDDQ_GHJ      A @BASEBOARD_FAB2_LIB.BASEBOARD_FAB2(SCH_1):PVDDQ_GHJ
   2    GND      B @BASEBOARD_FAB2_LIB.BASEBOARD_FAB2(SCH_1):GND

CAP_A_0603V-22.0UF,4V,20%,X6S,A  I63  C5G95
   1 PVDDQ_GHJ      A @BASEBOARD_FAB2_LIB.BASEBOARD_FAB2(SCH_1):PVDDQ_GHJ
   2    GND      B @BASEBOARD_FAB2_LIB.BASEBOARD_FAB2(SCH_1):GND

CAP_A_0603V-22.0UF,4V,20%,X6S,A  I64  C5G94
   1 PVDDQ_GHJ      A @BASEBOARD_FAB2_LIB.BASEBOARD_FAB2(SCH_1):PVDDQ_GHJ
   2    GND      B @BASEBOARD_FAB2_LIB.BASEBOARD_FAB2(SCH_1):GND

CAP_A_0603V-22.0UF,4V,20%,X6S,A  I65  C5G93
   1 PVDDQ_GHJ      A @BASEBOARD_FAB2_LIB.BASEBOARD_FAB2(SCH_1):PVDDQ_GHJ
   2    GND      B @BASEBOARD_FAB2_LIB.BASEBOARD_FAB2(SCH_1):GND

CAP_A_0603V-22.0UF,4V,20%,X6S,A  I66  C5G92
   1 PVDDQ_GHJ      A @BASEBOARD_FAB2_LIB.BASEBOARD_FAB2(SCH_1):PVDDQ_GHJ
   2    GND      B @BASEBOARD_FAB2_LIB.BASEBOARD_FAB2(SCH_1):GND

CAP_A_0603V-22.0UF,4V,20%,X6S,A  I67  C5G91
   1 PVDDQ_GHJ      A @BASEBOARD_FAB2_LIB.BASEBOARD_FAB2(SCH_1):PVDDQ_GHJ
   2    GND      B @BASEBOARD_FAB2_LIB.BASEBOARD_FAB2(SCH_1):GND

CAP_A_0603V-22.0UF,4V,20%,X6S,A  I68  C5G90
   1 PVDDQ_GHJ      A @BASEBOARD_FAB2_LIB.BASEBOARD_FAB2(SCH_1):PVDDQ_GHJ
   2    GND      B @BASEBOARD_FAB2_LIB.BASEBOARD_FAB2(SCH_1):GND

CAP_A_0603V-22.0UF,4V,20%,X6S,A  I69  C5G89
   1 PVDDQ_GHJ      A @BASEBOARD_FAB2_LIB.BASEBOARD_FAB2(SCH_1):PVDDQ_GHJ
   2    GND      B @BASEBOARD_FAB2_LIB.BASEBOARD_FAB2(SCH_1):GND

CAP_A_0603V-22.0UF,4V,20%,X6S,A  I70  C5G88
   1 PVDDQ_GHJ      A @BASEBOARD_FAB2_LIB.BASEBOARD_FAB2(SCH_1):PVDDQ_GHJ
   2    GND      B @BASEBOARD_FAB2_LIB.BASEBOARD_FAB2(SCH_1):GND

CAP_A_0603V-22.0UF,4V,20%,X6S,A  I71  C5G103
   1 PVDDQ_KLM      A @BASEBOARD_FAB2_LIB.BASEBOARD_FAB2(SCH_1):PVDDQ_KLM
   2    GND      B @BASEBOARD_FAB2_LIB.BASEBOARD_FAB2(SCH_1):GND

CAP_A_0603V-22.0UF,4V,20%,X6S,A  I72  C5G104
   1 PVDDQ_KLM      A @BASEBOARD_FAB2_LIB.BASEBOARD_FAB2(SCH_1):PVDDQ_KLM
   2    GND      B @BASEBOARD_FAB2_LIB.BASEBOARD_FAB2(SCH_1):GND

CAP_A_0603V-22.0UF,4V,20%,X6S,A  I73  C5G105
   1 PVDDQ_KLM      A @BASEBOARD_FAB2_LIB.BASEBOARD_FAB2(SCH_1):PVDDQ_KLM
   2    GND      B @BASEBOARD_FAB2_LIB.BASEBOARD_FAB2(SCH_1):GND

CAP_A_0603V-22.0UF,4V,20%,X6S,A  I74  C5G102
   1 PVDDQ_KLM      A @BASEBOARD_FAB2_LIB.BASEBOARD_FAB2(SCH_1):PVDDQ_KLM
   2    GND      B @BASEBOARD_FAB2_LIB.BASEBOARD_FAB2(SCH_1):GND

CAP_A_0603V-22.0UF,4V,20%,X6S,A  I75  C5G101
   1 PVDDQ_KLM      A @BASEBOARD_FAB2_LIB.BASEBOARD_FAB2(SCH_1):PVDDQ_KLM
   2    GND      B @BASEBOARD_FAB2_LIB.BASEBOARD_FAB2(SCH_1):GND

CAP_A_0603V-22.0UF,4V,20%,X6S,A  I76  C5G100
   1 PVDDQ_KLM      A @BASEBOARD_FAB2_LIB.BASEBOARD_FAB2(SCH_1):PVDDQ_KLM
   2    GND      B @BASEBOARD_FAB2_LIB.BASEBOARD_FAB2(SCH_1):GND

CAP_A_0603V-22.0UF,4V,20%,X6S,A  I77  C5G99
   1 PVDDQ_KLM      A @BASEBOARD_FAB2_LIB.BASEBOARD_FAB2(SCH_1):PVDDQ_KLM
   2    GND      B @BASEBOARD_FAB2_LIB.BASEBOARD_FAB2(SCH_1):GND

CAP_A_0603V-22.0UF,4V,20%,X6S,A  I78  C5G98
   1 PVDDQ_KLM      A @BASEBOARD_FAB2_LIB.BASEBOARD_FAB2(SCH_1):PVDDQ_KLM
   2    GND      B @BASEBOARD_FAB2_LIB.BASEBOARD_FAB2(SCH_1):GND

CAP_A_0603V-22.0UF,4V,20%,X6S,A  I79  C5G97
   1 PVDDQ_KLM      A @BASEBOARD_FAB2_LIB.BASEBOARD_FAB2(SCH_1):PVDDQ_KLM
   2    GND      B @BASEBOARD_FAB2_LIB.BASEBOARD_FAB2(SCH_1):GND

CAP_A_0603V-22.0UF,4V,20%,X6S,A  I80  C5G114
   1 PVDDQ_KLM      A @BASEBOARD_FAB2_LIB.BASEBOARD_FAB2(SCH_1):PVDDQ_KLM
   2    GND      B @BASEBOARD_FAB2_LIB.BASEBOARD_FAB2(SCH_1):GND

CAP_A_0603V-22.0UF,4V,20%,X6S,A  I81  C5G113
   1 PVDDQ_KLM      A @BASEBOARD_FAB2_LIB.BASEBOARD_FAB2(SCH_1):PVDDQ_KLM
   2    GND      B @BASEBOARD_FAB2_LIB.BASEBOARD_FAB2(SCH_1):GND

CAP_A_0603V-22.0UF,4V,20%,X6S,A  I82  C5G112
   1 PVDDQ_KLM      A @BASEBOARD_FAB2_LIB.BASEBOARD_FAB2(SCH_1):PVDDQ_KLM
   2    GND      B @BASEBOARD_FAB2_LIB.BASEBOARD_FAB2(SCH_1):GND

CAP_A_0603V-22.0UF,4V,20%,X6S,A  I83  C5G111
   1 PVDDQ_KLM      A @BASEBOARD_FAB2_LIB.BASEBOARD_FAB2(SCH_1):PVDDQ_KLM
   2    GND      B @BASEBOARD_FAB2_LIB.BASEBOARD_FAB2(SCH_1):GND

CAP_A_0603V-22.0UF,4V,20%,X6S,A  I84  C5G110
   1 PVDDQ_KLM      A @BASEBOARD_FAB2_LIB.BASEBOARD_FAB2(SCH_1):PVDDQ_KLM
   2    GND      B @BASEBOARD_FAB2_LIB.BASEBOARD_FAB2(SCH_1):GND

CAP_A_0603V-22.0UF,4V,20%,X6S,A  I85  C5G109
   1 PVDDQ_KLM      A @BASEBOARD_FAB2_LIB.BASEBOARD_FAB2(SCH_1):PVDDQ_KLM
   2    GND      B @BASEBOARD_FAB2_LIB.BASEBOARD_FAB2(SCH_1):GND

CAP_A_0603V-22.0UF,4V,20%,X6S,A  I86  C5G108
   1 PVDDQ_KLM      A @BASEBOARD_FAB2_LIB.BASEBOARD_FAB2(SCH_1):PVDDQ_KLM
   2    GND      B @BASEBOARD_FAB2_LIB.BASEBOARD_FAB2(SCH_1):GND

CAP_A_0603V-22.0UF,4V,20%,X6S,A  I87  C5G107
   1 PVDDQ_KLM      A @BASEBOARD_FAB2_LIB.BASEBOARD_FAB2(SCH_1):PVDDQ_KLM
   2    GND      B @BASEBOARD_FAB2_LIB.BASEBOARD_FAB2(SCH_1):GND

CAP_A_0603V-22.0UF,4V,20%,X6S,A  I88  C5G106
   1 PVDDQ_KLM      A @BASEBOARD_FAB2_LIB.BASEBOARD_FAB2(SCH_1):PVDDQ_KLM
   2    GND      B @BASEBOARD_FAB2_LIB.BASEBOARD_FAB2(SCH_1):GND

CAP_0805-47UF,4V,20%,X6S,C9533A  I89  C5G115
   1 PVDDQ_KLM      A @BASEBOARD_FAB2_LIB.BASEBOARD_FAB2(SCH_1):PVDDQ_KLM
   2    GND      B @BASEBOARD_FAB2_LIB.BASEBOARD_FAB2(SCH_1):GND

CAP_0805-47UF,4V,20%,X6S,C9533A  I90  C5G116
   1 PVDDQ_KLM      A @BASEBOARD_FAB2_LIB.BASEBOARD_FAB2(SCH_1):PVDDQ_KLM
   2    GND      B @BASEBOARD_FAB2_LIB.BASEBOARD_FAB2(SCH_1):GND

CAP_0805-47UF,4V,20%,X6S,C9533A  I91  C5G118
   1 PVDDQ_GHJ      A @BASEBOARD_FAB2_LIB.BASEBOARD_FAB2(SCH_1):PVDDQ_GHJ
   2    GND      B @BASEBOARD_FAB2_LIB.BASEBOARD_FAB2(SCH_1):GND

CAP_0805-47UF,4V,20%,X6S,C9533A  I92  C5G117
   1 PVDDQ_GHJ      A @BASEBOARD_FAB2_LIB.BASEBOARD_FAB2(SCH_1):PVDDQ_GHJ
   2    GND      B @BASEBOARD_FAB2_LIB.BASEBOARD_FAB2(SCH_1):GND


DRAWING: @BASEBOARD_FAB2_LIB.BASEBOARD_FAB2(SCH_1):PAGE244 

CAP_0402-0.22UF,16V,10%,X7R,A3A  I2  C831
   1 P3E_CPU0_PE1_PCH_TXP<15>      A @BASEBOARD_FAB2_LIB.BASEBOARD_FAB2(SCH_1):P3E_CPU0_PE1_PCH_TXP(15)
   2 P3E_CPU0_PE1_PCH_CON_TXP<15>      B @BASEBOARD_FAB2_LIB.BASEBOARD_FAB2(SCH_1):P3E_CPU0_PE1_PCH_CON_TXP(15)

CAP_0402-0.22UF,16V,10%,X7R,A3A  I5  C829
   1 P3E_CPU0_PE1_PCH_TXP<13>      A @BASEBOARD_FAB2_LIB.BASEBOARD_FAB2(SCH_1):P3E_CPU0_PE1_PCH_TXP(13)
   2 P3E_CPU0_PE1_PCH_CON_TXP<13>      B @BASEBOARD_FAB2_LIB.BASEBOARD_FAB2(SCH_1):P3E_CPU0_PE1_PCH_CON_TXP(13)

CAP_0402-0.22UF,16V,10%,X7R,A3A  I8  C833
   1 P3E_CPU0_PE1_PCH_TXP<11>      A @BASEBOARD_FAB2_LIB.BASEBOARD_FAB2(SCH_1):P3E_CPU0_PE1_PCH_TXP(11)
   2 P3E_CPU0_PE1_PCH_CON_TXP<11>      B @BASEBOARD_FAB2_LIB.BASEBOARD_FAB2(SCH_1):P3E_CPU0_PE1_PCH_CON_TXP(11)

CAP_0402-0.22UF,16V,10%,X7R,A3A  I12  C827
   1 P3E_CPU0_PE1_PCH_TXP<14>      A @BASEBOARD_FAB2_LIB.BASEBOARD_FAB2(SCH_1):P3E_CPU0_PE1_PCH_TXP(14)
   2 P3E_CPU0_PE1_PCH_CON_TXP<14>      B @BASEBOARD_FAB2_LIB.BASEBOARD_FAB2(SCH_1):P3E_CPU0_PE1_PCH_CON_TXP(14)

CAP_0402-0.22UF,16V,10%,X7R,A3A  I17  C841
   1 P3E_CPU0_PE1_PCH_TXP<12>      A @BASEBOARD_FAB2_LIB.BASEBOARD_FAB2(SCH_1):P3E_CPU0_PE1_PCH_TXP(12)
   2 P3E_CPU0_PE1_PCH_CON_TXP<12>      B @BASEBOARD_FAB2_LIB.BASEBOARD_FAB2(SCH_1):P3E_CPU0_PE1_PCH_CON_TXP(12)

CAP_0402-0.22UF,16V,10%,X7R,A3A  I23  C830
   1 P3E_CPU0_PE1_PCH_TXN<15>      A @BASEBOARD_FAB2_LIB.BASEBOARD_FAB2(SCH_1):P3E_CPU0_PE1_PCH_TXN(15)
   2 P3E_CPU0_PE1_PCH_CON_TXN<15>      B @BASEBOARD_FAB2_LIB.BASEBOARD_FAB2(SCH_1):P3E_CPU0_PE1_PCH_CON_TXN(15)

CAP_0402-0.22UF,16V,10%,X7R,A3A  I24  C826
   1 P3E_CPU0_PE1_PCH_TXN<14>      A @BASEBOARD_FAB2_LIB.BASEBOARD_FAB2(SCH_1):P3E_CPU0_PE1_PCH_TXN(14)
   2 P3E_CPU0_PE1_PCH_CON_TXN<14>      B @BASEBOARD_FAB2_LIB.BASEBOARD_FAB2(SCH_1):P3E_CPU0_PE1_PCH_CON_TXN(14)

CAP_0402-0.22UF,16V,10%,X7R,A3A  I28  C828
   1 P3E_CPU0_PE1_PCH_TXN<13>      A @BASEBOARD_FAB2_LIB.BASEBOARD_FAB2(SCH_1):P3E_CPU0_PE1_PCH_TXN(13)
   2 P3E_CPU0_PE1_PCH_CON_TXN<13>      B @BASEBOARD_FAB2_LIB.BASEBOARD_FAB2(SCH_1):P3E_CPU0_PE1_PCH_CON_TXN(13)

CAP_0402-0.22UF,16V,10%,X7R,A3A  I29  C840
   1 P3E_CPU0_PE1_PCH_TXN<12>      A @BASEBOARD_FAB2_LIB.BASEBOARD_FAB2(SCH_1):P3E_CPU0_PE1_PCH_TXN(12)
   2 P3E_CPU0_PE1_PCH_CON_TXN<12>      B @BASEBOARD_FAB2_LIB.BASEBOARD_FAB2(SCH_1):P3E_CPU0_PE1_PCH_CON_TXN(12)

CAP_0402-0.22UF,16V,10%,X7R,A3A  I30  C832
   1 P3E_CPU0_PE1_PCH_TXN<11>      A @BASEBOARD_FAB2_LIB.BASEBOARD_FAB2(SCH_1):P3E_CPU0_PE1_PCH_TXN(11)
   2 P3E_CPU0_PE1_PCH_CON_TXN<11>      B @BASEBOARD_FAB2_LIB.BASEBOARD_FAB2(SCH_1):P3E_CPU0_PE1_PCH_CON_TXN(11)

CAP_0402-0.22UF,16V,10%,X7R,A3A  I35  C845
   1 P3E_CPU0_PE1_PCH_TXP<9>      A @BASEBOARD_FAB2_LIB.BASEBOARD_FAB2(SCH_1):P3E_CPU0_PE1_PCH_TXP(9)
   2 P3E_CPU0_PE1_PCH_CON_TXP<9>      B @BASEBOARD_FAB2_LIB.BASEBOARD_FAB2(SCH_1):P3E_CPU0_PE1_PCH_CON_TXP(9)

RES_0402-0.0,5%,1/16W,CHIP,G21A  I39  R767
   1 P3E_CPU0_PE1_PCH_RXP<15>      A @BASEBOARD_FAB2_LIB.BASEBOARD_FAB2(SCH_1):P3E_CPU0_PE1_PCH_RXP(15)
   2 P3E_CPU0_PE1_PCH_CON_RXP<15>      B @BASEBOARD_FAB2_LIB.BASEBOARD_FAB2(SCH_1):P3E_CPU0_PE1_PCH_CON_RXP(15)

CAP_0402-0.22UF,16V,10%,X7R,A3A  I41  C835
   1 P3E_CPU0_PE1_PCH_TXP<10>      A @BASEBOARD_FAB2_LIB.BASEBOARD_FAB2(SCH_1):P3E_CPU0_PE1_PCH_TXP(10)
   2 P3E_CPU0_PE1_PCH_CON_TXP<10>      B @BASEBOARD_FAB2_LIB.BASEBOARD_FAB2(SCH_1):P3E_CPU0_PE1_PCH_CON_TXP(10)

CAP_0402-0.22UF,16V,10%,X7R,A3A  I47  C843
   1 P3E_CPU0_PE1_PCH_TXP<8>      A @BASEBOARD_FAB2_LIB.BASEBOARD_FAB2(SCH_1):P3E_CPU0_PE1_PCH_TXP(8)
   2 P3E_CPU0_PE1_PCH_CON_TXP<8>      B @BASEBOARD_FAB2_LIB.BASEBOARD_FAB2(SCH_1):P3E_CPU0_PE1_PCH_CON_TXP(8)

CAP_0402-0.22UF,16V,10%,X7R,A3A  I50  C834
   1 P3E_CPU0_PE1_PCH_TXN<10>      A @BASEBOARD_FAB2_LIB.BASEBOARD_FAB2(SCH_1):P3E_CPU0_PE1_PCH_TXN(10)
   2 P3E_CPU0_PE1_PCH_CON_TXN<10>      B @BASEBOARD_FAB2_LIB.BASEBOARD_FAB2(SCH_1):P3E_CPU0_PE1_PCH_CON_TXN(10)

CAP_0402-0.22UF,16V,10%,X7R,A3A  I51  C844
   1 P3E_CPU0_PE1_PCH_TXN<9>      A @BASEBOARD_FAB2_LIB.BASEBOARD_FAB2(SCH_1):P3E_CPU0_PE1_PCH_TXN(9)
   2 P3E_CPU0_PE1_PCH_CON_TXN<9>      B @BASEBOARD_FAB2_LIB.BASEBOARD_FAB2(SCH_1):P3E_CPU0_PE1_PCH_CON_TXN(9)

CAP_0402-0.22UF,16V,10%,X7R,A3A  I52  C842
   1 P3E_CPU0_PE1_PCH_TXN<8>      A @BASEBOARD_FAB2_LIB.BASEBOARD_FAB2(SCH_1):P3E_CPU0_PE1_PCH_TXN(8)
   2 P3E_CPU0_PE1_PCH_CON_TXN<8>      B @BASEBOARD_FAB2_LIB.BASEBOARD_FAB2(SCH_1):P3E_CPU0_PE1_PCH_CON_TXN(8)

RES_0402-0.0,5%,1/16W,CHIP,G21A  I58  R769
   1 P3E_CPU0_PE1_PCH_RXP<14>      A @BASEBOARD_FAB2_LIB.BASEBOARD_FAB2(SCH_1):P3E_CPU0_PE1_PCH_RXP(14)
   2 P3E_CPU0_PE1_PCH_CON_RXP<14>      B @BASEBOARD_FAB2_LIB.BASEBOARD_FAB2(SCH_1):P3E_CPU0_PE1_PCH_CON_RXP(14)

RES_0402-0.0,5%,1/16W,CHIP,G21A  I64  R760
   1 P3E_CPU0_PE1_PCH_RXN<15>      A @BASEBOARD_FAB2_LIB.BASEBOARD_FAB2(SCH_1):P3E_CPU0_PE1_PCH_RXN(15)
   2 P3E_CPU0_PE1_PCH_CON_RXN<15>      B @BASEBOARD_FAB2_LIB.BASEBOARD_FAB2(SCH_1):P3E_CPU0_PE1_PCH_CON_RXN(15)

RES_0402-0.0,5%,1/16W,CHIP,G21A  I65  R771
   1 P3E_CPU0_PE1_PCH_RXN<13>      A @BASEBOARD_FAB2_LIB.BASEBOARD_FAB2(SCH_1):P3E_CPU0_PE1_PCH_RXN(13)
   2 P3E_CPU0_PE1_PCH_CON_RXN<13>      B @BASEBOARD_FAB2_LIB.BASEBOARD_FAB2(SCH_1):P3E_CPU0_PE1_PCH_CON_RXN(13)

RES_0402-0.0,5%,1/16W,CHIP,G21A  I66  R768
   1 P3E_CPU0_PE1_PCH_RXN<14>      A @BASEBOARD_FAB2_LIB.BASEBOARD_FAB2(SCH_1):P3E_CPU0_PE1_PCH_RXN(14)
   2 P3E_CPU0_PE1_PCH_CON_RXN<14>      B @BASEBOARD_FAB2_LIB.BASEBOARD_FAB2(SCH_1):P3E_CPU0_PE1_PCH_CON_RXN(14)

RES_0402-0.0,5%,1/16W,CHIP,G21A  I72  R774
   1 P3E_CPU0_PE1_PCH_RXP<13>      A @BASEBOARD_FAB2_LIB.BASEBOARD_FAB2(SCH_1):P3E_CPU0_PE1_PCH_RXP(13)
   2 P3E_CPU0_PE1_PCH_CON_RXP<13>      B @BASEBOARD_FAB2_LIB.BASEBOARD_FAB2(SCH_1):P3E_CPU0_PE1_PCH_CON_RXP(13)

RES_0402-0.0,5%,1/16W,CHIP,G21A  I74  R779
   1 P3E_CPU0_PE1_PCH_RXP<11>      A @BASEBOARD_FAB2_LIB.BASEBOARD_FAB2(SCH_1):P3E_CPU0_PE1_PCH_RXP(11)
   2 P3E_CPU0_PE1_PCH_CON_RXP<11>      B @BASEBOARD_FAB2_LIB.BASEBOARD_FAB2(SCH_1):P3E_CPU0_PE1_PCH_CON_RXP(11)

RES_0402-0.0,5%,1/16W,CHIP,G21A  I77  R783
   1 P3E_CPU0_PE1_PCH_RXP<9>      A @BASEBOARD_FAB2_LIB.BASEBOARD_FAB2(SCH_1):P3E_CPU0_PE1_PCH_RXP(9)
   2 P3E_CPU0_PE1_PCH_CON_RXP<9>      B @BASEBOARD_FAB2_LIB.BASEBOARD_FAB2(SCH_1):P3E_CPU0_PE1_PCH_CON_RXP(9)

RES_0402-0.0,5%,1/16W,CHIP,G21A  I80  R777
   1 P3E_CPU0_PE1_PCH_RXP<12>      A @BASEBOARD_FAB2_LIB.BASEBOARD_FAB2(SCH_1):P3E_CPU0_PE1_PCH_RXP(12)
   2 P3E_CPU0_PE1_PCH_CON_RXP<12>      B @BASEBOARD_FAB2_LIB.BASEBOARD_FAB2(SCH_1):P3E_CPU0_PE1_PCH_CON_RXP(12)

RES_0402-0.0,5%,1/16W,CHIP,G21A  I86  R781
   1 P3E_CPU0_PE1_PCH_RXP<10>      A @BASEBOARD_FAB2_LIB.BASEBOARD_FAB2(SCH_1):P3E_CPU0_PE1_PCH_RXP(10)
   2 P3E_CPU0_PE1_PCH_CON_RXP<10>      B @BASEBOARD_FAB2_LIB.BASEBOARD_FAB2(SCH_1):P3E_CPU0_PE1_PCH_CON_RXP(10)

RES_0402-0.0,5%,1/16W,CHIP,G21A  I93  R775
   1 P3E_CPU0_PE1_PCH_RXN<12>      A @BASEBOARD_FAB2_LIB.BASEBOARD_FAB2(SCH_1):P3E_CPU0_PE1_PCH_RXN(12)
   2 P3E_CPU0_PE1_PCH_CON_RXN<12>      B @BASEBOARD_FAB2_LIB.BASEBOARD_FAB2(SCH_1):P3E_CPU0_PE1_PCH_CON_RXN(12)

RES_0402-0.0,5%,1/16W,CHIP,G21A  I94  R778
   1 P3E_CPU0_PE1_PCH_RXN<11>      A @BASEBOARD_FAB2_LIB.BASEBOARD_FAB2(SCH_1):P3E_CPU0_PE1_PCH_RXN(11)
   2 P3E_CPU0_PE1_PCH_CON_RXN<11>      B @BASEBOARD_FAB2_LIB.BASEBOARD_FAB2(SCH_1):P3E_CPU0_PE1_PCH_CON_RXN(11)

RES_0402-0.0,5%,1/16W,CHIP,G21A  I97  R780
   1 P3E_CPU0_PE1_PCH_RXN<10>      A @BASEBOARD_FAB2_LIB.BASEBOARD_FAB2(SCH_1):P3E_CPU0_PE1_PCH_RXN(10)
   2 P3E_CPU0_PE1_PCH_CON_RXN<10>      B @BASEBOARD_FAB2_LIB.BASEBOARD_FAB2(SCH_1):P3E_CPU0_PE1_PCH_CON_RXN(10)

RES_0402-0.0,5%,1/16W,CHIP,G21A  I98  R782
   1 P3E_CPU0_PE1_PCH_RXN<9>      A @BASEBOARD_FAB2_LIB.BASEBOARD_FAB2(SCH_1):P3E_CPU0_PE1_PCH_RXN(9)
   2 P3E_CPU0_PE1_PCH_CON_RXN<9>      B @BASEBOARD_FAB2_LIB.BASEBOARD_FAB2(SCH_1):P3E_CPU0_PE1_PCH_CON_RXN(9)

RES_0402-0.0,5%,1/16W,CHIP,G21A  I99  R784
   1 P3E_CPU0_PE1_PCH_RXN<8>      A @BASEBOARD_FAB2_LIB.BASEBOARD_FAB2(SCH_1):P3E_CPU0_PE1_PCH_RXN(8)
   2 P3E_CPU0_PE1_PCH_CON_RXN<8>      B @BASEBOARD_FAB2_LIB.BASEBOARD_FAB2(SCH_1):P3E_CPU0_PE1_PCH_CON_RXN(8)

RES_0402-0.0,5%,1/16W,CHIP,G21A  I103  R785
   1 P3E_CPU0_PE1_PCH_RXP<8>      A @BASEBOARD_FAB2_LIB.BASEBOARD_FAB2(SCH_1):P3E_CPU0_PE1_PCH_RXP(8)
   2 P3E_CPU0_PE1_PCH_CON_RXP<8>      B @BASEBOARD_FAB2_LIB.BASEBOARD_FAB2(SCH_1):P3E_CPU0_PE1_PCH_CON_RXP(8)


DRAWING: @BASEBOARD_FAB2_LIB.BASEBOARD_FAB2(SCH_1):PAGE245 

SMC-CONN60A-22-GP_CONN-G7-SMC-A  I48  CONX8
   1    GND      1 @BASEBOARD_FAB2_LIB.BASEBOARD_FAB2(SCH_1):GND
   3 P3E_CPU0_PE2_SS_C_TXN<8>      3 @BASEBOARD_FAB2_LIB.BASEBOARD_FAB2(SCH_1):P3E_CPU0_PE2_SS_C_TXN(8)
   5 P3E_CPU0_PE2_SS_C_TXP<8>      5 @BASEBOARD_FAB2_LIB.BASEBOARD_FAB2(SCH_1):P3E_CPU0_PE2_SS_C_TXP(8)
   7    GND      7 @BASEBOARD_FAB2_LIB.BASEBOARD_FAB2(SCH_1):GND
   2     NC      2     NC
   4    GND      4 @BASEBOARD_FAB2_LIB.BASEBOARD_FAB2(SCH_1):GND
   6 P3E_CPU0_PE2_SS_RXN<8>      6 @BASEBOARD_FAB2_LIB.BASEBOARD_FAB2(SCH_1):P3E_CPU0_PE2_SS_RXN(8)
   8 P3E_CPU0_PE2_SS_RXP<8>      8 @BASEBOARD_FAB2_LIB.BASEBOARD_FAB2(SCH_1):P3E_CPU0_PE2_SS_RXP(8)
   9 P3E_CPU0_PE2_SS_C_TXN<9>      9 @BASEBOARD_FAB2_LIB.BASEBOARD_FAB2(SCH_1):P3E_CPU0_PE2_SS_C_TXN(9)
  11 P3E_CPU0_PE2_SS_C_TXP<9>     11 @BASEBOARD_FAB2_LIB.BASEBOARD_FAB2(SCH_1):P3E_CPU0_PE2_SS_C_TXP(9)
  13    GND     13 @BASEBOARD_FAB2_LIB.BASEBOARD_FAB2(SCH_1):GND
  15 P3E_CPU0_PE2_SS_C_TXN<10>     15 @BASEBOARD_FAB2_LIB.BASEBOARD_FAB2(SCH_1):P3E_CPU0_PE2_SS_C_TXN(10)
  17 P3E_CPU0_PE2_SS_C_TXP<10>     17 @BASEBOARD_FAB2_LIB.BASEBOARD_FAB2(SCH_1):P3E_CPU0_PE2_SS_C_TXP(10)
  19    GND     19 @BASEBOARD_FAB2_LIB.BASEBOARD_FAB2(SCH_1):GND
  21 P3E_CPU0_PE2_SS_C_TXP<11>     21 @BASEBOARD_FAB2_LIB.BASEBOARD_FAB2(SCH_1):P3E_CPU0_PE2_SS_C_TXP(11)
  23 P3E_CPU0_PE2_SS_C_TXN<11>     23 @BASEBOARD_FAB2_LIB.BASEBOARD_FAB2(SCH_1):P3E_CPU0_PE2_SS_C_TXN(11)
  25    GND     25 @BASEBOARD_FAB2_LIB.BASEBOARD_FAB2(SCH_1):GND
  27 P3E_CPU0_PE2_SS_C_TXN<12>     27 @BASEBOARD_FAB2_LIB.BASEBOARD_FAB2(SCH_1):P3E_CPU0_PE2_SS_C_TXN(12)
  29 P3E_CPU0_PE2_SS_C_TXP<12>     29 @BASEBOARD_FAB2_LIB.BASEBOARD_FAB2(SCH_1):P3E_CPU0_PE2_SS_C_TXP(12)
  31    GND     31 @BASEBOARD_FAB2_LIB.BASEBOARD_FAB2(SCH_1):GND
  33 P3E_CPU0_PE2_SS_C_TXN<13>     33 @BASEBOARD_FAB2_LIB.BASEBOARD_FAB2(SCH_1):P3E_CPU0_PE2_SS_C_TXN(13)
  35 P3E_CPU0_PE2_SS_C_TXP<13>     35 @BASEBOARD_FAB2_LIB.BASEBOARD_FAB2(SCH_1):P3E_CPU0_PE2_SS_C_TXP(13)
  37    GND     37 @BASEBOARD_FAB2_LIB.BASEBOARD_FAB2(SCH_1):GND
  39 P3E_CPU0_PE2_SS_C_TXP<14>     39 @BASEBOARD_FAB2_LIB.BASEBOARD_FAB2(SCH_1):P3E_CPU0_PE2_SS_C_TXP(14)
  41 P3E_CPU0_PE2_SS_C_TXN<14>     41 @BASEBOARD_FAB2_LIB.BASEBOARD_FAB2(SCH_1):P3E_CPU0_PE2_SS_C_TXN(14)
  43    GND     43 @BASEBOARD_FAB2_LIB.BASEBOARD_FAB2(SCH_1):GND
  45 P3E_CPU0_PE2_SS_C_TXN<15>     45 @BASEBOARD_FAB2_LIB.BASEBOARD_FAB2(SCH_1):P3E_CPU0_PE2_SS_C_TXN(15)
  47 P3E_CPU0_PE2_SS_C_TXP<15>     47 @BASEBOARD_FAB2_LIB.BASEBOARD_FAB2(SCH_1):P3E_CPU0_PE2_SS_C_TXP(15)
  49    GND     49 @BASEBOARD_FAB2_LIB.BASEBOARD_FAB2(SCH_1):GND
  51 JTAG_RISER_TDI     51 @BASEBOARD_FAB2_LIB.BASEBOARD_FAB2(SCH_1):JTAG_RISER_TDI
  53 JTAG_RISER_TDO     53 @BASEBOARD_FAB2_LIB.BASEBOARD_FAB2(SCH_1):JTAG_RISER_TDO
  55    GND     55 @BASEBOARD_FAB2_LIB.BASEBOARD_FAB2(SCH_1):GND
  57 USB2_P02_DN     57 @BASEBOARD_FAB2_LIB.BASEBOARD_FAB2(SCH_1):USB2_P02_DN
  59 USB2_P02_DP     59 @BASEBOARD_FAB2_LIB.BASEBOARD_FAB2(SCH_1):USB2_P02_DP
  10    GND     10 @BASEBOARD_FAB2_LIB.BASEBOARD_FAB2(SCH_1):GND
  12 P3E_CPU0_PE2_SS_RXN<9>     12 @BASEBOARD_FAB2_LIB.BASEBOARD_FAB2(SCH_1):P3E_CPU0_PE2_SS_RXN(9)
  14 P3E_CPU0_PE2_SS_RXP<9>     14 @BASEBOARD_FAB2_LIB.BASEBOARD_FAB2(SCH_1):P3E_CPU0_PE2_SS_RXP(9)
  16    GND     16 @BASEBOARD_FAB2_LIB.BASEBOARD_FAB2(SCH_1):GND
  18 P3E_CPU0_PE2_SS_RXN<10>     18 @BASEBOARD_FAB2_LIB.BASEBOARD_FAB2(SCH_1):P3E_CPU0_PE2_SS_RXN(10)
  20 P3E_CPU0_PE2_SS_RXP<10>     20 @BASEBOARD_FAB2_LIB.BASEBOARD_FAB2(SCH_1):P3E_CPU0_PE2_SS_RXP(10)
  22    GND     22 @BASEBOARD_FAB2_LIB.BASEBOARD_FAB2(SCH_1):GND
  24 P3E_CPU0_PE2_SS_RXN<11>     24 @BASEBOARD_FAB2_LIB.BASEBOARD_FAB2(SCH_1):P3E_CPU0_PE2_SS_RXN(11)
  26 P3E_CPU0_PE2_SS_RXP<11>     26 @BASEBOARD_FAB2_LIB.BASEBOARD_FAB2(SCH_1):P3E_CPU0_PE2_SS_RXP(11)
  28    GND     28 @BASEBOARD_FAB2_LIB.BASEBOARD_FAB2(SCH_1):GND
  30 P3E_CPU0_PE2_SS_RXN<12>     30 @BASEBOARD_FAB2_LIB.BASEBOARD_FAB2(SCH_1):P3E_CPU0_PE2_SS_RXN(12)
  32 P3E_CPU0_PE2_SS_RXP<12>     32 @BASEBOARD_FAB2_LIB.BASEBOARD_FAB2(SCH_1):P3E_CPU0_PE2_SS_RXP(12)
  34    GND     34 @BASEBOARD_FAB2_LIB.BASEBOARD_FAB2(SCH_1):GND
  36 P3E_CPU0_PE2_SS_RXP<13>     36 @BASEBOARD_FAB2_LIB.BASEBOARD_FAB2(SCH_1):P3E_CPU0_PE2_SS_RXP(13)
  38 P3E_CPU0_PE2_SS_RXN<13>     38 @BASEBOARD_FAB2_LIB.BASEBOARD_FAB2(SCH_1):P3E_CPU0_PE2_SS_RXN(13)
  40    GND     40 @BASEBOARD_FAB2_LIB.BASEBOARD_FAB2(SCH_1):GND
  42 P3E_CPU0_PE2_SS_RXN<14>     42 @BASEBOARD_FAB2_LIB.BASEBOARD_FAB2(SCH_1):P3E_CPU0_PE2_SS_RXN(14)
  44 P3E_CPU0_PE2_SS_RXP<14>     44 @BASEBOARD_FAB2_LIB.BASEBOARD_FAB2(SCH_1):P3E_CPU0_PE2_SS_RXP(14)
  46    GND     46 @BASEBOARD_FAB2_LIB.BASEBOARD_FAB2(SCH_1):GND
  48 P3E_CPU0_PE2_SS_RXN<15>     48 @BASEBOARD_FAB2_LIB.BASEBOARD_FAB2(SCH_1):P3E_CPU0_PE2_SS_RXN(15)
  50 P3E_CPU0_PE2_SS_RXP<15>     50 @BASEBOARD_FAB2_LIB.BASEBOARD_FAB2(SCH_1):P3E_CPU0_PE2_SS_RXP(15)
  52    GND     52 @BASEBOARD_FAB2_LIB.BASEBOARD_FAB2(SCH_1):GND
  54 JTAG_RISER_TMS     54 @BASEBOARD_FAB2_LIB.BASEBOARD_FAB2(SCH_1):JTAG_RISER_TMS
  56 JTAG_RISER_TCK     56 @BASEBOARD_FAB2_LIB.BASEBOARD_FAB2(SCH_1):JTAG_RISER_TCK
  58    GND     58 @BASEBOARD_FAB2_LIB.BASEBOARD_FAB2(SCH_1):GND
  60 JTAG_RISER_TRST     60 @BASEBOARD_FAB2_LIB.BASEBOARD_FAB2(SCH_1):JTAG_RISER_TRST
 NP1     NC    NP1     NC
 NP2     NC    NP2     NC
PTH1    GND   PTH1 @BASEBOARD_FAB2_LIB.BASEBOARD_FAB2(SCH_1):GND
PTH2    GND   PTH2 @BASEBOARD_FAB2_LIB.BASEBOARD_FAB2(SCH_1):GND

RES_0402-0.0,5%,1/16W,CHIP,G21A  I56  R8W10
   1 JTAG_RISER_TMS      A @BASEBOARD_FAB2_LIB.BASEBOARD_FAB2(SCH_1):JTAG_RISER_TMS
   2 JTAG_PLD_TMS_MUX      B @BASEBOARD_FAB2_LIB.BASEBOARD_FAB2(SCH_1):JTAG_PLD_TMS_MUX

RES_0402-0.0,5%,1/16W,CHIP,G21A  I57  R8W11
   1 JTAG_RISER_TCK      A @BASEBOARD_FAB2_LIB.BASEBOARD_FAB2(SCH_1):JTAG_RISER_TCK
   2 JTAG_PLD_TCK_MUX      B @BASEBOARD_FAB2_LIB.BASEBOARD_FAB2(SCH_1):JTAG_PLD_TCK_MUX

RES_0402-0.0,5%,1/16W,CHIP,G21A  I58  R8W12
   1 JTAG_RISER_TRST      A @BASEBOARD_FAB2_LIB.BASEBOARD_FAB2(SCH_1):JTAG_RISER_TRST
   2 JTAG_BMC_TRST_N      B @BASEBOARD_FAB2_LIB.BASEBOARD_FAB2(SCH_1):JTAG_BMC_TRST_N

RES_0402-0.0,5%,1/16W,CHIP,G21A  I59  R8W13
   1 JTAG_RISER_TDI_R      A @BASEBOARD_FAB2_LIB.BASEBOARD_FAB2(SCH_1):JTAG_RISER_TDI_R
   2 JTAG_RISER_TDI      B @BASEBOARD_FAB2_LIB.BASEBOARD_FAB2(SCH_1):JTAG_RISER_TDI

RES_0402-0.0,5%,1/16W,CHIP,G21A  I60  R8W14
   1 JTAG_RISER_TDO_R      A @BASEBOARD_FAB2_LIB.BASEBOARD_FAB2(SCH_1):JTAG_RISER_TDO_R
   2 JTAG_RISER_TDO      B @BASEBOARD_FAB2_LIB.BASEBOARD_FAB2(SCH_1):JTAG_RISER_TDO

74CBTLV1G125_SMLF-IC,C88177-00A  I64  U8W1
   4 JTAG_RISER_TDI_R      B @BASEBOARD_FAB2_LIB.BASEBOARD_FAB2(SCH_1):JTAG_RISER_TDI_R
   1 JTAG_RISER_N   OE_N @BASEBOARD_FAB2_LIB.BASEBOARD_FAB2(SCH_1):JTAG_RISER_N
   2 JTAG_PLD_TDO      A @BASEBOARD_FAB2_LIB.BASEBOARD_FAB2(SCH_1):JTAG_PLD_TDO

NC7SB3157_SMLF-IC,C99406-001  I66  U8W2
   6 JTAG_RISER_N      S @BASEBOARD_FAB2_LIB.BASEBOARD_FAB2(SCH_1):JTAG_RISER_N
   3 JTAG_RISER_TDO_R     B0 @BASEBOARD_FAB2_LIB.BASEBOARD_FAB2(SCH_1):JTAG_RISER_TDO_R
   1 JTAG_PLD_TDO     B1 @BASEBOARD_FAB2_LIB.BASEBOARD_FAB2(SCH_1):JTAG_PLD_TDO
   4 JTAG_PLD_TDO_MUX_R      A @BASEBOARD_FAB2_LIB.BASEBOARD_FAB2(SCH_1):JTAG_PLD_TDO_MUX_R
   5 P3V3_STBY    VCC @BASEBOARD_FAB2_LIB.BASEBOARD_FAB2(SCH_1):P3V3_STBY
   2    GND    GND @BASEBOARD_FAB2_LIB.BASEBOARD_FAB2(SCH_1):GND

CAP_A_0402V-0.01UF,25V,10%,X7RA  I71  C8W6
   1 P3V3_STBY      A @BASEBOARD_FAB2_LIB.BASEBOARD_FAB2(SCH_1):P3V3_STBY
   2    GND      B @BASEBOARD_FAB2_LIB.BASEBOARD_FAB2(SCH_1):GND

CAP_A_0402V-1.0UF,6.3V,10%,X6SA  I74  C8W5
   1 P3V3_STBY      A @BASEBOARD_FAB2_LIB.BASEBOARD_FAB2(SCH_1):P3V3_STBY
   2    GND      B @BASEBOARD_FAB2_LIB.BASEBOARD_FAB2(SCH_1):GND

RES_0402-4.75K,1%,1/16W,CHIP,GA  I78  R8W15
   1 P3V3_STBY      A @BASEBOARD_FAB2_LIB.BASEBOARD_FAB2(SCH_1):P3V3_STBY
   2 JTAG_RISER_N      B @BASEBOARD_FAB2_LIB.BASEBOARD_FAB2(SCH_1):JTAG_RISER_N


DRAWING: @BASEBOARD_FAB2_LIB.BASEBOARD_FAB2(SCH_1):PAGE109 

SCONN200_H68296001_SM-CONN,H68A  I78  J8G1
 101    GND  IO101 @BASEBOARD_FAB2_LIB.BASEBOARD_FAB2(SCH_1):GND
 102 P3E_CPU0_PE1_PCH_CON_RXP<8>  IO102 @BASEBOARD_FAB2_LIB.BASEBOARD_FAB2(SCH_1):P3E_CPU0_PE1_PCH_CON_RXP(8)
 103 P3E_CPU0_PE1_SS_C_TXP<7>  IO103 @BASEBOARD_FAB2_LIB.BASEBOARD_FAB2(SCH_1):P3E_CPU0_PE1_SS_C_TXP(7)
 104    GND  IO104 @BASEBOARD_FAB2_LIB.BASEBOARD_FAB2(SCH_1):GND
 105 P3E_CPU0_PE1_SS_C_TXN<7>  IO105 @BASEBOARD_FAB2_LIB.BASEBOARD_FAB2(SCH_1):P3E_CPU0_PE1_SS_C_TXN(7)
 106 P3E_CPU0_PE1_SS_R_RXN<7>  IO106 @BASEBOARD_FAB2_LIB.BASEBOARD_FAB2(SCH_1):P3E_CPU0_PE1_SS_R_RXN(7)
 107    GND  IO107 @BASEBOARD_FAB2_LIB.BASEBOARD_FAB2(SCH_1):GND
 108 P3E_CPU0_PE1_SS_R_RXP<7>  IO108 @BASEBOARD_FAB2_LIB.BASEBOARD_FAB2(SCH_1):P3E_CPU0_PE1_SS_R_RXP(7)
 109 P3E_CPU0_PE1_SS_C_TXN<6>  IO109 @BASEBOARD_FAB2_LIB.BASEBOARD_FAB2(SCH_1):P3E_CPU0_PE1_SS_C_TXN(6)
 110    GND  IO110 @BASEBOARD_FAB2_LIB.BASEBOARD_FAB2(SCH_1):GND
 111 P3E_CPU0_PE1_SS_C_TXP<6>  IO111 @BASEBOARD_FAB2_LIB.BASEBOARD_FAB2(SCH_1):P3E_CPU0_PE1_SS_C_TXP(6)
 112 P3E_CPU0_PE1_SS_R_RXN<6>  IO112 @BASEBOARD_FAB2_LIB.BASEBOARD_FAB2(SCH_1):P3E_CPU0_PE1_SS_R_RXN(6)
 113    GND  IO113 @BASEBOARD_FAB2_LIB.BASEBOARD_FAB2(SCH_1):GND
 114 P3E_CPU0_PE1_SS_R_RXP<6>  IO114 @BASEBOARD_FAB2_LIB.BASEBOARD_FAB2(SCH_1):P3E_CPU0_PE1_SS_R_RXP(6)
 115 P3E_CPU0_PE1_SS_C_TXN<5>  IO115 @BASEBOARD_FAB2_LIB.BASEBOARD_FAB2(SCH_1):P3E_CPU0_PE1_SS_C_TXN(5)
 116    GND  IO116 @BASEBOARD_FAB2_LIB.BASEBOARD_FAB2(SCH_1):GND
 117 P3E_CPU0_PE1_SS_C_TXP<5>  IO117 @BASEBOARD_FAB2_LIB.BASEBOARD_FAB2(SCH_1):P3E_CPU0_PE1_SS_C_TXP(5)
 118 P3E_CPU0_PE1_SS_R_RXN<5>  IO118 @BASEBOARD_FAB2_LIB.BASEBOARD_FAB2(SCH_1):P3E_CPU0_PE1_SS_R_RXN(5)
 119    GND  IO119 @BASEBOARD_FAB2_LIB.BASEBOARD_FAB2(SCH_1):GND
 120 P3E_CPU0_PE1_SS_R_RXP<5>  IO120 @BASEBOARD_FAB2_LIB.BASEBOARD_FAB2(SCH_1):P3E_CPU0_PE1_SS_R_RXP(5)
 121 P3E_CPU0_PE1_SS_C_TXN<4>  IO121 @BASEBOARD_FAB2_LIB.BASEBOARD_FAB2(SCH_1):P3E_CPU0_PE1_SS_C_TXN(4)
 122    GND  IO122 @BASEBOARD_FAB2_LIB.BASEBOARD_FAB2(SCH_1):GND
 123 P3E_CPU0_PE1_SS_C_TXP<4>  IO123 @BASEBOARD_FAB2_LIB.BASEBOARD_FAB2(SCH_1):P3E_CPU0_PE1_SS_C_TXP(4)
 124 P3E_CPU0_PE1_SS_R_RXN<4>  IO124 @BASEBOARD_FAB2_LIB.BASEBOARD_FAB2(SCH_1):P3E_CPU0_PE1_SS_R_RXN(4)
 125    GND  IO125 @BASEBOARD_FAB2_LIB.BASEBOARD_FAB2(SCH_1):GND
 126 P3E_CPU0_PE1_SS_R_RXP<4>  IO126 @BASEBOARD_FAB2_LIB.BASEBOARD_FAB2(SCH_1):P3E_CPU0_PE1_SS_R_RXP(4)
 127 P3E_CPU0_PE1_SS_C_TXN<3>  IO127 @BASEBOARD_FAB2_LIB.BASEBOARD_FAB2(SCH_1):P3E_CPU0_PE1_SS_C_TXN(3)
 128    GND  IO128 @BASEBOARD_FAB2_LIB.BASEBOARD_FAB2(SCH_1):GND
 129 P3E_CPU0_PE1_SS_C_TXP<3>  IO129 @BASEBOARD_FAB2_LIB.BASEBOARD_FAB2(SCH_1):P3E_CPU0_PE1_SS_C_TXP(3)
 130 P3E_CPU0_PE1_SS_R_RXN<3>  IO130 @BASEBOARD_FAB2_LIB.BASEBOARD_FAB2(SCH_1):P3E_CPU0_PE1_SS_R_RXN(3)
 131    GND  IO131 @BASEBOARD_FAB2_LIB.BASEBOARD_FAB2(SCH_1):GND
 132 P3E_CPU0_PE1_SS_R_RXP<3>  IO132 @BASEBOARD_FAB2_LIB.BASEBOARD_FAB2(SCH_1):P3E_CPU0_PE1_SS_R_RXP(3)
 133 P3E_CPU0_PE1_SS_C_TXN<2>  IO133 @BASEBOARD_FAB2_LIB.BASEBOARD_FAB2(SCH_1):P3E_CPU0_PE1_SS_C_TXN(2)
 134    GND  IO134 @BASEBOARD_FAB2_LIB.BASEBOARD_FAB2(SCH_1):GND
 135 P3E_CPU0_PE1_SS_C_TXP<2>  IO135 @BASEBOARD_FAB2_LIB.BASEBOARD_FAB2(SCH_1):P3E_CPU0_PE1_SS_C_TXP(2)
 136 P3E_CPU0_PE1_SS_R_RXN<2>  IO136 @BASEBOARD_FAB2_LIB.BASEBOARD_FAB2(SCH_1):P3E_CPU0_PE1_SS_R_RXN(2)
 137    GND  IO137 @BASEBOARD_FAB2_LIB.BASEBOARD_FAB2(SCH_1):GND
 138 P3E_CPU0_PE1_SS_R_RXP<2>  IO138 @BASEBOARD_FAB2_LIB.BASEBOARD_FAB2(SCH_1):P3E_CPU0_PE1_SS_R_RXP(2)
 139 P3E_CPU0_PE1_SS_C_TXN<1>  IO139 @BASEBOARD_FAB2_LIB.BASEBOARD_FAB2(SCH_1):P3E_CPU0_PE1_SS_C_TXN(1)
 140    GND  IO140 @BASEBOARD_FAB2_LIB.BASEBOARD_FAB2(SCH_1):GND
 141 P3E_CPU0_PE1_SS_C_TXP<1>  IO141 @BASEBOARD_FAB2_LIB.BASEBOARD_FAB2(SCH_1):P3E_CPU0_PE1_SS_C_TXP(1)
 142 P3E_CPU0_PE1_SS_R_RXN<1>  IO142 @BASEBOARD_FAB2_LIB.BASEBOARD_FAB2(SCH_1):P3E_CPU0_PE1_SS_R_RXN(1)
 143    GND  IO143 @BASEBOARD_FAB2_LIB.BASEBOARD_FAB2(SCH_1):GND
 144 P3E_CPU0_PE1_SS_R_RXP<1>  IO144 @BASEBOARD_FAB2_LIB.BASEBOARD_FAB2(SCH_1):P3E_CPU0_PE1_SS_R_RXP(1)
 145 P3E_CPU0_PE1_SS_C_TXN<0>  IO145 @BASEBOARD_FAB2_LIB.BASEBOARD_FAB2(SCH_1):P3E_CPU0_PE1_SS_C_TXN(0)
 146    GND  IO146 @BASEBOARD_FAB2_LIB.BASEBOARD_FAB2(SCH_1):GND
 147 P3E_CPU0_PE1_SS_C_TXP<0>  IO147 @BASEBOARD_FAB2_LIB.BASEBOARD_FAB2(SCH_1):P3E_CPU0_PE1_SS_C_TXP(0)
 148 P3E_CPU0_PE1_SS_R_RXN<0>  IO148 @BASEBOARD_FAB2_LIB.BASEBOARD_FAB2(SCH_1):P3E_CPU0_PE1_SS_R_RXN(0)
 149    GND  IO149 @BASEBOARD_FAB2_LIB.BASEBOARD_FAB2(SCH_1):GND
 150 P3E_CPU0_PE1_SS_R_RXP<0>  IO150 @BASEBOARD_FAB2_LIB.BASEBOARD_FAB2(SCH_1):P3E_CPU0_PE1_SS_R_RXP(0)
 151 P3E_CPU0_PE2_SS_C_TXN<0>  IO151 @BASEBOARD_FAB2_LIB.BASEBOARD_FAB2(SCH_1):P3E_CPU0_PE2_SS_C_TXN(0)
 152    GND  IO152 @BASEBOARD_FAB2_LIB.BASEBOARD_FAB2(SCH_1):GND
 153 P3E_CPU0_PE2_SS_C_TXP<0>  IO153 @BASEBOARD_FAB2_LIB.BASEBOARD_FAB2(SCH_1):P3E_CPU0_PE2_SS_C_TXP(0)
 154 P3E_CPU0_PE2_SS_RXN<0>  IO154 @BASEBOARD_FAB2_LIB.BASEBOARD_FAB2(SCH_1):P3E_CPU0_PE2_SS_RXN(0)
 155    GND  IO155 @BASEBOARD_FAB2_LIB.BASEBOARD_FAB2(SCH_1):GND
 156 P3E_CPU0_PE2_SS_RXP<0>  IO156 @BASEBOARD_FAB2_LIB.BASEBOARD_FAB2(SCH_1):P3E_CPU0_PE2_SS_RXP(0)
 157 P3E_CPU0_PE2_SS_C_TXP<1>  IO157 @BASEBOARD_FAB2_LIB.BASEBOARD_FAB2(SCH_1):P3E_CPU0_PE2_SS_C_TXP(1)
 158    GND  IO158 @BASEBOARD_FAB2_LIB.BASEBOARD_FAB2(SCH_1):GND
 159 P3E_CPU0_PE2_SS_C_TXN<1>  IO159 @BASEBOARD_FAB2_LIB.BASEBOARD_FAB2(SCH_1):P3E_CPU0_PE2_SS_C_TXN(1)
 160 P3E_CPU0_PE2_SS_RXN<1>  IO160 @BASEBOARD_FAB2_LIB.BASEBOARD_FAB2(SCH_1):P3E_CPU0_PE2_SS_RXN(1)
 161    GND  IO161 @BASEBOARD_FAB2_LIB.BASEBOARD_FAB2(SCH_1):GND
 162 P3E_CPU0_PE2_SS_RXP<1>  IO162 @BASEBOARD_FAB2_LIB.BASEBOARD_FAB2(SCH_1):P3E_CPU0_PE2_SS_RXP(1)
 163 P3E_CPU0_PE2_SS_C_TXN<2>  IO163 @BASEBOARD_FAB2_LIB.BASEBOARD_FAB2(SCH_1):P3E_CPU0_PE2_SS_C_TXN(2)
 164    GND  IO164 @BASEBOARD_FAB2_LIB.BASEBOARD_FAB2(SCH_1):GND
 165 P3E_CPU0_PE2_SS_C_TXP<2>  IO165 @BASEBOARD_FAB2_LIB.BASEBOARD_FAB2(SCH_1):P3E_CPU0_PE2_SS_C_TXP(2)
 166 P3E_CPU0_PE2_SS_RXN<2>  IO166 @BASEBOARD_FAB2_LIB.BASEBOARD_FAB2(SCH_1):P3E_CPU0_PE2_SS_RXN(2)
 167    GND  IO167 @BASEBOARD_FAB2_LIB.BASEBOARD_FAB2(SCH_1):GND
 168 P3E_CPU0_PE2_SS_RXP<2>  IO168 @BASEBOARD_FAB2_LIB.BASEBOARD_FAB2(SCH_1):P3E_CPU0_PE2_SS_RXP(2)
 169 P3E_CPU0_PE2_SS_C_TXN<3>  IO169 @BASEBOARD_FAB2_LIB.BASEBOARD_FAB2(SCH_1):P3E_CPU0_PE2_SS_C_TXN(3)
 170    GND  IO170 @BASEBOARD_FAB2_LIB.BASEBOARD_FAB2(SCH_1):GND
 171 P3E_CPU0_PE2_SS_C_TXP<3>  IO171 @BASEBOARD_FAB2_LIB.BASEBOARD_FAB2(SCH_1):P3E_CPU0_PE2_SS_C_TXP(3)
 172 P3E_CPU0_PE2_SS_RXN<3>  IO172 @BASEBOARD_FAB2_LIB.BASEBOARD_FAB2(SCH_1):P3E_CPU0_PE2_SS_RXN(3)
 173    GND  IO173 @BASEBOARD_FAB2_LIB.BASEBOARD_FAB2(SCH_1):GND
 174 P3E_CPU0_PE2_SS_RXP<3>  IO174 @BASEBOARD_FAB2_LIB.BASEBOARD_FAB2(SCH_1):P3E_CPU0_PE2_SS_RXP(3)
 175 P3E_CPU0_PE2_SS_C_TXN<4>  IO175 @BASEBOARD_FAB2_LIB.BASEBOARD_FAB2(SCH_1):P3E_CPU0_PE2_SS_C_TXN(4)
 176    GND  IO176 @BASEBOARD_FAB2_LIB.BASEBOARD_FAB2(SCH_1):GND
 177 P3E_CPU0_PE2_SS_C_TXP<4>  IO177 @BASEBOARD_FAB2_LIB.BASEBOARD_FAB2(SCH_1):P3E_CPU0_PE2_SS_C_TXP(4)
 178 P3E_CPU0_PE2_SS_RXN<4>  IO178 @BASEBOARD_FAB2_LIB.BASEBOARD_FAB2(SCH_1):P3E_CPU0_PE2_SS_RXN(4)
 179    GND  IO179 @BASEBOARD_FAB2_LIB.BASEBOARD_FAB2(SCH_1):GND
 180 P3E_CPU0_PE2_SS_RXP<4>  IO180 @BASEBOARD_FAB2_LIB.BASEBOARD_FAB2(SCH_1):P3E_CPU0_PE2_SS_RXP(4)
 181 P3E_CPU0_PE2_SS_C_TXN<5>  IO181 @BASEBOARD_FAB2_LIB.BASEBOARD_FAB2(SCH_1):P3E_CPU0_PE2_SS_C_TXN(5)
 182    GND  IO182 @BASEBOARD_FAB2_LIB.BASEBOARD_FAB2(SCH_1):GND
 183 P3E_CPU0_PE2_SS_C_TXP<5>  IO183 @BASEBOARD_FAB2_LIB.BASEBOARD_FAB2(SCH_1):P3E_CPU0_PE2_SS_C_TXP(5)
 184 P3E_CPU0_PE2_SS_RXN<5>  IO184 @BASEBOARD_FAB2_LIB.BASEBOARD_FAB2(SCH_1):P3E_CPU0_PE2_SS_RXN(5)
 185    GND  IO185 @BASEBOARD_FAB2_LIB.BASEBOARD_FAB2(SCH_1):GND
 186 P3E_CPU0_PE2_SS_RXP<5>  IO186 @BASEBOARD_FAB2_LIB.BASEBOARD_FAB2(SCH_1):P3E_CPU0_PE2_SS_RXP(5)
 187 P3E_CPU0_PE2_SS_C_TXN<6>  IO187 @BASEBOARD_FAB2_LIB.BASEBOARD_FAB2(SCH_1):P3E_CPU0_PE2_SS_C_TXN(6)
 188    GND  IO188 @BASEBOARD_FAB2_LIB.BASEBOARD_FAB2(SCH_1):GND
 189 P3E_CPU0_PE2_SS_C_TXP<6>  IO189 @BASEBOARD_FAB2_LIB.BASEBOARD_FAB2(SCH_1):P3E_CPU0_PE2_SS_C_TXP(6)
 190 P3E_CPU0_PE2_SS_RXP<6>  IO190 @BASEBOARD_FAB2_LIB.BASEBOARD_FAB2(SCH_1):P3E_CPU0_PE2_SS_RXP(6)
 191    GND  IO191 @BASEBOARD_FAB2_LIB.BASEBOARD_FAB2(SCH_1):GND
 192 P3E_CPU0_PE2_SS_RXN<6>  IO192 @BASEBOARD_FAB2_LIB.BASEBOARD_FAB2(SCH_1):P3E_CPU0_PE2_SS_RXN(6)
 193 P3E_CPU0_PE2_SS_C_TXN<7>  IO193 @BASEBOARD_FAB2_LIB.BASEBOARD_FAB2(SCH_1):P3E_CPU0_PE2_SS_C_TXN(7)
 194    GND  IO194 @BASEBOARD_FAB2_LIB.BASEBOARD_FAB2(SCH_1):GND
 195 P3E_CPU0_PE2_SS_C_TXP<7>  IO195 @BASEBOARD_FAB2_LIB.BASEBOARD_FAB2(SCH_1):P3E_CPU0_PE2_SS_C_TXP(7)
 196 P3E_CPU0_PE2_SS_RXN<7>  IO196 @BASEBOARD_FAB2_LIB.BASEBOARD_FAB2(SCH_1):P3E_CPU0_PE2_SS_RXN(7)
 197    GND  IO197 @BASEBOARD_FAB2_LIB.BASEBOARD_FAB2(SCH_1):GND
 198 P3E_CPU0_PE2_SS_RXP<7>  IO198 @BASEBOARD_FAB2_LIB.BASEBOARD_FAB2(SCH_1):P3E_CPU0_PE2_SS_RXP(7)
 199 FM_PRSNT_2_6_N  IO199 @BASEBOARD_FAB2_LIB.BASEBOARD_FAB2(SCH_1):FM_PRSNT_2_6_N
 200    GND  IO200 @BASEBOARD_FAB2_LIB.BASEBOARD_FAB2(SCH_1):GND


DRAWING: @BASEBOARD_FAB2_LIB.BASEBOARD_FAB2(SCH_1):PAGE246 

RES_0402-33.2,1%,1/16W,CHIP,G2A  I9  RN8F5
   1 SPI_BMC_BT_DI      A @BASEBOARD_FAB2_LIB.BASEBOARD_FAB2(SCH_1):SPI_BMC_BT_DI
   2 SPI_TPM_BMC_DI_R      B @BASEBOARD_FAB2_LIB.BASEBOARD_FAB2(SCH_1):SPI_TPM_BMC_DI_R

RES_0402-4.75K,1%,1/16W,CHIP,GA  I11  RN8F3
   1 P3V3_STBY      A @BASEBOARD_FAB2_LIB.BASEBOARD_FAB2(SCH_1):P3V3_STBY
   2 PU_TPM_SPI_BMC_HOLD_N      B @BASEBOARD_FAB2_LIB.BASEBOARD_FAB2(SCH_1):PU_TPM_SPI_BMC_HOLD_N

RES_0402-4.75K,1%,1/16W,EMPTY,A  I12  RN8F4
   1 P3V3_STBY      A @BASEBOARD_FAB2_LIB.BASEBOARD_FAB2(SCH_1):P3V3_STBY
   2 PU_TPM_SPI_FLASH_RESET_2_N      B @BASEBOARD_FAB2_LIB.BASEBOARD_FAB2(SCH_1):PU_TPM_SPI_FLASH_RESET_2_N

W25Q256_XSOI-IC,H25002-001  I17  UN8F2
   9 TPM_SPI_BMC_WP_N WP_N_IO<2> @BASEBOARD_FAB2_LIB.BASEBOARD_FAB2(SCH_1):TPM_SPI_BMC_WP_N
  14 TP_TPM_SPI_0  NC<0> @BASEBOARD_FAB2_LIB.BASEBOARD_FAB2(SCH_1):TP_TPM_SPI_0
  13 TP_TPM_SPI_1  NC<1> @BASEBOARD_FAB2_LIB.BASEBOARD_FAB2(SCH_1):TP_TPM_SPI_1
  12 TP_TPM_SPI_2  NC<2> @BASEBOARD_FAB2_LIB.BASEBOARD_FAB2(SCH_1):TP_TPM_SPI_2
  11 TP_TPM_SPI_3  NC<3> @BASEBOARD_FAB2_LIB.BASEBOARD_FAB2(SCH_1):TP_TPM_SPI_3
   6 TP_TPM_SPI_4  NC<4> @BASEBOARD_FAB2_LIB.BASEBOARD_FAB2(SCH_1):TP_TPM_SPI_4
   5 TP_TPM_SPI_5  NC<5> @BASEBOARD_FAB2_LIB.BASEBOARD_FAB2(SCH_1):TP_TPM_SPI_5
   4 TP_TPM_SPI_6  NC<6> @BASEBOARD_FAB2_LIB.BASEBOARD_FAB2(SCH_1):TP_TPM_SPI_6
  10    GND    GND @BASEBOARD_FAB2_LIB.BASEBOARD_FAB2(SCH_1):GND
   8 SPI_TPM_BMC_DI_R DO_IO<1> @BASEBOARD_FAB2_LIB.BASEBOARD_FAB2(SCH_1):SPI_TPM_BMC_DI_R
  16 SPI_BMC_BT_CLK    CLK @BASEBOARD_FAB2_LIB.BASEBOARD_FAB2(SCH_1):SPI_BMC_BT_CLK
   2 P3V3_STBY    VCC @BASEBOARD_FAB2_LIB.BASEBOARD_FAB2(SCH_1):P3V3_STBY
   7 SPI_BMC_BT_CS0_N   CS_N @BASEBOARD_FAB2_LIB.BASEBOARD_FAB2(SCH_1):SPI_BMC_BT_CS0_N
  15 SPI_BMC_BT_DO DI_IO<0> @BASEBOARD_FAB2_LIB.BASEBOARD_FAB2(SCH_1):SPI_BMC_BT_DO
   3 PU_TPM_SPI_FLASH_RESET_2_N RESET_N @BASEBOARD_FAB2_LIB.BASEBOARD_FAB2(SCH_1):PU_TPM_SPI_FLASH_RESET_2_N
   1 PU_TPM_SPI_BMC_HOLD_N HOLD_N_IO<3> @BASEBOARD_FAB2_LIB.BASEBOARD_FAB2(SCH_1):PU_TPM_SPI_BMC_HOLD_N

82KR2F-1-GP_SMD-RG-82KR2F-1-GPA  I19  RN8F6
   1 TPM_SPI_BMC_WP_N      1 @BASEBOARD_FAB2_LIB.BASEBOARD_FAB2(SCH_1):TPM_SPI_BMC_WP_N
   2    GND      2 @BASEBOARD_FAB2_LIB.BASEBOARD_FAB2(SCH_1):GND

RES_0402-4.75K,1%,1/16W,EMPTY,A  I20  RN8F2
   1 P3V3_STBY      A @BASEBOARD_FAB2_LIB.BASEBOARD_FAB2(SCH_1):P3V3_STBY
   2 TPM_SPI_BMC_WP_N      B @BASEBOARD_FAB2_LIB.BASEBOARD_FAB2(SCH_1):TPM_SPI_BMC_WP_N

CAP_A_0402V-1.0UF,6.3V,10%,X6SA  I21  CN8F1
   1 P3V3_STBY      A @BASEBOARD_FAB2_LIB.BASEBOARD_FAB2(SCH_1):P3V3_STBY
   2    GND      B @BASEBOARD_FAB2_LIB.BASEBOARD_FAB2(SCH_1):GND

CAP_A_0402V-0.01UF,25V,10%,X7RA  I22  CN8F2
   1 P3V3_STBY      A @BASEBOARD_FAB2_LIB.BASEBOARD_FAB2(SCH_1):P3V3_STBY
   2    GND      B @BASEBOARD_FAB2_LIB.BASEBOARD_FAB2(SCH_1):GND


DRAWING: @BASEBOARD_FAB2_LIB.BASEBOARD_FAB2(SCH_1):PAGE247 

RES_0402-4.75K,1%,1/16W,CHIP,GA  I1  R6W10
   1 P3V3_STBY      A @BASEBOARD_FAB2_LIB.BASEBOARD_FAB2(SCH_1):P3V3_STBY
   2 PCA9555_INT_N      B @BASEBOARD_FAB2_LIB.BASEBOARD_FAB2(SCH_1):PCA9555_INT_N

CAP_A_0402V-0.1UF,16V,10%,X7R,A  I85  C6W3
   1 P3V3_STBY      A @BASEBOARD_FAB2_LIB.BASEBOARD_FAB2(SCH_1):P3V3_STBY
   2    GND      B @BASEBOARD_FAB2_LIB.BASEBOARD_FAB2(SCH_1):GND

RES_0402-20.0,1%,1/16W,CHIP,G2A  I87  R6W20
   1 SMB_HOST_STBY_LVC3_SDA_R3      A @BASEBOARD_FAB2_LIB.BASEBOARD_FAB2(SCH_1):SMB_HOST_STBY_LVC3_SDA_R3
   2 SMB_HOST_STBY_LVC3_SDA      B @BASEBOARD_FAB2_LIB.BASEBOARD_FAB2(SCH_1):SMB_HOST_STBY_LVC3_SDA

AT24C64_SOICLF-IC,C47049-001-GA  I89  U6W3
   1 PU_ID_EEPROM_A0     A0 @BASEBOARD_FAB2_LIB.BASEBOARD_FAB2(SCH_1):PU_ID_EEPROM_A0
   2    GND     A1 @BASEBOARD_FAB2_LIB.BASEBOARD_FAB2(SCH_1):GND
   3    GND     A2 @BASEBOARD_FAB2_LIB.BASEBOARD_FAB2(SCH_1):GND
   6 SMB_HOST_STBY_LVC3_SCL_R3    SCL @BASEBOARD_FAB2_LIB.BASEBOARD_FAB2(SCH_1):SMB_HOST_STBY_LVC3_SCL_R3
   7 PD_ID_EEPROM_WP     WP @BASEBOARD_FAB2_LIB.BASEBOARD_FAB2(SCH_1):PD_ID_EEPROM_WP
   5 SMB_HOST_STBY_LVC3_SDA_R3    SDA @BASEBOARD_FAB2_LIB.BASEBOARD_FAB2(SCH_1):SMB_HOST_STBY_LVC3_SDA_R3

RES_0402-1.00K,1%,1/16W,CHIP,GA  I90  R6W21
   1 P3V3_STBY      A @BASEBOARD_FAB2_LIB.BASEBOARD_FAB2(SCH_1):P3V3_STBY
   2 PU_ID_EEPROM_A0      B @BASEBOARD_FAB2_LIB.BASEBOARD_FAB2(SCH_1):PU_ID_EEPROM_A0

RES_0402-1.00K,1%,1/16W,CHIP,GA  I92  R6W23
   1 PD_ID_EEPROM_WP      A @BASEBOARD_FAB2_LIB.BASEBOARD_FAB2(SCH_1):PD_ID_EEPROM_WP
   2    GND      B @BASEBOARD_FAB2_LIB.BASEBOARD_FAB2(SCH_1):GND

RES_0402-20.0,1%,1/16W,CHIP,G2A  I94  R6W22
   1 SMB_HOST_STBY_LVC3_SCL      A @BASEBOARD_FAB2_LIB.BASEBOARD_FAB2(SCH_1):SMB_HOST_STBY_LVC3_SCL
   2 SMB_HOST_STBY_LVC3_SCL_R3      B @BASEBOARD_FAB2_LIB.BASEBOARD_FAB2(SCH_1):SMB_HOST_STBY_LVC3_SCL_R3

RES_0402-4.75K,1%,1/16W,CHIP,GA  I98  R6W11
   1 SMB_DEBUG_STBY_LVC3_SCL      A @BASEBOARD_FAB2_LIB.BASEBOARD_FAB2(SCH_1):SMB_DEBUG_STBY_LVC3_SCL
   2 P3V3_STBY      B @BASEBOARD_FAB2_LIB.BASEBOARD_FAB2(SCH_1):P3V3_STBY

RES_0402-4.75K,1%,1/16W,CHIP,GA  I99  R6W12
   1 SMB_DEBUG_STBY_LVC3_SDA      A @BASEBOARD_FAB2_LIB.BASEBOARD_FAB2(SCH_1):SMB_DEBUG_STBY_LVC3_SDA
   2 P3V3_STBY      B @BASEBOARD_FAB2_LIB.BASEBOARD_FAB2(SCH_1):P3V3_STBY

RES_0402-4.75K,1%,1/16W,CHIP,GA  I100  R6W24
   1 P3V3_STBY      A @BASEBOARD_FAB2_LIB.BASEBOARD_FAB2(SCH_1):P3V3_STBY
   2 SMB_PMBUS_BMC_STBY_LVC3_SDA_R1      B @BASEBOARD_FAB2_LIB.BASEBOARD_FAB2(SCH_1):SMB_PMBUS_BMC_STBY_LVC3_SDA_R1

RES_0402-4.75K,1%,1/16W,CHIP,GA  I101  R6W25
   1 P3V3_STBY      A @BASEBOARD_FAB2_LIB.BASEBOARD_FAB2(SCH_1):P3V3_STBY
   2 SMB_PMBUS_BMC_STBY_LVC3_SCL_R1      B @BASEBOARD_FAB2_LIB.BASEBOARD_FAB2(SCH_1):SMB_PMBUS_BMC_STBY_LVC3_SCL_R1

CAP_A_0402V-0.1UF,16V,10%,X7R,A  I105  C6W4
   1 P3V3_STBY      A @BASEBOARD_FAB2_LIB.BASEBOARD_FAB2(SCH_1):P3V3_STBY
   2    GND      B @BASEBOARD_FAB2_LIB.BASEBOARD_FAB2(SCH_1):GND

CAP_A_0402V-0.1UF,16V,10%,X7R,A  I107  C6W2
   1 P3V3_STBY      A @BASEBOARD_FAB2_LIB.BASEBOARD_FAB2(SCH_1):P3V3_STBY
   2    GND      B @BASEBOARD_FAB2_LIB.BASEBOARD_FAB2(SCH_1):GND

RES_0402-4.75K,1%,1/16W,CHIP,GA  I112  R6W28
   1 P3V3_STBY      A @BASEBOARD_FAB2_LIB.BASEBOARD_FAB2(SCH_1):P3V3_STBY
   2 HSC_SMBUS_SWITCH_EN      B @BASEBOARD_FAB2_LIB.BASEBOARD_FAB2(SCH_1):HSC_SMBUS_SWITCH_EN

TCA9517DGKR-GP_DISCRET-G8-TCA9A  I118  U6W2
   1 P3V3_STBY   VCCA @BASEBOARD_FAB2_LIB.BASEBOARD_FAB2(SCH_1):P3V3_STBY
   2 SMB_PMBUS_BMC_STBY_LVC3_SCL_R1   SCLA @BASEBOARD_FAB2_LIB.BASEBOARD_FAB2(SCH_1):SMB_PMBUS_BMC_STBY_LVC3_SCL_R1
   3 SMB_PMBUS_BMC_STBY_LVC3_SDA_R1   SDAA @BASEBOARD_FAB2_LIB.BASEBOARD_FAB2(SCH_1):SMB_PMBUS_BMC_STBY_LVC3_SDA_R1
   4    GND    GND @BASEBOARD_FAB2_LIB.BASEBOARD_FAB2(SCH_1):GND
   8 P3V3_STBY   VCCB @BASEBOARD_FAB2_LIB.BASEBOARD_FAB2(SCH_1):P3V3_STBY
   7 SMB_BMC_PMBUS_STBY_LVC3_SCL   SCLB @BASEBOARD_FAB2_LIB.BASEBOARD_FAB2(SCH_1):SMB_BMC_PMBUS_STBY_LVC3_SCL
   6 SMB_BMC_PMBUS_STBY_LVC3_SDA   SDAB @BASEBOARD_FAB2_LIB.BASEBOARD_FAB2(SCH_1):SMB_BMC_PMBUS_STBY_LVC3_SDA
   5 HSC_SMBUS_SWITCH_EN     EN @BASEBOARD_FAB2_LIB.BASEBOARD_FAB2(SCH_1):HSC_SMBUS_SWITCH_EN

TCA9555PWR-GP_DISCRET-GC1-TCA9A  I120  U6W1
   1 PCA9555_INT_N   INT# @BASEBOARD_FAB2_LIB.BASEBOARD_FAB2(SCH_1):PCA9555_INT_N
   2 PCA9555_A1     A1 @BASEBOARD_FAB2_LIB.BASEBOARD_FAB2(SCH_1):PCA9555_A1
   3 PCA9555_A2     A2 @BASEBOARD_FAB2_LIB.BASEBOARD_FAB2(SCH_1):PCA9555_A2
   4 LED_POSTCODE_0_R    P00 @BASEBOARD_FAB2_LIB.BASEBOARD_FAB2(SCH_1):LED_POSTCODE_0_R
   5 LED_POSTCODE_1_R    P01 @BASEBOARD_FAB2_LIB.BASEBOARD_FAB2(SCH_1):LED_POSTCODE_1_R
   6 LED_POSTCODE_2_R    P02 @BASEBOARD_FAB2_LIB.BASEBOARD_FAB2(SCH_1):LED_POSTCODE_2_R
   7 LED_POSTCODE_3_R    P03 @BASEBOARD_FAB2_LIB.BASEBOARD_FAB2(SCH_1):LED_POSTCODE_3_R
   8 LED_POSTCODE_4_R    P04 @BASEBOARD_FAB2_LIB.BASEBOARD_FAB2(SCH_1):LED_POSTCODE_4_R
   9 LED_POSTCODE_5_R    P05 @BASEBOARD_FAB2_LIB.BASEBOARD_FAB2(SCH_1):LED_POSTCODE_5_R
  10 LED_POSTCODE_6_R    P06 @BASEBOARD_FAB2_LIB.BASEBOARD_FAB2(SCH_1):LED_POSTCODE_6_R
  11 LED_POSTCODE_7_R    P07 @BASEBOARD_FAB2_LIB.BASEBOARD_FAB2(SCH_1):LED_POSTCODE_7_R
  12    GND    GND @BASEBOARD_FAB2_LIB.BASEBOARD_FAB2(SCH_1):GND
  24 P3V3_STBY    VCC @BASEBOARD_FAB2_LIB.BASEBOARD_FAB2(SCH_1):P3V3_STBY
  23 SMB_DEBUG_STBY_LVC3_SDA    SDA @BASEBOARD_FAB2_LIB.BASEBOARD_FAB2(SCH_1):SMB_DEBUG_STBY_LVC3_SDA
  22 SMB_DEBUG_STBY_LVC3_SCL    SCL @BASEBOARD_FAB2_LIB.BASEBOARD_FAB2(SCH_1):SMB_DEBUG_STBY_LVC3_SCL
  21 PCA9555_A0     A0 @BASEBOARD_FAB2_LIB.BASEBOARD_FAB2(SCH_1):PCA9555_A0
  13 FM_DEBUG_RST_BTN_N    P10 @BASEBOARD_FAB2_LIB.BASEBOARD_FAB2(SCH_1):FM_DEBUG_RST_BTN_N
  14 FP_PWR_BTN_R_N    P11 @BASEBOARD_FAB2_LIB.BASEBOARD_FAB2(SCH_1):FP_PWR_BTN_R_N
  15 PWRGD_SYS_PWROK    P12 @BASEBOARD_FAB2_LIB.BASEBOARD_FAB2(SCH_1):PWRGD_SYS_PWROK
  16 RST_PLTRST_N    P13 @BASEBOARD_FAB2_LIB.BASEBOARD_FAB2(SCH_1):RST_PLTRST_N
  17 PWRGD_DSW_PWROK    P14 @BASEBOARD_FAB2_LIB.BASEBOARD_FAB2(SCH_1):PWRGD_DSW_PWROK
  18 FM_CPU_CATERR_MSMI_LVT3_N    P15 @BASEBOARD_FAB2_LIB.BASEBOARD_FAB2(SCH_1):FM_CPU_CATERR_MSMI_LVT3_N
  19 FM_SLPS3_N    P16 @BASEBOARD_FAB2_LIB.BASEBOARD_FAB2(SCH_1):FM_SLPS3_N
  20 FM_UART_SWITCH_N    P17 @BASEBOARD_FAB2_LIB.BASEBOARD_FAB2(SCH_1):FM_UART_SWITCH_N

CAP_A_0402V-0.1UF,16V,10%,X7R,A  I151  C6W1
   1 P3V3_STBY      A @BASEBOARD_FAB2_LIB.BASEBOARD_FAB2(SCH_1):P3V3_STBY
   2    GND      B @BASEBOARD_FAB2_LIB.BASEBOARD_FAB2(SCH_1):GND

DIODE_SMLF-BAT54WS,IC,C73510-0A  I157  CR6W1
   1 FM_CPU_CATERR_LVT3_N      C @BASEBOARD_FAB2_LIB.BASEBOARD_FAB2(SCH_1):FM_CPU_CATERR_LVT3_N
   2 FM_CPU_CATERR_MSMI_LVT3_N      A @BASEBOARD_FAB2_LIB.BASEBOARD_FAB2(SCH_1):FM_CPU_CATERR_MSMI_LVT3_N

DIODE_SMLF-BAT54WS,IC,C73510-0A  I158  CR6W2
   1 FM_CPU_MSMI_LVT3_N      C @BASEBOARD_FAB2_LIB.BASEBOARD_FAB2(SCH_1):FM_CPU_MSMI_LVT3_N
   2 FM_CPU_CATERR_MSMI_LVT3_N      A @BASEBOARD_FAB2_LIB.BASEBOARD_FAB2(SCH_1):FM_CPU_CATERR_MSMI_LVT3_N

RES_0402-4.75K,1%,1/16W,CHIP,GA  I159  R6W4
   1 P3V3_STBY      A @BASEBOARD_FAB2_LIB.BASEBOARD_FAB2(SCH_1):P3V3_STBY
   2 PCA9555_A2      B @BASEBOARD_FAB2_LIB.BASEBOARD_FAB2(SCH_1):PCA9555_A2

RES_0402-4.75K,1%,1/16W,CHIP,GA  I160  R6W5
   1 P3V3_STBY      A @BASEBOARD_FAB2_LIB.BASEBOARD_FAB2(SCH_1):P3V3_STBY
   2 PCA9555_A1      B @BASEBOARD_FAB2_LIB.BASEBOARD_FAB2(SCH_1):PCA9555_A1

RES_0402-4.75K,1%,1/16W,CHIP,GA  I161  R6W6
   1 P3V3_STBY      A @BASEBOARD_FAB2_LIB.BASEBOARD_FAB2(SCH_1):P3V3_STBY
   2 PCA9555_A0      B @BASEBOARD_FAB2_LIB.BASEBOARD_FAB2(SCH_1):PCA9555_A0

RES_0402-4.75K,1%,1/16W,EMPTY,A  I162  R6W9
   1 PCA9555_A0      A @BASEBOARD_FAB2_LIB.BASEBOARD_FAB2(SCH_1):PCA9555_A0
   2    GND      B @BASEBOARD_FAB2_LIB.BASEBOARD_FAB2(SCH_1):GND

RES_0402-4.75K,1%,1/16W,EMPTY,A  I163  R6W8
   1 PCA9555_A1      A @BASEBOARD_FAB2_LIB.BASEBOARD_FAB2(SCH_1):PCA9555_A1
   2    GND      B @BASEBOARD_FAB2_LIB.BASEBOARD_FAB2(SCH_1):GND

RES_0402-4.75K,1%,1/16W,EMPTY,A  I164  R6W7
   1 PCA9555_A2      A @BASEBOARD_FAB2_LIB.BASEBOARD_FAB2(SCH_1):PCA9555_A2
   2    GND      B @BASEBOARD_FAB2_LIB.BASEBOARD_FAB2(SCH_1):GND

RES_0402-100.0K,1%,1/16W,CHIP,A  I165  R6W35
   1 P3V3_STBY      A @BASEBOARD_FAB2_LIB.BASEBOARD_FAB2(SCH_1):P3V3_STBY
   2 FM_CPU_CATERR_MSMI_LVT3_N      B @BASEBOARD_FAB2_LIB.BASEBOARD_FAB2(SCH_1):FM_CPU_CATERR_MSMI_LVT3_N


DRAWING: @BASEBOARD_FAB2_LIB.BASEBOARD_FAB2(SCH_1):PAGE249 

RES_0402-1.00K,1%,1/16W,CHIP,GA  I2  R3W1
   1 BMC_SELF_HW_D_RST      A @BASEBOARD_FAB2_LIB.BASEBOARD_FAB2(SCH_1):BMC_SELF_HW_D_RST
   2    GND      B @BASEBOARD_FAB2_LIB.BASEBOARD_FAB2(SCH_1):GND

RES_0402-10.0K,1%,1/16W,CHIP,GA  I7  R3W9
   1 VREF_2V2      A @BASEBOARD_FAB2_LIB.BASEBOARD_FAB2(SCH_1):VREF_2V2
   2    GND      B @BASEBOARD_FAB2_LIB.BASEBOARD_FAB2(SCH_1):GND

RES_0402-4.75K,1%,1/16W,CHIP,GA  I8  R3W7
   1 P3V3_STBY      A @BASEBOARD_FAB2_LIB.BASEBOARD_FAB2(SCH_1):P3V3_STBY
   2 VREF_2V2      B @BASEBOARD_FAB2_LIB.BASEBOARD_FAB2(SCH_1):VREF_2V2

LMV331IDCKRG4-GP_DISCRET-G-LMVA  I15  Q9W4
   1 FM_TPM_PRES_RST_N    +IN @BASEBOARD_FAB2_LIB.BASEBOARD_FAB2(SCH_1):FM_TPM_PRES_RST_N
   3 VREF_2V2    -IN @BASEBOARD_FAB2_LIB.BASEBOARD_FAB2(SCH_1):VREF_2V2
   4 FM_TPM_PRES_N    OUT @BASEBOARD_FAB2_LIB.BASEBOARD_FAB2(SCH_1):FM_TPM_PRES_N
   5 P5V_STBY    VCC @BASEBOARD_FAB2_LIB.BASEBOARD_FAB2(SCH_1):P5V_STBY
   2    GND    GND @BASEBOARD_FAB2_LIB.BASEBOARD_FAB2(SCH_1):GND

NPN_SM-MMBT3904,IC,C52245-001  I29  Q9W2
   1 FM_TPM_PRES_RST_N_R      B @BASEBOARD_FAB2_LIB.BASEBOARD_FAB2(SCH_1):FM_TPM_PRES_RST_N_R
   3 FM_TPM_PRES_RST      C @BASEBOARD_FAB2_LIB.BASEBOARD_FAB2(SCH_1):FM_TPM_PRES_RST
   2    GND      E @BASEBOARD_FAB2_LIB.BASEBOARD_FAB2(SCH_1):GND

FET_N_SOT23LF-2N7002,FET,C7925A  I30  Q9W1
   1 BMC_TPM_HW_C_RST   GATE @BASEBOARD_FAB2_LIB.BASEBOARD_FAB2(SCH_1):BMC_TPM_HW_C_RST
   2    GND    SRC @BASEBOARD_FAB2_LIB.BASEBOARD_FAB2(SCH_1):GND
   3 FM_TPM_PRES_RST_N    DRN @BASEBOARD_FAB2_LIB.BASEBOARD_FAB2(SCH_1):FM_TPM_PRES_RST_N

47KR2F-GP_RCL_GP-47KR2F-GP,64.A  I31  R3W4
   1 FM_TPM_PRES_RST_N      1 @BASEBOARD_FAB2_LIB.BASEBOARD_FAB2(SCH_1):FM_TPM_PRES_RST_N
   2 FM_TPM_PRES_RST_N_R      2 @BASEBOARD_FAB2_LIB.BASEBOARD_FAB2(SCH_1):FM_TPM_PRES_RST_N_R

RES_0402-0.0,5%,1/16W,CHIP,G21A  I34  R8W1
   1 BMC_SELF_HW_D_RST      A @BASEBOARD_FAB2_LIB.BASEBOARD_FAB2(SCH_1):BMC_SELF_HW_D_RST
   2 FM_TPM_PRES_RST_N      B @BASEBOARD_FAB2_LIB.BASEBOARD_FAB2(SCH_1):FM_TPM_PRES_RST_N

RES_0402-10.0K,1%,1/16W,EMPTY,A  I36  R3W3
   1 P3V3_STBY      A @BASEBOARD_FAB2_LIB.BASEBOARD_FAB2(SCH_1):P3V3_STBY
   2 FM_TPM_PRES_RST_N      B @BASEBOARD_FAB2_LIB.BASEBOARD_FAB2(SCH_1):FM_TPM_PRES_RST_N

CAP_A_0402V-0.1UF,16V,10%,X7R,A  I37  C8W2
   1 P5V_STBY      A @BASEBOARD_FAB2_LIB.BASEBOARD_FAB2(SCH_1):P5V_STBY
   2    GND      B @BASEBOARD_FAB2_LIB.BASEBOARD_FAB2(SCH_1):GND

RES_0402-4.75K,1%,1/16W,CHIP,GA  I48  R3W6
   1 P3V3_STBY      A @BASEBOARD_FAB2_LIB.BASEBOARD_FAB2(SCH_1):P3V3_STBY
   2 RST_BMC_EXTRST_N      B @BASEBOARD_FAB2_LIB.BASEBOARD_FAB2(SCH_1):RST_BMC_EXTRST_N

NPN_SM-MMBT3904,IC,C52245-001  I49  Q9W3
   1 FM_TPM_PRES_RST      B @BASEBOARD_FAB2_LIB.BASEBOARD_FAB2(SCH_1):FM_TPM_PRES_RST
   3 RST_BMC_EXTRST_N      C @BASEBOARD_FAB2_LIB.BASEBOARD_FAB2(SCH_1):RST_BMC_EXTRST_N
   2    GND      E @BASEBOARD_FAB2_LIB.BASEBOARD_FAB2(SCH_1):GND

SC1U16V3KX-2GP_SMD-BCG-SC1U16VA  I52  C8W1
   1 BMC_SELF_HW_D_RST      1 @BASEBOARD_FAB2_LIB.BASEBOARD_FAB2(SCH_1):BMC_SELF_HW_D_RST
   2 BMC_TPM_HW_C_RST      2 @BASEBOARD_FAB2_LIB.BASEBOARD_FAB2(SCH_1):BMC_TPM_HW_C_RST

DIODE_SMLF-BAT54WS,IC,C73510-0A  I55  CR3W1
   1 BMC_SELF_HW_D_RST      C @BASEBOARD_FAB2_LIB.BASEBOARD_FAB2(SCH_1):BMC_SELF_HW_D_RST
   2 BMC_SELF_HW_RST      A @BASEBOARD_FAB2_LIB.BASEBOARD_FAB2(SCH_1):BMC_SELF_HW_RST

RES_0402-100.0K,1%,1/16W,CHIP,A  I56  R3W2
   1 BMC_TPM_HW_C_RST      A @BASEBOARD_FAB2_LIB.BASEBOARD_FAB2(SCH_1):BMC_TPM_HW_C_RST
   2    GND      B @BASEBOARD_FAB2_LIB.BASEBOARD_FAB2(SCH_1):GND

CAP_A_0402V-0.1UF,16V,10%,X7R,A  I57  C3W2
   1 BMC_TPM_HW_C_RST      A @BASEBOARD_FAB2_LIB.BASEBOARD_FAB2(SCH_1):BMC_TPM_HW_C_RST
   2    GND      B @BASEBOARD_FAB2_LIB.BASEBOARD_FAB2(SCH_1):GND

RES_0402-10.0K,1%,1/16W,CHIP,GA  I58  R3W5
   1 P3V3_STBY      A @BASEBOARD_FAB2_LIB.BASEBOARD_FAB2(SCH_1):P3V3_STBY
   2 FM_TPM_PRES_RST      B @BASEBOARD_FAB2_LIB.BASEBOARD_FAB2(SCH_1):FM_TPM_PRES_RST


DRAWING: @BASEBOARD_FAB2_LIB.BASEBOARD_FAB2(SCH_1):PAGE143 

RES_0402-240,1.0%,1/16W,CHIP,GA  I58  R1T27
   1    GND      A @BASEBOARD_FAB2_LIB.BASEBOARD_FAB2(SCH_1):GND
   2 BMC_MIOZ      B @BASEBOARD_FAB2_LIB.BASEBOARD_FAB2(SCH_1):BMC_MIOZ

AST2520A1-GP-GP_ASIC2-GB1-AST2A  I63  U25W4
  U9 BMC_M_DQ4   MDQ4 @BASEBOARD_FAB2_LIB.BASEBOARD_FAB2(SCH_1):BMC_M_DQ4
AA10 BMC_M_DQ3   MDQ3 @BASEBOARD_FAB2_LIB.BASEBOARD_FAB2(SCH_1):BMC_M_DQ3
 Y10 BMC_M_DQ2   MDQ2 @BASEBOARD_FAB2_LIB.BASEBOARD_FAB2(SCH_1):BMC_M_DQ2
 W10 BMC_M_DQ1   MDQ1 @BASEBOARD_FAB2_LIB.BASEBOARD_FAB2(SCH_1):BMC_M_DQ1
 U10 BMC_M_DQ0   MDQ0 @BASEBOARD_FAB2_LIB.BASEBOARD_FAB2(SCH_1):BMC_M_DQ0
 U15 TP_BMC_M_A15   MA15 @BASEBOARD_FAB2_LIB.BASEBOARD_FAB2(SCH_1):TP_BMC_M_A15
  U7 BMC_M_DQ15  MDQ15 @BASEBOARD_FAB2_LIB.BASEBOARD_FAB2(SCH_1):BMC_M_DQ15
  V7 BMC_M_DQ14  MDQ14 @BASEBOARD_FAB2_LIB.BASEBOARD_FAB2(SCH_1):BMC_M_DQ14
 AB8 BMC_M_DM1   MDM1 @BASEBOARD_FAB2_LIB.BASEBOARD_FAB2(SCH_1):BMC_M_DM1
 W11 BMC_MIOZ   MIOZ @BASEBOARD_FAB2_LIB.BASEBOARD_FAB2(SCH_1):BMC_MIOZ
AB13 BMC_M_CAS_N  MCAS# @BASEBOARD_FAB2_LIB.BASEBOARD_FAB2(SCH_1):BMC_M_CAS_N
 U13 BMC_M_A10   MA10 @BASEBOARD_FAB2_LIB.BASEBOARD_FAB2(SCH_1):BMC_M_A10
AA14 BMC_M_A11   MA11 @BASEBOARD_FAB2_LIB.BASEBOARD_FAB2(SCH_1):BMC_M_A11
  T9 BMC_M_VREFCA  MVREF @BASEBOARD_FAB2_LIB.BASEBOARD_FAB2(SCH_1):BMC_M_VREFCA
  Y8 BMC_M_DQ9   MDQ9 @BASEBOARD_FAB2_LIB.BASEBOARD_FAB2(SCH_1):BMC_M_DQ9
 V11 BMC_M_ODT   MODT @BASEBOARD_FAB2_LIB.BASEBOARD_FAB2(SCH_1):BMC_M_ODT
 Y11 BMC_M_CKE   MCKE @BASEBOARD_FAB2_LIB.BASEBOARD_FAB2(SCH_1):BMC_M_CKE
AB12 BMC_M_CLK_DN   MCKN @BASEBOARD_FAB2_LIB.BASEBOARD_FAB2(SCH_1):BMC_M_CLK_DN
 W13 BMC_M_BG0 MBA2_MBG0 @BASEBOARD_FAB2_LIB.BASEBOARD_FAB2(SCH_1):BMC_M_BG0
 Y13 BMC_M_BA1   MBA1 @BASEBOARD_FAB2_LIB.BASEBOARD_FAB2(SCH_1):BMC_M_BA1
 U12 BMC_M_BA0   MBA0 @BASEBOARD_FAB2_LIB.BASEBOARD_FAB2(SCH_1):BMC_M_BA0
 Y16 BMC_M_A9    MA9 @BASEBOARD_FAB2_LIB.BASEBOARD_FAB2(SCH_1):BMC_M_A9
 W16 BMC_M_A8    MA8 @BASEBOARD_FAB2_LIB.BASEBOARD_FAB2(SCH_1):BMC_M_A8
AA16 BMC_M_A7    MA7 @BASEBOARD_FAB2_LIB.BASEBOARD_FAB2(SCH_1):BMC_M_A7
AB16 BMC_M_A6    MA6 @BASEBOARD_FAB2_LIB.BASEBOARD_FAB2(SCH_1):BMC_M_A6
 V15 BMC_M_A5    MA5 @BASEBOARD_FAB2_LIB.BASEBOARD_FAB2(SCH_1):BMC_M_A5
 W15 BMC_M_A4    MA4 @BASEBOARD_FAB2_LIB.BASEBOARD_FAB2(SCH_1):BMC_M_A4
 U14 BMC_M_A3    MA3 @BASEBOARD_FAB2_LIB.BASEBOARD_FAB2(SCH_1):BMC_M_A3
 W14 BMC_M_A2    MA2 @BASEBOARD_FAB2_LIB.BASEBOARD_FAB2(SCH_1):BMC_M_A2
 Y14 BMC_M_A12   MA12 @BASEBOARD_FAB2_LIB.BASEBOARD_FAB2(SCH_1):BMC_M_A12
AB14 BMC_M_A1    MA1 @BASEBOARD_FAB2_LIB.BASEBOARD_FAB2(SCH_1):BMC_M_A1
 V13 BMC_M_A0    MA0 @BASEBOARD_FAB2_LIB.BASEBOARD_FAB2(SCH_1):BMC_M_A0
 AB7 BMC_M_DQS1_DP MDQS1P @BASEBOARD_FAB2_LIB.BASEBOARD_FAB2(SCH_1):BMC_M_DQS1_DP
 AB6 BMC_M_DQS1_DN MDQS1N @BASEBOARD_FAB2_LIB.BASEBOARD_FAB2(SCH_1):BMC_M_DQS1_DN
 AB9 BMC_M_DQS0_DP MDQS0P @BASEBOARD_FAB2_LIB.BASEBOARD_FAB2(SCH_1):BMC_M_DQS0_DP
AB10 BMC_M_DQS0_DN MDQS0N @BASEBOARD_FAB2_LIB.BASEBOARD_FAB2(SCH_1):BMC_M_DQS0_DN
  W9 BMC_M_DQ6   MDQ6 @BASEBOARD_FAB2_LIB.BASEBOARD_FAB2(SCH_1):BMC_M_DQ6
  Y9 BMC_M_DQ5   MDQ5 @BASEBOARD_FAB2_LIB.BASEBOARD_FAB2(SCH_1):BMC_M_DQ5
  W7 BMC_M_DQ13  MDQ13 @BASEBOARD_FAB2_LIB.BASEBOARD_FAB2(SCH_1):BMC_M_DQ13
 AA6 BMC_M_DQ12  MDQ12 @BASEBOARD_FAB2_LIB.BASEBOARD_FAB2(SCH_1):BMC_M_DQ12
  U8 BMC_M_DM0   MDM0 @BASEBOARD_FAB2_LIB.BASEBOARD_FAB2(SCH_1):BMC_M_DM0
AB15 BMC_M_A13   MA13 @BASEBOARD_FAB2_LIB.BASEBOARD_FAB2(SCH_1):BMC_M_A13
 Y15 BMC_M_MACT_N MA14_MACT# @BASEBOARD_FAB2_LIB.BASEBOARD_FAB2(SCH_1):BMC_M_MACT_N
  W8 BMC_M_DQ11  MDQ11 @BASEBOARD_FAB2_LIB.BASEBOARD_FAB2(SCH_1):BMC_M_DQ11
  Y7 BMC_M_DQ10  MDQ10 @BASEBOARD_FAB2_LIB.BASEBOARD_FAB2(SCH_1):BMC_M_DQ10
 Y12 BMC_M_WE_N   MWE# @BASEBOARD_FAB2_LIB.BASEBOARD_FAB2(SCH_1):BMC_M_WE_N
 W12 BMC_M_RAS_N  MRAS# @BASEBOARD_FAB2_LIB.BASEBOARD_FAB2(SCH_1):BMC_M_RAS_N
  V9 BMC_M_DQ7   MDQ7 @BASEBOARD_FAB2_LIB.BASEBOARD_FAB2(SCH_1):BMC_M_DQ7
 AA8 BMC_M_DQ8   MDQ8 @BASEBOARD_FAB2_LIB.BASEBOARD_FAB2(SCH_1):BMC_M_DQ8
AB11 BMC_M_CLK_DP   MCKP @BASEBOARD_FAB2_LIB.BASEBOARD_FAB2(SCH_1):BMC_M_CLK_DP
AA12 BMC_M_CS_N   MCS# @BASEBOARD_FAB2_LIB.BASEBOARD_FAB2(SCH_1):BMC_M_CS_N

CAP_A_0402V-0.1UF,16V,10%,X7R,A  I67  C25W22
   1 BMC_M_VREFCA      A @BASEBOARD_FAB2_LIB.BASEBOARD_FAB2(SCH_1):BMC_M_VREFCA
   2    GND      B @BASEBOARD_FAB2_LIB.BASEBOARD_FAB2(SCH_1):GND


DRAWING: @BASEBOARD_FAB2_LIB.BASEBOARD_FAB2(SCH_1):PAGE144 

RES_0402-51,5.0%,1/16W,CHIP,G2A  I57  R1U14
   1 SGPIO_BMC_CLK_R      A @BASEBOARD_FAB2_LIB.BASEBOARD_FAB2(SCH_1):SGPIO_BMC_CLK_R
   2 SGPIO_BMC_CLK      B @BASEBOARD_FAB2_LIB.BASEBOARD_FAB2(SCH_1):SGPIO_BMC_CLK

RES_0402-51,5.0%,1/16W,CHIP,G2A  I58  R1U13
   1 SGPIO_BMC_DOUT_R      A @BASEBOARD_FAB2_LIB.BASEBOARD_FAB2(SCH_1):SGPIO_BMC_DOUT_R
   2 SGPIO_BMC_DOUT      B @BASEBOARD_FAB2_LIB.BASEBOARD_FAB2(SCH_1):SGPIO_BMC_DOUT

RES_0402-51,5.0%,1/16W,CHIP,G2A  I59  R1U12
   1 SGPIO_BMC_LD_R_N      A @BASEBOARD_FAB2_LIB.BASEBOARD_FAB2(SCH_1):SGPIO_BMC_LD_R_N
   2 SGPIO_BMC_LD_N      B @BASEBOARD_FAB2_LIB.BASEBOARD_FAB2(SCH_1):SGPIO_BMC_LD_N

AST2520A1-GP-GP_ASIC2-GB1-AST2A  I95  U25W4
 H22 PWRGD_SYS_PWROK GPIOB6_LPCPME# @BASEBOARD_FAB2_LIB.BASEBOARD_FAB2(SCH_1):PWRGD_SYS_PWROK
 J20 CLK_48M_USB_BMC_R GPIOB4_USBCKI @BASEBOARD_FAB2_LIB.BASEBOARD_FAB2(SCH_1):CLK_48M_USB_BMC_R
 M18 SMB_LAN_STBY_LVC3_SCL_R GPIOY4_SCL1 @BASEBOARD_FAB2_LIB.BASEBOARD_FAB2(SCH_1):SMB_LAN_STBY_LVC3_SCL_R
 A15 SPI_BMC_DI GPIOI7_SPI1MISO_VBMISO @BASEBOARD_FAB2_LIB.BASEBOARD_FAB2(SCH_1):SPI_BMC_DI
  K4 A_DACRSET DACRSET @BASEBOARD_FAB2_LIB.BASEBOARD_FAB2(SCH_1):A_DACRSET
  J4 BMC_VGA_RED   DACR @BASEBOARD_FAB2_LIB.BASEBOARD_FAB2(SCH_1):BMC_VGA_RED
  J3 BMC_VGA_GREEN   DACG @BASEBOARD_FAB2_LIB.BASEBOARD_FAB2(SCH_1):BMC_VGA_GREEN
  C8 JTAG_BMC_TMS    TMS @BASEBOARD_FAB2_LIB.BASEBOARD_FAB2(SCH_1):JTAG_BMC_TMS
 D12 JTAG_BMC_TDI    TDI @BASEBOARD_FAB2_LIB.BASEBOARD_FAB2(SCH_1):JTAG_BMC_TDI
 C10 JTAG_BMC_TCK    TCK @BASEBOARD_FAB2_LIB.BASEBOARD_FAB2(SCH_1):JTAG_BMC_TCK
  C9 PU_JTAG_BMC_RTCK   RTCK @BASEBOARD_FAB2_LIB.BASEBOARD_FAB2(SCH_1):PU_JTAG_BMC_RTCK
 E11 JTAG_BMC_TRST_N  NTRST @BASEBOARD_FAB2_LIB.BASEBOARD_FAB2(SCH_1):JTAG_BMC_TRST_N
 E15 FM_CPU1_FIVR_FAULT_LVT3_R_N GPIOI1_SYSCK @BASEBOARD_FAB2_LIB.BASEBOARD_FAB2(SCH_1):FM_CPU1_FIVR_FAULT_LVT3_R_N
 C18 FM_CPU0_FIVR_FAULT_LVT3_R_N GPIOI0_SYSCS# @BASEBOARD_FAB2_LIB.BASEBOARD_FAB2(SCH_1):FM_CPU0_FIVR_FAULT_LVT3_R_N
 C15 SPI_BMC_CLK GPIOI5_SPI1CK_VBCK @BASEBOARD_FAB2_LIB.BASEBOARD_FAB2(SCH_1):SPI_BMC_CLK
 B15 SPI_BMC_CS0_N GPIOI4_SPI1CS0#_VBCS# @BASEBOARD_FAB2_LIB.BASEBOARD_FAB2(SCH_1):SPI_BMC_CS0_N
 A14 SPI_BMC_DO GPIOI6_SPI1MOSI_VBMOSI @BASEBOARD_FAB2_LIB.BASEBOARD_FAB2(SCH_1):SPI_BMC_DO
  L2 SGPIO_BMC_LD_R_N GPIOJ1_SGPMLD @BASEBOARD_FAB2_LIB.BASEBOARD_FAB2(SCH_1):SGPIO_BMC_LD_R_N
  R2 SGPIO_BMC_CLK_R GPIOJ0_SGPMCK @BASEBOARD_FAB2_LIB.BASEBOARD_FAB2(SCH_1):SGPIO_BMC_CLK_R
  N3 SGPIO_BMC_DOUT_R GPIOJ2_SGPMO @BASEBOARD_FAB2_LIB.BASEBOARD_FAB2(SCH_1):SGPIO_BMC_DOUT_R
 E16 FM_CPU0_SKTOCC_LVT3_N GPIOG3_SGPS1I1 @BASEBOARD_FAB2_LIB.BASEBOARD_FAB2(SCH_1):FM_CPU0_SKTOCC_LVT3_N
 C19 FM_PCH_BMC_THERMTRIP_N GPIOG2_SGPS1I0 @BASEBOARD_FAB2_LIB.BASEBOARD_FAB2(SCH_1):FM_PCH_BMC_THERMTRIP_N
  J2 BMC_VGA_BLUE   DACB @BASEBOARD_FAB2_LIB.BASEBOARD_FAB2(SCH_1):BMC_VGA_BLUE
 M19 SMB_LAN_STBY_LVC3_SDA_R GPIOY5_SDA1 @BASEBOARD_FAB2_LIB.BASEBOARD_FAB2(SCH_1):SMB_LAN_STBY_LVC3_SDA_R
 D11 JTAG_BMC_TDO    TDO @BASEBOARD_FAB2_LIB.BASEBOARD_FAB2(SCH_1):JTAG_BMC_TDO
 K19 PWRGD_PCH_PWROK GPIOB0 @BASEBOARD_FAB2_LIB.BASEBOARD_FAB2(SCH_1):PWRGD_PCH_PWROK
 L19 BMC_DEBUG_EN_N GPIOB1 @BASEBOARD_FAB2_LIB.BASEBOARD_FAB2(SCH_1):BMC_DEBUG_EN_N
 L18 FM_MP_PS_FAIL_N GPIOB2 @BASEBOARD_FAB2_LIB.BASEBOARD_FAB2(SCH_1):FM_MP_PS_FAIL_N
 K18 H_CPU0_FAST_WAKE_LVT3_N GPIOB3 @BASEBOARD_FAB2_LIB.BASEBOARD_FAB2(SCH_1):H_CPU0_FAST_WAKE_LVT3_N
 H20 IRQ_PVDDQ_GHJ_VRHOT_LVT3_N GPIOB7 @BASEBOARD_FAB2_LIB.BASEBOARD_FAB2(SCH_1):IRQ_PVDDQ_GHJ_VRHOT_LVT3_N
 M20 SMB_SLOTX24_STBY_LVC3_SCL_R GPIOY6_SCL2 @BASEBOARD_FAB2_LIB.BASEBOARD_FAB2(SCH_1):SMB_SLOTX24_STBY_LVC3_SCL_R
 P20 SMB_SLOTX24_STBY_LVC3_SDA_R GPIOY7_SDA2 @BASEBOARD_FAB2_LIB.BASEBOARD_FAB2(SCH_1):SMB_SLOTX24_STBY_LVC3_SDA_R
 A11 SMB_OCP_LAN_STBY_LVC3_SCL_R GPIOQ0_SCL3 @BASEBOARD_FAB2_LIB.BASEBOARD_FAB2(SCH_1):SMB_OCP_LAN_STBY_LVC3_SCL_R
 A10 SMB_OCP_LAN_STBY_LVC3_SDA_R GPIOQ1_SDA3 @BASEBOARD_FAB2_LIB.BASEBOARD_FAB2(SCH_1):SMB_OCP_LAN_STBY_LVC3_SDA_R
  A9 SMB_HOST_STBY_LVC3_SCL_R GPIOQ2_SCL4 @BASEBOARD_FAB2_LIB.BASEBOARD_FAB2(SCH_1):SMB_HOST_STBY_LVC3_SCL_R
  B9 SMB_HOST_STBY_LVC3_SDA_R GPIOQ3_SDA4 @BASEBOARD_FAB2_LIB.BASEBOARD_FAB2(SCH_1):SMB_HOST_STBY_LVC3_SDA_R
  L3 SMB_SMLINK0_STBY_LVC3_SCL_R GPIOK0_SCL5 @BASEBOARD_FAB2_LIB.BASEBOARD_FAB2(SCH_1):SMB_SMLINK0_STBY_LVC3_SCL_R
  L4 SMB_SMLINK0_STBY_LVC3_SDA_R GPIOK1_SDA5 @BASEBOARD_FAB2_LIB.BASEBOARD_FAB2(SCH_1):SMB_SMLINK0_STBY_LVC3_SDA_R
  L1 SMB_VR_STBY_LVC3_SCL_R GPIOK2_SCL6 @BASEBOARD_FAB2_LIB.BASEBOARD_FAB2(SCH_1):SMB_VR_STBY_LVC3_SCL_R
  N2 SMB_VR_STBY_LVC3_SDA_R GPIOK3_SDA6 @BASEBOARD_FAB2_LIB.BASEBOARD_FAB2(SCH_1):SMB_VR_STBY_LVC3_SDA_R
 E19 FM_CPU_CATERR_LVT3_N GPIOG1_SGPS1LD @BASEBOARD_FAB2_LIB.BASEBOARD_FAB2(SCH_1):FM_CPU_CATERR_LVT3_N
 A19 FM_CPU_ERR2_LVT3_N GPIOG0_SGPS1CK @BASEBOARD_FAB2_LIB.BASEBOARD_FAB2(SCH_1):FM_CPU_ERR2_LVT3_N
  N4 SGPIO_BMC_DIN GPIOJ3_SGPMI @BASEBOARD_FAB2_LIB.BASEBOARD_FAB2(SCH_1):SGPIO_BMC_DIN
 B16 FM_FORCE_ADR_N GPIOI2_SYSMOSI @BASEBOARD_FAB2_LIB.BASEBOARD_FAB2(SCH_1):FM_FORCE_ADR_N
 C16 FM_UV_ADR_TRIGGER_EN GPIOI3_SYSMISO @BASEBOARD_FAB2_LIB.BASEBOARD_FAB2(SCH_1):FM_UV_ADR_TRIGGER_EN
 A13 SMB_OCP_FRU_STBY_LVC3_SDA_R GPIOA5_TIMER6_SDA9 @BASEBOARD_FAB2_LIB.BASEBOARD_FAB2(SCH_1):SMB_OCP_FRU_STBY_LVC3_SDA_R
 C14 SMB_OCP_FRU_STBY_LVC3_SCL_R GPIOA4_TIMER5_SCL9 @BASEBOARD_FAB2_LIB.BASEBOARD_FAB2(SCH_1):SMB_OCP_FRU_STBY_LVC3_SCL_R
  R1 SMB_BMC_PMBUS_STBY_LVC3_SDA_R GPIOK7_SDA8 @BASEBOARD_FAB2_LIB.BASEBOARD_FAB2(SCH_1):SMB_BMC_PMBUS_STBY_LVC3_SDA_R
  P2 SMB_BMC_PMBUS_STBY_LVC3_SCL_R GPIOK6_SCL8 @BASEBOARD_FAB2_LIB.BASEBOARD_FAB2(SCH_1):SMB_BMC_PMBUS_STBY_LVC3_SCL_R
  P1 SMB_SENSOR_BMC_STBY_LVC3_SDA GPIOK5_SDA7 @BASEBOARD_FAB2_LIB.BASEBOARD_FAB2(SCH_1):SMB_SENSOR_BMC_STBY_LVC3_SDA
  N1 SMB_SENSOR_BMC_STBY_LVC3_SCL GPIOK4_SCL7 @BASEBOARD_FAB2_LIB.BASEBOARD_FAB2(SCH_1):SMB_SENSOR_BMC_STBY_LVC3_SCL
 H21 IRQ_BMC_PCH_SMI_LPC_N GPIOB5_LPCPD#_LPCSMI# @BASEBOARD_FAB2_LIB.BASEBOARD_FAB2(SCH_1):IRQ_BMC_PCH_SMI_LPC_N
 N21 FM_UARTSW_LSB_N GPIOQ4_SCL14 @BASEBOARD_FAB2_LIB.BASEBOARD_FAB2(SCH_1):FM_UARTSW_LSB_N
 N22 FM_UARTSW_MSB_N GPIOQ5_SDA14 @BASEBOARD_FAB2_LIB.BASEBOARD_FAB2(SCH_1):FM_UARTSW_MSB_N

RES_0402-33.2,1%,1/16W,CHIP,G2A  I114  R25W70
   1 FM_CPU0_FIVR_FAULT_LVT3_R_N      A @BASEBOARD_FAB2_LIB.BASEBOARD_FAB2(SCH_1):FM_CPU0_FIVR_FAULT_LVT3_R_N
   2 FM_CPU0_FIVR_FAULT_LVT3_N      B @BASEBOARD_FAB2_LIB.BASEBOARD_FAB2(SCH_1):FM_CPU0_FIVR_FAULT_LVT3_N

RES_0402-33.2,1%,1/16W,CHIP,G2A  I118  R25W75
   1 FM_CPU1_FIVR_FAULT_LVT3_R_N      A @BASEBOARD_FAB2_LIB.BASEBOARD_FAB2(SCH_1):FM_CPU1_FIVR_FAULT_LVT3_R_N
   2 FM_CPU1_FIVR_FAULT_LVT3_N      B @BASEBOARD_FAB2_LIB.BASEBOARD_FAB2(SCH_1):FM_CPU1_FIVR_FAULT_LVT3_N

RES_0402-150.0,1%,1/16W,CHIP,GA  I139  R25W123
   1 BMC_VGA_BLUE      A @BASEBOARD_FAB2_LIB.BASEBOARD_FAB2(SCH_1):BMC_VGA_BLUE
   2    GND      B @BASEBOARD_FAB2_LIB.BASEBOARD_FAB2(SCH_1):GND

RES_0402-150.0,1%,1/16W,CHIP,GA  I140  R25W124
   1 BMC_VGA_GREEN      A @BASEBOARD_FAB2_LIB.BASEBOARD_FAB2(SCH_1):BMC_VGA_GREEN
   2    GND      B @BASEBOARD_FAB2_LIB.BASEBOARD_FAB2(SCH_1):GND

RES_0402-150.0,1%,1/16W,CHIP,GA  I141  R25W125
   1 BMC_VGA_RED      A @BASEBOARD_FAB2_LIB.BASEBOARD_FAB2(SCH_1):BMC_VGA_RED
   2    GND      B @BASEBOARD_FAB2_LIB.BASEBOARD_FAB2(SCH_1):GND

RES_0402-0.0,5%,1/16W,EMPTY,G2A  I148  R25W140
   1 CLK_48M_USB_BMC      A @BASEBOARD_FAB2_LIB.BASEBOARD_FAB2(SCH_1):CLK_48M_USB_BMC
   2 CLK_48M_USB_BMC_R      B @BASEBOARD_FAB2_LIB.BASEBOARD_FAB2(SCH_1):CLK_48M_USB_BMC_R

18KR2F-GP_RCL_GP-18KR2F-GP,64.A  I150  R25W58
   1 A_DACRSET      1 @BASEBOARD_FAB2_LIB.BASEBOARD_FAB2(SCH_1):A_DACRSET
   2    GND      2 @BASEBOARD_FAB2_LIB.BASEBOARD_FAB2(SCH_1):GND

RES_0402-0.0,5%,1/16W,CHIP,G21A  I151  R25W182
   1 XDP_SYSPWROK      A @BASEBOARD_FAB2_LIB.BASEBOARD_FAB2(SCH_1):XDP_SYSPWROK
   2 PWRGD_SYS_PWROK      B @BASEBOARD_FAB2_LIB.BASEBOARD_FAB2(SCH_1):PWRGD_SYS_PWROK


DRAWING: @BASEBOARD_FAB2_LIB.BASEBOARD_FAB2(SCH_1):PAGE145 

OSC_C_SM4-24MHZ,OSC,D34520-021  I8  Y9F2
   1 PU_24M_OSC_OE ENABLE_CONTROL @BASEBOARD_FAB2_LIB.BASEBOARD_FAB2(SCH_1):PU_24M_OSC_OE
   2    GND    GND @BASEBOARD_FAB2_LIB.BASEBOARD_FAB2(SCH_1):GND
   3 CLK_24M_BMC_CLKIN_R    OUT @BASEBOARD_FAB2_LIB.BASEBOARD_FAB2(SCH_1):CLK_24M_BMC_CLKIN_R
   4 P3V3_STBY    VDD @BASEBOARD_FAB2_LIB.BASEBOARD_FAB2(SCH_1):P3V3_STBY

RES_0402-0.0,5%,1/16W,EMPTY,G2A  I10  R9F60
   1 CLK_25M_BMC      A @BASEBOARD_FAB2_LIB.BASEBOARD_FAB2(SCH_1):CLK_25M_BMC
   2 CLK_24M_25M_BMC_CLKIN      B @BASEBOARD_FAB2_LIB.BASEBOARD_FAB2(SCH_1):CLK_24M_25M_BMC_CLKIN

RES_0402-0.0,5%,1/16W,CHIP,G21A  I11  R9F62
   1 CLK_24M_BMC_CLKIN_R      A @BASEBOARD_FAB2_LIB.BASEBOARD_FAB2(SCH_1):CLK_24M_BMC_CLKIN_R
   2 CLK_24M_25M_BMC_CLKIN      B @BASEBOARD_FAB2_LIB.BASEBOARD_FAB2(SCH_1):CLK_24M_25M_BMC_CLKIN

RES_0402-10.0K,1%,1/16W,CHIP,GA  I14  R9F61
   1 P3V3_STBY      A @BASEBOARD_FAB2_LIB.BASEBOARD_FAB2(SCH_1):P3V3_STBY
   2 PU_24M_OSC_OE      B @BASEBOARD_FAB2_LIB.BASEBOARD_FAB2(SCH_1):PU_24M_OSC_OE

CAP_A_0402V-0.1UF,16V,10%,X7R,A  I15  C9F23
   1 P3V3_STBY      A @BASEBOARD_FAB2_LIB.BASEBOARD_FAB2(SCH_1):P3V3_STBY
   2    GND      B @BASEBOARD_FAB2_LIB.BASEBOARD_FAB2(SCH_1):GND

RES_0402-0.0,5%,1/16W,CHIP,G21A  I20  R9F33
   1 PECI_BMC      A @BASEBOARD_FAB2_LIB.BASEBOARD_FAB2(SCH_1):PECI_BMC
   2 PECI_BMC_R      B @BASEBOARD_FAB2_LIB.BASEBOARD_FAB2(SCH_1):PECI_BMC_R

RES_0402-348,1%,1/16W,EMPTY,G2A  I22  R9F20
   1 PECI_BMC      A @BASEBOARD_FAB2_LIB.BASEBOARD_FAB2(SCH_1):PECI_BMC
   2    GND      B @BASEBOARD_FAB2_LIB.BASEBOARD_FAB2(SCH_1):GND

RES_0402-100.0K,1%,1/16W,CHIP,A  I30  R25W61
   1 CLK_100M_BMC_PE_R_DP      A @BASEBOARD_FAB2_LIB.BASEBOARD_FAB2(SCH_1):CLK_100M_BMC_PE_R_DP
   2    GND      B @BASEBOARD_FAB2_LIB.BASEBOARD_FAB2(SCH_1):GND

RES_0402-100.0K,1%,1/16W,CHIP,A  I31  R25W62
   1 RST_PLTRST_BUF_N_R      A @BASEBOARD_FAB2_LIB.BASEBOARD_FAB2(SCH_1):RST_PLTRST_BUF_N_R
   2    GND      B @BASEBOARD_FAB2_LIB.BASEBOARD_FAB2(SCH_1):GND

RES_0402-100.0K,1%,1/16W,CHIP,A  I34  R25W60
   1 CLK_100M_BMC_PE_R_DN      A @BASEBOARD_FAB2_LIB.BASEBOARD_FAB2(SCH_1):CLK_100M_BMC_PE_R_DN
   2    GND      B @BASEBOARD_FAB2_LIB.BASEBOARD_FAB2(SCH_1):GND

RES_0402-100.0K,1%,1/16W,CHIP,A  I36  R25W64
   1 P2E_SSB_BMC_TX_C_DP      A @BASEBOARD_FAB2_LIB.BASEBOARD_FAB2(SCH_1):P2E_SSB_BMC_TX_C_DP
   2    GND      B @BASEBOARD_FAB2_LIB.BASEBOARD_FAB2(SCH_1):GND

RES_0402-100.0K,1%,1/16W,CHIP,A  I38  R25W65
   1 P2E_SSB_BMC_TX_C_DN      A @BASEBOARD_FAB2_LIB.BASEBOARD_FAB2(SCH_1):P2E_SSB_BMC_TX_C_DN
   2    GND      B @BASEBOARD_FAB2_LIB.BASEBOARD_FAB2(SCH_1):GND

RES_0402-0.0,5%,1/16W,EMPTY,G2A  I100  R1T15
   1 FM_BMC_ONCTL_N      A @BASEBOARD_FAB2_LIB.BASEBOARD_FAB2(SCH_1):FM_BMC_ONCTL_N
   2 FM_BMC_ONCTL_R_N      B @BASEBOARD_FAB2_LIB.BASEBOARD_FAB2(SCH_1):FM_BMC_ONCTL_R_N

RES_0402-0.0,5%,1/16W,EMPTY,G2A  I101  R1T23
   1 FM_BMC_ONCTL_R_N      A @BASEBOARD_FAB2_LIB.BASEBOARD_FAB2(SCH_1):FM_BMC_ONCTL_R_N
   2    GND      B @BASEBOARD_FAB2_LIB.BASEBOARD_FAB2(SCH_1):GND

AST2520A1-GP-GP_ASIC2-GB1-AST2A  I117  U25W4
 B12 SMB_PEHPCPU0_STBY_LVC3_SCL GPIOC2_SD1DAT0_SCL11 @BASEBOARD_FAB2_LIB.BASEBOARD_FAB2(SCH_1):SMB_PEHPCPU0_STBY_LVC3_SCL
  D9 SMB_PEHPCPU0_STBY_LVC3_SDA GPIOC3_SD1DAT1_SDA11 @BASEBOARD_FAB2_LIB.BASEBOARD_FAB2(SCH_1):SMB_PEHPCPU0_STBY_LVC3_SDA
 A12 SMB_DEBUG_STBY_LVC3_SDA_R GPIOC1_SD1CMD_SDA10 @BASEBOARD_FAB2_LIB.BASEBOARD_FAB2(SCH_1):SMB_DEBUG_STBY_LVC3_SDA_R
 C12 SMB_DEBUG_STBY_LVC3_SCL_R GPIOC0_SD1CLK_SCL10 @BASEBOARD_FAB2_LIB.BASEBOARD_FAB2(SCH_1):SMB_DEBUG_STBY_LVC3_SCL_R
 B14 JTAG_RISER_N GPIOA0_MAC1LINK @BASEBOARD_FAB2_LIB.BASEBOARD_FAB2(SCH_1):JTAG_RISER_N
 D14 FM_CPLD_BMC_PWRDN_N GPIOA1_MAC2LINK @BASEBOARD_FAB2_LIB.BASEBOARD_FAB2(SCH_1):FM_CPLD_BMC_PWRDN_N
 P21 FM_BMC_ONCTL_R_N GPIOY3_SIOONCTRL# @BASEBOARD_FAB2_LIB.BASEBOARD_FAB2(SCH_1):FM_BMC_ONCTL_R_N
 D15 IRQ_MEZZ_LAN_ALERT_N GPIOG6_SGPS2I0_SALT3 @BASEBOARD_FAB2_LIB.BASEBOARD_FAB2(SCH_1):IRQ_MEZZ_LAN_ALERT_N
 C11 SMB_PEHPCPU0_STBY_LVC3_R2_SCL GPIOC6_SD1CD#_SCL13 @BASEBOARD_FAB2_LIB.BASEBOARD_FAB2(SCH_1):SMB_PEHPCPU0_STBY_LVC3_R2_SCL
 D10 SMB_PEHPCPU1_STBY_LVC3_SCL GPIOC4_SD1DAT2_SCL12 @BASEBOARD_FAB2_LIB.BASEBOARD_FAB2(SCH_1):SMB_PEHPCPU1_STBY_LVC3_SCL
 E14 FM_BIOS_SMI_ACTIVE_N GPIOG7_SGPS2I1_SALT4 @BASEBOARD_FAB2_LIB.BASEBOARD_FAB2(SCH_1):FM_BIOS_SMI_ACTIVE_N
 D13 TP_BMC_GPIOA2 GPIOA2_TIMER3_SPI1CS1# @BASEBOARD_FAB2_LIB.BASEBOARD_FAB2(SCH_1):TP_BMC_GPIOA2
 D16 IRQ_OOB_MGMT_RISER_ALERT_N GPIOG5_SGPS2LD_SALT2 @BASEBOARD_FAB2_LIB.BASEBOARD_FAB2(SCH_1):IRQ_OOB_MGMT_RISER_ALERT_N
 E17 IRQ_PCH_NIC_ALERT_N GPIOG4_SGPS2CK_SALT1 @BASEBOARD_FAB2_LIB.BASEBOARD_FAB2(SCH_1):IRQ_PCH_NIC_ALERT_N
 H19 FM_OCP_MEZZB_PRES_LVT3_BMC GPIOF5_NRTS4_LHFRAME# @BASEBOARD_FAB2_LIB.BASEBOARD_FAB2(SCH_1):FM_OCP_MEZZB_PRES_LVT3_BMC
 H18 FM_OCP_MEZZC_PRES_LVT3_BMC GPIOF7_RXD4_LHRST# @BASEBOARD_FAB2_LIB.BASEBOARD_FAB2(SCH_1):FM_OCP_MEZZC_PRES_LVT3_BMC
  U1 FM_HSC_TIMER_EXP_N GPIOL2_NDSR1 @BASEBOARD_FAB2_LIB.BASEBOARD_FAB2(SCH_1):FM_HSC_TIMER_EXP_N
  U2 FM_BIOS_TOP_SWAP GPIOL3_NRI1_VPIHS @BASEBOARD_FAB2_LIB.BASEBOARD_FAB2(SCH_1):FM_BIOS_TOP_SWAP
  P4 FM_MEM_THERM_EVENT_PCH_N GPIOL4_NDTR1_VPIVS @BASEBOARD_FAB2_LIB.BASEBOARD_FAB2(SCH_1):FM_MEM_THERM_EVENT_PCH_N
 K22 CLK_100M_BMC_PE_R_DN PEREFCLKN @BASEBOARD_FAB2_LIB.BASEBOARD_FAB2(SCH_1):CLK_100M_BMC_PE_R_DN
 K21 CLK_100M_BMC_PE_R_DP PEREFCLKP @BASEBOARD_FAB2_LIB.BASEBOARD_FAB2(SCH_1):CLK_100M_BMC_PE_R_DP
  K2 UART_BMC_RXD5   RXD5 @BASEBOARD_FAB2_LIB.BASEBOARD_FAB2(SCH_1):UART_BMC_RXD5
AB18 PECI_BMC_R   PECI @BASEBOARD_FAB2_LIB.BASEBOARD_FAB2(SCH_1):PECI_BMC_R
 D20 FM_BOARD_REV_ID1 GPIOD3_SD2DAT1 @BASEBOARD_FAB2_LIB.BASEBOARD_FAB2(SCH_1):FM_BOARD_REV_ID1
 D21 IRQ_DIMM_SAVE_LVT3_N GPIOD4_SD2DAT2 @BASEBOARD_FAB2_LIB.BASEBOARD_FAB2(SCH_1):IRQ_DIMM_SAVE_LVT3_N
 E21 FM_BOARD_REV_ID0 GPIOD1_SD2CMD @BASEBOARD_FAB2_LIB.BASEBOARD_FAB2(SCH_1):FM_BOARD_REV_ID0
 W18 CLK_24M_25M_BMC_CLKIN  CLKIN @BASEBOARD_FAB2_LIB.BASEBOARD_FAB2(SCH_1):CLK_24M_25M_BMC_CLKIN
 U18 RST_BMC_SRST_N  SRST# @BASEBOARD_FAB2_LIB.BASEBOARD_FAB2(SCH_1):RST_BMC_SRST_N
 E13 FM_BMC_SYS_THROTTLE_R_N GPIOA3_TIMER4 @BASEBOARD_FAB2_LIB.BASEBOARD_FAB2(SCH_1):FM_BMC_SYS_THROTTLE_R_N
 L20 RST_PLTRST_BUF_N_R PERST# @BASEBOARD_FAB2_LIB.BASEBOARD_FAB2(SCH_1):RST_PLTRST_BUF_N_R
 M22 P2E_SSB_BMC_TX_C_DN  PERXN @BASEBOARD_FAB2_LIB.BASEBOARD_FAB2(SCH_1):P2E_SSB_BMC_TX_C_DN
 M21 P2E_SSB_BMC_TX_C_DP  PERXP @BASEBOARD_FAB2_LIB.BASEBOARD_FAB2(SCH_1):P2E_SSB_BMC_TX_C_DP
  Y1 FM_CPU0_RC_ERROR_N GPIOM0_NCTS2_VPIB2 @BASEBOARD_FAB2_LIB.BASEBOARD_FAB2(SCH_1):FM_CPU0_RC_ERROR_N
 AB2 FM_CPU1_RC_ERROR_N GPIOM1_NDCD2_VPIB3 @BASEBOARD_FAB2_LIB.BASEBOARD_FAB2(SCH_1):FM_CPU1_RC_ERROR_N
 AA1 IRQ_BOARD_BMC_ALERT_N GPIOM2_NDSR2_VPIB4 @BASEBOARD_FAB2_LIB.BASEBOARD_FAB2(SCH_1):IRQ_BOARD_BMC_ALERT_N
  Y2 FM_OC_DETECT_EN_N GPIOM3_NRI2_VPIB5 @BASEBOARD_FAB2_LIB.BASEBOARD_FAB2(SCH_1):FM_OC_DETECT_EN_N
 AA2 FM_CPU0_THERMTRIP_LATCH_LVT3_N GPIOM4_NDTR2_VPIB6 @BASEBOARD_FAB2_LIB.BASEBOARD_FAB2(SCH_1):FM_CPU0_THERMTRIP_LATCH_LVT3_N
  P5 FM_CPU1_THERMTRIP_LATCH_LVT3_N GPIOM5_NRTS2_VPIB7 @BASEBOARD_FAB2_LIB.BASEBOARD_FAB2(SCH_1):FM_CPU1_THERMTRIP_LATCH_LVT3_N
  R5 SP2_BMC_CM_UART_TX GPIOM6_TXD2_VPIB8 @BASEBOARD_FAB2_LIB.BASEBOARD_FAB2(SCH_1):SP2_BMC_CM_UART_TX
  T5 SP2_BMC_CM_UART_RX GPIOM7_RXD2_VPIB9 @BASEBOARD_FAB2_LIB.BASEBOARD_FAB2(SCH_1):SP2_BMC_CM_UART_RX
  T1 IRQ_OC_DETECT_N GPIOL1_NDCD1_VPIDE @BASEBOARD_FAB2_LIB.BASEBOARD_FAB2(SCH_1):IRQ_OC_DETECT_N
  P3 FM_PMBUS_ALERT_BUF_EN_R3_N GPIOL5_NRTS1_VPICLK @BASEBOARD_FAB2_LIB.BASEBOARD_FAB2(SCH_1):FM_PMBUS_ALERT_BUF_EN_R3_N
  W1 SP1_BMC_HOST_UART_RX GPIOL7_RXD1 @BASEBOARD_FAB2_LIB.BASEBOARD_FAB2(SCH_1):SP1_BMC_HOST_UART_RX
 J19 IRQ_PVDDQ_ABC_VRHOT_LVT3_N GPIOF0_NCTS4_LHAD0 @BASEBOARD_FAB2_LIB.BASEBOARD_FAB2(SCH_1):IRQ_PVDDQ_ABC_VRHOT_LVT3_N
 J18 SPI_BMC_BT_WP0_N GPIOF1_NDCD4_LHAD1 @BASEBOARD_FAB2_LIB.BASEBOARD_FAB2(SCH_1):SPI_BMC_BT_WP0_N
 B22 IRQ_PVCCIN_CPU0_VRHOT_LVC3_N GPIOF2_NDSR4_LHAD2 @BASEBOARD_FAB2_LIB.BASEBOARD_FAB2(SCH_1):IRQ_PVCCIN_CPU0_VRHOT_LVC3_N
 F18 FM_PWR_BTN_R1_N GPIOE2_NDSR3 @BASEBOARD_FAB2_LIB.BASEBOARD_FAB2(SCH_1):FM_PWR_BTN_R1_N
 F17 FM_BMC_PWRBTN_OUT_N GPIOE3_NRI3 @BASEBOARD_FAB2_LIB.BASEBOARD_FAB2(SCH_1):FM_BMC_PWRBTN_OUT_N
 E18 FP_NMI_BTN_N GPIOE4_NDTR3 @BASEBOARD_FAB2_LIB.BASEBOARD_FAB2(SCH_1):FP_NMI_BTN_N
 A20 FM_CPU0_PROCHOT_LVT3_BMC_N GPIOE6_TXD3 @BASEBOARD_FAB2_LIB.BASEBOARD_FAB2(SCH_1):FM_CPU0_PROCHOT_LVT3_BMC_N
 B19 FM_CPU1_PROCHOT_LVT3_BMC_N GPIOE7_RXD3 @BASEBOARD_FAB2_LIB.BASEBOARD_FAB2(SCH_1):FM_CPU1_PROCHOT_LVT3_BMC_N
  K1 UART_BMC_TXD5   TXD5 @BASEBOARD_FAB2_LIB.BASEBOARD_FAB2(SCH_1):UART_BMC_TXD5
 K20 PD_PEREXT PEREXT @BASEBOARD_FAB2_LIB.BASEBOARD_FAB2(SCH_1):PD_PEREXT
 L22 P2E_SSB_BMC_RX_DN  PETXN @BASEBOARD_FAB2_LIB.BASEBOARD_FAB2(SCH_1):P2E_SSB_BMC_RX_DN
 L21 P2E_SSB_BMC_RX_DP  PETXP @BASEBOARD_FAB2_LIB.BASEBOARD_FAB2(SCH_1):P2E_SSB_BMC_RX_DP
 D19 IRQ_BMC_PCH_NMI_STBY_N GPIOE5_NRTS3 @BASEBOARD_FAB2_LIB.BASEBOARD_FAB2(SCH_1):IRQ_BMC_PCH_NMI_STBY_N
 C20 RST_BMC_SYSRST_BTN_OUT_N GPIOE1_NDCD3 @BASEBOARD_FAB2_LIB.BASEBOARD_FAB2(SCH_1):RST_BMC_SYSRST_BTN_OUT_N
 B20 RST_SYSTEM_BTN_R_N GPIOE0_NCTS3 @BASEBOARD_FAB2_LIB.BASEBOARD_FAB2(SCH_1):RST_SYSTEM_BTN_R_N
 F19 FM_BIOS_MRC_DEBUG_MSG_DIS_N GPIOD0_SD2CLK @BASEBOARD_FAB2_LIB.BASEBOARD_FAB2(SCH_1):FM_BIOS_MRC_DEBUG_MSG_DIS_N
 F20 FM_SOL_UART_CH_SEL GPIOD2_SD2DAT0 @BASEBOARD_FAB2_LIB.BASEBOARD_FAB2(SCH_1):FM_SOL_UART_CH_SEL
 C21 FM_CPU_ERR1_LVT3_BMC_N GPIOD7_SD2WP# @BASEBOARD_FAB2_LIB.BASEBOARD_FAB2(SCH_1):FM_CPU_ERR1_LVT3_BMC_N
 B11 SMB_PEHPCPU0_STBY_LVC3_R2_SDA GPIOC7_SD1WP#_SDA13 @BASEBOARD_FAB2_LIB.BASEBOARD_FAB2(SCH_1):SMB_PEHPCPU0_STBY_LVC3_R2_SDA
 E12 SMB_PEHPCPU1_STBY_LVC3_SDA GPIOC5_SD1DAT3_SDA12 @BASEBOARD_FAB2_LIB.BASEBOARD_FAB2(SCH_1):SMB_PEHPCPU1_STBY_LVC3_SDA
  T2 IRQ_UV_DETECT_N GPIOL0_NCTS1 @BASEBOARD_FAB2_LIB.BASEBOARD_FAB2(SCH_1):IRQ_UV_DETECT_N
 B21 IRQ_PVCCIN_CPU1_VRHOT_LVC3_N GPIOF3_NRI4_LHAD3 @BASEBOARD_FAB2_LIB.BASEBOARD_FAB2(SCH_1):IRQ_PVCCIN_CPU1_VRHOT_LVC3_N
 A21 IRQ_PVDDQ_KLM_VRHOT_LVT3_N GPIOF4_NDTR4_LHCLK @BASEBOARD_FAB2_LIB.BASEBOARD_FAB2(SCH_1):IRQ_PVDDQ_KLM_VRHOT_LVT3_N
 G17 FM_BATTERY_SENSE_EN_N GPIOF6_TXD4_LHSIRQ# @BASEBOARD_FAB2_LIB.BASEBOARD_FAB2(SCH_1):FM_BATTERY_SENSE_EN_N
  V1 SP1_BMC_HOST_UART_TX GPIOL6_TXD1 @BASEBOARD_FAB2_LIB.BASEBOARD_FAB2(SCH_1):SP1_BMC_HOST_UART_TX
 G18 FM_CPU_ERR0_LVT3_BMC_N GPIOD6_SD2CD# @BASEBOARD_FAB2_LIB.BASEBOARD_FAB2(SCH_1):FM_CPU_ERR0_LVT3_BMC_N
 E20 FM_BOARD_REV_ID2 GPIOD5_SD2DAT3 @BASEBOARD_FAB2_LIB.BASEBOARD_FAB2(SCH_1):FM_BOARD_REV_ID2

200R2F-L1-GP_SMD-RG4-200R2F-L1A  I118  R25W67
   1 PD_PEREXT      1 @BASEBOARD_FAB2_LIB.BASEBOARD_FAB2(SCH_1):PD_PEREXT
   2    GND      2 @BASEBOARD_FAB2_LIB.BASEBOARD_FAB2(SCH_1):GND

RES_0402-0.0,5%,1/16W,CHIP,G21A  I119  R6W18
   1 SMB_DEBUG_STBY_LVC3_SDA      A @BASEBOARD_FAB2_LIB.BASEBOARD_FAB2(SCH_1):SMB_DEBUG_STBY_LVC3_SDA
   2 SMB_DEBUG_STBY_LVC3_SDA_R      B @BASEBOARD_FAB2_LIB.BASEBOARD_FAB2(SCH_1):SMB_DEBUG_STBY_LVC3_SDA_R

RES_0402-0.0,5%,1/16W,CHIP,G21A  I120  R6W17
   1 SMB_DEBUG_STBY_LVC3_SCL      A @BASEBOARD_FAB2_LIB.BASEBOARD_FAB2(SCH_1):SMB_DEBUG_STBY_LVC3_SCL
   2 SMB_DEBUG_STBY_LVC3_SCL_R      B @BASEBOARD_FAB2_LIB.BASEBOARD_FAB2(SCH_1):SMB_DEBUG_STBY_LVC3_SCL_R

RES_0402-22.1,1.0%,1/16W,CHIP,A  I136  R2T41
   1 IRQ_FORCE_NM_THROTTLE_N      A @BASEBOARD_FAB2_LIB.BASEBOARD_FAB2(SCH_1):IRQ_FORCE_NM_THROTTLE_N
   2 FM_BMC_SYS_THROTTLE_R_N      B @BASEBOARD_FAB2_LIB.BASEBOARD_FAB2(SCH_1):FM_BMC_SYS_THROTTLE_R_N

CAP_A_0402V-0.1UF,16V,10%,X7R,A  I158  C25W20
   1 P2E_SSB_BMC_RX_DP      A @BASEBOARD_FAB2_LIB.BASEBOARD_FAB2(SCH_1):P2E_SSB_BMC_RX_DP
   2 P2E_SSB_BMC_RX_C_DP      B @BASEBOARD_FAB2_LIB.BASEBOARD_FAB2(SCH_1):P2E_SSB_BMC_RX_C_DP

CAP_A_0402V-0.1UF,16V,10%,X7R,A  I159  C25W21
   1 P2E_SSB_BMC_RX_DN      A @BASEBOARD_FAB2_LIB.BASEBOARD_FAB2(SCH_1):P2E_SSB_BMC_RX_DN
   2 P2E_SSB_BMC_RX_C_DN      B @BASEBOARD_FAB2_LIB.BASEBOARD_FAB2(SCH_1):P2E_SSB_BMC_RX_C_DN

RES_0402-0.0,5%,1/16W,CHIP,G21A  I160  R25W141
   1 RST_PLTRST_BUF_N      A @BASEBOARD_FAB2_LIB.BASEBOARD_FAB2(SCH_1):RST_PLTRST_BUF_N
   2 RST_PLTRST_BUF_N_R      B @BASEBOARD_FAB2_LIB.BASEBOARD_FAB2(SCH_1):RST_PLTRST_BUF_N_R

RES_0402-20.0,1%,1/16W,CHIP,G2A  I163  R25W121
   1 SMB_PEHPCPU0_STBY_LVC3_R_SDA      A @BASEBOARD_FAB2_LIB.BASEBOARD_FAB2(SCH_1):SMB_PEHPCPU0_STBY_LVC3_R_SDA
   2 SMB_PEHPCPU0_STBY_LVC3_R2_SDA      B @BASEBOARD_FAB2_LIB.BASEBOARD_FAB2(SCH_1):SMB_PEHPCPU0_STBY_LVC3_R2_SDA

RES_0402-20.0,1%,1/16W,CHIP,G2A  I164  R25W122
   1 SMB_PEHPCPU0_STBY_LVC3_R_SCL      A @BASEBOARD_FAB2_LIB.BASEBOARD_FAB2(SCH_1):SMB_PEHPCPU0_STBY_LVC3_R_SCL
   2 SMB_PEHPCPU0_STBY_LVC3_R2_SCL      B @BASEBOARD_FAB2_LIB.BASEBOARD_FAB2(SCH_1):SMB_PEHPCPU0_STBY_LVC3_R2_SCL

RES_0402-0.0,5%,1/16W,CHIP,G21A  I173  R25W144
   1 FM_PWR_BTN_R1_N      A @BASEBOARD_FAB2_LIB.BASEBOARD_FAB2(SCH_1):FM_PWR_BTN_R1_N
   2 FM_PWR_BTN_N      B @BASEBOARD_FAB2_LIB.BASEBOARD_FAB2(SCH_1):FM_PWR_BTN_N

RES_0402-0.0,5%,1/16W,CHIP,G21A  I175  R25W145
   1 RST_SYSTEM_BTN_R_N      A @BASEBOARD_FAB2_LIB.BASEBOARD_FAB2(SCH_1):RST_SYSTEM_BTN_R_N
   2 RST_SYSTEM_BTN_N      B @BASEBOARD_FAB2_LIB.BASEBOARD_FAB2(SCH_1):RST_SYSTEM_BTN_N

RES_0402-0.0,5%,1/16W,CHIP,G21A  I176  R2W5
   1 FM_PMBUS_ALERT_BUF_EN_R3_N      A @BASEBOARD_FAB2_LIB.BASEBOARD_FAB2(SCH_1):FM_PMBUS_ALERT_BUF_EN_R3_N
   2 FM_PMBUS_ALERT_BUF_EN_N      B @BASEBOARD_FAB2_LIB.BASEBOARD_FAB2(SCH_1):FM_PMBUS_ALERT_BUF_EN_N


DRAWING: @BASEBOARD_FAB2_LIB.BASEBOARD_FAB2(SCH_1):PAGE146 

RES_0402-0.0,5%,1/16W,CHIP,G21A  I26  R25W83
   1 FM_BMC_NMI_N      A @BASEBOARD_FAB2_LIB.BASEBOARD_FAB2(SCH_1):FM_BMC_NMI_N
   2 FM_BMC_NMI_N_R      B @BASEBOARD_FAB2_LIB.BASEBOARD_FAB2(SCH_1):FM_BMC_NMI_N_R

RES_0402-8.2K,1%,1/16W,CHIP,G2A  I35  R1T25
   1 A_USB2BVRES      A @BASEBOARD_FAB2_LIB.BASEBOARD_FAB2(SCH_1):A_USB2BVRES
   2    GND      B @BASEBOARD_FAB2_LIB.BASEBOARD_FAB2(SCH_1):GND

RES_0402-8.2K,1%,1/16W,CHIP,G2A  I37  R1T26
   1 A_USB2AVRES      A @BASEBOARD_FAB2_LIB.BASEBOARD_FAB2(SCH_1):A_USB2AVRES
   2    GND      B @BASEBOARD_FAB2_LIB.BASEBOARD_FAB2(SCH_1):GND

RES_0402-100.0K,1%,1/16W,CHIP,A  I65  R25W63
   1 FM_PE_BMC_WAKE_N      A @BASEBOARD_FAB2_LIB.BASEBOARD_FAB2(SCH_1):FM_PE_BMC_WAKE_N
   2    GND      B @BASEBOARD_FAB2_LIB.BASEBOARD_FAB2(SCH_1):GND

RES_0402-33.2,1%,1/16W,CHIP,G2A  I67  R25W81
   1 SPI_BMC_BT_CLK      A @BASEBOARD_FAB2_LIB.BASEBOARD_FAB2(SCH_1):SPI_BMC_BT_CLK
   2 SPI_BMC_BT_CLK_R      B @BASEBOARD_FAB2_LIB.BASEBOARD_FAB2(SCH_1):SPI_BMC_BT_CLK_R

RES_0402-33.2,1%,1/16W,CHIP,G2A  I68  R25W82
   1 SPI_BMC_BT_DO      A @BASEBOARD_FAB2_LIB.BASEBOARD_FAB2(SCH_1):SPI_BMC_BT_DO
   2 SPI_BMC_BT_DO_R      B @BASEBOARD_FAB2_LIB.BASEBOARD_FAB2(SCH_1):SPI_BMC_BT_DO_R

RES_0402-0.0,5%,1/16W,CHIP,G21A  I70  R25W74
   1 RST_PLTRST_BUF_N      A @BASEBOARD_FAB2_LIB.BASEBOARD_FAB2(SCH_1):RST_PLTRST_BUF_N
   2 RST_BMC_LVC3_N      B @BASEBOARD_FAB2_LIB.BASEBOARD_FAB2(SCH_1):RST_BMC_LVC3_N

RES_0402-33.2,1%,1/16W,CHIP,G2A  I71  R25W72
   1 LPC_LFRAME_N_CS0_N      A @BASEBOARD_FAB2_LIB.BASEBOARD_FAB2(SCH_1):LPC_LFRAME_N_CS0_N
   2 LPC_LFRAME_N_CS0_R_N      B @BASEBOARD_FAB2_LIB.BASEBOARD_FAB2(SCH_1):LPC_LFRAME_N_CS0_R_N

RES_0402-33.2,1%,1/16W,CHIP,G2A  I73  R25W73
   1 IRQ_LPC_SERIRQ_N      A @BASEBOARD_FAB2_LIB.BASEBOARD_FAB2(SCH_1):IRQ_LPC_SERIRQ_N
   2 IRQ_LPC_SERIRQ_R      B @BASEBOARD_FAB2_LIB.BASEBOARD_FAB2(SCH_1):IRQ_LPC_SERIRQ_R

RES_0402-33.2,1%,1/16W,CHIP,G2A  I74  R3N24
   1 LPC_LAD2_IO2      A @BASEBOARD_FAB2_LIB.BASEBOARD_FAB2(SCH_1):LPC_LAD2_IO2
   2 LPC_LAD2_IO2_R      B @BASEBOARD_FAB2_LIB.BASEBOARD_FAB2(SCH_1):LPC_LAD2_IO2_R

RES_0402-33.2,1%,1/16W,CHIP,G2A  I75  R3N26
   1 LPC_LAD0_IO0      A @BASEBOARD_FAB2_LIB.BASEBOARD_FAB2(SCH_1):LPC_LAD0_IO0
   2 LPC_LAD0_IO0_R      B @BASEBOARD_FAB2_LIB.BASEBOARD_FAB2(SCH_1):LPC_LAD0_IO0_R

RES_0402-100.0K,1%,1/16W,CHIP,A  I76  R25W66
   1 CLK_24M_BMC_LPC      A @BASEBOARD_FAB2_LIB.BASEBOARD_FAB2(SCH_1):CLK_24M_BMC_LPC
   2    GND      B @BASEBOARD_FAB2_LIB.BASEBOARD_FAB2(SCH_1):GND

RES_0402-10.0K,1%,1/16W,CHIP,GA  I78  R1U7
   1    GND      A @BASEBOARD_FAB2_LIB.BASEBOARD_FAB2(SCH_1):GND
   2 PD_SP_ENTEST      B @BASEBOARD_FAB2_LIB.BASEBOARD_FAB2(SCH_1):PD_SP_ENTEST

RES_0402-33.2,1%,1/16W,CHIP,G2A  I84  R25W68
   1 LPC_LAD3_IO3      A @BASEBOARD_FAB2_LIB.BASEBOARD_FAB2(SCH_1):LPC_LAD3_IO3
   2 LPC_LAD3_IO3_R      B @BASEBOARD_FAB2_LIB.BASEBOARD_FAB2(SCH_1):LPC_LAD3_IO3_R

RES_0402-33.2,1%,1/16W,CHIP,G2A  I85  R25W69
   1 LPC_LAD1_IO1      A @BASEBOARD_FAB2_LIB.BASEBOARD_FAB2(SCH_1):LPC_LAD1_IO1
   2 LPC_LAD1_IO1_R      B @BASEBOARD_FAB2_LIB.BASEBOARD_FAB2(SCH_1):LPC_LAD1_IO1_R

AST2520A1-GP-GP_ASIC2-GB1-AST2A  I104  U25W4
  B7 A_USB2BVRES USB2BVRES @BASEBOARD_FAB2_LIB.BASEBOARD_FAB2(SCH_1):A_USB2BVRES
  B8 A_USB2AVRES USB2AVRES @BASEBOARD_FAB2_LIB.BASEBOARD_FAB2(SCH_1):A_USB2AVRES
 A18 LED_POSTCODE_0 GPIOH0_NCTS6 @BASEBOARD_FAB2_LIB.BASEBOARD_FAB2(SCH_1):LED_POSTCODE_0
 D17 LED_POSTCODE_2 GPIOH2_NDSR6 @BASEBOARD_FAB2_LIB.BASEBOARD_FAB2(SCH_1):LED_POSTCODE_2
 B18 LED_POSTCODE_1 GPIOH1_NDCD6 @BASEBOARD_FAB2_LIB.BASEBOARD_FAB2(SCH_1):LED_POSTCODE_1
 A17 LED_POSTCODE_4 GPIOH4_NDTR6 @BASEBOARD_FAB2_LIB.BASEBOARD_FAB2(SCH_1):LED_POSTCODE_4
 C17 LED_POSTCODE_3 GPIOH3_NRI6 @BASEBOARD_FAB2_LIB.BASEBOARD_FAB2(SCH_1):LED_POSTCODE_3
 B17 LED_POSTCODE_5 GPIOH5_NRTS6 @BASEBOARD_FAB2_LIB.BASEBOARD_FAB2(SCH_1):LED_POSTCODE_5
 D18 LED_POSTCODE_7 GPIOH7_RXD6 @BASEBOARD_FAB2_LIB.BASEBOARD_FAB2(SCH_1):LED_POSTCODE_7
 A16 LED_POSTCODE_6 GPIOH6_TXD6 @BASEBOARD_FAB2_LIB.BASEBOARD_FAB2(SCH_1):LED_POSTCODE_6
 V20 FM_THROTTLE_N GPIOS0_VPOB2_SPI2CS1# @BASEBOARD_FAB2_LIB.BASEBOARD_FAB2(SCH_1):FM_THROTTLE_N
 R18 IRQ_SML0_ALERT_N GPIOS2_VPOB4_SALT5 @BASEBOARD_FAB2_LIB.BASEBOARD_FAB2(SCH_1):IRQ_SML0_ALERT_N
AB20 FM_BMC_NMI_N_R GPIOZ1_VPOG3_NORA1_SIOPWRGD @BASEBOARD_FAB2_LIB.BASEBOARD_FAB2(SCH_1):FM_BMC_NMI_N_R
AB21 IRQ_PVDDQ_DEF_VRHOT_LVT3_N GPIOZ2_VPOG4_NORA2_SIOPBO# @BASEBOARD_FAB2_LIB.BASEBOARD_FAB2(SCH_1):IRQ_PVDDQ_DEF_VRHOT_LVT3_N
AA21 IRQ_BMC_PCH_SCI_LPC_N GPIOZ3_VPOG5_NORA3_SIOSCI# @BASEBOARD_FAB2_LIB.BASEBOARD_FAB2(SCH_1):IRQ_BMC_PCH_SCI_LPC_N
 U21 BMC_STRAP_BIT17 GPIOZ4_VPOG6_NORA4 @BASEBOARD_FAB2_LIB.BASEBOARD_FAB2(SCH_1):BMC_STRAP_BIT17
 W22 BMC_STRAP_BIT18 GPIOZ5_VPOG7_NORA5 @BASEBOARD_FAB2_LIB.BASEBOARD_FAB2(SCH_1):BMC_STRAP_BIT18
 V22 BMC_STRAP_BIT20 GPIOZ6_VPOG8_NORA6 @BASEBOARD_FAB2_LIB.BASEBOARD_FAB2(SCH_1):BMC_STRAP_BIT20
 W21 BMC_STRAP_BIT27 GPIOZ7_VPOG9_NORA7 @BASEBOARD_FAB2_LIB.BASEBOARD_FAB2(SCH_1):BMC_STRAP_BIT27
 Y21 FM_CPU1_SKTOCC_LVT3_N GPIOAA0_VPOR2_NORD0_SALT7 @BASEBOARD_FAB2_LIB.BASEBOARD_FAB2(SCH_1):FM_CPU1_SKTOCC_LVT3_N
 P18 HSC_SMBUS_SWITCH_EN GPIOS3_VPOB5_SALT6 @BASEBOARD_FAB2_LIB.BASEBOARD_FAB2(SCH_1):HSC_SMBUS_SWITCH_EN
AA20 GPIOS7 GPIOS7_VPOB9 @BASEBOARD_FAB2_LIB.BASEBOARD_FAB2(SCH_1):GPIOS7
 Y20 FM_BMC_CPLD_GPO GPIOZ0_VPOG2_NORA0_SIOPBI# @BASEBOARD_FAB2_LIB.BASEBOARD_FAB2(SCH_1):FM_BMC_CPLD_GPO
 Y22 FP_PWR_ID_LED_N GPIOAA2_VPOR4_NORD2_SALT9 @BASEBOARD_FAB2_LIB.BASEBOARD_FAB2(SCH_1):FP_PWR_ID_LED_N
  A7 USB_PCH_BMC_P4_DP USB2A_DP @BASEBOARD_FAB2_LIB.BASEBOARD_FAB2(SCH_1):USB_PCH_BMC_P4_DP
  A8 USB_PCH_BMC_P4_DN USB2A_DN @BASEBOARD_FAB2_LIB.BASEBOARD_FAB2(SCH_1):USB_PCH_BMC_P4_DN
  B6 USB2_PCH_BMC_P5_DP USB2B_DP @BASEBOARD_FAB2_LIB.BASEBOARD_FAB2(SCH_1):USB2_PCH_BMC_P5_DP
  A6 USB2_PCH_BMC_P5_DN USB2B_DN @BASEBOARD_FAB2_LIB.BASEBOARD_FAB2(SCH_1):USB2_PCH_BMC_P5_DN
 U20 BMC_STRAP_BIT5 GPIOS6_VPOB8 @BASEBOARD_FAB2_LIB.BASEBOARD_FAB2(SCH_1):BMC_STRAP_BIT5
 W20     NC GPIOS5_VPOB7     NC
 R19 BMC_STRAP_BIT3 GPIOS4_VPOB6 @BASEBOARD_FAB2_LIB.BASEBOARD_FAB2(SCH_1):BMC_STRAP_BIT3
 U19 FM_BMC_READY_N GPIOS1_VPOB3_BMCINT @BASEBOARD_FAB2_LIB.BASEBOARD_FAB2(SCH_1):FM_BMC_READY_N
 V21 IRQ_SML1_PMBUS_ALERT_N GPIOAA1_VPOR3_NORD1_SALT8 @BASEBOARD_FAB2_LIB.BASEBOARD_FAB2(SCH_1):IRQ_SML1_PMBUS_ALERT_N
 P19 FM_BIOS_POST_CMPLT_N GPIOAA7_VPOR9_NORD7_SALT14 @BASEBOARD_FAB2_LIB.BASEBOARD_FAB2(SCH_1):FM_BIOS_POST_CMPLT_N
 N18 IRQ_LOM_ALERT_N GPIOAA6_VPOR8_NORD6_SALT13 @BASEBOARD_FAB2_LIB.BASEBOARD_FAB2(SCH_1):IRQ_LOM_ALERT_N
 T20 UV_HIGH_SET GPIOAA5_VPOR7_NORD5_SALT12 @BASEBOARD_FAB2_LIB.BASEBOARD_FAB2(SCH_1):UV_HIGH_SET
 U22 PECI_SEL GPIOAA4_VPOR6_NORD4_SALT11 @BASEBOARD_FAB2_LIB.BASEBOARD_FAB2(SCH_1):PECI_SEL
AA22 FM_TPM_PRES_N GPIOAA3_VPOR5_NORD3_SALT10 @BASEBOARD_FAB2_LIB.BASEBOARD_FAB2(SCH_1):FM_TPM_PRES_N

AST2520A1-GP-GP_ASIC2-GB1-AST2A  I105  U25W4
 G22 RST_BMC_LVC3_N GPIOAC7_ESPIRST#_LPCRST# @BASEBOARD_FAB2_LIB.BASEBOARD_FAB2(SCH_1):RST_BMC_LVC3_N
  K3 PD_SP_ENTEST ENTEST @BASEBOARD_FAB2_LIB.BASEBOARD_FAB2(SCH_1):PD_SP_ENTEST
 V18 RST_BMC_EXTRST_N EXTRST# @BASEBOARD_FAB2_LIB.BASEBOARD_FAB2(SCH_1):RST_BMC_EXTRST_N
 B10 FM_POST_CARD_PRES_BMC_N GPIOQ6_OSCCLK @BASEBOARD_FAB2_LIB.BASEBOARD_FAB2(SCH_1):FM_POST_CARD_PRES_BMC_N
 N20 FM_PE_BMC_WAKE_N GPIOQ7_PEWAKE# @BASEBOARD_FAB2_LIB.BASEBOARD_FAB2(SCH_1):FM_PE_BMC_WAKE_N
 V19 RST_BMC_PLTRST_BUF_N GPIOR5_SPI2MISO @BASEBOARD_FAB2_LIB.BASEBOARD_FAB2(SCH_1):RST_BMC_PLTRST_BUF_N
 T17 BMC_TCK_MUX_SEL GPIOR2_SPI2CS0# @BASEBOARD_FAB2_LIB.BASEBOARD_FAB2(SCH_1):BMC_TCK_MUX_SEL
 T19 FM_MP_PS_REDUNDANT_LOST_N GPIOR1_FWSPICS2# @BASEBOARD_FAB2_LIB.BASEBOARD_FAB2(SCH_1):FM_MP_PS_REDUNDANT_LOST_N
AA19 SPI_BMC_BT_CS_R_N GPIOR0_FWSPICS1# @BASEBOARD_FAB2_LIB.BASEBOARD_FAB2(SCH_1):SPI_BMC_BT_CS_R_N
AB17 BMC_M_RST_N MRESET# @BASEBOARD_FAB2_LIB.BASEBOARD_FAB2(SCH_1):BMC_M_RST_N
 U16 BMC_M_MALERT_N MALERT# @BASEBOARD_FAB2_LIB.BASEBOARD_FAB2(SCH_1):BMC_M_MALERT_N
 Y18 FM_BMC_HEARTBEAT_N HBLED# @BASEBOARD_FAB2_LIB.BASEBOARD_FAB2(SCH_1):FM_BMC_HEARTBEAT_N
  N5 BMC_VGA_HSYNC GPIOJ4_VGAHS @BASEBOARD_FAB2_LIB.BASEBOARD_FAB2(SCH_1):BMC_VGA_HSYNC
 U17 SPI_BMC_BT_DO_R FWSPIMOSI @BASEBOARD_FAB2_LIB.BASEBOARD_FAB2(SCH_1):SPI_BMC_BT_DO_R
AA18 SPI_BMC_BT_CLK_R FWSPICK @BASEBOARD_FAB2_LIB.BASEBOARD_FAB2(SCH_1):SPI_BMC_BT_CLK_R
  T3 I2C_BMC_VGA_DDC_SDA GPIOJ7_DDCDAT @BASEBOARD_FAB2_LIB.BASEBOARD_FAB2(SCH_1):I2C_BMC_VGA_DDC_SDA
  R3 I2C_BMC_VGA_DDC_SCL GPIOJ6_DDCCLK @BASEBOARD_FAB2_LIB.BASEBOARD_FAB2(SCH_1):I2C_BMC_VGA_DDC_SCL
  R4 BMC_VGA_VSYNC GPIOJ5_VGAVS @BASEBOARD_FAB2_LIB.BASEBOARD_FAB2(SCH_1):BMC_VGA_VSYNC
 R20     NC GPIOAB3_VPOCLK_WDTRST2     NC
 T22 BMC_SELF_HW_RST GPIOAB2_VPOVS_WDTRST1 @BASEBOARD_FAB2_LIB.BASEBOARD_FAB2(SCH_1):BMC_SELF_HW_RST
 T21 FM_OCP_MEZZA_PRES GPIOAB1_VPOHS_NORWE# @BASEBOARD_FAB2_LIB.BASEBOARD_FAB2(SCH_1):FM_OCP_MEZZA_PRES
 N19 IRQ_HSC_FAULT_N GPIOAB0_VPODE_NOROE# @BASEBOARD_FAB2_LIB.BASEBOARD_FAB2(SCH_1):IRQ_HSC_FAULT_N
 C22 CLK_24M_BMC_LPC GPIOAC4_ESPICK_LCLK @BASEBOARD_FAB2_LIB.BASEBOARD_FAB2(SCH_1):CLK_24M_BMC_LPC
 E22 LPC_LAD3_IO3_R GPIOAC3_ESPID3_LAD3 @BASEBOARD_FAB2_LIB.BASEBOARD_FAB2(SCH_1):LPC_LAD3_IO3_R
 D22 LPC_LAD2_IO2_R GPIOAC2_ESPID2_LAD2 @BASEBOARD_FAB2_LIB.BASEBOARD_FAB2(SCH_1):LPC_LAD2_IO2_R
 G20 LPC_LAD1_IO1_R GPIOAC1_ESPID1_LAD1 @BASEBOARD_FAB2_LIB.BASEBOARD_FAB2(SCH_1):LPC_LAD1_IO1_R
 G21 LPC_LAD0_IO0_R GPIOAC0_ESPID0_LAD0 @BASEBOARD_FAB2_LIB.BASEBOARD_FAB2(SCH_1):LPC_LAD0_IO0_R
 T18 SPI_BMC_BT_DI FWSPIMISO @BASEBOARD_FAB2_LIB.BASEBOARD_FAB2(SCH_1):SPI_BMC_BT_DI
AB19 SPI_BMC_BT_CS0_N FWSPICS0# @BASEBOARD_FAB2_LIB.BASEBOARD_FAB2(SCH_1):SPI_BMC_BT_CS0_N
 F22 IRQ_LPC_SERIRQ_R GPIOAC6_ESPIALT#_LSIRQ# @BASEBOARD_FAB2_LIB.BASEBOARD_FAB2(SCH_1):IRQ_LPC_SERIRQ_R
 F21 LPC_LFRAME_N_CS0_R_N GPIOAC5_ESPICS#_LFRAME# @BASEBOARD_FAB2_LIB.BASEBOARD_FAB2(SCH_1):LPC_LFRAME_N_CS0_R_N
 Y19 BMC_PRDY_N GPIOR3_SPI2CK @BASEBOARD_FAB2_LIB.BASEBOARD_FAB2(SCH_1):BMC_PRDY_N
 W19 XDP_PRESENT_N GPIOR4_SPI2MOSI @BASEBOARD_FAB2_LIB.BASEBOARD_FAB2(SCH_1):XDP_PRESENT_N

RES_0402-22.1,1.0%,1/16W,CHIP,A  I123  R25W78
   1 SPI_BMC_BT_CS_R_N      A @BASEBOARD_FAB2_LIB.BASEBOARD_FAB2(SCH_1):SPI_BMC_BT_CS_R_N
   2 SPI_BMC_BT_CS_N      B @BASEBOARD_FAB2_LIB.BASEBOARD_FAB2(SCH_1):SPI_BMC_BT_CS_N

RES_0402-4.75K,1%,1/16W,CHIP,GA  I152  R25W129
   1   P3V3      A @BASEBOARD_FAB2_LIB.BASEBOARD_FAB2(SCH_1):P3V3
   2 I2C_BMC_VGA_DDC_SCL      B @BASEBOARD_FAB2_LIB.BASEBOARD_FAB2(SCH_1):I2C_BMC_VGA_DDC_SCL

RES_0402-4.75K,1%,1/16W,CHIP,GA  I153  R25W130
   1   P3V3      A @BASEBOARD_FAB2_LIB.BASEBOARD_FAB2(SCH_1):P3V3
   2 I2C_BMC_VGA_DDC_SDA      B @BASEBOARD_FAB2_LIB.BASEBOARD_FAB2(SCH_1):I2C_BMC_VGA_DDC_SDA

CAP_0603LF-0.033UF,50V,10%,X7RA  I160  C1W21
   1 A_USB2AVRES      A @BASEBOARD_FAB2_LIB.BASEBOARD_FAB2(SCH_1):A_USB2AVRES
   2    GND      B @BASEBOARD_FAB2_LIB.BASEBOARD_FAB2(SCH_1):GND

RES_0402-0.0,5%,1/16W,CHIP,G21A  I166  R25W184
   1 RST_BMC_PLTRST_BUF_N      A @BASEBOARD_FAB2_LIB.BASEBOARD_FAB2(SCH_1):RST_BMC_PLTRST_BUF_N
   2 RST_PLTRST_BUF_N      B @BASEBOARD_FAB2_LIB.BASEBOARD_FAB2(SCH_1):RST_PLTRST_BUF_N


DRAWING: @BASEBOARD_FAB2_LIB.BASEBOARD_FAB2(SCH_1):PAGE147 

RES_0402-22.1,1.0%,1/16W,CHIP,A  I21  R25W90
   1 RMII_BMC_PCH_SPRNGVLLE_TXD1_R      A @BASEBOARD_FAB2_LIB.BASEBOARD_FAB2(SCH_1):RMII_BMC_PCH_SPRNGVLLE_TXD1_R
   2 RMII_BMC_PCH_SPRNGVLLE_TXD1      B @BASEBOARD_FAB2_LIB.BASEBOARD_FAB2(SCH_1):RMII_BMC_PCH_SPRNGVLLE_TXD1

RES_0402-100.0K,1%,1/16W,CHIP,A  I62  R1U2
   1 FAN_TACH2      A @BASEBOARD_FAB2_LIB.BASEBOARD_FAB2(SCH_1):FAN_TACH2
   2    GND      B @BASEBOARD_FAB2_LIB.BASEBOARD_FAB2(SCH_1):GND

RES_0402-22.1,1.0%,1/16W,CHIP,A  I8  R25W88
   1 RMII_BMC_SPRNGVLLE_TXEN_R      A @BASEBOARD_FAB2_LIB.BASEBOARD_FAB2(SCH_1):RMII_BMC_SPRNGVLLE_TXEN_R
   2 RMII_BMC_PCH_SPRNGVLLE_TXEN      B @BASEBOARD_FAB2_LIB.BASEBOARD_FAB2(SCH_1):RMII_BMC_PCH_SPRNGVLLE_TXEN

RES_0402-22.1,1.0%,1/16W,CHIP,A  I22  R25W89
   1 RMII_BMC_PCH_SPRNGVLLE_TXD0_R      A @BASEBOARD_FAB2_LIB.BASEBOARD_FAB2(SCH_1):RMII_BMC_PCH_SPRNGVLLE_TXD0_R
   2 RMII_BMC_PCH_SPRNGVLLE_TXD0      B @BASEBOARD_FAB2_LIB.BASEBOARD_FAB2(SCH_1):RMII_BMC_PCH_SPRNGVLLE_TXD0

RES_0402-22.1,1.0%,1/16W,CHIP,A  I23  R25W85
   1 RMII_BMC_OCP_TXEN_R      A @BASEBOARD_FAB2_LIB.BASEBOARD_FAB2(SCH_1):RMII_BMC_OCP_TXEN_R
   2 RMII_BMC_OCP_TXEN      B @BASEBOARD_FAB2_LIB.BASEBOARD_FAB2(SCH_1):RMII_BMC_OCP_TXEN

RES_0402-22.1,1.0%,1/16W,CHIP,A  I24  R25W86
   1 RMII_BMC_OCP_TXD0_R      A @BASEBOARD_FAB2_LIB.BASEBOARD_FAB2(SCH_1):RMII_BMC_OCP_TXD0_R
   2 RMII_BMC_OCP_TXD0      B @BASEBOARD_FAB2_LIB.BASEBOARD_FAB2(SCH_1):RMII_BMC_OCP_TXD0

RES_0402-22.1,1.0%,1/16W,CHIP,A  I25  R25W87
   1 RMII_BMC_OCP_TXD1_R      A @BASEBOARD_FAB2_LIB.BASEBOARD_FAB2(SCH_1):RMII_BMC_OCP_TXD1_R
   2 RMII_BMC_OCP_TXD1      B @BASEBOARD_FAB2_LIB.BASEBOARD_FAB2(SCH_1):RMII_BMC_OCP_TXD1

RES_0402-10.0K,1%,1/16W,CHIP,GA  I42  R25W79
   1 P3V3_STBY      A @BASEBOARD_FAB2_LIB.BASEBOARD_FAB2(SCH_1):P3V3_STBY
   2 RMII_SPRNGVLLE_BMC_PCH_RXD0      B @BASEBOARD_FAB2_LIB.BASEBOARD_FAB2(SCH_1):RMII_SPRNGVLLE_BMC_PCH_RXD0

RES_0402-10.0K,1%,1/16W,CHIP,GA  I43  R25W80
   1 P3V3_STBY      A @BASEBOARD_FAB2_LIB.BASEBOARD_FAB2(SCH_1):P3V3_STBY
   2 RMII_SPRNGVLLE_BMC_PCH_RXD1      B @BASEBOARD_FAB2_LIB.BASEBOARD_FAB2(SCH_1):RMII_SPRNGVLLE_BMC_PCH_RXD1

RES_0402-100.0K,1%,1/16W,CHIP,A  I65  R1U4
   1 FAN_TACH1      A @BASEBOARD_FAB2_LIB.BASEBOARD_FAB2(SCH_1):FAN_TACH1
   2    GND      B @BASEBOARD_FAB2_LIB.BASEBOARD_FAB2(SCH_1):GND

RES_0402-100.0K,1%,1/16W,CHIP,A  I66  R1U5
   1 FAN_TACH0      A @BASEBOARD_FAB2_LIB.BASEBOARD_FAB2(SCH_1):FAN_TACH0
   2    GND      B @BASEBOARD_FAB2_LIB.BASEBOARD_FAB2(SCH_1):GND

RES_0402-100.0K,1%,1/16W,CHIP,A  I61  R1U1
   1 FAN_TACH3      A @BASEBOARD_FAB2_LIB.BASEBOARD_FAB2(SCH_1):FAN_TACH3
   2    GND      B @BASEBOARD_FAB2_LIB.BASEBOARD_FAB2(SCH_1):GND

RES_0402-10.0K,1%,1/16W,CHIP,GA  I75  R2N13
   1 FM_BIOS_PREFRB2_GOOD      A @BASEBOARD_FAB2_LIB.BASEBOARD_FAB2(SCH_1):FM_BIOS_PREFRB2_GOOD
   2    GND      B @BASEBOARD_FAB2_LIB.BASEBOARD_FAB2(SCH_1):GND

AST2520A1-GP-GP_ASIC2-GB1-AST2A  I106  U25W4
  F2    GND ADC8_GPIX0 @BASEBOARD_FAB2_LIB.BASEBOARD_FAB2(SCH_1):GND
  G4 A_P3V_BAT_SCALED ADC7_GPIW7 @BASEBOARD_FAB2_LIB.BASEBOARD_FAB2(SCH_1):A_P3V_BAT_SCALED
 C13 FM_BB_BMC_MP_GPIO GPIOA6_TIMER7_MDC2 @BASEBOARD_FAB2_LIB.BASEBOARD_FAB2(SCH_1):FM_BB_BMC_MP_GPIO
 B13 FM_BMC_CPLD_MP_RST_N GPIOA7_TIMER8_MDIO2 @BASEBOARD_FAB2_LIB.BASEBOARD_FAB2(SCH_1):FM_BMC_CPLD_MP_RST_N
  D3     NC RGMIICK     NC
  Y3 PUMP_PWM_OUT GPION6_PWM6_VPIG6 @BASEBOARD_FAB2_LIB.BASEBOARD_FAB2(SCH_1):PUMP_PWM_OUT
  T4 FM_PWRBRK_N GPION7_PWM7_VPIG7 @BASEBOARD_FAB2_LIB.BASEBOARD_FAB2(SCH_1):FM_PWRBRK_N
  W3 FM_BACKUP_BIOS_SEL_N GPION4_PWM4_VPIG4 @BASEBOARD_FAB2_LIB.BASEBOARD_FAB2(SCH_1):FM_BACKUP_BIOS_SEL_N
 AA3 FM_BIOS_SPI_BMC_CTRL GPION5_PWM5_VPIG5 @BASEBOARD_FAB2_LIB.BASEBOARD_FAB2(SCH_1):FM_BIOS_SPI_BMC_CTRL
  U3 FM_CPU_MSMI_LVT3_N GPION3_PWM3_VPIG3 @BASEBOARD_FAB2_LIB.BASEBOARD_FAB2(SCH_1):FM_CPU_MSMI_LVT3_N
  W2 FAN_PWM_OUT_SYS1 GPION1_PWM1 @BASEBOARD_FAB2_LIB.BASEBOARD_FAB2(SCH_1):FAN_PWM_OUT_SYS1
  V3 FM_BIOS_PREFRB2_GOOD GPION2_PWM2_VPIG2 @BASEBOARD_FAB2_LIB.BASEBOARD_FAB2(SCH_1):FM_BIOS_PREFRB2_GOOD
  V2 FAN_PWM_OUT_SYS0 GPION0_PWM0 @BASEBOARD_FAB2_LIB.BASEBOARD_FAB2(SCH_1):FAN_PWM_OUT_SYS0
  H2 P3V3_STBY_BMC_ADCVREFP ADCVREFP @BASEBOARD_FAB2_LIB.BASEBOARD_FAB2(SCH_1):P3V3_STBY_BMC_ADCVREFP
  J1 PD_ADCREXT ADCREXT @BASEBOARD_FAB2_LIB.BASEBOARD_FAB2(SCH_1):PD_ADCREXT
  H1 P3V3_STBY_BMC_ADCVREFN ADCVREFN @BASEBOARD_FAB2_LIB.BASEBOARD_FAB2(SCH_1):P3V3_STBY_BMC_ADCVREFN
  H3 H_CPU1_MEMGHJ_MEMHOT_LVT3_BMC_N ADC14_GPIX6 @BASEBOARD_FAB2_LIB.BASEBOARD_FAB2(SCH_1):H_CPU1_MEMGHJ_MEMHOT_LVT3_BMC_N
  H4 H_CPU1_MEMKLM_MEMHOT_LVT3_BMC_N ADC15_GPIX7 @BASEBOARD_FAB2_LIB.BASEBOARD_FAB2(SCH_1):H_CPU1_MEMKLM_MEMHOT_LVT3_BMC_N
  G1 H_CPU0_MEMDEF_MEMHOT_LVT3_BMC_N ADC13_GPIX5 @BASEBOARD_FAB2_LIB.BASEBOARD_FAB2(SCH_1):H_CPU0_MEMDEF_MEMHOT_LVT3_BMC_N
  H5 H_CPU0_MEMABC_MEMHOT_LVT3_BMC_N ADC12_GPIX4 @BASEBOARD_FAB2_LIB.BASEBOARD_FAB2(SCH_1):H_CPU0_MEMABC_MEMHOT_LVT3_BMC_N
  F1 FM_GLOBAL_RST_WARN_N_R ADC11_GPIX3 @BASEBOARD_FAB2_LIB.BASEBOARD_FAB2(SCH_1):FM_GLOBAL_RST_WARN_N_R
  G3    GND ADC9_GPIX1 @BASEBOARD_FAB2_LIB.BASEBOARD_FAB2(SCH_1):GND
  G2    GND ADC10_GPIX2 @BASEBOARD_FAB2_LIB.BASEBOARD_FAB2(SCH_1):GND
  G5 A_P5V_STBY_SCALED ADC6_GPIW6 @BASEBOARD_FAB2_LIB.BASEBOARD_FAB2(SCH_1):A_P5V_STBY_SCALED
  F3 A_PVNN_STBY_PCH_SENSOR ADC4_GPIW4 @BASEBOARD_FAB2_LIB.BASEBOARD_FAB2(SCH_1):A_PVNN_STBY_PCH_SENSOR
  E3 A_P3V3_STBY_SCALED ADC5_GPIW5 @BASEBOARD_FAB2_LIB.BASEBOARD_FAB2(SCH_1):A_P3V3_STBY_SCALED
  E1 A_P1V05_STBY_PCH_SENSOR ADC3_GPIW3 @BASEBOARD_FAB2_LIB.BASEBOARD_FAB2(SCH_1):A_P1V05_STBY_PCH_SENSOR
  E2 A_P12V_STBY_SCALED ADC2_GPIW2 @BASEBOARD_FAB2_LIB.BASEBOARD_FAB2(SCH_1):A_P12V_STBY_SCALED
  F5 A_P5V_SCALED ADC1_GPIW1 @BASEBOARD_FAB2_LIB.BASEBOARD_FAB2(SCH_1):A_P5V_SCALED
  F4 A_P3V3_SCALED ADC0_GPIW0 @BASEBOARD_FAB2_LIB.BASEBOARD_FAB2(SCH_1):A_P3V3_SCALED
  V6 BMC_RSMRST_B_N GPIOP7_TACH15 @BASEBOARD_FAB2_LIB.BASEBOARD_FAB2(SCH_1):BMC_RSMRST_B_N
  W6 BMC_PWR_DEBUG_N GPIOP6_TACH14 @BASEBOARD_FAB2_LIB.BASEBOARD_FAB2(SCH_1):BMC_PWR_DEBUG_N
 AB5 FM_BOARD_SKU_ID3 GPIOP3_TACH11_VPIR9 @BASEBOARD_FAB2_LIB.BASEBOARD_FAB2(SCH_1):FM_BOARD_SKU_ID3
  Y6 FM_BOARD_SKU_ID4 GPIOP4_TACH12 @BASEBOARD_FAB2_LIB.BASEBOARD_FAB2(SCH_1):FM_BOARD_SKU_ID4
  Y5 BMC_PREQ_N GPIOP5_TACH13 @BASEBOARD_FAB2_LIB.BASEBOARD_FAB2(SCH_1):BMC_PREQ_N
 AA5 FM_BOARD_SKU_ID2 GPIOP2_TACH10_VPIR8 @BASEBOARD_FAB2_LIB.BASEBOARD_FAB2(SCH_1):FM_BOARD_SKU_ID2
  W5 FM_BOARD_SKU_ID1 GPIOP1_TACH9_VPIR7 @BASEBOARD_FAB2_LIB.BASEBOARD_FAB2(SCH_1):FM_BOARD_SKU_ID1
 AA4 FM_XRC_PRESENT_N GPIOO6_TACH6_VPIR4 @BASEBOARD_FAB2_LIB.BASEBOARD_FAB2(SCH_1):FM_XRC_PRESENT_N
  W4 FM_XRC_READY_N GPIOO7_TACH7_VPIR5 @BASEBOARD_FAB2_LIB.BASEBOARD_FAB2(SCH_1):FM_XRC_READY_N
  V4 FM_BOARD_SKU_ID0 GPIOP0_TACH8_VPIR6 @BASEBOARD_FAB2_LIB.BASEBOARD_FAB2(SCH_1):FM_BOARD_SKU_ID0
 AB3 PUMP_TACH0 GPIOO4_TACH4_VPIR2 @BASEBOARD_FAB2_LIB.BASEBOARD_FAB2(SCH_1):PUMP_TACH0
  Y4 PUMP_TACH1 GPIOO5_TACH5_VPIR3 @BASEBOARD_FAB2_LIB.BASEBOARD_FAB2(SCH_1):PUMP_TACH1
 AB4 FAN_TACH3 GPIOO3_TACH3 @BASEBOARD_FAB2_LIB.BASEBOARD_FAB2(SCH_1):FAN_TACH3
  U4 FAN_TACH1 GPIOO1_TACH1_VPIG9 @BASEBOARD_FAB2_LIB.BASEBOARD_FAB2(SCH_1):FAN_TACH1
  V5 FAN_TACH2 GPIOO2_TACH2 @BASEBOARD_FAB2_LIB.BASEBOARD_FAB2(SCH_1):FAN_TACH2
  U5 FAN_TACH0 GPIOO0_TACH0_VPIG8 @BASEBOARD_FAB2_LIB.BASEBOARD_FAB2(SCH_1):FAN_TACH0
  B1 RMII_BMC_SPRNGVLLE_TXEN_R RGMII2TXCTL_RMII2TXEN_GPIOT7 @BASEBOARD_FAB2_LIB.BASEBOARD_FAB2(SCH_1):RMII_BMC_SPRNGVLLE_TXEN_R
  B2     NC RGMII2TXCK_RMII2RCLKO_GPIOT6     NC
  D5 TP_RGMII2TXD2_GPIOU2 RGMII2TXD2_GPIOU2 @BASEBOARD_FAB2_LIB.BASEBOARD_FAB2(SCH_1):TP_RGMII2TXD2_GPIOU2
  D4 TP_RGMII2TXD3_GPIOU3 RGMII2TXD3_GPIOU3 @BASEBOARD_FAB2_LIB.BASEBOARD_FAB2(SCH_1):TP_RGMII2TXD3_GPIOU3
  B3 RMII_BMC_PCH_SPRNGVLLE_TXD1_R RGMII2TXD1_RMII2TXD1_GPIOU1 @BASEBOARD_FAB2_LIB.BASEBOARD_FAB2(SCH_1):RMII_BMC_PCH_SPRNGVLLE_TXD1_R
  A2 RMII_BMC_PCH_SPRNGVLLE_TXD0_R RGMII2TXD0_RMII2TXD0_GPIOU0 @BASEBOARD_FAB2_LIB.BASEBOARD_FAB2(SCH_1):RMII_BMC_PCH_SPRNGVLLE_TXD0_R
  B5     NC RGMII1TXCK_RMII1RCLKO_GPIOT0     NC
  E9 RMII_BMC_OCP_TXEN_R RGMII1TXCTL_RMII1TXEN_GPIOT1 @BASEBOARD_FAB2_LIB.BASEBOARD_FAB2(SCH_1):RMII_BMC_OCP_TXEN_R
  E7 TP_RGMII1TXD2_GPIOT4 RGMII1TXD2_GPIOT4 @BASEBOARD_FAB2_LIB.BASEBOARD_FAB2(SCH_1):TP_RGMII1TXD2_GPIOT4
  D7 TP_RGMII1TXD3_GPIOT5 RGMII1TXD3_GPIOT5 @BASEBOARD_FAB2_LIB.BASEBOARD_FAB2(SCH_1):TP_RGMII1TXD3_GPIOT5
  F9 RMII_BMC_OCP_TXD0_R RGMII1TXD0_RMII1TXD0_GPIOT2 @BASEBOARD_FAB2_LIB.BASEBOARD_FAB2(SCH_1):RMII_BMC_OCP_TXD0_R
  A5 RMII_BMC_OCP_TXD1_R RGMII1TXD1_RMII1TXD1_GPIOT3 @BASEBOARD_FAB2_LIB.BASEBOARD_FAB2(SCH_1):RMII_BMC_OCP_TXD1_R
  C1 FM_FAST_PROCHOT_EN_N RGMII2RXCTL_GPIOV3 @BASEBOARD_FAB2_LIB.BASEBOARD_FAB2(SCH_1):FM_FAST_PROCHOT_EN_N
  D8 FM_SLT_CFG0 GPIOR6_MDC1 @BASEBOARD_FAB2_LIB.BASEBOARD_FAB2(SCH_1):FM_SLT_CFG0
 E10 FM_SLT_CFG1 GPIOR7_MDIO1 @BASEBOARD_FAB2_LIB.BASEBOARD_FAB2(SCH_1):FM_SLT_CFG1
  A3 RMII_BMC_OCP_RXD0 RGMII1RXD0_RMII1RXD0_GPIOU6 @BASEBOARD_FAB2_LIB.BASEBOARD_FAB2(SCH_1):RMII_BMC_OCP_RXD0
  D6 RMII_BMC_OCP_RXD1 RGMII1RXD1_RMII1RXD1_GPIOU7 @BASEBOARD_FAB2_LIB.BASEBOARD_FAB2(SCH_1):RMII_BMC_OCP_RXD1
  C5 RMII_BMC_OCP_CRSDV RGMII1RXD2_RMII1CRSDV_GPIOV0 @BASEBOARD_FAB2_LIB.BASEBOARD_FAB2(SCH_1):RMII_BMC_OCP_CRSDV
  C4 RMII_BMC_OCP_RXER RGMII1RXD3_RMII1RXER_GPIOV1 @BASEBOARD_FAB2_LIB.BASEBOARD_FAB2(SCH_1):RMII_BMC_OCP_RXER
  A4 FM_BMC_FAULT_LED_N RGMII1RXCTL_GPIOU5 @BASEBOARD_FAB2_LIB.BASEBOARD_FAB2(SCH_1):FM_BMC_FAULT_LED_N
  B4 CLK_50M_CKMNG_BMC_1 RGMII1RXCK_RMII1RCLKI_GPIOU4 @BASEBOARD_FAB2_LIB.BASEBOARD_FAB2(SCH_1):CLK_50M_CKMNG_BMC_1
  C3 RMII_SPRNGVLLE_BMC_PCH_RXD0 RGMII2RXD0_RMII2RXD0_GPIOV4 @BASEBOARD_FAB2_LIB.BASEBOARD_FAB2(SCH_1):RMII_SPRNGVLLE_BMC_PCH_RXD0
  D1 RMII_SPRNGVLLE_BMC_PCH_RXD1 RGMII2RXD1_RMII2RXD1_GPIOV5 @BASEBOARD_FAB2_LIB.BASEBOARD_FAB2(SCH_1):RMII_SPRNGVLLE_BMC_PCH_RXD1
  D2 RMII_BMC_PCH_SPRNGVLLE_CRSDV RGMII2RXD2_RMII2CRSDV_GPIOV6 @BASEBOARD_FAB2_LIB.BASEBOARD_FAB2(SCH_1):RMII_BMC_PCH_SPRNGVLLE_CRSDV
  E6 RMII_BMC_PCH_SPRNGVLLE_RXER RGMII2RXD3_RMII2RXER_GPIOV7 @BASEBOARD_FAB2_LIB.BASEBOARD_FAB2(SCH_1):RMII_BMC_PCH_SPRNGVLLE_RXER
  C2 CLK_50M_CKMNG_BMC_2 RGMII2RXCK_RMII2RCLKI_GPIOV2 @BASEBOARD_FAB2_LIB.BASEBOARD_FAB2(SCH_1):CLK_50M_CKMNG_BMC_2

RES_0402-0.0,5%,1/16W,EMPTY,G2A  I129  R1T24
   1 PUMP_TACH0      A @BASEBOARD_FAB2_LIB.BASEBOARD_FAB2(SCH_1):PUMP_TACH0
   2 FM_FLASH_DESC_OVERRIDE      B @BASEBOARD_FAB2_LIB.BASEBOARD_FAB2(SCH_1):FM_FLASH_DESC_OVERRIDE

RES_0402-49.9K,1%,1/16W,CHIP,GA  I151  R25W57
   1 PD_ADCREXT      A @BASEBOARD_FAB2_LIB.BASEBOARD_FAB2(SCH_1):PD_ADCREXT
   2    GND      B @BASEBOARD_FAB2_LIB.BASEBOARD_FAB2(SCH_1):GND

RES_0402-100.0K,1%,1/16W,CHIP,A  I156  R25W142
   1 PUMP_TACH1      A @BASEBOARD_FAB2_LIB.BASEBOARD_FAB2(SCH_1):PUMP_TACH1
   2    GND      B @BASEBOARD_FAB2_LIB.BASEBOARD_FAB2(SCH_1):GND

RES_0402-0.0,5%,1/16W,CHIP,G21A  I159  R25W143
   1 FM_GLOBAL_RST_WARN_N_R      A @BASEBOARD_FAB2_LIB.BASEBOARD_FAB2(SCH_1):FM_GLOBAL_RST_WARN_N_R
   2 FM_GLOBAL_RST_WARN_N      B @BASEBOARD_FAB2_LIB.BASEBOARD_FAB2(SCH_1):FM_GLOBAL_RST_WARN_N

CAP_A_0402V-0.1UF,16V,10%,X7R,A  I160  C25W9
   1 P3V3_STBY_BMC_ADCVREFP      A @BASEBOARD_FAB2_LIB.BASEBOARD_FAB2(SCH_1):P3V3_STBY_BMC_ADCVREFP
   2 P3V3_STBY_BMC_ADCVREFN      B @BASEBOARD_FAB2_LIB.BASEBOARD_FAB2(SCH_1):P3V3_STBY_BMC_ADCVREFN

CAP_A_0402V-0.1UF,16V,10%,X7R,A  I161  C25W7
   1 P3V3_STBY_BMC_ADCVREFP      A @BASEBOARD_FAB2_LIB.BASEBOARD_FAB2(SCH_1):P3V3_STBY_BMC_ADCVREFP
   2 VCC_ADCAV3V3      B @BASEBOARD_FAB2_LIB.BASEBOARD_FAB2(SCH_1):VCC_ADCAV3V3

CAP_A_0402V-0.1UF,16V,10%,X7R,A  I162  C25W8
   1 P3V3_STBY_BMC_ADCVREFN      A @BASEBOARD_FAB2_LIB.BASEBOARD_FAB2(SCH_1):P3V3_STBY_BMC_ADCVREFN
   2    GND      B @BASEBOARD_FAB2_LIB.BASEBOARD_FAB2(SCH_1):GND

RES_0402-100.0K,1%,1/16W,CHIP,A  I164  R25W157
   1 PUMP_TACH0      A @BASEBOARD_FAB2_LIB.BASEBOARD_FAB2(SCH_1):PUMP_TACH0
   2    GND      B @BASEBOARD_FAB2_LIB.BASEBOARD_FAB2(SCH_1):GND

RES_0402-0.0,5%,1/16W,CHIP,G21A  I173  R25W181
   1 RST_RSMRST_N      A @BASEBOARD_FAB2_LIB.BASEBOARD_FAB2(SCH_1):RST_RSMRST_N
   2 BMC_RSMRST_B_N      B @BASEBOARD_FAB2_LIB.BASEBOARD_FAB2(SCH_1):BMC_RSMRST_B_N


DRAWING: @BASEBOARD_FAB2_LIB.BASEBOARD_FAB2(SCH_1):PAGE148 

RES_0402-0.0,5%,1/16W,CHIP,G21A  I16  R25W59
   1 P3V3_STBY      A @BASEBOARD_FAB2_LIB.BASEBOARD_FAB2(SCH_1):P3V3_STBY
   2 VCCBAT_TW12      B @BASEBOARD_FAB2_LIB.BASEBOARD_FAB2(SCH_1):VCCBAT_TW12

CAP_A_0402V-1.0UF,6.3V,10%,X6SA  I20  C1T21
   1 PVCCIO_CPU0      A @BASEBOARD_FAB2_LIB.BASEBOARD_FAB2(SCH_1):PVCCIO_CPU0
   2    GND      B @BASEBOARD_FAB2_LIB.BASEBOARD_FAB2(SCH_1):GND

AST2520A1-GP-GP_ASIC2-GB1-AST2A  I28  U25W4
 K17 P3V3_STBY LPVDD1 @BASEBOARD_FAB2_LIB.BASEBOARD_FAB2(SCH_1):P3V3_STBY
 J17 P3V3_STBY LPVDD0 @BASEBOARD_FAB2_LIB.BASEBOARD_FAB2(SCH_1):P3V3_STBY
  E5    GND  GND68 @BASEBOARD_FAB2_LIB.BASEBOARD_FAB2(SCH_1):GND
  K6 VCC_DACAV3V3 DACAV33 @BASEBOARD_FAB2_LIB.BASEBOARD_FAB2(SCH_1):VCC_DACAV3V3
 F12 VCC_D_3V3 PV33D0 @BASEBOARD_FAB2_LIB.BASEBOARD_FAB2(SCH_1):VCC_D_3V3
  T8 P1V2_AUX_BMC  MVDD4 @BASEBOARD_FAB2_LIB.BASEBOARD_FAB2(SCH_1):P1V2_AUX_BMC
 P22 BMC_JTAG_SEL_N GPIOY2_SIOPWREQ# @BASEBOARD_FAB2_LIB.BASEBOARD_FAB2(SCH_1):BMC_JTAG_SEL_N
 R21 FM_SLPS4_N GPIOY1_SIOS5# @BASEBOARD_FAB2_LIB.BASEBOARD_FAB2(SCH_1):FM_SLPS4_N
 R22 FM_SLPS3_N GPIOY0_SIOS3# @BASEBOARD_FAB2_LIB.BASEBOARD_FAB2(SCH_1):FM_SLPS3_N
  F6 P1V15_AUX_BMC IV11D0 @BASEBOARD_FAB2_LIB.BASEBOARD_FAB2(SCH_1):P1V15_AUX_BMC
 G10 P1V15_AUX_BMC IV11D1 @BASEBOARD_FAB2_LIB.BASEBOARD_FAB2(SCH_1):P1V15_AUX_BMC
 G11 P1V15_AUX_BMC IV11D2 @BASEBOARD_FAB2_LIB.BASEBOARD_FAB2(SCH_1):P1V15_AUX_BMC
 G12 P1V15_AUX_BMC IV11D3 @BASEBOARD_FAB2_LIB.BASEBOARD_FAB2(SCH_1):P1V15_AUX_BMC
 G13 P1V15_AUX_BMC IV11D4 @BASEBOARD_FAB2_LIB.BASEBOARD_FAB2(SCH_1):P1V15_AUX_BMC
 G14 P1V15_AUX_BMC IV11D5 @BASEBOARD_FAB2_LIB.BASEBOARD_FAB2(SCH_1):P1V15_AUX_BMC
 G15 P1V15_AUX_BMC IV11D6 @BASEBOARD_FAB2_LIB.BASEBOARD_FAB2(SCH_1):P1V15_AUX_BMC
  G7 P1V15_AUX_BMC IV11D7 @BASEBOARD_FAB2_LIB.BASEBOARD_FAB2(SCH_1):P1V15_AUX_BMC
  G8 P1V15_AUX_BMC IV11D8 @BASEBOARD_FAB2_LIB.BASEBOARD_FAB2(SCH_1):P1V15_AUX_BMC
  G9 P1V15_AUX_BMC IV11D9 @BASEBOARD_FAB2_LIB.BASEBOARD_FAB2(SCH_1):P1V15_AUX_BMC
 H16 P1V15_AUX_BMC IV11D10 @BASEBOARD_FAB2_LIB.BASEBOARD_FAB2(SCH_1):P1V15_AUX_BMC
 J16 P1V15_AUX_BMC IV11D11 @BASEBOARD_FAB2_LIB.BASEBOARD_FAB2(SCH_1):P1V15_AUX_BMC
  L7 P1V15_AUX_BMC IV11D12 @BASEBOARD_FAB2_LIB.BASEBOARD_FAB2(SCH_1):P1V15_AUX_BMC
 N16 P1V15_AUX_BMC IV11D13 @BASEBOARD_FAB2_LIB.BASEBOARD_FAB2(SCH_1):P1V15_AUX_BMC
  N7 P1V15_AUX_BMC IV11D14 @BASEBOARD_FAB2_LIB.BASEBOARD_FAB2(SCH_1):P1V15_AUX_BMC
 P10 P1V15_AUX_BMC IV11D15 @BASEBOARD_FAB2_LIB.BASEBOARD_FAB2(SCH_1):P1V15_AUX_BMC
 P11 P1V15_AUX_BMC IV11D16 @BASEBOARD_FAB2_LIB.BASEBOARD_FAB2(SCH_1):P1V15_AUX_BMC
 P12 P1V15_AUX_BMC IV11D17 @BASEBOARD_FAB2_LIB.BASEBOARD_FAB2(SCH_1):P1V15_AUX_BMC
 P13 P1V15_AUX_BMC IV11D18 @BASEBOARD_FAB2_LIB.BASEBOARD_FAB2(SCH_1):P1V15_AUX_BMC
 P14 P1V15_AUX_BMC IV11D19 @BASEBOARD_FAB2_LIB.BASEBOARD_FAB2(SCH_1):P1V15_AUX_BMC
 P16 P1V15_AUX_BMC IV11D20 @BASEBOARD_FAB2_LIB.BASEBOARD_FAB2(SCH_1):P1V15_AUX_BMC
  P7 P1V15_AUX_BMC IV11D21 @BASEBOARD_FAB2_LIB.BASEBOARD_FAB2(SCH_1):P1V15_AUX_BMC
  P9 P1V15_AUX_BMC IV11D22 @BASEBOARD_FAB2_LIB.BASEBOARD_FAB2(SCH_1):P1V15_AUX_BMC
 R16 P1V15_AUX_BMC IV11D23 @BASEBOARD_FAB2_LIB.BASEBOARD_FAB2(SCH_1):P1V15_AUX_BMC
  R7 P1V15_AUX_BMC IV11D24 @BASEBOARD_FAB2_LIB.BASEBOARD_FAB2(SCH_1):P1V15_AUX_BMC
  L5 VCC_A_1V1 VPLLAV110 @BASEBOARD_FAB2_LIB.BASEBOARD_FAB2(SCH_1):VCC_A_1V1
  L6 VCC_A_1V1 VPLLAV111 @BASEBOARD_FAB2_LIB.BASEBOARD_FAB2(SCH_1):VCC_A_1V1
 L17 P1V15_AUX_BMC PEAV11 @BASEBOARD_FAB2_LIB.BASEBOARD_FAB2(SCH_1):P1V15_AUX_BMC
 V17 P1V15_AUX_BMC PLLDV11 @BASEBOARD_FAB2_LIB.BASEBOARD_FAB2(SCH_1):P1V15_AUX_BMC
AA17 PVCCIO_CPU0_R PECIVDD @BASEBOARD_FAB2_LIB.BASEBOARD_FAB2(SCH_1):PVCCIO_CPU0_R
 T10 P1V2_AUX_BMC  MVDD0 @BASEBOARD_FAB2_LIB.BASEBOARD_FAB2(SCH_1):P1V2_AUX_BMC
 T12 P1V2_AUX_BMC  MVDD1 @BASEBOARD_FAB2_LIB.BASEBOARD_FAB2(SCH_1):P1V2_AUX_BMC
 T13 P1V2_AUX_BMC  MVDD2 @BASEBOARD_FAB2_LIB.BASEBOARD_FAB2(SCH_1):P1V2_AUX_BMC
 T14 P1V2_AUX_BMC  MVDD3 @BASEBOARD_FAB2_LIB.BASEBOARD_FAB2(SCH_1):P1V2_AUX_BMC
 F13 VCC_D_3V3 PV33D1 @BASEBOARD_FAB2_LIB.BASEBOARD_FAB2(SCH_1):VCC_D_3V3
 F14 VCC_D_3V3 PV33D2 @BASEBOARD_FAB2_LIB.BASEBOARD_FAB2(SCH_1):VCC_D_3V3
 F15 VCC_D_3V3 PV33D3 @BASEBOARD_FAB2_LIB.BASEBOARD_FAB2(SCH_1):VCC_D_3V3
 G16 VCC_D_3V3 PV33D4 @BASEBOARD_FAB2_LIB.BASEBOARD_FAB2(SCH_1):VCC_D_3V3
 H17 VCC_D_3V3 PV33D5 @BASEBOARD_FAB2_LIB.BASEBOARD_FAB2(SCH_1):VCC_D_3V3
  K7 VCC_D_3V3 PV33D6 @BASEBOARD_FAB2_LIB.BASEBOARD_FAB2(SCH_1):VCC_D_3V3
 N17 VCC_D_3V3 PV33D7 @BASEBOARD_FAB2_LIB.BASEBOARD_FAB2(SCH_1):VCC_D_3V3
  N6 VCC_D_3V3 PV33D8 @BASEBOARD_FAB2_LIB.BASEBOARD_FAB2(SCH_1):VCC_D_3V3
 P17 VCC_D_3V3 PV33D9 @BASEBOARD_FAB2_LIB.BASEBOARD_FAB2(SCH_1):VCC_D_3V3
  P6 VCC_D_3V3 PV33D10 @BASEBOARD_FAB2_LIB.BASEBOARD_FAB2(SCH_1):VCC_D_3V3
 R17 VCC_D_3V3 PV33D11 @BASEBOARD_FAB2_LIB.BASEBOARD_FAB2(SCH_1):VCC_D_3V3
  R6 VCC_D_3V3 PV33D12 @BASEBOARD_FAB2_LIB.BASEBOARD_FAB2(SCH_1):VCC_D_3V3
 T11 VCC_PA_3V3 PV33D13 @BASEBOARD_FAB2_LIB.BASEBOARD_FAB2(SCH_1):VCC_PA_3V3
 T15 VCC_D_3V3 PV33D14 @BASEBOARD_FAB2_LIB.BASEBOARD_FAB2(SCH_1):VCC_D_3V3
 Y17 VCC_PA_3V3 PLLAV330 @BASEBOARD_FAB2_LIB.BASEBOARD_FAB2(SCH_1):VCC_PA_3V3
 W17 VCC_PA_3V3 PLLAV331 @BASEBOARD_FAB2_LIB.BASEBOARD_FAB2(SCH_1):VCC_PA_3V3
  J7 VCC_VA_3V3 VPLLAV330 @BASEBOARD_FAB2_LIB.BASEBOARD_FAB2(SCH_1):VCC_VA_3V3
  H7 VCC_VA_3V3 VPLLAV331 @BASEBOARD_FAB2_LIB.BASEBOARD_FAB2(SCH_1):VCC_VA_3V3
 L16 VCC_D_3V3 PEAV33 @BASEBOARD_FAB2_LIB.BASEBOARD_FAB2(SCH_1):VCC_D_3V3
  E4 VCCBAT_TW12 BATVDD @BASEBOARD_FAB2_LIB.BASEBOARD_FAB2(SCH_1):VCCBAT_TW12
  C7 P3V3_USB2A_ALG USB2AV33 @BASEBOARD_FAB2_LIB.BASEBOARD_FAB2(SCH_1):P3V3_USB2A_ALG
  K5 VCC_DACAV3V3 DACDV33 @BASEBOARD_FAB2_LIB.BASEBOARD_FAB2(SCH_1):VCC_DACAV3V3
  J6 VCC_ADCAV3V3 ADCAV33 @BASEBOARD_FAB2_LIB.BASEBOARD_FAB2(SCH_1):VCC_ADCAV3V3
  F7 P3V3_STBY R2VDD0 @BASEBOARD_FAB2_LIB.BASEBOARD_FAB2(SCH_1):P3V3_STBY
  F8 P3V3_STBY R2VDD1 @BASEBOARD_FAB2_LIB.BASEBOARD_FAB2(SCH_1):P3V3_STBY
 F10 P3V3_STBY R1VDD0 @BASEBOARD_FAB2_LIB.BASEBOARD_FAB2(SCH_1):P3V3_STBY
 F11 P3V3_STBY R1VDD1 @BASEBOARD_FAB2_LIB.BASEBOARD_FAB2(SCH_1):P3V3_STBY
  V8    GND  GND67 @BASEBOARD_FAB2_LIB.BASEBOARD_FAB2(SCH_1):GND
 V16    GND  GND66 @BASEBOARD_FAB2_LIB.BASEBOARD_FAB2(SCH_1):GND
 V14    GND  GND65 @BASEBOARD_FAB2_LIB.BASEBOARD_FAB2(SCH_1):GND
  T7    GND  GND60 @BASEBOARD_FAB2_LIB.BASEBOARD_FAB2(SCH_1):GND
 U11    GND  GND61 @BASEBOARD_FAB2_LIB.BASEBOARD_FAB2(SCH_1):GND
 V12    GND  GND64 @BASEBOARD_FAB2_LIB.BASEBOARD_FAB2(SCH_1):GND
 V10    GND  GND63 @BASEBOARD_FAB2_LIB.BASEBOARD_FAB2(SCH_1):GND
  U6    GND  GND62 @BASEBOARD_FAB2_LIB.BASEBOARD_FAB2(SCH_1):GND
 N13    GND  GND55 @BASEBOARD_FAB2_LIB.BASEBOARD_FAB2(SCH_1):GND
 N14    GND  GND56 @BASEBOARD_FAB2_LIB.BASEBOARD_FAB2(SCH_1):GND
  T6    GND  GND59 @BASEBOARD_FAB2_LIB.BASEBOARD_FAB2(SCH_1):GND
 T16    GND  GND58 @BASEBOARD_FAB2_LIB.BASEBOARD_FAB2(SCH_1):GND
  N9    GND  GND57 @BASEBOARD_FAB2_LIB.BASEBOARD_FAB2(SCH_1):GND
  M7    GND  GND50 @BASEBOARD_FAB2_LIB.BASEBOARD_FAB2(SCH_1):GND
  M9    GND  GND51 @BASEBOARD_FAB2_LIB.BASEBOARD_FAB2(SCH_1):GND
 N12    GND  GND54 @BASEBOARD_FAB2_LIB.BASEBOARD_FAB2(SCH_1):GND
 N11    GND  GND53 @BASEBOARD_FAB2_LIB.BASEBOARD_FAB2(SCH_1):GND
 N10    GND  GND52 @BASEBOARD_FAB2_LIB.BASEBOARD_FAB2(SCH_1):GND
  M2    GND  GND45 @BASEBOARD_FAB2_LIB.BASEBOARD_FAB2(SCH_1):GND
  M3    GND  GND46 @BASEBOARD_FAB2_LIB.BASEBOARD_FAB2(SCH_1):GND
  M6    GND  GND49 @BASEBOARD_FAB2_LIB.BASEBOARD_FAB2(SCH_1):GND
  M5    GND  GND48 @BASEBOARD_FAB2_LIB.BASEBOARD_FAB2(SCH_1):GND
  M4    GND  GND47 @BASEBOARD_FAB2_LIB.BASEBOARD_FAB2(SCH_1):GND
 M12    GND  GND40 @BASEBOARD_FAB2_LIB.BASEBOARD_FAB2(SCH_1):GND
 M13    GND  GND41 @BASEBOARD_FAB2_LIB.BASEBOARD_FAB2(SCH_1):GND
 M17    GND  GND44 @BASEBOARD_FAB2_LIB.BASEBOARD_FAB2(SCH_1):GND
 M16    GND  GND43 @BASEBOARD_FAB2_LIB.BASEBOARD_FAB2(SCH_1):GND
 M14    GND  GND42 @BASEBOARD_FAB2_LIB.BASEBOARD_FAB2(SCH_1):GND
 L14    GND  GND35 @BASEBOARD_FAB2_LIB.BASEBOARD_FAB2(SCH_1):GND
 M11    GND  GND39 @BASEBOARD_FAB2_LIB.BASEBOARD_FAB2(SCH_1):GND
 M10    GND  GND38 @BASEBOARD_FAB2_LIB.BASEBOARD_FAB2(SCH_1):GND
  M1    GND  GND37 @BASEBOARD_FAB2_LIB.BASEBOARD_FAB2(SCH_1):GND
  L9    GND  GND36 @BASEBOARD_FAB2_LIB.BASEBOARD_FAB2(SCH_1):GND
  K9    GND  GND30 @BASEBOARD_FAB2_LIB.BASEBOARD_FAB2(SCH_1):GND
 L13    GND  GND34 @BASEBOARD_FAB2_LIB.BASEBOARD_FAB2(SCH_1):GND
 L12    GND  GND33 @BASEBOARD_FAB2_LIB.BASEBOARD_FAB2(SCH_1):GND
 L11    GND  GND32 @BASEBOARD_FAB2_LIB.BASEBOARD_FAB2(SCH_1):GND
 L10    GND  GND31 @BASEBOARD_FAB2_LIB.BASEBOARD_FAB2(SCH_1):GND
 K16    GND  GND29 @BASEBOARD_FAB2_LIB.BASEBOARD_FAB2(SCH_1):GND
 K11    GND  GND25 @BASEBOARD_FAB2_LIB.BASEBOARD_FAB2(SCH_1):GND
 K13    GND  GND27 @BASEBOARD_FAB2_LIB.BASEBOARD_FAB2(SCH_1):GND
 K14    GND  GND28 @BASEBOARD_FAB2_LIB.BASEBOARD_FAB2(SCH_1):GND
 K12    GND  GND26 @BASEBOARD_FAB2_LIB.BASEBOARD_FAB2(SCH_1):GND
 K10    GND  GND24 @BASEBOARD_FAB2_LIB.BASEBOARD_FAB2(SCH_1):GND
 J21    GND  GND20 @BASEBOARD_FAB2_LIB.BASEBOARD_FAB2(SCH_1):GND
  J9    GND  GND23 @BASEBOARD_FAB2_LIB.BASEBOARD_FAB2(SCH_1):GND
  J5    GND  GND22 @BASEBOARD_FAB2_LIB.BASEBOARD_FAB2(SCH_1):GND
 J22    GND  GND21 @BASEBOARD_FAB2_LIB.BASEBOARD_FAB2(SCH_1):GND
 J14    GND  GND19 @BASEBOARD_FAB2_LIB.BASEBOARD_FAB2(SCH_1):GND
  H6    GND  GND14 @BASEBOARD_FAB2_LIB.BASEBOARD_FAB2(SCH_1):GND
 J10    GND  GND15 @BASEBOARD_FAB2_LIB.BASEBOARD_FAB2(SCH_1):GND
 J13    GND  GND18 @BASEBOARD_FAB2_LIB.BASEBOARD_FAB2(SCH_1):GND
 J12    GND  GND17 @BASEBOARD_FAB2_LIB.BASEBOARD_FAB2(SCH_1):GND
 J11    GND  GND16 @BASEBOARD_FAB2_LIB.BASEBOARD_FAB2(SCH_1):GND
  C6    GND   GND9 @BASEBOARD_FAB2_LIB.BASEBOARD_FAB2(SCH_1):GND
  E8    GND  GND10 @BASEBOARD_FAB2_LIB.BASEBOARD_FAB2(SCH_1):GND
  G6    GND  GND13 @BASEBOARD_FAB2_LIB.BASEBOARD_FAB2(SCH_1):GND
 G19    GND  GND12 @BASEBOARD_FAB2_LIB.BASEBOARD_FAB2(SCH_1):GND
 F16    GND  GND11 @BASEBOARD_FAB2_LIB.BASEBOARD_FAB2(SCH_1):GND
AA15    GND   GND4 @BASEBOARD_FAB2_LIB.BASEBOARD_FAB2(SCH_1):GND
 AA7    GND   GND5 @BASEBOARD_FAB2_LIB.BASEBOARD_FAB2(SCH_1):GND
 AB1    GND   GND7 @BASEBOARD_FAB2_LIB.BASEBOARD_FAB2(SCH_1):GND
AB22    GND   GND8 @BASEBOARD_FAB2_LIB.BASEBOARD_FAB2(SCH_1):GND
 AA9    GND   GND6 @BASEBOARD_FAB2_LIB.BASEBOARD_FAB2(SCH_1):GND
AA13    GND   GND3 @BASEBOARD_FAB2_LIB.BASEBOARD_FAB2(SCH_1):GND
AA11    GND   GND2 @BASEBOARD_FAB2_LIB.BASEBOARD_FAB2(SCH_1):GND
 A22    GND   GND1 @BASEBOARD_FAB2_LIB.BASEBOARD_FAB2(SCH_1):GND
  A1    GND   GND0 @BASEBOARD_FAB2_LIB.BASEBOARD_FAB2(SCH_1):GND

RES_0402-0.0,5%,1/16W,CHIP,G21A  I29  R25W155
   1 PVCCIO_CPU0      A @BASEBOARD_FAB2_LIB.BASEBOARD_FAB2(SCH_1):PVCCIO_CPU0
   2 PVCCIO_CPU0_R      B @BASEBOARD_FAB2_LIB.BASEBOARD_FAB2(SCH_1):PVCCIO_CPU0_R


DRAWING: @BASEBOARD_FAB2_LIB.BASEBOARD_FAB2(SCH_1):PAGE248 

TTL1G08_SOTLF-NC7SZ08,IC,D1032C  I11  U14E2
   4 RST_PCIE_M2_DEV_IC_N   Y<0> @BASEBOARD_FAB2_LIB.BASEBOARD_FAB2(SCH_1):RST_PCIE_M2_DEV_IC_N
   1 RST_PCIE_M2_DEV_N   A<0> @BASEBOARD_FAB2_LIB.BASEBOARD_FAB2(SCH_1):RST_PCIE_M2_DEV_N
   2 RST_PCIE_M2_DEV_AND   B<0> @BASEBOARD_FAB2_LIB.BASEBOARD_FAB2(SCH_1):RST_PCIE_M2_DEV_AND

CAP_A_0402V-0.1UF,16V,10%,X7R,A  I13  C14W1
   1   P3V3      A @BASEBOARD_FAB2_LIB.BASEBOARD_FAB2(SCH_1):P3V3
   2    GND      B @BASEBOARD_FAB2_LIB.BASEBOARD_FAB2(SCH_1):GND

CAP_A_0402V-0.1UF,16V,10%,X7R,A  I17  C14W2
   1   P3V3      A @BASEBOARD_FAB2_LIB.BASEBOARD_FAB2(SCH_1):P3V3
   2    GND      B @BASEBOARD_FAB2_LIB.BASEBOARD_FAB2(SCH_1):GND

TTL1G08_SOTLF-NC7SZ08,IC,D1032C  I19  U14E3
   4 RST_PCIE_M2_DEV_AND   Y<0> @BASEBOARD_FAB2_LIB.BASEBOARD_FAB2(SCH_1):RST_PCIE_M2_DEV_AND
   1 PWRGD_P12V_HSC_DLY   A<0> @BASEBOARD_FAB2_LIB.BASEBOARD_FAB2(SCH_1):PWRGD_P12V_HSC_DLY
   2 PWRGD_P3V3   B<0> @BASEBOARD_FAB2_LIB.BASEBOARD_FAB2(SCH_1):PWRGD_P3V3

RES_0402-10.0,1%,1/16W,CHIP,G2A  I24  R6W26
   1 SMB_CPU0_PE_HP_GTL_SCL      A @BASEBOARD_FAB2_LIB.BASEBOARD_FAB2(SCH_1):SMB_CPU0_PE_HP_GTL_SCL
   2 SMB_CPU0_PE_HP_GTL_R_SCL      B @BASEBOARD_FAB2_LIB.BASEBOARD_FAB2(SCH_1):SMB_CPU0_PE_HP_GTL_R_SCL

RES_0402-10.0,1%,1/16W,CHIP,G2A  I25  R6W27
   1 SMB_CPU0_PE_HP_GTL_SDA      A @BASEBOARD_FAB2_LIB.BASEBOARD_FAB2(SCH_1):SMB_CPU0_PE_HP_GTL_SDA
   2 SMB_CPU0_PE_HP_GTL_R_SDA      B @BASEBOARD_FAB2_LIB.BASEBOARD_FAB2(SCH_1):SMB_CPU0_PE_HP_GTL_R_SDA

RES_0402-240,1.0%,1/16W,CHIP,GA  I26  R9W19
   1 PVCCIO_CPU0      A @BASEBOARD_FAB2_LIB.BASEBOARD_FAB2(SCH_1):PVCCIO_CPU0
   2 SMB_CPU0_PE_HP_GTL_R_SCL      B @BASEBOARD_FAB2_LIB.BASEBOARD_FAB2(SCH_1):SMB_CPU0_PE_HP_GTL_R_SCL

RES_0402-240,1.0%,1/16W,CHIP,GA  I27  R9W18
   1 PVCCIO_CPU0      A @BASEBOARD_FAB2_LIB.BASEBOARD_FAB2(SCH_1):PVCCIO_CPU0
   2 SMB_CPU0_PE_HP_GTL_R_SDA      B @BASEBOARD_FAB2_LIB.BASEBOARD_FAB2(SCH_1):SMB_CPU0_PE_HP_GTL_R_SDA

CAP_A_0402V-0.1UF,16V,10%,X7R,A  I30  C9W8
   1 PVCCIO_CPU0      A @BASEBOARD_FAB2_LIB.BASEBOARD_FAB2(SCH_1):PVCCIO_CPU0
   2    GND      B @BASEBOARD_FAB2_LIB.BASEBOARD_FAB2(SCH_1):GND

CAP_A_0402V-0.1UF,16V,10%,X7R,A  I32  C9W7
   1 P3V3_STBY      A @BASEBOARD_FAB2_LIB.BASEBOARD_FAB2(SCH_1):P3V3_STBY
   2    GND      B @BASEBOARD_FAB2_LIB.BASEBOARD_FAB2(SCH_1):GND

RES_0402-2.0K,1%,1/16W,CHIP,G2A  I34  R9W16
   1 P3V3_STBY      A @BASEBOARD_FAB2_LIB.BASEBOARD_FAB2(SCH_1):P3V3_STBY
   2 SMB_PEHPCPU0_STBY_LVC3_R_SDA      B @BASEBOARD_FAB2_LIB.BASEBOARD_FAB2(SCH_1):SMB_PEHPCPU0_STBY_LVC3_R_SDA

RES_0402-2.0K,1%,1/16W,CHIP,G2A  I35  R9W17
   1 P3V3_STBY      A @BASEBOARD_FAB2_LIB.BASEBOARD_FAB2(SCH_1):P3V3_STBY
   2 SMB_PEHPCPU0_STBY_LVC3_R_SCL      B @BASEBOARD_FAB2_LIB.BASEBOARD_FAB2(SCH_1):SMB_PEHPCPU0_STBY_LVC3_R_SCL

RES_0402-20.0,1%,1/16W,CHIP,G2A  I37  R9W14
   1 SMB_PEHPCPU0_STBY_LVC3_R_SCL      A @BASEBOARD_FAB2_LIB.BASEBOARD_FAB2(SCH_1):SMB_PEHPCPU0_STBY_LVC3_R_SCL
   2 SMB_PEHPCPU0_STBY_LVC3_SCL      B @BASEBOARD_FAB2_LIB.BASEBOARD_FAB2(SCH_1):SMB_PEHPCPU0_STBY_LVC3_SCL

RES_0402-20.0,1%,1/16W,CHIP,G2A  I38  R9W13
   1 SMB_PEHPCPU0_STBY_LVC3_R_SDA      A @BASEBOARD_FAB2_LIB.BASEBOARD_FAB2(SCH_1):SMB_PEHPCPU0_STBY_LVC3_R_SDA
   2 SMB_PEHPCPU0_STBY_LVC3_SDA      B @BASEBOARD_FAB2_LIB.BASEBOARD_FAB2(SCH_1):SMB_PEHPCPU0_STBY_LVC3_SDA

TCA9517DGKR-GP_DISCRET-G8-TCA9A  I49  U1W2
   1 PVCCIO_CPU0   VCCA @BASEBOARD_FAB2_LIB.BASEBOARD_FAB2(SCH_1):PVCCIO_CPU0
   2 SMB_CPU0_PE_HP_GTL_R_SCL   SCLA @BASEBOARD_FAB2_LIB.BASEBOARD_FAB2(SCH_1):SMB_CPU0_PE_HP_GTL_R_SCL
   3 SMB_CPU0_PE_HP_GTL_R_SDA   SDAA @BASEBOARD_FAB2_LIB.BASEBOARD_FAB2(SCH_1):SMB_CPU0_PE_HP_GTL_R_SDA
   4    GND    GND @BASEBOARD_FAB2_LIB.BASEBOARD_FAB2(SCH_1):GND
   8 P3V3_STBY   VCCB @BASEBOARD_FAB2_LIB.BASEBOARD_FAB2(SCH_1):P3V3_STBY
   7 SMB_PEHPCPU0_STBY_LVC3_R_SCL   SCLB @BASEBOARD_FAB2_LIB.BASEBOARD_FAB2(SCH_1):SMB_PEHPCPU0_STBY_LVC3_R_SCL
   6 SMB_PEHPCPU0_STBY_LVC3_R_SDA   SDAB @BASEBOARD_FAB2_LIB.BASEBOARD_FAB2(SCH_1):SMB_PEHPCPU0_STBY_LVC3_R_SDA
   5 TP_SMB_PEHPCPU0_EN     EN @BASEBOARD_FAB2_LIB.BASEBOARD_FAB2(SCH_1):TP_SMB_PEHPCPU0_EN


DRAWING: @BASEBOARD_FAB2_LIB.BASEBOARD_FAB2(SCH_1):PAGE149 

CAP_0603-4.7UF,6.3V,10%,X6S,E1A  I5  C25W70
   1 P3V3_USB2A_ALG      A @BASEBOARD_FAB2_LIB.BASEBOARD_FAB2(SCH_1):P3V3_USB2A_ALG
   2    GND      B @BASEBOARD_FAB2_LIB.BASEBOARD_FAB2(SCH_1):GND

CAP_0603-4.7UF,6.3V,10%,X6S,E1A  I17  C25W69
   1 VCC_VA_3V3      A @BASEBOARD_FAB2_LIB.BASEBOARD_FAB2(SCH_1):VCC_VA_3V3
   2    GND      B @BASEBOARD_FAB2_LIB.BASEBOARD_FAB2(SCH_1):GND

HCB1608KF-800T30-GP_DISCRET-G9A  I22  FB2T1
   1 P3V3_STBY      1 @BASEBOARD_FAB2_LIB.BASEBOARD_FAB2(SCH_1):P3V3_STBY
   2 VCC_VA_3V3      2 @BASEBOARD_FAB2_LIB.BASEBOARD_FAB2(SCH_1):VCC_VA_3V3

CAP_0603-4.7UF,6.3V,10%,X6S,E1A  I25  C25W39
   1 VCC_A_1V1      A @BASEBOARD_FAB2_LIB.BASEBOARD_FAB2(SCH_1):VCC_A_1V1
   2    GND      B @BASEBOARD_FAB2_LIB.BASEBOARD_FAB2(SCH_1):GND

CAP_0603-4.7UF,6.3V,10%,X6S,E1A  I31  C25W50
   1 P3V3_STBY      A @BASEBOARD_FAB2_LIB.BASEBOARD_FAB2(SCH_1):P3V3_STBY
   2    GND      B @BASEBOARD_FAB2_LIB.BASEBOARD_FAB2(SCH_1):GND

CAP_0603-4.7UF,6.3V,10%,X6S,E1A  I40  C25W62
   1 P3V3_STBY      A @BASEBOARD_FAB2_LIB.BASEBOARD_FAB2(SCH_1):P3V3_STBY
   2    GND      B @BASEBOARD_FAB2_LIB.BASEBOARD_FAB2(SCH_1):GND

HCB1608KF-800T30-GP_DISCRET-G9A  I42  FB2T7
   1 P1V15_AUX_BMC      1 @BASEBOARD_FAB2_LIB.BASEBOARD_FAB2(SCH_1):P1V15_AUX_BMC
   2 VCC_A_1V1      2 @BASEBOARD_FAB2_LIB.BASEBOARD_FAB2(SCH_1):VCC_A_1V1

CAP_0603-4.7UF,6.3V,10%,X6S,E1A  I46  C25W36
   1 VCC_DACAV3V3      A @BASEBOARD_FAB2_LIB.BASEBOARD_FAB2(SCH_1):VCC_DACAV3V3
   2    GND      B @BASEBOARD_FAB2_LIB.BASEBOARD_FAB2(SCH_1):GND

CAP_0603-4.7UF,6.3V,10%,X6S,E1A  I50  C25W47
   1 VCC_D_3V3      A @BASEBOARD_FAB2_LIB.BASEBOARD_FAB2(SCH_1):VCC_D_3V3
   2    GND      B @BASEBOARD_FAB2_LIB.BASEBOARD_FAB2(SCH_1):GND

CAP_0805-10UF,16V,10%,X6S,C953A  I51  C25W46
   1 VCC_D_3V3      A @BASEBOARD_FAB2_LIB.BASEBOARD_FAB2(SCH_1):VCC_D_3V3
   2    GND      B @BASEBOARD_FAB2_LIB.BASEBOARD_FAB2(SCH_1):GND

CAP_0603-4.7UF,6.3V,10%,X6S,E1A  I79  C25W59
   1 VCC_PA_3V3      A @BASEBOARD_FAB2_LIB.BASEBOARD_FAB2(SCH_1):VCC_PA_3V3
   2    GND      B @BASEBOARD_FAB2_LIB.BASEBOARD_FAB2(SCH_1):GND

HCB1608KF-800T30-GP_DISCRET-G9A  I85  FB2T3
   1 P3V3_STBY      1 @BASEBOARD_FAB2_LIB.BASEBOARD_FAB2(SCH_1):P3V3_STBY
   2 VCC_ADCAV3V3      2 @BASEBOARD_FAB2_LIB.BASEBOARD_FAB2(SCH_1):VCC_ADCAV3V3

HCB1608KF-800T30-GP_DISCRET-G9A  I86  FB2T4
   1 P3V3_STBY      1 @BASEBOARD_FAB2_LIB.BASEBOARD_FAB2(SCH_1):P3V3_STBY
   2 VCC_D_3V3      2 @BASEBOARD_FAB2_LIB.BASEBOARD_FAB2(SCH_1):VCC_D_3V3

HCB1608KF-800T30-GP_DISCRET-G9A  I88  FB2T5
   1 P3V3_STBY      1 @BASEBOARD_FAB2_LIB.BASEBOARD_FAB2(SCH_1):P3V3_STBY
   2 VCC_PA_3V3      2 @BASEBOARD_FAB2_LIB.BASEBOARD_FAB2(SCH_1):VCC_PA_3V3

CAP_0603-4.7UF,6.3V,10%,X6S,E1A  I1  C25W30
   1 P1V15_AUX_BMC      A @BASEBOARD_FAB2_LIB.BASEBOARD_FAB2(SCH_1):P1V15_AUX_BMC
   2    GND      B @BASEBOARD_FAB2_LIB.BASEBOARD_FAB2(SCH_1):GND

RES_0603-0,5.0%,1/10W,CHIP,G22A  I90  R25W93
   1 P3V3_STBY      A @BASEBOARD_FAB2_LIB.BASEBOARD_FAB2(SCH_1):P3V3_STBY
   2 VCC_DACAV3V3      B @BASEBOARD_FAB2_LIB.BASEBOARD_FAB2(SCH_1):VCC_DACAV3V3

RES_0603-0,5.0%,1/10W,CHIP,G22A  I91  R25W120
   1 P3V3_STBY      A @BASEBOARD_FAB2_LIB.BASEBOARD_FAB2(SCH_1):P3V3_STBY
   2 P3V3_USB2A_ALG      B @BASEBOARD_FAB2_LIB.BASEBOARD_FAB2(SCH_1):P3V3_USB2A_ALG

CAP_0402-1.0UF,16V,10%,X6S,D97A  I92  C25W53
   1 P1V2_AUX_BMC      A @BASEBOARD_FAB2_LIB.BASEBOARD_FAB2(SCH_1):P1V2_AUX_BMC
   2    GND      B @BASEBOARD_FAB2_LIB.BASEBOARD_FAB2(SCH_1):GND

CAP_0402-1.0UF,16V,10%,X6S,D97A  I93  C25W56
   1 VCC_PA_3V3      A @BASEBOARD_FAB2_LIB.BASEBOARD_FAB2(SCH_1):VCC_PA_3V3
   2    GND      B @BASEBOARD_FAB2_LIB.BASEBOARD_FAB2(SCH_1):GND

CAP_0402-1.0UF,16V,10%,X6S,D97A  I95  C25W54
   1 P1V2_AUX_BMC      A @BASEBOARD_FAB2_LIB.BASEBOARD_FAB2(SCH_1):P1V2_AUX_BMC
   2    GND      B @BASEBOARD_FAB2_LIB.BASEBOARD_FAB2(SCH_1):GND

CAP_0402-1.0UF,16V,10%,X6S,D97A  I96  C25W40
   1 VCC_D_3V3      A @BASEBOARD_FAB2_LIB.BASEBOARD_FAB2(SCH_1):VCC_D_3V3
   2    GND      B @BASEBOARD_FAB2_LIB.BASEBOARD_FAB2(SCH_1):GND

CAP_0402-1.0UF,16V,10%,X6S,D97A  I97  C25W41
   1 VCC_D_3V3      A @BASEBOARD_FAB2_LIB.BASEBOARD_FAB2(SCH_1):VCC_D_3V3
   2    GND      B @BASEBOARD_FAB2_LIB.BASEBOARD_FAB2(SCH_1):GND

CAP_0402-1.0UF,16V,10%,X6S,D97A  I98  C25W42
   1 VCC_D_3V3      A @BASEBOARD_FAB2_LIB.BASEBOARD_FAB2(SCH_1):VCC_D_3V3
   2    GND      B @BASEBOARD_FAB2_LIB.BASEBOARD_FAB2(SCH_1):GND

CAP_0402-1.0UF,16V,10%,X6S,D97A  I99  C25W32
   1 VCC_ADCAV3V3      A @BASEBOARD_FAB2_LIB.BASEBOARD_FAB2(SCH_1):VCC_ADCAV3V3
   2    GND      B @BASEBOARD_FAB2_LIB.BASEBOARD_FAB2(SCH_1):GND

CAP_0402-1.0UF,16V,10%,X6S,D97A  I100  C25W43
   1 VCC_D_3V3      A @BASEBOARD_FAB2_LIB.BASEBOARD_FAB2(SCH_1):VCC_D_3V3
   2    GND      B @BASEBOARD_FAB2_LIB.BASEBOARD_FAB2(SCH_1):GND

CAP_0402-1.0UF,16V,10%,X6S,D97A  I101  C25W44
   1 VCC_D_3V3      A @BASEBOARD_FAB2_LIB.BASEBOARD_FAB2(SCH_1):VCC_D_3V3
   2    GND      B @BASEBOARD_FAB2_LIB.BASEBOARD_FAB2(SCH_1):GND

CAP_0402-1.0UF,16V,10%,X6S,D97A  I102  C25W33
   1 VCC_ADCAV3V3      A @BASEBOARD_FAB2_LIB.BASEBOARD_FAB2(SCH_1):VCC_ADCAV3V3
   2    GND      B @BASEBOARD_FAB2_LIB.BASEBOARD_FAB2(SCH_1):GND

CAP_0402-1.0UF,16V,10%,X6S,D97A  I103  C25W23
   1 P1V15_AUX_BMC      A @BASEBOARD_FAB2_LIB.BASEBOARD_FAB2(SCH_1):P1V15_AUX_BMC
   2    GND      B @BASEBOARD_FAB2_LIB.BASEBOARD_FAB2(SCH_1):GND

CAP_0402-1.0UF,16V,10%,X6S,D97A  I104  C25W24
   1 P1V15_AUX_BMC      A @BASEBOARD_FAB2_LIB.BASEBOARD_FAB2(SCH_1):P1V15_AUX_BMC
   2    GND      B @BASEBOARD_FAB2_LIB.BASEBOARD_FAB2(SCH_1):GND

CAP_0402-1.0UF,16V,10%,X6S,D97A  I105  C25W25
   1 P1V15_AUX_BMC      A @BASEBOARD_FAB2_LIB.BASEBOARD_FAB2(SCH_1):P1V15_AUX_BMC
   2    GND      B @BASEBOARD_FAB2_LIB.BASEBOARD_FAB2(SCH_1):GND

CAP_0402-1.0UF,16V,10%,X6S,D97A  I106  C25W26
   1 P1V15_AUX_BMC      A @BASEBOARD_FAB2_LIB.BASEBOARD_FAB2(SCH_1):P1V15_AUX_BMC
   2    GND      B @BASEBOARD_FAB2_LIB.BASEBOARD_FAB2(SCH_1):GND

CAP_0402-1.0UF,16V,10%,X6S,D97A  I107  C25W27
   1 P1V15_AUX_BMC      A @BASEBOARD_FAB2_LIB.BASEBOARD_FAB2(SCH_1):P1V15_AUX_BMC
   2    GND      B @BASEBOARD_FAB2_LIB.BASEBOARD_FAB2(SCH_1):GND

CAP_0402-1.0UF,16V,10%,X6S,D97A  I108  C25W28
   1 P1V15_AUX_BMC      A @BASEBOARD_FAB2_LIB.BASEBOARD_FAB2(SCH_1):P1V15_AUX_BMC
   2    GND      B @BASEBOARD_FAB2_LIB.BASEBOARD_FAB2(SCH_1):GND

CAP_0402-1.0UF,16V,10%,X6S,D97A  I109  C25W60
   1 P3V3_STBY      A @BASEBOARD_FAB2_LIB.BASEBOARD_FAB2(SCH_1):P3V3_STBY
   2    GND      B @BASEBOARD_FAB2_LIB.BASEBOARD_FAB2(SCH_1):GND

CAP_0402-1.0UF,16V,10%,X6S,D97A  I110  C25W35
   1 VCC_DACAV3V3      A @BASEBOARD_FAB2_LIB.BASEBOARD_FAB2(SCH_1):VCC_DACAV3V3
   2    GND      B @BASEBOARD_FAB2_LIB.BASEBOARD_FAB2(SCH_1):GND

CAP_0402-1.0UF,16V,10%,X6S,D97A  I112  C25W48
   1 P3V3_STBY      A @BASEBOARD_FAB2_LIB.BASEBOARD_FAB2(SCH_1):P3V3_STBY
   2    GND      B @BASEBOARD_FAB2_LIB.BASEBOARD_FAB2(SCH_1):GND

CAP_0402-1.0UF,16V,10%,X6S,D97A  I113  C25W37
   1 VCC_A_1V1      A @BASEBOARD_FAB2_LIB.BASEBOARD_FAB2(SCH_1):VCC_A_1V1
   2    GND      B @BASEBOARD_FAB2_LIB.BASEBOARD_FAB2(SCH_1):GND

CAP_0402-1.0UF,16V,10%,X6S,D97A  I114  C25W51
   1 P1V2_AUX_BMC      A @BASEBOARD_FAB2_LIB.BASEBOARD_FAB2(SCH_1):P1V2_AUX_BMC
   2    GND      B @BASEBOARD_FAB2_LIB.BASEBOARD_FAB2(SCH_1):GND

CAP_0402-1.0UF,16V,10%,X6S,D97A  I115  C25W71
   1 P3V3_USB2A_ALG      A @BASEBOARD_FAB2_LIB.BASEBOARD_FAB2(SCH_1):P3V3_USB2A_ALG
   2    GND      B @BASEBOARD_FAB2_LIB.BASEBOARD_FAB2(SCH_1):GND

CAP_0402-1.0UF,16V,10%,X6S,D97A  I116  C25W66
   1 VCC_VA_3V3      A @BASEBOARD_FAB2_LIB.BASEBOARD_FAB2(SCH_1):VCC_VA_3V3
   2    GND      B @BASEBOARD_FAB2_LIB.BASEBOARD_FAB2(SCH_1):GND

CAP_0402-1.0UF,16V,10%,X6S,D97A  I117  C25W67
   1 VCC_VA_3V3      A @BASEBOARD_FAB2_LIB.BASEBOARD_FAB2(SCH_1):VCC_VA_3V3
   2    GND      B @BASEBOARD_FAB2_LIB.BASEBOARD_FAB2(SCH_1):GND

CAP_0402-1.0UF,16V,10%,X6S,D97A  I118  C25W52
   1 P1V2_AUX_BMC      A @BASEBOARD_FAB2_LIB.BASEBOARD_FAB2(SCH_1):P1V2_AUX_BMC
   2    GND      B @BASEBOARD_FAB2_LIB.BASEBOARD_FAB2(SCH_1):GND

CAP_A_0402V-0.1UF,16V,10%,X7R,A  I119  C25W31
   1 VCC_ADCAV3V3      A @BASEBOARD_FAB2_LIB.BASEBOARD_FAB2(SCH_1):VCC_ADCAV3V3
   2    GND      B @BASEBOARD_FAB2_LIB.BASEBOARD_FAB2(SCH_1):GND

CAP_A_0402V-0.1UF,16V,10%,X7R,A  I120  C25W34
   1 VCC_DACAV3V3      A @BASEBOARD_FAB2_LIB.BASEBOARD_FAB2(SCH_1):VCC_DACAV3V3
   2    GND      B @BASEBOARD_FAB2_LIB.BASEBOARD_FAB2(SCH_1):GND

CAP_A_0402V-0.1UF,16V,10%,X7R,A  I121  C25W38
   1 VCC_A_1V1      A @BASEBOARD_FAB2_LIB.BASEBOARD_FAB2(SCH_1):VCC_A_1V1
   2    GND      B @BASEBOARD_FAB2_LIB.BASEBOARD_FAB2(SCH_1):GND

CAP_A_0402V-0.1UF,16V,10%,X7R,A  I122  C25W45
   1 VCC_D_3V3      A @BASEBOARD_FAB2_LIB.BASEBOARD_FAB2(SCH_1):VCC_D_3V3
   2    GND      B @BASEBOARD_FAB2_LIB.BASEBOARD_FAB2(SCH_1):GND

CAP_A_0402V-0.1UF,16V,10%,X7R,A  I123  C25W49
   1 P3V3_STBY      A @BASEBOARD_FAB2_LIB.BASEBOARD_FAB2(SCH_1):P3V3_STBY
   2    GND      B @BASEBOARD_FAB2_LIB.BASEBOARD_FAB2(SCH_1):GND

CAP_A_0402V-0.1UF,16V,10%,X7R,A  I124  C25W55
   1 P1V2_AUX_BMC      A @BASEBOARD_FAB2_LIB.BASEBOARD_FAB2(SCH_1):P1V2_AUX_BMC
   2    GND      B @BASEBOARD_FAB2_LIB.BASEBOARD_FAB2(SCH_1):GND

CAP_A_0402V-0.1UF,16V,10%,X7R,A  I125  C25W58
   1 VCC_PA_3V3      A @BASEBOARD_FAB2_LIB.BASEBOARD_FAB2(SCH_1):VCC_PA_3V3
   2    GND      B @BASEBOARD_FAB2_LIB.BASEBOARD_FAB2(SCH_1):GND

CAP_A_0402V-0.1UF,16V,10%,X7R,A  I126  C25W61
   1 P3V3_STBY      A @BASEBOARD_FAB2_LIB.BASEBOARD_FAB2(SCH_1):P3V3_STBY
   2    GND      B @BASEBOARD_FAB2_LIB.BASEBOARD_FAB2(SCH_1):GND

CAP_A_0402V-0.1UF,16V,10%,X7R,A  I128  C25W68
   1 VCC_VA_3V3      A @BASEBOARD_FAB2_LIB.BASEBOARD_FAB2(SCH_1):VCC_VA_3V3
   2    GND      B @BASEBOARD_FAB2_LIB.BASEBOARD_FAB2(SCH_1):GND

CAP_0603LF-10UF,4V,20%,X6S,E15A  I129  C25W29
   1 P1V15_AUX_BMC      A @BASEBOARD_FAB2_LIB.BASEBOARD_FAB2(SCH_1):P1V15_AUX_BMC
   2    GND      B @BASEBOARD_FAB2_LIB.BASEBOARD_FAB2(SCH_1):GND

CAP_0402LF-100.0PF,50V,5%,COG,A  I130  C25W57
   1 VCC_PA_3V3      A @BASEBOARD_FAB2_LIB.BASEBOARD_FAB2(SCH_1):VCC_PA_3V3
   2    GND      B @BASEBOARD_FAB2_LIB.BASEBOARD_FAB2(SCH_1):GND


DRAWING: @BASEBOARD_FAB2_LIB.BASEBOARD_FAB2(SCH_1):PAGE151 

H5AN4G6NAFR-TFC-GP_MEMORY-G2-HA  I49  U25W5
  B1 P2V5_AUX_BMC VPP<0> @BASEBOARD_FAB2_LIB.BASEBOARD_FAB2(SCH_1):P2V5_AUX_BMC
  B3 P1V2_AUX_BMC VDD<0> @BASEBOARD_FAB2_LIB.BASEBOARD_FAB2(SCH_1):P1V2_AUX_BMC
  B9 P1V2_AUX_BMC VDD<1> @BASEBOARD_FAB2_LIB.BASEBOARD_FAB2(SCH_1):P1V2_AUX_BMC
  D1 P1V2_AUX_BMC VDD<2> @BASEBOARD_FAB2_LIB.BASEBOARD_FAB2(SCH_1):P1V2_AUX_BMC
  G7 P1V2_AUX_BMC VDD<3> @BASEBOARD_FAB2_LIB.BASEBOARD_FAB2(SCH_1):P1V2_AUX_BMC
  J1 P1V2_AUX_BMC VDD<4> @BASEBOARD_FAB2_LIB.BASEBOARD_FAB2(SCH_1):P1V2_AUX_BMC
  J9 P1V2_AUX_BMC VDD<5> @BASEBOARD_FAB2_LIB.BASEBOARD_FAB2(SCH_1):P1V2_AUX_BMC
  L1 P1V2_AUX_BMC VDD<6> @BASEBOARD_FAB2_LIB.BASEBOARD_FAB2(SCH_1):P1V2_AUX_BMC
  L9 P1V2_AUX_BMC VDD<7> @BASEBOARD_FAB2_LIB.BASEBOARD_FAB2(SCH_1):P1V2_AUX_BMC
  R1 P1V2_AUX_BMC VDD<8> @BASEBOARD_FAB2_LIB.BASEBOARD_FAB2(SCH_1):P1V2_AUX_BMC
  T9 P1V2_AUX_BMC VDD<9> @BASEBOARD_FAB2_LIB.BASEBOARD_FAB2(SCH_1):P1V2_AUX_BMC
  A1 P1V2_AUX_BMC VDDQ<0> @BASEBOARD_FAB2_LIB.BASEBOARD_FAB2(SCH_1):P1V2_AUX_BMC
  A9 P1V2_AUX_BMC VDDQ<1> @BASEBOARD_FAB2_LIB.BASEBOARD_FAB2(SCH_1):P1V2_AUX_BMC
  C1 P1V2_AUX_BMC VDDQ<2> @BASEBOARD_FAB2_LIB.BASEBOARD_FAB2(SCH_1):P1V2_AUX_BMC
  D9 P1V2_AUX_BMC VDDQ<3> @BASEBOARD_FAB2_LIB.BASEBOARD_FAB2(SCH_1):P1V2_AUX_BMC
  F2 P1V2_AUX_BMC VDDQ<4> @BASEBOARD_FAB2_LIB.BASEBOARD_FAB2(SCH_1):P1V2_AUX_BMC
  F8 P1V2_AUX_BMC VDDQ<5> @BASEBOARD_FAB2_LIB.BASEBOARD_FAB2(SCH_1):P1V2_AUX_BMC
  G1 P1V2_AUX_BMC VDDQ<6> @BASEBOARD_FAB2_LIB.BASEBOARD_FAB2(SCH_1):P1V2_AUX_BMC
  G9 P1V2_AUX_BMC VDDQ<7> @BASEBOARD_FAB2_LIB.BASEBOARD_FAB2(SCH_1):P1V2_AUX_BMC
  J2 P1V2_AUX_BMC VDDQ<8> @BASEBOARD_FAB2_LIB.BASEBOARD_FAB2(SCH_1):P1V2_AUX_BMC
  J8 P1V2_AUX_BMC VDDQ<9> @BASEBOARD_FAB2_LIB.BASEBOARD_FAB2(SCH_1):P1V2_AUX_BMC
  C2 BMC_M_DQ12   DQU4 @BASEBOARD_FAB2_LIB.BASEBOARD_FAB2(SCH_1):BMC_M_DQ12
  C8 BMC_M_DQ13   DQU5 @BASEBOARD_FAB2_LIB.BASEBOARD_FAB2(SCH_1):BMC_M_DQ13
  D3 BMC_M_DQ14   DQU6 @BASEBOARD_FAB2_LIB.BASEBOARD_FAB2(SCH_1):BMC_M_DQ14
  D7 BMC_M_DQ15   DQU7 @BASEBOARD_FAB2_LIB.BASEBOARD_FAB2(SCH_1):BMC_M_DQ15
  A3 BMC_M_DQ8   DQU0 @BASEBOARD_FAB2_LIB.BASEBOARD_FAB2(SCH_1):BMC_M_DQ8
  B8 BMC_M_DQ9   DQU1 @BASEBOARD_FAB2_LIB.BASEBOARD_FAB2(SCH_1):BMC_M_DQ9
  C3 BMC_M_DQ10   DQU2 @BASEBOARD_FAB2_LIB.BASEBOARD_FAB2(SCH_1):BMC_M_DQ10
  C7 BMC_M_DQ11   DQU3 @BASEBOARD_FAB2_LIB.BASEBOARD_FAB2(SCH_1):BMC_M_DQ11
  F7 BMC_M_DQ1   DQL1 @BASEBOARD_FAB2_LIB.BASEBOARD_FAB2(SCH_1):BMC_M_DQ1
  G2 BMC_M_DQ0   DQL0 @BASEBOARD_FAB2_LIB.BASEBOARD_FAB2(SCH_1):BMC_M_DQ0
  H2 BMC_M_DQ4   DQL4 @BASEBOARD_FAB2_LIB.BASEBOARD_FAB2(SCH_1):BMC_M_DQ4
  H3 BMC_M_DQ2   DQL2 @BASEBOARD_FAB2_LIB.BASEBOARD_FAB2(SCH_1):BMC_M_DQ2
  H7 BMC_M_DQ3   DQL3 @BASEBOARD_FAB2_LIB.BASEBOARD_FAB2(SCH_1):BMC_M_DQ3
  H8 BMC_M_DQ5   DQL5 @BASEBOARD_FAB2_LIB.BASEBOARD_FAB2(SCH_1):BMC_M_DQ5
  J3 BMC_M_DQ6   DQL6 @BASEBOARD_FAB2_LIB.BASEBOARD_FAB2(SCH_1):BMC_M_DQ6
  J7 BMC_M_DQ7   DQL7 @BASEBOARD_FAB2_LIB.BASEBOARD_FAB2(SCH_1):BMC_M_DQ7
  P3 BMC_M_A0     A0 @BASEBOARD_FAB2_LIB.BASEBOARD_FAB2(SCH_1):BMC_M_A0
  P7 BMC_M_A1     A1 @BASEBOARD_FAB2_LIB.BASEBOARD_FAB2(SCH_1):BMC_M_A1
  R3 BMC_M_A2     A2 @BASEBOARD_FAB2_LIB.BASEBOARD_FAB2(SCH_1):BMC_M_A2
  N7 BMC_M_A3     A3 @BASEBOARD_FAB2_LIB.BASEBOARD_FAB2(SCH_1):BMC_M_A3
  N3 BMC_M_A4     A4 @BASEBOARD_FAB2_LIB.BASEBOARD_FAB2(SCH_1):BMC_M_A4
  P8 BMC_M_A5     A5 @BASEBOARD_FAB2_LIB.BASEBOARD_FAB2(SCH_1):BMC_M_A5
  P2 BMC_M_A6     A6 @BASEBOARD_FAB2_LIB.BASEBOARD_FAB2(SCH_1):BMC_M_A6
  R8 BMC_M_A7     A7 @BASEBOARD_FAB2_LIB.BASEBOARD_FAB2(SCH_1):BMC_M_A7
  R2 BMC_M_A8     A8 @BASEBOARD_FAB2_LIB.BASEBOARD_FAB2(SCH_1):BMC_M_A8
  R7 BMC_M_A9     A9 @BASEBOARD_FAB2_LIB.BASEBOARD_FAB2(SCH_1):BMC_M_A9
  M3 BMC_M_A10 A10/AP @BASEBOARD_FAB2_LIB.BASEBOARD_FAB2(SCH_1):BMC_M_A10
  T2 BMC_M_A11    A11 @BASEBOARD_FAB2_LIB.BASEBOARD_FAB2(SCH_1):BMC_M_A11
  M7 BMC_M_A12 A12/BC# @BASEBOARD_FAB2_LIB.BASEBOARD_FAB2(SCH_1):BMC_M_A12
  T8 BMC_M_A13    A13 @BASEBOARD_FAB2_LIB.BASEBOARD_FAB2(SCH_1):BMC_M_A13
  L2 BMC_M_WE_N WE#/A14 @BASEBOARD_FAB2_LIB.BASEBOARD_FAB2(SCH_1):BMC_M_WE_N
  M8 BMC_M_CAS_N CAS#/A15 @BASEBOARD_FAB2_LIB.BASEBOARD_FAB2(SCH_1):BMC_M_CAS_N
  L8 BMC_M_RAS_N RAS#/A16 @BASEBOARD_FAB2_LIB.BASEBOARD_FAB2(SCH_1):BMC_M_RAS_N
  M1 BMC_M_VREFCA VREFCA @BASEBOARD_FAB2_LIB.BASEBOARD_FAB2(SCH_1):BMC_M_VREFCA
  F9 BMC_ZQ     ZQ @BASEBOARD_FAB2_LIB.BASEBOARD_FAB2(SCH_1):BMC_ZQ
  K2 BMC_M_CKE    CKE @BASEBOARD_FAB2_LIB.BASEBOARD_FAB2(SCH_1):BMC_M_CKE
  K3 BMC_M_ODT    ODT @BASEBOARD_FAB2_LIB.BASEBOARD_FAB2(SCH_1):BMC_M_ODT
  M2 BMC_M_BG0    BG0 @BASEBOARD_FAB2_LIB.BASEBOARD_FAB2(SCH_1):BMC_M_BG0
  N9    GND    TEN @BASEBOARD_FAB2_LIB.BASEBOARD_FAB2(SCH_1):GND
  T3 BMC_M_PAR    PAR @BASEBOARD_FAB2_LIB.BASEBOARD_FAB2(SCH_1):BMC_M_PAR
  T7     NC  NC#T7     NC
  K7 BMC_M_CLK_DP   CK_T @BASEBOARD_FAB2_LIB.BASEBOARD_FAB2(SCH_1):BMC_M_CLK_DP
  K8 BMC_M_CLK_DN   CK_C @BASEBOARD_FAB2_LIB.BASEBOARD_FAB2(SCH_1):BMC_M_CLK_DN
  R9 P2V5_AUX_BMC VPP<1> @BASEBOARD_FAB2_LIB.BASEBOARD_FAB2(SCH_1):P2V5_AUX_BMC
  L3 BMC_M_MACT_N   ACT# @BASEBOARD_FAB2_LIB.BASEBOARD_FAB2(SCH_1):BMC_M_MACT_N
  L7 BMC_M_CS_N    CS# @BASEBOARD_FAB2_LIB.BASEBOARD_FAB2(SCH_1):BMC_M_CS_N
  P1 BMC_M_RST_N RESET# @BASEBOARD_FAB2_LIB.BASEBOARD_FAB2(SCH_1):BMC_M_RST_N
  P9 BMC_M_MALERT_N ALERT# @BASEBOARD_FAB2_LIB.BASEBOARD_FAB2(SCH_1):BMC_M_MALERT_N
  B2    GND VSS<0> @BASEBOARD_FAB2_LIB.BASEBOARD_FAB2(SCH_1):GND
  E1    GND VSS<1> @BASEBOARD_FAB2_LIB.BASEBOARD_FAB2(SCH_1):GND
  E9    GND VSS<2> @BASEBOARD_FAB2_LIB.BASEBOARD_FAB2(SCH_1):GND
  G8    GND VSS<3> @BASEBOARD_FAB2_LIB.BASEBOARD_FAB2(SCH_1):GND
  K1    GND VSS<4> @BASEBOARD_FAB2_LIB.BASEBOARD_FAB2(SCH_1):GND
  K9    GND VSS<5> @BASEBOARD_FAB2_LIB.BASEBOARD_FAB2(SCH_1):GND
  M9    GND VSS<6> @BASEBOARD_FAB2_LIB.BASEBOARD_FAB2(SCH_1):GND
  N1    GND VSS<7> @BASEBOARD_FAB2_LIB.BASEBOARD_FAB2(SCH_1):GND
  T1    GND VSS<8> @BASEBOARD_FAB2_LIB.BASEBOARD_FAB2(SCH_1):GND
  A2    GND VSSQ<0> @BASEBOARD_FAB2_LIB.BASEBOARD_FAB2(SCH_1):GND
  A8    GND VSSQ<1> @BASEBOARD_FAB2_LIB.BASEBOARD_FAB2(SCH_1):GND
  C9    GND VSSQ<2> @BASEBOARD_FAB2_LIB.BASEBOARD_FAB2(SCH_1):GND
  D2    GND VSSQ<3> @BASEBOARD_FAB2_LIB.BASEBOARD_FAB2(SCH_1):GND
  D8    GND VSSQ<4> @BASEBOARD_FAB2_LIB.BASEBOARD_FAB2(SCH_1):GND
  E3    GND VSSQ<5> @BASEBOARD_FAB2_LIB.BASEBOARD_FAB2(SCH_1):GND
  E8    GND VSSQ<6> @BASEBOARD_FAB2_LIB.BASEBOARD_FAB2(SCH_1):GND
  F1    GND VSSQ<7> @BASEBOARD_FAB2_LIB.BASEBOARD_FAB2(SCH_1):GND
  H1    GND VSSQ<8> @BASEBOARD_FAB2_LIB.BASEBOARD_FAB2(SCH_1):GND
  H9    GND VSSQ<9> @BASEBOARD_FAB2_LIB.BASEBOARD_FAB2(SCH_1):GND
  A7 BMC_M_DQS1_DN DQSU_C @BASEBOARD_FAB2_LIB.BASEBOARD_FAB2(SCH_1):BMC_M_DQS1_DN
  B7 BMC_M_DQS1_DP DQSU_T @BASEBOARD_FAB2_LIB.BASEBOARD_FAB2(SCH_1):BMC_M_DQS1_DP
  F3 BMC_M_DQS0_DN DQSL_C @BASEBOARD_FAB2_LIB.BASEBOARD_FAB2(SCH_1):BMC_M_DQS0_DN
  G3 BMC_M_DQS0_DP DQSL_T @BASEBOARD_FAB2_LIB.BASEBOARD_FAB2(SCH_1):BMC_M_DQS0_DP
  E2 BMC_M_DM1 DMU#/DBIU# @BASEBOARD_FAB2_LIB.BASEBOARD_FAB2(SCH_1):BMC_M_DM1
  E7 BMC_M_DM0 DML#/DBIL# @BASEBOARD_FAB2_LIB.BASEBOARD_FAB2(SCH_1):BMC_M_DM0
  N2 BMC_M_BA0    BA0 @BASEBOARD_FAB2_LIB.BASEBOARD_FAB2(SCH_1):BMC_M_BA0
  N8 BMC_M_BA1    BA1 @BASEBOARD_FAB2_LIB.BASEBOARD_FAB2(SCH_1):BMC_M_BA1

RES_0402-4.75K,1%,1/16W,CHIP,GA  I55  R9F29
   1 P1V2_AUX_BMC      A @BASEBOARD_FAB2_LIB.BASEBOARD_FAB2(SCH_1):P1V2_AUX_BMC
   2 RST_BMC_DDR3_R_N      B @BASEBOARD_FAB2_LIB.BASEBOARD_FAB2(SCH_1):RST_BMC_DDR3_R_N

TTL1G07_A_SOP-74LVC1G07,IC,C88B  I56  U9F3
   2 RST_BMC_DDR3_BUF_IN_N      A @BASEBOARD_FAB2_LIB.BASEBOARD_FAB2(SCH_1):RST_BMC_DDR3_BUF_IN_N
   4 RST_BMC_DDR3_R_N      Y @BASEBOARD_FAB2_LIB.BASEBOARD_FAB2(SCH_1):RST_BMC_DDR3_R_N

CAP_0402LF-100.0PF,50V,5%,COG,A  I58  C25W16
   1 P1V2_AUX_BMC      A @BASEBOARD_FAB2_LIB.BASEBOARD_FAB2(SCH_1):P1V2_AUX_BMC
   2    GND      B @BASEBOARD_FAB2_LIB.BASEBOARD_FAB2(SCH_1):GND

RES_0402-240,1.0%,1/16W,CHIP,GA  I101  R25W117
   1 BMC_ZQ      A @BASEBOARD_FAB2_LIB.BASEBOARD_FAB2(SCH_1):BMC_ZQ
   2    GND      B @BASEBOARD_FAB2_LIB.BASEBOARD_FAB2(SCH_1):GND

SC1U16V3KX-2GP_SMD-BCG-SC1U16VA  I120  C25W17
   1 P1V2_AUX_BMC      1 @BASEBOARD_FAB2_LIB.BASEBOARD_FAB2(SCH_1):P1V2_AUX_BMC
   2    GND      2 @BASEBOARD_FAB2_LIB.BASEBOARD_FAB2(SCH_1):GND

SC1U16V3KX-2GP_SMD-BCG-SC1U16VA  I121  C25W18
   1 P1V2_AUX_BMC      1 @BASEBOARD_FAB2_LIB.BASEBOARD_FAB2(SCH_1):P1V2_AUX_BMC
   2    GND      2 @BASEBOARD_FAB2_LIB.BASEBOARD_FAB2(SCH_1):GND

CAP_0603-4.7UF,6.3V,10%,X6S,E1A  I123  C25W19
   1 P1V2_AUX_BMC      A @BASEBOARD_FAB2_LIB.BASEBOARD_FAB2(SCH_1):P1V2_AUX_BMC
   2    GND      B @BASEBOARD_FAB2_LIB.BASEBOARD_FAB2(SCH_1):GND

CAP_0402-1.0UF,16V,10%,X6S,D97A  I125  C25W1
   1 P1V2_AUX_BMC      A @BASEBOARD_FAB2_LIB.BASEBOARD_FAB2(SCH_1):P1V2_AUX_BMC
   2    GND      B @BASEBOARD_FAB2_LIB.BASEBOARD_FAB2(SCH_1):GND

RES_0402-221,1.0%,1/16W,CHIP,GA  I138  R9E24
   1 FM_HEARTBEAT_LED_A      A @BASEBOARD_FAB2_LIB.BASEBOARD_FAB2(SCH_1):FM_HEARTBEAT_LED_A
   2 P3V3_STBY      B @BASEBOARD_FAB2_LIB.BASEBOARD_FAB2(SCH_1):P3V3_STBY

CAP_0402-1.0UF,16V,10%,X6S,D97A  I139  C25W2
   1 P1V2_AUX_BMC      A @BASEBOARD_FAB2_LIB.BASEBOARD_FAB2(SCH_1):P1V2_AUX_BMC
   2    GND      B @BASEBOARD_FAB2_LIB.BASEBOARD_FAB2(SCH_1):GND

CAP_0402-1.0UF,16V,10%,X6S,D97A  I140  C25W3
   1 P1V2_AUX_BMC      A @BASEBOARD_FAB2_LIB.BASEBOARD_FAB2(SCH_1):P1V2_AUX_BMC
   2    GND      B @BASEBOARD_FAB2_LIB.BASEBOARD_FAB2(SCH_1):GND

CAP_0402-1.0UF,16V,10%,X6S,D97A  I141  C25W4
   1 P1V2_AUX_BMC      A @BASEBOARD_FAB2_LIB.BASEBOARD_FAB2(SCH_1):P1V2_AUX_BMC
   2    GND      B @BASEBOARD_FAB2_LIB.BASEBOARD_FAB2(SCH_1):GND

CAP_0402-1.0UF,16V,10%,X6S,D97A  I142  C25W5
   1 P1V2_AUX_BMC      A @BASEBOARD_FAB2_LIB.BASEBOARD_FAB2(SCH_1):P1V2_AUX_BMC
   2    GND      B @BASEBOARD_FAB2_LIB.BASEBOARD_FAB2(SCH_1):GND

CAP_0402-1.0UF,16V,10%,X6S,D97A  I143  C25W6
   1 P1V2_AUX_BMC      A @BASEBOARD_FAB2_LIB.BASEBOARD_FAB2(SCH_1):P1V2_AUX_BMC
   2    GND      B @BASEBOARD_FAB2_LIB.BASEBOARD_FAB2(SCH_1):GND

LED_A1LF-GREEN,IC,C97278-010  I144  DS9E1
   2 FM_HEARTBEAT_LED_K      C @BASEBOARD_FAB2_LIB.BASEBOARD_FAB2(SCH_1):FM_HEARTBEAT_LED_K
   1 FM_HEARTBEAT_LED_A      A @BASEBOARD_FAB2_LIB.BASEBOARD_FAB2(SCH_1):FM_HEARTBEAT_LED_A

FET_N_DUAL_SMLF-NTJD4001N,FET,A  I145  Q9E1
   5 FM_HEARTBEAT_LED GATE<0> @BASEBOARD_FAB2_LIB.BASEBOARD_FAB2(SCH_1):FM_HEARTBEAT_LED
   4    GND SOURCE<0> @BASEBOARD_FAB2_LIB.BASEBOARD_FAB2(SCH_1):GND
   3 FM_HEARTBEAT_LED_K DRAIN<0> @BASEBOARD_FAB2_LIB.BASEBOARD_FAB2(SCH_1):FM_HEARTBEAT_LED_K

RES_0402-4.75K,1%,1/16W,CHIP,GA  I173  R9E21
   1 P3V3_STBY      A @BASEBOARD_FAB2_LIB.BASEBOARD_FAB2(SCH_1):P3V3_STBY
   2 FM_HEARTBEAT_LED      B @BASEBOARD_FAB2_LIB.BASEBOARD_FAB2(SCH_1):FM_HEARTBEAT_LED

RES_0402-4.75K,1%,1/16W,CHIP,GA  I175  R8B25
   1 P3V3_STBY      A @BASEBOARD_FAB2_LIB.BASEBOARD_FAB2(SCH_1):P3V3_STBY
   2 FM_BMC_HEARTBEAT_N      B @BASEBOARD_FAB2_LIB.BASEBOARD_FAB2(SCH_1):FM_BMC_HEARTBEAT_N

FET_N_DUAL_SMLF-NTJD4001N,FET,A  I198  Q9E1
   2 FM_BMC_HEARTBEAT_N GATE<0> @BASEBOARD_FAB2_LIB.BASEBOARD_FAB2(SCH_1):FM_BMC_HEARTBEAT_N
   1    GND SOURCE<0> @BASEBOARD_FAB2_LIB.BASEBOARD_FAB2(SCH_1):GND
   6 FM_HEARTBEAT_LED DRAIN<0> @BASEBOARD_FAB2_LIB.BASEBOARD_FAB2(SCH_1):FM_HEARTBEAT_LED

RES_0402-1.00K,1%,1/16W,CHIP,GA  I201  R1T30
   1 P1V2_AUX_BMC      A @BASEBOARD_FAB2_LIB.BASEBOARD_FAB2(SCH_1):P1V2_AUX_BMC
   2 BMC_M_VREFCA      B @BASEBOARD_FAB2_LIB.BASEBOARD_FAB2(SCH_1):BMC_M_VREFCA

RES_0402-1.00K,1%,1/16W,CHIP,GA  I202  R1T29
   1 BMC_M_VREFCA      A @BASEBOARD_FAB2_LIB.BASEBOARD_FAB2(SCH_1):BMC_M_VREFCA
   2    GND      B @BASEBOARD_FAB2_LIB.BASEBOARD_FAB2(SCH_1):GND

RES_0402-33.2,1%,1/16W,EMPTY,GA  I209  R9F34
   1 RST_BMC_DDR3_R_N      A @BASEBOARD_FAB2_LIB.BASEBOARD_FAB2(SCH_1):RST_BMC_DDR3_R_N
   2 BMC_M_RST_N      B @BASEBOARD_FAB2_LIB.BASEBOARD_FAB2(SCH_1):BMC_M_RST_N

RES_0402-4.75K,1%,1/16W,EMPTY,A  I210  R25W119
   1 P1V2_AUX_BMC      A @BASEBOARD_FAB2_LIB.BASEBOARD_FAB2(SCH_1):P1V2_AUX_BMC
   2 BMC_M_PAR      B @BASEBOARD_FAB2_LIB.BASEBOARD_FAB2(SCH_1):BMC_M_PAR

RES_0402-0.0,5%,1/16W,CHIP,G21A  I211  R25W118
   1 BMC_M_PAR      A @BASEBOARD_FAB2_LIB.BASEBOARD_FAB2(SCH_1):BMC_M_PAR
   2    GND      B @BASEBOARD_FAB2_LIB.BASEBOARD_FAB2(SCH_1):GND

CAP_A_0402V-1.0UF,6.3V,10%,X6SA  I212  C25W12
   1 BMC_M_VREFCA      A @BASEBOARD_FAB2_LIB.BASEBOARD_FAB2(SCH_1):BMC_M_VREFCA
   2    GND      B @BASEBOARD_FAB2_LIB.BASEBOARD_FAB2(SCH_1):GND

CAP_A_0402V-0.01UF,25V,10%,X7RA  I213  C25W10
   1 P1V2_AUX_BMC      A @BASEBOARD_FAB2_LIB.BASEBOARD_FAB2(SCH_1):P1V2_AUX_BMC
   2 BMC_M_VREFCA      B @BASEBOARD_FAB2_LIB.BASEBOARD_FAB2(SCH_1):BMC_M_VREFCA

CAP_A_0402V-0.01UF,25V,10%,X7RA  I214  C25W11
   1 BMC_M_VREFCA      A @BASEBOARD_FAB2_LIB.BASEBOARD_FAB2(SCH_1):BMC_M_VREFCA
   2    GND      B @BASEBOARD_FAB2_LIB.BASEBOARD_FAB2(SCH_1):GND

CAP_A_0402V-0.1UF,16V,10%,X7R,A  I215  C25W14
   1 P2V5_AUX_BMC      A @BASEBOARD_FAB2_LIB.BASEBOARD_FAB2(SCH_1):P2V5_AUX_BMC
   2    GND      B @BASEBOARD_FAB2_LIB.BASEBOARD_FAB2(SCH_1):GND

CAP_A_0402V-0.1UF,16V,10%,X7R,A  I216  C25W15
   1 P2V5_AUX_BMC      A @BASEBOARD_FAB2_LIB.BASEBOARD_FAB2(SCH_1):P2V5_AUX_BMC
   2    GND      B @BASEBOARD_FAB2_LIB.BASEBOARD_FAB2(SCH_1):GND

CAP_A_0402V-0.1UF,16V,10%,X7R,A  I217  C25W13
   1 BMC_M_VREFCA      A @BASEBOARD_FAB2_LIB.BASEBOARD_FAB2(SCH_1):BMC_M_VREFCA
   2    GND      B @BASEBOARD_FAB2_LIB.BASEBOARD_FAB2(SCH_1):GND

CAP_0402-0.22UF,16V,10%,X7R,A3A  I220  C1W20
   1 BMC_M_CLK      A @BASEBOARD_FAB2_LIB.BASEBOARD_FAB2(SCH_1):BMC_M_CLK
   2    GND      B @BASEBOARD_FAB2_LIB.BASEBOARD_FAB2(SCH_1):GND

RES_0402-2.7K,1%,1/16W,CHIP,G2A  I222  R25W30
   1 BMC_M_MALERT_N      A @BASEBOARD_FAB2_LIB.BASEBOARD_FAB2(SCH_1):BMC_M_MALERT_N
   2 P1V2_AUX_BMC      B @BASEBOARD_FAB2_LIB.BASEBOARD_FAB2(SCH_1):P1V2_AUX_BMC

120R2F-GP_RCL_GP-120R2F-GP,64.A  I223  R25W27
   1 BMC_M_CKE      1 @BASEBOARD_FAB2_LIB.BASEBOARD_FAB2(SCH_1):BMC_M_CKE
   2 P1V2_AUX_BMC      2 @BASEBOARD_FAB2_LIB.BASEBOARD_FAB2(SCH_1):P1V2_AUX_BMC

120R2F-GP_RCL_GP-120R2F-GP,64.A  I224  R25W28
   1 BMC_M_ODT      1 @BASEBOARD_FAB2_LIB.BASEBOARD_FAB2(SCH_1):BMC_M_ODT
   2 P1V2_AUX_BMC      2 @BASEBOARD_FAB2_LIB.BASEBOARD_FAB2(SCH_1):P1V2_AUX_BMC

120R2F-GP_RCL_GP-120R2F-GP,64.A  I225  R25W29
   1 BMC_M_RST_N      1 @BASEBOARD_FAB2_LIB.BASEBOARD_FAB2(SCH_1):BMC_M_RST_N
   2 P1V2_AUX_BMC      2 @BASEBOARD_FAB2_LIB.BASEBOARD_FAB2(SCH_1):P1V2_AUX_BMC

120R2F-GP_RCL_GP-120R2F-GP,64.A  I226  R25W31
   1 BMC_M_CS_N      1 @BASEBOARD_FAB2_LIB.BASEBOARD_FAB2(SCH_1):BMC_M_CS_N
   2 P1V2_AUX_BMC      2 @BASEBOARD_FAB2_LIB.BASEBOARD_FAB2(SCH_1):P1V2_AUX_BMC

120R2F-GP_RCL_GP-120R2F-GP,64.A  I227  R25W32
   1 BMC_M_RAS_N      1 @BASEBOARD_FAB2_LIB.BASEBOARD_FAB2(SCH_1):BMC_M_RAS_N
   2 P1V2_AUX_BMC      2 @BASEBOARD_FAB2_LIB.BASEBOARD_FAB2(SCH_1):P1V2_AUX_BMC

120R2F-GP_RCL_GP-120R2F-GP,64.A  I228  R25W33
   1 BMC_M_CAS_N      1 @BASEBOARD_FAB2_LIB.BASEBOARD_FAB2(SCH_1):BMC_M_CAS_N
   2 P1V2_AUX_BMC      2 @BASEBOARD_FAB2_LIB.BASEBOARD_FAB2(SCH_1):P1V2_AUX_BMC

120R2F-GP_RCL_GP-120R2F-GP,64.A  I229  R25W34
   1 BMC_M_WE_N      1 @BASEBOARD_FAB2_LIB.BASEBOARD_FAB2(SCH_1):BMC_M_WE_N
   2 P1V2_AUX_BMC      2 @BASEBOARD_FAB2_LIB.BASEBOARD_FAB2(SCH_1):P1V2_AUX_BMC

120R2F-GP_RCL_GP-120R2F-GP,64.A  I230  R25W35
   1 BMC_M_BA0      1 @BASEBOARD_FAB2_LIB.BASEBOARD_FAB2(SCH_1):BMC_M_BA0
   2 P1V2_AUX_BMC      2 @BASEBOARD_FAB2_LIB.BASEBOARD_FAB2(SCH_1):P1V2_AUX_BMC

120R2F-GP_RCL_GP-120R2F-GP,64.A  I231  R25W36
   1 BMC_M_BA1      1 @BASEBOARD_FAB2_LIB.BASEBOARD_FAB2(SCH_1):BMC_M_BA1
   2 P1V2_AUX_BMC      2 @BASEBOARD_FAB2_LIB.BASEBOARD_FAB2(SCH_1):P1V2_AUX_BMC

120R2F-GP_RCL_GP-120R2F-GP,64.A  I232  R25W37
   1 BMC_M_BG0      1 @BASEBOARD_FAB2_LIB.BASEBOARD_FAB2(SCH_1):BMC_M_BG0
   2 P1V2_AUX_BMC      2 @BASEBOARD_FAB2_LIB.BASEBOARD_FAB2(SCH_1):P1V2_AUX_BMC

120R2F-GP_RCL_GP-120R2F-GP,64.A  I233  R25W38
   1 BMC_M_A0      1 @BASEBOARD_FAB2_LIB.BASEBOARD_FAB2(SCH_1):BMC_M_A0
   2 P1V2_AUX_BMC      2 @BASEBOARD_FAB2_LIB.BASEBOARD_FAB2(SCH_1):P1V2_AUX_BMC

120R2F-GP_RCL_GP-120R2F-GP,64.A  I234  R25W39
   1 BMC_M_A1      1 @BASEBOARD_FAB2_LIB.BASEBOARD_FAB2(SCH_1):BMC_M_A1
   2 P1V2_AUX_BMC      2 @BASEBOARD_FAB2_LIB.BASEBOARD_FAB2(SCH_1):P1V2_AUX_BMC

120R2F-GP_RCL_GP-120R2F-GP,64.A  I235  R25W41
   1 BMC_M_A3      1 @BASEBOARD_FAB2_LIB.BASEBOARD_FAB2(SCH_1):BMC_M_A3
   2 P1V2_AUX_BMC      2 @BASEBOARD_FAB2_LIB.BASEBOARD_FAB2(SCH_1):P1V2_AUX_BMC

120R2F-GP_RCL_GP-120R2F-GP,64.A  I236  R25W42
   1 BMC_M_A4      1 @BASEBOARD_FAB2_LIB.BASEBOARD_FAB2(SCH_1):BMC_M_A4
   2 P1V2_AUX_BMC      2 @BASEBOARD_FAB2_LIB.BASEBOARD_FAB2(SCH_1):P1V2_AUX_BMC

120R2F-GP_RCL_GP-120R2F-GP,64.A  I237  R25W44
   1 BMC_M_A6      1 @BASEBOARD_FAB2_LIB.BASEBOARD_FAB2(SCH_1):BMC_M_A6
   2 P1V2_AUX_BMC      2 @BASEBOARD_FAB2_LIB.BASEBOARD_FAB2(SCH_1):P1V2_AUX_BMC

120R2F-GP_RCL_GP-120R2F-GP,64.A  I238  R25W43
   1 BMC_M_A5      1 @BASEBOARD_FAB2_LIB.BASEBOARD_FAB2(SCH_1):BMC_M_A5
   2 P1V2_AUX_BMC      2 @BASEBOARD_FAB2_LIB.BASEBOARD_FAB2(SCH_1):P1V2_AUX_BMC

120R2F-GP_RCL_GP-120R2F-GP,64.A  I239  R25W47
   1 BMC_M_A9      1 @BASEBOARD_FAB2_LIB.BASEBOARD_FAB2(SCH_1):BMC_M_A9
   2 P1V2_AUX_BMC      2 @BASEBOARD_FAB2_LIB.BASEBOARD_FAB2(SCH_1):P1V2_AUX_BMC

120R2F-GP_RCL_GP-120R2F-GP,64.A  I240  R25W48
   1 BMC_M_A10      1 @BASEBOARD_FAB2_LIB.BASEBOARD_FAB2(SCH_1):BMC_M_A10
   2 P1V2_AUX_BMC      2 @BASEBOARD_FAB2_LIB.BASEBOARD_FAB2(SCH_1):P1V2_AUX_BMC

120R2F-GP_RCL_GP-120R2F-GP,64.A  I241  R25W46
   1 BMC_M_A8      1 @BASEBOARD_FAB2_LIB.BASEBOARD_FAB2(SCH_1):BMC_M_A8
   2 P1V2_AUX_BMC      2 @BASEBOARD_FAB2_LIB.BASEBOARD_FAB2(SCH_1):P1V2_AUX_BMC

120R2F-GP_RCL_GP-120R2F-GP,64.A  I242  R25W45
   1 BMC_M_A7      1 @BASEBOARD_FAB2_LIB.BASEBOARD_FAB2(SCH_1):BMC_M_A7
   2 P1V2_AUX_BMC      2 @BASEBOARD_FAB2_LIB.BASEBOARD_FAB2(SCH_1):P1V2_AUX_BMC

120R2F-GP_RCL_GP-120R2F-GP,64.A  I243  R25W49
   1 BMC_M_A11      1 @BASEBOARD_FAB2_LIB.BASEBOARD_FAB2(SCH_1):BMC_M_A11
   2 P1V2_AUX_BMC      2 @BASEBOARD_FAB2_LIB.BASEBOARD_FAB2(SCH_1):P1V2_AUX_BMC

120R2F-GP_RCL_GP-120R2F-GP,64.A  I244  R25W50
   1 BMC_M_A12      1 @BASEBOARD_FAB2_LIB.BASEBOARD_FAB2(SCH_1):BMC_M_A12
   2 P1V2_AUX_BMC      2 @BASEBOARD_FAB2_LIB.BASEBOARD_FAB2(SCH_1):P1V2_AUX_BMC

120R2F-GP_RCL_GP-120R2F-GP,64.A  I245  R25W51
   1 BMC_M_A13      1 @BASEBOARD_FAB2_LIB.BASEBOARD_FAB2(SCH_1):BMC_M_A13
   2 P1V2_AUX_BMC      2 @BASEBOARD_FAB2_LIB.BASEBOARD_FAB2(SCH_1):P1V2_AUX_BMC

120R2F-GP_RCL_GP-120R2F-GP,64.A  I246  R25W52
   1 BMC_M_MACT_N      1 @BASEBOARD_FAB2_LIB.BASEBOARD_FAB2(SCH_1):BMC_M_MACT_N
   2 P1V2_AUX_BMC      2 @BASEBOARD_FAB2_LIB.BASEBOARD_FAB2(SCH_1):P1V2_AUX_BMC

120R2F-GP_RCL_GP-120R2F-GP,64.A  I247  R25W40
   1 BMC_M_A2      1 @BASEBOARD_FAB2_LIB.BASEBOARD_FAB2(SCH_1):BMC_M_A2
   2 P1V2_AUX_BMC      2 @BASEBOARD_FAB2_LIB.BASEBOARD_FAB2(SCH_1):P1V2_AUX_BMC

120R2F-GP_RCL_GP-120R2F-GP,64.A  I248  R25W1
   1    GND      1 @BASEBOARD_FAB2_LIB.BASEBOARD_FAB2(SCH_1):GND
   2 BMC_M_CKE      2 @BASEBOARD_FAB2_LIB.BASEBOARD_FAB2(SCH_1):BMC_M_CKE

120R2F-GP_RCL_GP-120R2F-GP,64.A  I249  R25W2
   1    GND      1 @BASEBOARD_FAB2_LIB.BASEBOARD_FAB2(SCH_1):GND
   2 BMC_M_ODT      2 @BASEBOARD_FAB2_LIB.BASEBOARD_FAB2(SCH_1):BMC_M_ODT

120R2F-GP_RCL_GP-120R2F-GP,64.A  I250  R25W3
   1    GND      1 @BASEBOARD_FAB2_LIB.BASEBOARD_FAB2(SCH_1):GND
   2 BMC_M_RST_N      2 @BASEBOARD_FAB2_LIB.BASEBOARD_FAB2(SCH_1):BMC_M_RST_N

120R2F-GP_RCL_GP-120R2F-GP,64.A  I251  R25W4
   1    GND      1 @BASEBOARD_FAB2_LIB.BASEBOARD_FAB2(SCH_1):GND
   2 BMC_M_MALERT_N      2 @BASEBOARD_FAB2_LIB.BASEBOARD_FAB2(SCH_1):BMC_M_MALERT_N

120R2F-GP_RCL_GP-120R2F-GP,64.A  I252  R25W5
   1    GND      1 @BASEBOARD_FAB2_LIB.BASEBOARD_FAB2(SCH_1):GND
   2 BMC_M_CS_N      2 @BASEBOARD_FAB2_LIB.BASEBOARD_FAB2(SCH_1):BMC_M_CS_N

120R2F-GP_RCL_GP-120R2F-GP,64.A  I253  R25W6
   1    GND      1 @BASEBOARD_FAB2_LIB.BASEBOARD_FAB2(SCH_1):GND
   2 BMC_M_RAS_N      2 @BASEBOARD_FAB2_LIB.BASEBOARD_FAB2(SCH_1):BMC_M_RAS_N

120R2F-GP_RCL_GP-120R2F-GP,64.A  I254  R25W7
   1    GND      1 @BASEBOARD_FAB2_LIB.BASEBOARD_FAB2(SCH_1):GND
   2 BMC_M_CAS_N      2 @BASEBOARD_FAB2_LIB.BASEBOARD_FAB2(SCH_1):BMC_M_CAS_N

120R2F-GP_RCL_GP-120R2F-GP,64.A  I255  R25W8
   1    GND      1 @BASEBOARD_FAB2_LIB.BASEBOARD_FAB2(SCH_1):GND
   2 BMC_M_WE_N      2 @BASEBOARD_FAB2_LIB.BASEBOARD_FAB2(SCH_1):BMC_M_WE_N

120R2F-GP_RCL_GP-120R2F-GP,64.A  I256  R25W12
   1    GND      1 @BASEBOARD_FAB2_LIB.BASEBOARD_FAB2(SCH_1):GND
   2 BMC_M_A0      2 @BASEBOARD_FAB2_LIB.BASEBOARD_FAB2(SCH_1):BMC_M_A0

120R2F-GP_RCL_GP-120R2F-GP,64.A  I257  R25W11
   1    GND      1 @BASEBOARD_FAB2_LIB.BASEBOARD_FAB2(SCH_1):GND
   2 BMC_M_BG0      2 @BASEBOARD_FAB2_LIB.BASEBOARD_FAB2(SCH_1):BMC_M_BG0

120R2F-GP_RCL_GP-120R2F-GP,64.A  I258  R25W9
   1    GND      1 @BASEBOARD_FAB2_LIB.BASEBOARD_FAB2(SCH_1):GND
   2 BMC_M_BA0      2 @BASEBOARD_FAB2_LIB.BASEBOARD_FAB2(SCH_1):BMC_M_BA0

120R2F-GP_RCL_GP-120R2F-GP,64.A  I259  R25W10
   1    GND      1 @BASEBOARD_FAB2_LIB.BASEBOARD_FAB2(SCH_1):GND
   2 BMC_M_BA1      2 @BASEBOARD_FAB2_LIB.BASEBOARD_FAB2(SCH_1):BMC_M_BA1

120R2F-GP_RCL_GP-120R2F-GP,64.A  I260  R25W13
   1    GND      1 @BASEBOARD_FAB2_LIB.BASEBOARD_FAB2(SCH_1):GND
   2 BMC_M_A1      2 @BASEBOARD_FAB2_LIB.BASEBOARD_FAB2(SCH_1):BMC_M_A1

120R2F-GP_RCL_GP-120R2F-GP,64.A  I261  R25W16
   1    GND      1 @BASEBOARD_FAB2_LIB.BASEBOARD_FAB2(SCH_1):GND
   2 BMC_M_A4      2 @BASEBOARD_FAB2_LIB.BASEBOARD_FAB2(SCH_1):BMC_M_A4

120R2F-GP_RCL_GP-120R2F-GP,64.A  I262  R25W15
   1    GND      1 @BASEBOARD_FAB2_LIB.BASEBOARD_FAB2(SCH_1):GND
   2 BMC_M_A3      2 @BASEBOARD_FAB2_LIB.BASEBOARD_FAB2(SCH_1):BMC_M_A3

120R2F-GP_RCL_GP-120R2F-GP,64.A  I263  R25W14
   1    GND      1 @BASEBOARD_FAB2_LIB.BASEBOARD_FAB2(SCH_1):GND
   2 BMC_M_A2      2 @BASEBOARD_FAB2_LIB.BASEBOARD_FAB2(SCH_1):BMC_M_A2

120R2F-GP_RCL_GP-120R2F-GP,64.A  I264  R25W17
   1    GND      1 @BASEBOARD_FAB2_LIB.BASEBOARD_FAB2(SCH_1):GND
   2 BMC_M_A5      2 @BASEBOARD_FAB2_LIB.BASEBOARD_FAB2(SCH_1):BMC_M_A5

120R2F-GP_RCL_GP-120R2F-GP,64.A  I265  R25W18
   1    GND      1 @BASEBOARD_FAB2_LIB.BASEBOARD_FAB2(SCH_1):GND
   2 BMC_M_A6      2 @BASEBOARD_FAB2_LIB.BASEBOARD_FAB2(SCH_1):BMC_M_A6

120R2F-GP_RCL_GP-120R2F-GP,64.A  I266  R25W20
   1    GND      1 @BASEBOARD_FAB2_LIB.BASEBOARD_FAB2(SCH_1):GND
   2 BMC_M_A8      2 @BASEBOARD_FAB2_LIB.BASEBOARD_FAB2(SCH_1):BMC_M_A8

120R2F-GP_RCL_GP-120R2F-GP,64.A  I267  R25W19
   1    GND      1 @BASEBOARD_FAB2_LIB.BASEBOARD_FAB2(SCH_1):GND
   2 BMC_M_A7      2 @BASEBOARD_FAB2_LIB.BASEBOARD_FAB2(SCH_1):BMC_M_A7

120R2F-GP_RCL_GP-120R2F-GP,64.A  I268  R25W24
   1    GND      1 @BASEBOARD_FAB2_LIB.BASEBOARD_FAB2(SCH_1):GND
   2 BMC_M_A12      2 @BASEBOARD_FAB2_LIB.BASEBOARD_FAB2(SCH_1):BMC_M_A12

120R2F-GP_RCL_GP-120R2F-GP,64.A  I269  R25W23
   1    GND      1 @BASEBOARD_FAB2_LIB.BASEBOARD_FAB2(SCH_1):GND
   2 BMC_M_A11      2 @BASEBOARD_FAB2_LIB.BASEBOARD_FAB2(SCH_1):BMC_M_A11

120R2F-GP_RCL_GP-120R2F-GP,64.A  I270  R25W22
   1    GND      1 @BASEBOARD_FAB2_LIB.BASEBOARD_FAB2(SCH_1):GND
   2 BMC_M_A10      2 @BASEBOARD_FAB2_LIB.BASEBOARD_FAB2(SCH_1):BMC_M_A10

120R2F-GP_RCL_GP-120R2F-GP,64.A  I271  R25W21
   1    GND      1 @BASEBOARD_FAB2_LIB.BASEBOARD_FAB2(SCH_1):GND
   2 BMC_M_A9      2 @BASEBOARD_FAB2_LIB.BASEBOARD_FAB2(SCH_1):BMC_M_A9

120R2F-GP_RCL_GP-120R2F-GP,64.A  I274  R25W26
   1    GND      1 @BASEBOARD_FAB2_LIB.BASEBOARD_FAB2(SCH_1):GND
   2 BMC_M_MACT_N      2 @BASEBOARD_FAB2_LIB.BASEBOARD_FAB2(SCH_1):BMC_M_MACT_N

120R2F-GP_RCL_GP-120R2F-GP,64.A  I275  R25W25
   1    GND      1 @BASEBOARD_FAB2_LIB.BASEBOARD_FAB2(SCH_1):GND
   2 BMC_M_A13      2 @BASEBOARD_FAB2_LIB.BASEBOARD_FAB2(SCH_1):BMC_M_A13

RES_0402-49.9,1%,1/16W,CHIP,G2A  I278  R1T40
   1 BMC_M_CLK_DP      A @BASEBOARD_FAB2_LIB.BASEBOARD_FAB2(SCH_1):BMC_M_CLK_DP
   2 BMC_M_CLK      B @BASEBOARD_FAB2_LIB.BASEBOARD_FAB2(SCH_1):BMC_M_CLK

RES_0402-49.9,1%,1/16W,CHIP,G2A  I279  R1T28
   1 BMC_M_CLK_DN      A @BASEBOARD_FAB2_LIB.BASEBOARD_FAB2(SCH_1):BMC_M_CLK_DN
   2 BMC_M_CLK      B @BASEBOARD_FAB2_LIB.BASEBOARD_FAB2(SCH_1):BMC_M_CLK


DRAWING: @BASEBOARD_FAB2_LIB.BASEBOARD_FAB2(SCH_1):PAGE150 

RES_0402-4.75K,1%,1/16W,CHIP,GA  I144  R25W95
   1 P3V3_STBY      A @BASEBOARD_FAB2_LIB.BASEBOARD_FAB2(SCH_1):P3V3_STBY
   2 SPI_BMC_BT_CLK      B @BASEBOARD_FAB2_LIB.BASEBOARD_FAB2(SCH_1):SPI_BMC_BT_CLK

RES_0402-4.75K,1%,1/16W,CHIP,GA  I145  R25W96
   1 P3V3_STBY      A @BASEBOARD_FAB2_LIB.BASEBOARD_FAB2(SCH_1):P3V3_STBY
   2 SPI_BMC_BT_DO      B @BASEBOARD_FAB2_LIB.BASEBOARD_FAB2(SCH_1):SPI_BMC_BT_DO

RES_0402-4.75K,1%,1/16W,EMPTY,A  I146  R25W97
   1 P3V3_STBY      A @BASEBOARD_FAB2_LIB.BASEBOARD_FAB2(SCH_1):P3V3_STBY
   2 SPI_BMC_BT_DI      B @BASEBOARD_FAB2_LIB.BASEBOARD_FAB2(SCH_1):SPI_BMC_BT_DI

RES_0402-4.75K,1%,1/16W,EMPTY,A  I175  R25W106
   1 P3V3_STBY      A @BASEBOARD_FAB2_LIB.BASEBOARD_FAB2(SCH_1):P3V3_STBY
   2 RMII_BMC_OCP_TXEN      B @BASEBOARD_FAB2_LIB.BASEBOARD_FAB2(SCH_1):RMII_BMC_OCP_TXEN

RES_0402-4.75K,1%,1/16W,EMPTY,A  I180  R25W111
   1 P3V3_STBY      A @BASEBOARD_FAB2_LIB.BASEBOARD_FAB2(SCH_1):P3V3_STBY
   2 RMII_BMC_PCH_SPRNGVLLE_TXEN      B @BASEBOARD_FAB2_LIB.BASEBOARD_FAB2(SCH_1):RMII_BMC_PCH_SPRNGVLLE_TXEN

RES_0402-3.32K,1%,1/16W,EMPTY,A  I189  R25W116
   1    GND      A @BASEBOARD_FAB2_LIB.BASEBOARD_FAB2(SCH_1):GND
   2 UART_BMC_TXD5      B @BASEBOARD_FAB2_LIB.BASEBOARD_FAB2(SCH_1):UART_BMC_TXD5

RES_0402-4.75K,1%,1/16W,CHIP,GA  I190  R25W107
   1 P3V3_STBY      A @BASEBOARD_FAB2_LIB.BASEBOARD_FAB2(SCH_1):P3V3_STBY
   2 RMII_BMC_OCP_TXD0_R      B @BASEBOARD_FAB2_LIB.BASEBOARD_FAB2(SCH_1):RMII_BMC_OCP_TXD0_R

RES_0402-4.75K,1%,1/16W,EMPTY,A  I191  R25W108
   1 P3V3_STBY      A @BASEBOARD_FAB2_LIB.BASEBOARD_FAB2(SCH_1):P3V3_STBY
   2 RMII_BMC_OCP_TXD1_R      B @BASEBOARD_FAB2_LIB.BASEBOARD_FAB2(SCH_1):RMII_BMC_OCP_TXD1_R

RES_0402-4.75K,1%,1/16W,EMPTY,A  I196  R25W105
   1 P3V3_STBY      A @BASEBOARD_FAB2_LIB.BASEBOARD_FAB2(SCH_1):P3V3_STBY
   2 PU_JTAG_BMC_RTCK      B @BASEBOARD_FAB2_LIB.BASEBOARD_FAB2(SCH_1):PU_JTAG_BMC_RTCK

RES_0402-4.75K,1%,1/16W,CHIP,GA  I199  R25W146
   1    GND      A @BASEBOARD_FAB2_LIB.BASEBOARD_FAB2(SCH_1):GND
   2 RMII_BMC_OCP_TXEN      B @BASEBOARD_FAB2_LIB.BASEBOARD_FAB2(SCH_1):RMII_BMC_OCP_TXEN

RES_0402-4.75K,1%,1/16W,EMPTY,A  I209  R25W98
   1 P3V3_STBY      A @BASEBOARD_FAB2_LIB.BASEBOARD_FAB2(SCH_1):P3V3_STBY
   2 BMC_STRAP_BIT3      B @BASEBOARD_FAB2_LIB.BASEBOARD_FAB2(SCH_1):BMC_STRAP_BIT3

RES_0402-4.75K,1%,1/16W,EMPTY,A  I210  R25W99
   1 P3V3_STBY      A @BASEBOARD_FAB2_LIB.BASEBOARD_FAB2(SCH_1):P3V3_STBY
   2 BMC_STRAP_BIT5      B @BASEBOARD_FAB2_LIB.BASEBOARD_FAB2(SCH_1):BMC_STRAP_BIT5

RES_0402-4.75K,1%,1/16W,CHIP,GA  I211  R25W100
   1 P3V3_STBY      A @BASEBOARD_FAB2_LIB.BASEBOARD_FAB2(SCH_1):P3V3_STBY
   2 GPIOS7      B @BASEBOARD_FAB2_LIB.BASEBOARD_FAB2(SCH_1):GPIOS7

RES_0402-4.75K,1%,1/16W,EMPTY,A  I214  R25W103
   1 P3V3_STBY      A @BASEBOARD_FAB2_LIB.BASEBOARD_FAB2(SCH_1):P3V3_STBY
   2 BMC_STRAP_BIT20      B @BASEBOARD_FAB2_LIB.BASEBOARD_FAB2(SCH_1):BMC_STRAP_BIT20

RES_0402-4.75K,1%,1/16W,CHIP,GA  I215  R25W104
   1 P3V3_STBY      A @BASEBOARD_FAB2_LIB.BASEBOARD_FAB2(SCH_1):P3V3_STBY
   2 BMC_STRAP_BIT27      B @BASEBOARD_FAB2_LIB.BASEBOARD_FAB2(SCH_1):BMC_STRAP_BIT27

RES_0402-4.75K,1%,1/16W,CHIP,GA  I216  R25W148
   1    GND      A @BASEBOARD_FAB2_LIB.BASEBOARD_FAB2(SCH_1):GND
   2 RMII_BMC_OCP_TXD1_R      B @BASEBOARD_FAB2_LIB.BASEBOARD_FAB2(SCH_1):RMII_BMC_OCP_TXD1_R

RES_0402-4.75K,1%,1/16W,EMPTY,A  I228  R25W112
   1 P3V3_STBY      A @BASEBOARD_FAB2_LIB.BASEBOARD_FAB2(SCH_1):P3V3_STBY
   2 RMII_BMC_PCH_SPRNGVLLE_TXD0_R      B @BASEBOARD_FAB2_LIB.BASEBOARD_FAB2(SCH_1):RMII_BMC_PCH_SPRNGVLLE_TXD0_R

RES_0402-4.75K,1%,1/16W,EMPTY,A  I230  R25W113
   1 P3V3_STBY      A @BASEBOARD_FAB2_LIB.BASEBOARD_FAB2(SCH_1):P3V3_STBY
   2 RMII_BMC_PCH_SPRNGVLLE_TXD1_R      B @BASEBOARD_FAB2_LIB.BASEBOARD_FAB2(SCH_1):RMII_BMC_PCH_SPRNGVLLE_TXD1_R

RES_0402-4.75K,1%,1/16W,CHIP,GA  I232  R25W151
   1    GND      A @BASEBOARD_FAB2_LIB.BASEBOARD_FAB2(SCH_1):GND
   2 RMII_BMC_PCH_SPRNGVLLE_TXD1_R      B @BASEBOARD_FAB2_LIB.BASEBOARD_FAB2(SCH_1):RMII_BMC_PCH_SPRNGVLLE_TXD1_R

RES_0402-4.75K,1%,1/16W,EMPTY,A  I218  R25W114
   1 P3V3_STBY      A @BASEBOARD_FAB2_LIB.BASEBOARD_FAB2(SCH_1):P3V3_STBY
   2 TP_RGMII1TXD2_GPIOT4      B @BASEBOARD_FAB2_LIB.BASEBOARD_FAB2(SCH_1):TP_RGMII1TXD2_GPIOT4

RES_0402-4.75K,1%,1/16W,CHIP,GA  I219  R25W149
   1    GND      A @BASEBOARD_FAB2_LIB.BASEBOARD_FAB2(SCH_1):GND
   2 TP_RGMII1TXD2_GPIOT4      B @BASEBOARD_FAB2_LIB.BASEBOARD_FAB2(SCH_1):TP_RGMII1TXD2_GPIOT4

RES_0402-4.75K,1%,1/16W,CHIP,GA  I229  R25W150
   1    GND      A @BASEBOARD_FAB2_LIB.BASEBOARD_FAB2(SCH_1):GND
   2 RMII_BMC_PCH_SPRNGVLLE_TXD0_R      B @BASEBOARD_FAB2_LIB.BASEBOARD_FAB2(SCH_1):RMII_BMC_PCH_SPRNGVLLE_TXD0_R

RES_0402-4.75K,1%,1/16W,EMPTY,A  I233  R25W110
   1 P3V3_STBY      A @BASEBOARD_FAB2_LIB.BASEBOARD_FAB2(SCH_1):P3V3_STBY
   2 TP_RGMII2TXD2_GPIOU2      B @BASEBOARD_FAB2_LIB.BASEBOARD_FAB2(SCH_1):TP_RGMII2TXD2_GPIOU2

RES_0402-4.75K,1%,1/16W,CHIP,GA  I234  R25W152
   1    GND      A @BASEBOARD_FAB2_LIB.BASEBOARD_FAB2(SCH_1):GND
   2 TP_RGMII2TXD2_GPIOU2      B @BASEBOARD_FAB2_LIB.BASEBOARD_FAB2(SCH_1):TP_RGMII2TXD2_GPIOU2

RES_0402-4.75K,1%,1/16W,CHIP,GA  I236  R25W109
   1 P3V3_STBY      A @BASEBOARD_FAB2_LIB.BASEBOARD_FAB2(SCH_1):P3V3_STBY
   2 TP_RGMII2TXD3_GPIOU3      B @BASEBOARD_FAB2_LIB.BASEBOARD_FAB2(SCH_1):TP_RGMII2TXD3_GPIOU3

RES_0402-4.75K,1%,1/16W,EMPTY,A  I239  R25W102
   1 P3V3_STBY      A @BASEBOARD_FAB2_LIB.BASEBOARD_FAB2(SCH_1):P3V3_STBY
   2 BMC_STRAP_BIT18      B @BASEBOARD_FAB2_LIB.BASEBOARD_FAB2(SCH_1):BMC_STRAP_BIT18

RES_0402-3.32K,1%,1/16W,EMPTY,A  I240  R25W156
   1 P3V3_STBY      A @BASEBOARD_FAB2_LIB.BASEBOARD_FAB2(SCH_1):P3V3_STBY
   2 UART_BMC_TXD5      B @BASEBOARD_FAB2_LIB.BASEBOARD_FAB2(SCH_1):UART_BMC_TXD5

RES_0402-4.75K,1%,1/16W,EMPTY,A  I241  R25W101
   1 P3V3_STBY      A @BASEBOARD_FAB2_LIB.BASEBOARD_FAB2(SCH_1):P3V3_STBY
   2 BMC_STRAP_BIT17      B @BASEBOARD_FAB2_LIB.BASEBOARD_FAB2(SCH_1):BMC_STRAP_BIT17

RES_0402-4.75K,1%,1/16W,EMPTY,A  I242  R25W115
   1 P3V3_STBY      A @BASEBOARD_FAB2_LIB.BASEBOARD_FAB2(SCH_1):P3V3_STBY
   2 TP_RGMII1TXD3_GPIOT5      B @BASEBOARD_FAB2_LIB.BASEBOARD_FAB2(SCH_1):TP_RGMII1TXD3_GPIOT5


DRAWING: @BASEBOARD_FAB2_LIB.BASEBOARD_FAB2(SCH_1):PAGE250 

1MR2F-L-GP_SMD-RG1-1MR2F-L-GP,A  I2  R1W6
   1 P3V3_STBY      1 @BASEBOARD_FAB2_LIB.BASEBOARD_FAB2(SCH_1):P3V3_STBY
   2 FM_OCP_MEZZC_PRES_N      2 @BASEBOARD_FAB2_LIB.BASEBOARD_FAB2(SCH_1):FM_OCP_MEZZC_PRES_N

FET_N_DUAL_SMLF-2N7002DW,FET,DA  I3  Q1W4
   2 FM_OCP_MEZZC_PRES_N GATE<0> @BASEBOARD_FAB2_LIB.BASEBOARD_FAB2(SCH_1):FM_OCP_MEZZC_PRES_N
   1    GND SOURCE<0> @BASEBOARD_FAB2_LIB.BASEBOARD_FAB2(SCH_1):GND
   6 FM_OCP_MEZZC_PRES_LVT3_BMC DRAIN<0> @BASEBOARD_FAB2_LIB.BASEBOARD_FAB2(SCH_1):FM_OCP_MEZZC_PRES_LVT3_BMC

RES_0402-10.0K,1%,1/16W,CHIP,GA  I6  R1W7
   1 FM_OCP_MEZZC_PRES_LVT3_BMC      A @BASEBOARD_FAB2_LIB.BASEBOARD_FAB2(SCH_1):FM_OCP_MEZZC_PRES_LVT3_BMC
   2 P3V3_STBY      B @BASEBOARD_FAB2_LIB.BASEBOARD_FAB2(SCH_1):P3V3_STBY

FET_N_DUAL_SMLF-2N7002DW,FET,DA  I8  Q1W4
   5 FM_OCP_MEZZC_PRES_LVT3_BMC GATE<0> @BASEBOARD_FAB2_LIB.BASEBOARD_FAB2(SCH_1):FM_OCP_MEZZC_PRES_LVT3_BMC
   4    GND SOURCE<0> @BASEBOARD_FAB2_LIB.BASEBOARD_FAB2(SCH_1):GND
   3 FM_OCP_MEZZC_PRES_1V05_PCH_N DRAIN<0> @BASEBOARD_FAB2_LIB.BASEBOARD_FAB2(SCH_1):FM_OCP_MEZZC_PRES_1V05_PCH_N

FET_N_DUAL_SMLF-2N7002DW,FET,DA  I12  Q1W2
   5 FM_OCP_MEZZB_PRES_LVT3_BMC GATE<0> @BASEBOARD_FAB2_LIB.BASEBOARD_FAB2(SCH_1):FM_OCP_MEZZB_PRES_LVT3_BMC
   4    GND SOURCE<0> @BASEBOARD_FAB2_LIB.BASEBOARD_FAB2(SCH_1):GND
   3 FM_OCP_MEZZB_PRES_1V05_PCH_N DRAIN<0> @BASEBOARD_FAB2_LIB.BASEBOARD_FAB2(SCH_1):FM_OCP_MEZZB_PRES_1V05_PCH_N

1MR2F-L-GP_SMD-RG1-1MR2F-L-GP,A  I18  R1W1
   1 P3V3_STBY      1 @BASEBOARD_FAB2_LIB.BASEBOARD_FAB2(SCH_1):P3V3_STBY
   2 FM_OCP_MEZZA_PRES_N      2 @BASEBOARD_FAB2_LIB.BASEBOARD_FAB2(SCH_1):FM_OCP_MEZZA_PRES_N

RES_0402-10.0K,1%,1/16W,CHIP,GA  I22  R1W4
   1 FM_OCP_MEZZB_PRES_LVT3_BMC      A @BASEBOARD_FAB2_LIB.BASEBOARD_FAB2(SCH_1):FM_OCP_MEZZB_PRES_LVT3_BMC
   2 P3V3_STBY      B @BASEBOARD_FAB2_LIB.BASEBOARD_FAB2(SCH_1):P3V3_STBY

FET_N_DUAL_SMLF-2N7002DW,FET,DA  I24  Q1W2
   2 FM_OCP_MEZZB_PRES_N GATE<0> @BASEBOARD_FAB2_LIB.BASEBOARD_FAB2(SCH_1):FM_OCP_MEZZB_PRES_N
   1    GND SOURCE<0> @BASEBOARD_FAB2_LIB.BASEBOARD_FAB2(SCH_1):GND
   6 FM_OCP_MEZZB_PRES_LVT3_BMC DRAIN<0> @BASEBOARD_FAB2_LIB.BASEBOARD_FAB2(SCH_1):FM_OCP_MEZZB_PRES_LVT3_BMC

1MR2F-L-GP_SMD-RG1-1MR2F-L-GP,A  I27  R1W3
   1 P3V3_STBY      1 @BASEBOARD_FAB2_LIB.BASEBOARD_FAB2(SCH_1):P3V3_STBY
   2 FM_OCP_MEZZB_PRES_N      2 @BASEBOARD_FAB2_LIB.BASEBOARD_FAB2(SCH_1):FM_OCP_MEZZB_PRES_N

FET_N_SOT23LF-2N7002,FET,C7925A  I29  Q1W1
   1 FM_OCP_MEZZA_PRES_N   GATE @BASEBOARD_FAB2_LIB.BASEBOARD_FAB2(SCH_1):FM_OCP_MEZZA_PRES_N
   2    GND    SRC @BASEBOARD_FAB2_LIB.BASEBOARD_FAB2(SCH_1):GND
   3 FM_OCP_MEZZA_PRES    DRN @BASEBOARD_FAB2_LIB.BASEBOARD_FAB2(SCH_1):FM_OCP_MEZZA_PRES


DRAWING: @BASEBOARD_FAB2_LIB.BASEBOARD_FAB2(SCH_1):PAGE251 

CAP_A_0402V-0.1UF,16V,10%,X7R,A  I1  C10W2
   1 P12V_PUMP      A @BASEBOARD_FAB2_LIB.BASEBOARD_FAB2(SCH_1):P12V_PUMP
   2    GND      B @BASEBOARD_FAB2_LIB.BASEBOARD_FAB2(SCH_1):GND

CAP_0805-10UF,16V,10%,X6S,C953A  I3  C10W1
   1 P12V_PUMP      A @BASEBOARD_FAB2_LIB.BASEBOARD_FAB2(SCH_1):P12V_PUMP
   2    GND      B @BASEBOARD_FAB2_LIB.BASEBOARD_FAB2(SCH_1):GND

RES_0805-0.0,5%,1/8W,CHIP,G221A  I5  R10W5
   1 P12V_FAN      A @BASEBOARD_FAB2_LIB.BASEBOARD_FAB2(SCH_1):P12V_FAN
   2 P12V_PUMP      B @BASEBOARD_FAB2_LIB.BASEBOARD_FAB2(SCH_1):P12V_PUMP

DIODE_SM-SDMK0340L,EMPTY,H7179A  I10  CR10W2
   1 P5V_STBY      C @BASEBOARD_FAB2_LIB.BASEBOARD_FAB2(SCH_1):P5V_STBY
   2 PUMP_PWM_OUT_R      A @BASEBOARD_FAB2_LIB.BASEBOARD_FAB2(SCH_1):PUMP_PWM_OUT_R

RES_0402-4.75K,1%,1/16W,CHIP,GA  I11  R10W3
   1 P5V_STBY      A @BASEBOARD_FAB2_LIB.BASEBOARD_FAB2(SCH_1):P5V_STBY
   2 PUMP_PWM_OUT_R      B @BASEBOARD_FAB2_LIB.BASEBOARD_FAB2(SCH_1):PUMP_PWM_OUT_R

DIODE_SM-SDMK0340L,IC,H71799-0A  I12  CR10W1
   1 PUMP_TACH_D      C @BASEBOARD_FAB2_LIB.BASEBOARD_FAB2(SCH_1):PUMP_TACH_D
   2 PUMP_TACH_R      A @BASEBOARD_FAB2_LIB.BASEBOARD_FAB2(SCH_1):PUMP_TACH_R

RES_0402-100.0,1%,1/16W,CHIP,GA  I13  R10W1
   1 PUMP_TACH0      A @BASEBOARD_FAB2_LIB.BASEBOARD_FAB2(SCH_1):PUMP_TACH0
   2 PUMP_TACH_R      B @BASEBOARD_FAB2_LIB.BASEBOARD_FAB2(SCH_1):PUMP_TACH_R

RES_0402-221,1.0%,1/16W,CHIP,GA  I14  R10W4
   1 PUMP_PWM_OUT_BUF      A @BASEBOARD_FAB2_LIB.BASEBOARD_FAB2(SCH_1):PUMP_PWM_OUT_BUF
   2 PUMP_PWM_OUT_R      B @BASEBOARD_FAB2_LIB.BASEBOARD_FAB2(SCH_1):PUMP_PWM_OUT_R

RES_0402-4.75K,1%,1/16W,CHIP,GA  I15  R10W2
   1 P3V3_STBY      A @BASEBOARD_FAB2_LIB.BASEBOARD_FAB2(SCH_1):P3V3_STBY
   2 PUMP_TACH0      B @BASEBOARD_FAB2_LIB.BASEBOARD_FAB2(SCH_1):PUMP_TACH0

CAP_A_0402V-0.01UF,25V,10%,X7RA  I16  C10W3
   1 PUMP_TACH0      A @BASEBOARD_FAB2_LIB.BASEBOARD_FAB2(SCH_1):PUMP_TACH0
   2    GND      B @BASEBOARD_FAB2_LIB.BASEBOARD_FAB2(SCH_1):GND

TTL1G07_A_SOP-74LVC1G07,IC,C88B  I19  U10W1
   2 PUMP_PWM_OUT      A @BASEBOARD_FAB2_LIB.BASEBOARD_FAB2(SCH_1):PUMP_PWM_OUT
   4 PUMP_PWM_OUT_BUF      Y @BASEBOARD_FAB2_LIB.BASEBOARD_FAB2(SCH_1):PUMP_PWM_OUT_BUF

CAP_A_0402V-0.1UF,16V,10%,X7R,A  I21  C10W4
   1 P3V3_STBY      A @BASEBOARD_FAB2_LIB.BASEBOARD_FAB2(SCH_1):P3V3_STBY
   2    GND      B @BASEBOARD_FAB2_LIB.BASEBOARD_FAB2(SCH_1):GND

CONN6_C74770005_PIP-HDR,C74770A  I25  J1B2
   1    GND    IO1 @BASEBOARD_FAB2_LIB.BASEBOARD_FAB2(SCH_1):GND
   2 P12V_PUMP    IO2 @BASEBOARD_FAB2_LIB.BASEBOARD_FAB2(SCH_1):P12V_PUMP
   3 PUMP_TACH_D    IO3 @BASEBOARD_FAB2_LIB.BASEBOARD_FAB2(SCH_1):PUMP_TACH_D
   4 PUMP_PWM_OUT_R    IO4 @BASEBOARD_FAB2_LIB.BASEBOARD_FAB2(SCH_1):PUMP_PWM_OUT_R
   5 PUMP_TACH1_D    IO5 @BASEBOARD_FAB2_LIB.BASEBOARD_FAB2(SCH_1):PUMP_TACH1_D
   6 TP_PUMP    IO6 @BASEBOARD_FAB2_LIB.BASEBOARD_FAB2(SCH_1):TP_PUMP

DIODE_SM-SDMK0340L,IC,H71799-0A  I26  CR10W3
   1 PUMP_TACH1_D      C @BASEBOARD_FAB2_LIB.BASEBOARD_FAB2(SCH_1):PUMP_TACH1_D
   2 PUMP_TACH1_R      A @BASEBOARD_FAB2_LIB.BASEBOARD_FAB2(SCH_1):PUMP_TACH1_R

RES_0402-100.0,1%,1/16W,CHIP,GA  I27  R10W6
   1 PUMP_TACH1      A @BASEBOARD_FAB2_LIB.BASEBOARD_FAB2(SCH_1):PUMP_TACH1
   2 PUMP_TACH1_R      B @BASEBOARD_FAB2_LIB.BASEBOARD_FAB2(SCH_1):PUMP_TACH1_R

CAP_A_0402V-0.01UF,25V,10%,X7RA  I29  C10W5
   1 PUMP_TACH1      A @BASEBOARD_FAB2_LIB.BASEBOARD_FAB2(SCH_1):PUMP_TACH1
   2    GND      B @BASEBOARD_FAB2_LIB.BASEBOARD_FAB2(SCH_1):GND

RES_0402-4.75K,1%,1/16W,CHIP,GA  I31  R10W7
   1 P3V3_STBY      A @BASEBOARD_FAB2_LIB.BASEBOARD_FAB2(SCH_1):P3V3_STBY
   2 PUMP_TACH1      B @BASEBOARD_FAB2_LIB.BASEBOARD_FAB2(SCH_1):PUMP_TACH1


DRAWING: @BASEBOARD_FAB2_LIB.BASEBOARD_FAB2(SCH_1):PAGE255 

CAP_0402LF-12.0PF,50V,5%,COG,AA  I7  C25W72
   1 BMC_VGA_BLUE      A @BASEBOARD_FAB2_LIB.BASEBOARD_FAB2(SCH_1):BMC_VGA_BLUE
   2    GND      B @BASEBOARD_FAB2_LIB.BASEBOARD_FAB2(SCH_1):GND

CAP_0402LF-12.0PF,50V,5%,COG,AA  I11  C25W73
   1 BMC_VGA_GREEN      A @BASEBOARD_FAB2_LIB.BASEBOARD_FAB2(SCH_1):BMC_VGA_GREEN
   2    GND      B @BASEBOARD_FAB2_LIB.BASEBOARD_FAB2(SCH_1):GND

CAP_0402LF-12.0PF,50V,5%,COG,AA  I12  C25W74
   1 BMC_VGA_RED      A @BASEBOARD_FAB2_LIB.BASEBOARD_FAB2(SCH_1):BMC_VGA_RED
   2    GND      B @BASEBOARD_FAB2_LIB.BASEBOARD_FAB2(SCH_1):GND

CAP_0402LF-12.0PF,50V,5%,COG,AA  I16  C25W77
   1 V_IO_R_J      A @BASEBOARD_FAB2_LIB.BASEBOARD_FAB2(SCH_1):V_IO_R_J
   2    GND      B @BASEBOARD_FAB2_LIB.BASEBOARD_FAB2(SCH_1):GND

CAP_0402LF-12.0PF,50V,5%,COG,AA  I18  C25W76
   1 V_IO_G_J      A @BASEBOARD_FAB2_LIB.BASEBOARD_FAB2(SCH_1):V_IO_G_J
   2    GND      B @BASEBOARD_FAB2_LIB.BASEBOARD_FAB2(SCH_1):GND

CAP_0402LF-12.0PF,50V,5%,COG,AA  I21  C25W75
   1 V_IO_B_J      A @BASEBOARD_FAB2_LIB.BASEBOARD_FAB2(SCH_1):V_IO_B_J
   2    GND      B @BASEBOARD_FAB2_LIB.BASEBOARD_FAB2(SCH_1):GND

RES_0402-150.0,1%,1/16W,CHIP,GA  I22  R25W128
   1 V_IO_R_J      A @BASEBOARD_FAB2_LIB.BASEBOARD_FAB2(SCH_1):V_IO_R_J
   2    GND      B @BASEBOARD_FAB2_LIB.BASEBOARD_FAB2(SCH_1):GND

RES_0402-150.0,1%,1/16W,CHIP,GA  I24  R25W127
   1 V_IO_G_J      A @BASEBOARD_FAB2_LIB.BASEBOARD_FAB2(SCH_1):V_IO_G_J
   2    GND      B @BASEBOARD_FAB2_LIB.BASEBOARD_FAB2(SCH_1):GND

RES_0402-150.0,1%,1/16W,CHIP,GA  I26  R25W126
   1 V_IO_B_J      A @BASEBOARD_FAB2_LIB.BASEBOARD_FAB2(SCH_1):V_IO_B_J
   2    GND      B @BASEBOARD_FAB2_LIB.BASEBOARD_FAB2(SCH_1):GND

RES_0402-4.75K,1%,1/16W,CHIP,GA  I30  R25W131
   1   P3V3      A @BASEBOARD_FAB2_LIB.BASEBOARD_FAB2(SCH_1):P3V3
   2 Q25W1_GATE      B @BASEBOARD_FAB2_LIB.BASEBOARD_FAB2(SCH_1):Q25W1_GATE

RES_0402-4.75K,1%,1/16W,CHIP,GA  I31  R25W132
   1 P5V_VGA_D      A @BASEBOARD_FAB2_LIB.BASEBOARD_FAB2(SCH_1):P5V_VGA_D
   2 I2C_BMC_VGA_DDC_SCL_G      B @BASEBOARD_FAB2_LIB.BASEBOARD_FAB2(SCH_1):I2C_BMC_VGA_DDC_SCL_G

RES_0402-33.2,1%,1/16W,CHIP,G2A  I34  R25W133
   1 I2C_BMC_VGA_DDC_SCL_G      A @BASEBOARD_FAB2_LIB.BASEBOARD_FAB2(SCH_1):I2C_BMC_VGA_DDC_SCL_G
   2 V_IBMC_5V_DDC_SCL_J      B @BASEBOARD_FAB2_LIB.BASEBOARD_FAB2(SCH_1):V_IBMC_5V_DDC_SCL_J

CAP_0402LF-100.0PF,50V,5%,COG,A  I35  C25W78
   1 V_IBMC_5V_DDC_SCL_J      A @BASEBOARD_FAB2_LIB.BASEBOARD_FAB2(SCH_1):V_IBMC_5V_DDC_SCL_J
   2    GND      B @BASEBOARD_FAB2_LIB.BASEBOARD_FAB2(SCH_1):GND

RES_0402-33.2,1%,1/16W,CHIP,G2A  I38  R25W136
   1 I2C_BMC_VGA_DDC_SDA_G      A @BASEBOARD_FAB2_LIB.BASEBOARD_FAB2(SCH_1):I2C_BMC_VGA_DDC_SDA_G
   2 V_IBMC_5V_DDC_SDA_J      B @BASEBOARD_FAB2_LIB.BASEBOARD_FAB2(SCH_1):V_IBMC_5V_DDC_SDA_J

CAP_0402LF-100.0PF,50V,5%,COG,A  I39  C25W79
   1 V_IBMC_5V_DDC_SDA_J      A @BASEBOARD_FAB2_LIB.BASEBOARD_FAB2(SCH_1):V_IBMC_5V_DDC_SDA_J
   2    GND      B @BASEBOARD_FAB2_LIB.BASEBOARD_FAB2(SCH_1):GND

RES_0402-4.75K,1%,1/16W,CHIP,GA  I43  R25W134
   1   P3V3      A @BASEBOARD_FAB2_LIB.BASEBOARD_FAB2(SCH_1):P3V3
   2 Q25W2_GATE      B @BASEBOARD_FAB2_LIB.BASEBOARD_FAB2(SCH_1):Q25W2_GATE

RES_0402-4.75K,1%,1/16W,CHIP,GA  I44  R25W135
   1 P5V_VGA_D      A @BASEBOARD_FAB2_LIB.BASEBOARD_FAB2(SCH_1):P5V_VGA_D
   2 I2C_BMC_VGA_DDC_SDA_G      B @BASEBOARD_FAB2_LIB.BASEBOARD_FAB2(SCH_1):I2C_BMC_VGA_DDC_SDA_G

RES_0402-33.2,1%,1/16W,CHIP,G2A  I49  R25W138
   1 VGA_REAR_HSYNC_S      A @BASEBOARD_FAB2_LIB.BASEBOARD_FAB2(SCH_1):VGA_REAR_HSYNC_S
   2 V_IO_HSYNC_J      B @BASEBOARD_FAB2_LIB.BASEBOARD_FAB2(SCH_1):V_IO_HSYNC_J

RES_0402-33.2,1%,1/16W,CHIP,G2A  I59  R25W139
   1 VGA_REAR_VSYNC_S      A @BASEBOARD_FAB2_LIB.BASEBOARD_FAB2(SCH_1):VGA_REAR_VSYNC_S
   2 V_IO_VSYNC_J      B @BASEBOARD_FAB2_LIB.BASEBOARD_FAB2(SCH_1):V_IO_VSYNC_J

CAP_0402LF-10.0PF,50V,5%,COG,AA  I60  C25W81
   1 V_IO_HSYNC_J      A @BASEBOARD_FAB2_LIB.BASEBOARD_FAB2(SCH_1):V_IO_HSYNC_J
   2    GND      B @BASEBOARD_FAB2_LIB.BASEBOARD_FAB2(SCH_1):GND

CAP_0402LF-10.0PF,50V,5%,COG,AA  I62  C25W82
   1 V_IO_VSYNC_J      A @BASEBOARD_FAB2_LIB.BASEBOARD_FAB2(SCH_1):V_IO_VSYNC_J
   2    GND      B @BASEBOARD_FAB2_LIB.BASEBOARD_FAB2(SCH_1):GND

CAP_A_0402V-0.1UF,16V,10%,X7R,A  I74  C25P83
   1 P5V_VGA      A @BASEBOARD_FAB2_LIB.BASEBOARD_FAB2(SCH_1):P5V_VGA
   2    GND      B @BASEBOARD_FAB2_LIB.BASEBOARD_FAB2(SCH_1):GND

IND-68NH-15-GP_DISCRET-GC1-INDA  I76  L25W1
   1 BMC_VGA_BLUE      1 @BASEBOARD_FAB2_LIB.BASEBOARD_FAB2(SCH_1):BMC_VGA_BLUE
   2 V_IO_B_J      2 @BASEBOARD_FAB2_LIB.BASEBOARD_FAB2(SCH_1):V_IO_B_J

IND-68NH-15-GP_DISCRET-GC1-INDA  I77  L25W2
   1 BMC_VGA_GREEN      1 @BASEBOARD_FAB2_LIB.BASEBOARD_FAB2(SCH_1):BMC_VGA_GREEN
   2 V_IO_G_J      2 @BASEBOARD_FAB2_LIB.BASEBOARD_FAB2(SCH_1):V_IO_G_J

IND-68NH-15-GP_DISCRET-GC1-INDA  I78  L25W3
   1 BMC_VGA_RED      1 @BASEBOARD_FAB2_LIB.BASEBOARD_FAB2(SCH_1):BMC_VGA_RED
   2 V_IO_R_J      2 @BASEBOARD_FAB2_LIB.BASEBOARD_FAB2(SCH_1):V_IO_R_J

POLYSW-D5A6V-2-GP-U_DISCRET-GAA  I89  F25W1
   1 P5V_VGA      1 @BASEBOARD_FAB2_LIB.BASEBOARD_FAB2(SCH_1):P5V_VGA
   2 P5V_VGA_D      2 @BASEBOARD_FAB2_LIB.BASEBOARD_FAB2(SCH_1):P5V_VGA_D

FET_N_DUAL_SMLF-2N7002DW,FET,DA  I95  Q25W4
   2 Q25W1_GATE GATE<0> @BASEBOARD_FAB2_LIB.BASEBOARD_FAB2(SCH_1):Q25W1_GATE
   1 I2C_BMC_VGA_DDC_SCL SOURCE<0> @BASEBOARD_FAB2_LIB.BASEBOARD_FAB2(SCH_1):I2C_BMC_VGA_DDC_SCL
   6 I2C_BMC_VGA_DDC_SCL_G DRAIN<0> @BASEBOARD_FAB2_LIB.BASEBOARD_FAB2(SCH_1):I2C_BMC_VGA_DDC_SCL_G

FET_N_DUAL_SMLF-2N7002DW,FET,DA  I96  Q25W4
   5 Q25W2_GATE GATE<0> @BASEBOARD_FAB2_LIB.BASEBOARD_FAB2(SCH_1):Q25W2_GATE
   4 I2C_BMC_VGA_DDC_SDA SOURCE<0> @BASEBOARD_FAB2_LIB.BASEBOARD_FAB2(SCH_1):I2C_BMC_VGA_DDC_SDA
   3 I2C_BMC_VGA_DDC_SDA_G DRAIN<0> @BASEBOARD_FAB2_LIB.BASEBOARD_FAB2(SCH_1):I2C_BMC_VGA_DDC_SDA_G

U74AHCT1G125G-AL5-R-GP-U_TTL-GA  I111  U25W7
   1    GND    OE# @BASEBOARD_FAB2_LIB.BASEBOARD_FAB2(SCH_1):GND
   2 BMC_VGA_HSYNC      A @BASEBOARD_FAB2_LIB.BASEBOARD_FAB2(SCH_1):BMC_VGA_HSYNC
   3    GND    GND @BASEBOARD_FAB2_LIB.BASEBOARD_FAB2(SCH_1):GND
   4 VGA_REAR_HSYNC_S      Y @BASEBOARD_FAB2_LIB.BASEBOARD_FAB2(SCH_1):VGA_REAR_HSYNC_S
   5 P5V_VGA_D    VCC @BASEBOARD_FAB2_LIB.BASEBOARD_FAB2(SCH_1):P5V_VGA_D

U74AHCT1G125G-AL5-R-GP-U_TTL-GA  I112  U25W8
   1    GND    OE# @BASEBOARD_FAB2_LIB.BASEBOARD_FAB2(SCH_1):GND
   2 BMC_VGA_VSYNC      A @BASEBOARD_FAB2_LIB.BASEBOARD_FAB2(SCH_1):BMC_VGA_VSYNC
   3    GND    GND @BASEBOARD_FAB2_LIB.BASEBOARD_FAB2(SCH_1):GND
   4 VGA_REAR_VSYNC_S      Y @BASEBOARD_FAB2_LIB.BASEBOARD_FAB2(SCH_1):VGA_REAR_VSYNC_S
   5 P5V_VGA_D    VCC @BASEBOARD_FAB2_LIB.BASEBOARD_FAB2(SCH_1):P5V_VGA_D

CAP_A_0402V-0.1UF,16V,10%,X7R,A  I118  C25W90
   1 P5V_VGA_D      A @BASEBOARD_FAB2_LIB.BASEBOARD_FAB2(SCH_1):P5V_VGA_D
   2    GND      B @BASEBOARD_FAB2_LIB.BASEBOARD_FAB2(SCH_1):GND

RB551V30-GP_DISCRET-G-RB551V30A  I128  D25W8
   K P5V_VGA_D CATHODE @BASEBOARD_FAB2_LIB.BASEBOARD_FAB2(SCH_1):P5V_VGA_D
   A    P5V  ANODE @BASEBOARD_FAB2_LIB.BASEBOARD_FAB2(SCH_1):P5V

DIODEAC_DUAL_ARRAY_SM9-ESD3V3UA  I129  CR25W1
   1 V_IO_B_J    AC0 @BASEBOARD_FAB2_LIB.BASEBOARD_FAB2(SCH_1):V_IO_B_J
   2 V_IO_G_J    AC1 @BASEBOARD_FAB2_LIB.BASEBOARD_FAB2(SCH_1):V_IO_G_J
   4 V_IO_R_J    AC2 @BASEBOARD_FAB2_LIB.BASEBOARD_FAB2(SCH_1):V_IO_R_J
   5     NC    AC3     NC
   3    GND GND<0> @BASEBOARD_FAB2_LIB.BASEBOARD_FAB2(SCH_1):GND
   9 V_IO_B_J   OUT0 @BASEBOARD_FAB2_LIB.BASEBOARD_FAB2(SCH_1):V_IO_B_J
   8 V_IO_G_J   OUT1 @BASEBOARD_FAB2_LIB.BASEBOARD_FAB2(SCH_1):V_IO_G_J
   7 V_IO_R_J   OUT2 @BASEBOARD_FAB2_LIB.BASEBOARD_FAB2(SCH_1):V_IO_R_J
   6     NC   OUT3     NC

DIODEAC_DUAL_ARRAY_SM9-ESD3V3UA  I131  CR25W2
   1 V_IBMC_5V_DDC_SDA_J    AC0 @BASEBOARD_FAB2_LIB.BASEBOARD_FAB2(SCH_1):V_IBMC_5V_DDC_SDA_J
   2 V_IBMC_5V_DDC_SCL_J    AC1 @BASEBOARD_FAB2_LIB.BASEBOARD_FAB2(SCH_1):V_IBMC_5V_DDC_SCL_J
   4 V_IO_VSYNC_J    AC2 @BASEBOARD_FAB2_LIB.BASEBOARD_FAB2(SCH_1):V_IO_VSYNC_J
   5 V_IO_HSYNC_J    AC3 @BASEBOARD_FAB2_LIB.BASEBOARD_FAB2(SCH_1):V_IO_HSYNC_J
   3    GND GND<0> @BASEBOARD_FAB2_LIB.BASEBOARD_FAB2(SCH_1):GND
   9 V_IBMC_5V_DDC_SDA_J   OUT0 @BASEBOARD_FAB2_LIB.BASEBOARD_FAB2(SCH_1):V_IBMC_5V_DDC_SDA_J
   8 V_IBMC_5V_DDC_SCL_J   OUT1 @BASEBOARD_FAB2_LIB.BASEBOARD_FAB2(SCH_1):V_IBMC_5V_DDC_SCL_J
   7 V_IO_VSYNC_J   OUT2 @BASEBOARD_FAB2_LIB.BASEBOARD_FAB2(SCH_1):V_IO_VSYNC_J
   6 V_IO_HSYNC_J   OUT3 @BASEBOARD_FAB2_LIB.BASEBOARD_FAB2(SCH_1):V_IO_HSYNC_J

CAP_A_0402V-0.1UF,16V,10%,X7R,A  I134  C25P80
   1 P5V_VGA_D      A @BASEBOARD_FAB2_LIB.BASEBOARD_FAB2(SCH_1):P5V_VGA_D
   2    GND      B @BASEBOARD_FAB2_LIB.BASEBOARD_FAB2(SCH_1):GND

SMC-CON13-GP_CONN-GC2-SMC-CON1A  I136  J25W1
   1 V_IO_R_J      1 @BASEBOARD_FAB2_LIB.BASEBOARD_FAB2(SCH_1):V_IO_R_J
   2    GND      2 @BASEBOARD_FAB2_LIB.BASEBOARD_FAB2(SCH_1):GND
   3 V_IO_G_J      3 @BASEBOARD_FAB2_LIB.BASEBOARD_FAB2(SCH_1):V_IO_G_J
   4    GND      4 @BASEBOARD_FAB2_LIB.BASEBOARD_FAB2(SCH_1):GND
   5 V_IO_B_J      5 @BASEBOARD_FAB2_LIB.BASEBOARD_FAB2(SCH_1):V_IO_B_J
   6    GND      6 @BASEBOARD_FAB2_LIB.BASEBOARD_FAB2(SCH_1):GND
   7 V_IO_VSYNC_J      7 @BASEBOARD_FAB2_LIB.BASEBOARD_FAB2(SCH_1):V_IO_VSYNC_J
   8    GND      8 @BASEBOARD_FAB2_LIB.BASEBOARD_FAB2(SCH_1):GND
   9 V_IO_HSYNC_J      9 @BASEBOARD_FAB2_LIB.BASEBOARD_FAB2(SCH_1):V_IO_HSYNC_J
  10    GND     10 @BASEBOARD_FAB2_LIB.BASEBOARD_FAB2(SCH_1):GND
  11 V_IBMC_5V_DDC_SDA_J     11 @BASEBOARD_FAB2_LIB.BASEBOARD_FAB2(SCH_1):V_IBMC_5V_DDC_SDA_J
  12 V_IBMC_5V_DDC_SCL_J     12 @BASEBOARD_FAB2_LIB.BASEBOARD_FAB2(SCH_1):V_IBMC_5V_DDC_SCL_J
  13 P5V_VGA     13 @BASEBOARD_FAB2_LIB.BASEBOARD_FAB2(SCH_1):P5V_VGA
PTH1    GND   PTH1 @BASEBOARD_FAB2_LIB.BASEBOARD_FAB2(SCH_1):GND
PTH2    GND   PTH2 @BASEBOARD_FAB2_LIB.BASEBOARD_FAB2(SCH_1):GND


DRAWING: @BASEBOARD_FAB2_LIB.BASEBOARD_FAB2(SCH_1):PAGE253 

DIODEAC_DUAL_ARRAY_SM9-ESD3V3UA  I5  CR30W1
   1 USB3_P01_FB_TXN    AC0 @BASEBOARD_FAB2_LIB.BASEBOARD_FAB2(SCH_1):USB3_P01_FB_TXN
   2 USB3_P01_FB_TXP    AC1 @BASEBOARD_FAB2_LIB.BASEBOARD_FAB2(SCH_1):USB3_P01_FB_TXP
   4 USB3_P01_FB_RXN    AC2 @BASEBOARD_FAB2_LIB.BASEBOARD_FAB2(SCH_1):USB3_P01_FB_RXN
   5 USB3_P01_FB_RXP    AC3 @BASEBOARD_FAB2_LIB.BASEBOARD_FAB2(SCH_1):USB3_P01_FB_RXP
   3    GND GND<0> @BASEBOARD_FAB2_LIB.BASEBOARD_FAB2(SCH_1):GND
   9 USB3_P01_FB_TXN   OUT0 @BASEBOARD_FAB2_LIB.BASEBOARD_FAB2(SCH_1):USB3_P01_FB_TXN
   8 USB3_P01_FB_TXP   OUT1 @BASEBOARD_FAB2_LIB.BASEBOARD_FAB2(SCH_1):USB3_P01_FB_TXP
   7 USB3_P01_FB_RXN   OUT2 @BASEBOARD_FAB2_LIB.BASEBOARD_FAB2(SCH_1):USB3_P01_FB_RXN
   6 USB3_P01_FB_RXP   OUT3 @BASEBOARD_FAB2_LIB.BASEBOARD_FAB2(SCH_1):USB3_P01_FB_RXP

CHOKE_4PIN_SM_B-67 OHM,EMPTY,7A  I11  L30W2
   1 USB3_P01_C_TXP      1 @BASEBOARD_FAB2_LIB.BASEBOARD_FAB2(SCH_1):USB3_P01_C_TXP
   2 USB3_P01_FB_TXP      2 @BASEBOARD_FAB2_LIB.BASEBOARD_FAB2(SCH_1):USB3_P01_FB_TXP
   3 USB3_P01_FB_TXN      3 @BASEBOARD_FAB2_LIB.BASEBOARD_FAB2(SCH_1):USB3_P01_FB_TXN
   4 USB3_P01_C_TXN      4 @BASEBOARD_FAB2_LIB.BASEBOARD_FAB2(SCH_1):USB3_P01_C_TXN

RES_0402-0.0,5%,1/16W,CHIP,G21A  I12  R30W2
   1 USB3_P01_RXP      A @BASEBOARD_FAB2_LIB.BASEBOARD_FAB2(SCH_1):USB3_P01_RXP
   2 USB3_P01_FB_RXP      B @BASEBOARD_FAB2_LIB.BASEBOARD_FAB2(SCH_1):USB3_P01_FB_RXP

RES_0402-0.0,5%,1/16W,CHIP,G21A  I13  R30W1
   1 USB3_P01_RXN      A @BASEBOARD_FAB2_LIB.BASEBOARD_FAB2(SCH_1):USB3_P01_RXN
   2 USB3_P01_FB_RXN      B @BASEBOARD_FAB2_LIB.BASEBOARD_FAB2(SCH_1):USB3_P01_FB_RXN

RES_0402-0.0,5%,1/16W,CHIP,G21A  I14  R30W4
   1 USB3_P01_C_TXP      A @BASEBOARD_FAB2_LIB.BASEBOARD_FAB2(SCH_1):USB3_P01_C_TXP
   2 USB3_P01_FB_TXP      B @BASEBOARD_FAB2_LIB.BASEBOARD_FAB2(SCH_1):USB3_P01_FB_TXP

RES_0402-0.0,5%,1/16W,CHIP,G21A  I15  R30W3
   1 USB3_P01_C_TXN      A @BASEBOARD_FAB2_LIB.BASEBOARD_FAB2(SCH_1):USB3_P01_C_TXN
   2 USB3_P01_FB_TXN      B @BASEBOARD_FAB2_LIB.BASEBOARD_FAB2(SCH_1):USB3_P01_FB_TXN

CHOKE_4PIN_SM_B-67 OHM,EMPTY,7A  I16  L30W1
   1 USB3_P01_RXP      1 @BASEBOARD_FAB2_LIB.BASEBOARD_FAB2(SCH_1):USB3_P01_RXP
   2 USB3_P01_FB_RXP      2 @BASEBOARD_FAB2_LIB.BASEBOARD_FAB2(SCH_1):USB3_P01_FB_RXP
   3 USB3_P01_FB_RXN      3 @BASEBOARD_FAB2_LIB.BASEBOARD_FAB2(SCH_1):USB3_P01_FB_RXN
   4 USB3_P01_RXN      4 @BASEBOARD_FAB2_LIB.BASEBOARD_FAB2(SCH_1):USB3_P01_RXN

CAP_A_0402V-0.1UF,16V,10%,X7R,A  I19  C30W2
   1 USB3_P01_TXP      A @BASEBOARD_FAB2_LIB.BASEBOARD_FAB2(SCH_1):USB3_P01_TXP
   2 USB3_P01_C_TXP      B @BASEBOARD_FAB2_LIB.BASEBOARD_FAB2(SCH_1):USB3_P01_C_TXP

CAP_A_0402V-0.1UF,16V,10%,X7R,A  I20  C30W1
   1 USB3_P01_TXN      A @BASEBOARD_FAB2_LIB.BASEBOARD_FAB2(SCH_1):USB3_P01_TXN
   2 USB3_P01_C_TXN      B @BASEBOARD_FAB2_LIB.BASEBOARD_FAB2(SCH_1):USB3_P01_C_TXN

SKT-USB32-8-GP_SOCKET-G4-SKT-UA  I26  J30W1
  A2 USB3_P01_FB_TXP SSTXP1 @BASEBOARD_FAB2_LIB.BASEBOARD_FAB2(SCH_1):USB3_P01_FB_TXP
  A3 USB3_P01_FB_TXN SSTXN1 @BASEBOARD_FAB2_LIB.BASEBOARD_FAB2(SCH_1):USB3_P01_FB_TXN
  A5     NC    CC1     NC
  A6     NC    DP1     NC
  A7     NC    DN1     NC
  B5     NC    CC2     NC
  B6     NC    DP2     NC
  B7     NC    DN2     NC
 B10 USB3_P01_FB_RXN SSRXN1 @BASEBOARD_FAB2_LIB.BASEBOARD_FAB2(SCH_1):USB3_P01_FB_RXN
 B11 USB3_P01_FB_RXP SSRXP1 @BASEBOARD_FAB2_LIB.BASEBOARD_FAB2(SCH_1):USB3_P01_FB_RXP
  A4 P5V_STBY_USBC VBUS<0> @BASEBOARD_FAB2_LIB.BASEBOARD_FAB2(SCH_1):P5V_STBY_USBC
  A9 P5V_STBY_USBC VBUS<1> @BASEBOARD_FAB2_LIB.BASEBOARD_FAB2(SCH_1):P5V_STBY_USBC
  B4 P5V_STBY_USBC VBUS<2> @BASEBOARD_FAB2_LIB.BASEBOARD_FAB2(SCH_1):P5V_STBY_USBC
  B9 P5V_STBY_USBC VBUS<3> @BASEBOARD_FAB2_LIB.BASEBOARD_FAB2(SCH_1):P5V_STBY_USBC
 A11     NC SSRXP2     NC
 A10     NC SSRXN2     NC
  B2     NC SSTXP2     NC
  B3     NC SSTXN2     NC
 NP1     NC    NP1     NC
 NP2     NC    NP2     NC
  A8     NC   SBU1     NC
  B8     NC   SBU2     NC
PTH1    GND   PTH1 @BASEBOARD_FAB2_LIB.BASEBOARD_FAB2(SCH_1):GND
PTH2    GND   PTH2 @BASEBOARD_FAB2_LIB.BASEBOARD_FAB2(SCH_1):GND
PTH3    GND   PTH3 @BASEBOARD_FAB2_LIB.BASEBOARD_FAB2(SCH_1):GND
PTH4    GND   PTH4 @BASEBOARD_FAB2_LIB.BASEBOARD_FAB2(SCH_1):GND
PTH5    GND   PTH5 @BASEBOARD_FAB2_LIB.BASEBOARD_FAB2(SCH_1):GND
PTH6    GND   PTH6 @BASEBOARD_FAB2_LIB.BASEBOARD_FAB2(SCH_1):GND
PTH7    GND   PTH7 @BASEBOARD_FAB2_LIB.BASEBOARD_FAB2(SCH_1):GND
PTH8    GND   PTH8 @BASEBOARD_FAB2_LIB.BASEBOARD_FAB2(SCH_1):GND
  A1    GND GND<0> @BASEBOARD_FAB2_LIB.BASEBOARD_FAB2(SCH_1):GND
 A12    GND GND<1> @BASEBOARD_FAB2_LIB.BASEBOARD_FAB2(SCH_1):GND
  B1    GND GND<2> @BASEBOARD_FAB2_LIB.BASEBOARD_FAB2(SCH_1):GND
 B12    GND GND<3> @BASEBOARD_FAB2_LIB.BASEBOARD_FAB2(SCH_1):GND

SC22U16V5MX-4-GP_SMD-BCG5-SC22A  I35  C30W3
   1 P5V_STBY_USBC      1 @BASEBOARD_FAB2_LIB.BASEBOARD_FAB2(SCH_1):P5V_STBY_USBC
   2    GND      2 @BASEBOARD_FAB2_LIB.BASEBOARD_FAB2(SCH_1):GND

SC22U16V5MX-4-GP_SMD-BCG5-SC22A  I36  C30W4
   1 P5V_STBY_USBC      1 @BASEBOARD_FAB2_LIB.BASEBOARD_FAB2(SCH_1):P5V_STBY_USBC
   2    GND      2 @BASEBOARD_FAB2_LIB.BASEBOARD_FAB2(SCH_1):GND

SC22U16V5MX-4-GP_SMD-BCG5-SC22A  I37  C30W6
   1 P5V_STBY_USBC      1 @BASEBOARD_FAB2_LIB.BASEBOARD_FAB2(SCH_1):P5V_STBY_USBC
   2    GND      2 @BASEBOARD_FAB2_LIB.BASEBOARD_FAB2(SCH_1):GND

SC22U16V5MX-4-GP_SMD-BCG5-SC22A  I38  C30W5
   1 P5V_STBY_USBC      1 @BASEBOARD_FAB2_LIB.BASEBOARD_FAB2(SCH_1):P5V_STBY_USBC
   2    GND      2 @BASEBOARD_FAB2_LIB.BASEBOARD_FAB2(SCH_1):GND

SC22U16V5MX-4-GP_SMD-BCG5-SC22A  I40  C30W9
   1 P5V_STBY_USBC      1 @BASEBOARD_FAB2_LIB.BASEBOARD_FAB2(SCH_1):P5V_STBY_USBC
   2    GND      2 @BASEBOARD_FAB2_LIB.BASEBOARD_FAB2(SCH_1):GND

SC22U16V5MX-4-GP_SMD-BCG5-SC22A  I41  C30W8
   1 P5V_STBY_USBC      1 @BASEBOARD_FAB2_LIB.BASEBOARD_FAB2(SCH_1):P5V_STBY_USBC
   2    GND      2 @BASEBOARD_FAB2_LIB.BASEBOARD_FAB2(SCH_1):GND

SC22U16V5MX-4-GP_SMD-BCG5-SC22A  I42  C30W7
   1 P5V_STBY_USBC      1 @BASEBOARD_FAB2_LIB.BASEBOARD_FAB2(SCH_1):P5V_STBY_USBC
   2    GND      2 @BASEBOARD_FAB2_LIB.BASEBOARD_FAB2(SCH_1):GND

POLYSW-1D1A6V-2-GP-U_DISCRET-GA  I44  F30W1
   1 P5V_STBY      1 @BASEBOARD_FAB2_LIB.BASEBOARD_FAB2(SCH_1):P5V_STBY
   2 P5V_STBY_USBC      2 @BASEBOARD_FAB2_LIB.BASEBOARD_FAB2(SCH_1):P5V_STBY_USBC


DRAWING: @BASEBOARD_FAB2_LIB.BASEBOARD_FAB2(SCH_1):PAGE183 

RES_0402-4.75K,1%,1/16W,CHIP,GA  I3  R9F55
   1 P3V3_STBY      A @BASEBOARD_FAB2_LIB.BASEBOARD_FAB2(SCH_1):P3V3_STBY
   2 FM_UART_ALERT_N      B @BASEBOARD_FAB2_LIB.BASEBOARD_FAB2(SCH_1):FM_UART_ALERT_N


DRAWING: @BASEBOARD_FAB2_LIB.BASEBOARD_FAB2(SCH_1):PAGE215 

RES_0402-10.0,1%,1/16W,CHIP,G2A  I12  R7G9
   1 VSENSE_PVDDQ_ABC_P      A @BASEBOARD_FAB2_LIB.BASEBOARD_FAB2(SCH_1):VSENSE_PVDDQ_ABC_P
   2 VR_PVDDQ_ABC_AVSP      B @BASEBOARD_FAB2_LIB.BASEBOARD_FAB2(SCH_1):VR_PVDDQ_ABC_AVSP

RES_0402-0.0,5%,1/16W,CHIP,G21A  I13  R7F21
   1 FM_PVDDQ_ABC_EN      A @BASEBOARD_FAB2_LIB.BASEBOARD_FAB2(SCH_1):FM_PVDDQ_ABC_EN
   2 VR_PVDDQ_ABC_VREN      B @BASEBOARD_FAB2_LIB.BASEBOARD_FAB2(SCH_1):VR_PVDDQ_ABC_VREN

CAP_0402LF-220PF,50V,10%,X7R,AA  I14  C7G4
   1 VR_PVDDQ_ABC_AVSP      A @BASEBOARD_FAB2_LIB.BASEBOARD_FAB2(SCH_1):VR_PVDDQ_ABC_AVSP
   2 VSENSE_PVDDQ_ABC_N      B @BASEBOARD_FAB2_LIB.BASEBOARD_FAB2(SCH_1):VSENSE_PVDDQ_ABC_N

RES_0402-1.0K,0.1%,1/16W,CHIP,A  I15  RF15
   1 VR_PVDDQ_ABC_AIREF1      A @BASEBOARD_FAB2_LIB.BASEBOARD_FAB2(SCH_1):VR_PVDDQ_ABC_AIREF1
   2 ISENSE_PVDDQ_ABC_PH1_IMON      B @BASEBOARD_FAB2_LIB.BASEBOARD_FAB2(SCH_1):ISENSE_PVDDQ_ABC_PH1_IMON

SC22P50V2JN-4GP_SMD-BCG-SC22P5A  I16  CF15
   1 VR_PVDDQ_ABC_AIREF1      1 @BASEBOARD_FAB2_LIB.BASEBOARD_FAB2(SCH_1):VR_PVDDQ_ABC_AIREF1
   2 ISENSE_PVDDQ_ABC_PH1_IMON      2 @BASEBOARD_FAB2_LIB.BASEBOARD_FAB2(SCH_1):ISENSE_PVDDQ_ABC_PH1_IMON

CAP_0402LF-220PF,50V,10%,X7R,AA  I22  C7G3
   1 A_TSENSE_PVDDQ_ABC      A @BASEBOARD_FAB2_LIB.BASEBOARD_FAB2(SCH_1):A_TSENSE_PVDDQ_ABC
   2    GND      B @BASEBOARD_FAB2_LIB.BASEBOARD_FAB2(SCH_1):GND

SC22P50V2JN-4GP_SMD-BCG-SC22P5A  I26  CF16
   1 VR_PVDDQ_ABC_AIREF2      1 @BASEBOARD_FAB2_LIB.BASEBOARD_FAB2(SCH_1):VR_PVDDQ_ABC_AIREF2
   2 ISENSE_PVDDQ_ABC_PH2_IMON      2 @BASEBOARD_FAB2_LIB.BASEBOARD_FAB2(SCH_1):ISENSE_PVDDQ_ABC_PH2_IMON

RES_0402-1.0K,0.1%,1/16W,CHIP,A  I27  RF16
   1 VR_PVDDQ_ABC_AIREF2      A @BASEBOARD_FAB2_LIB.BASEBOARD_FAB2(SCH_1):VR_PVDDQ_ABC_AIREF2
   2 ISENSE_PVDDQ_ABC_PH2_IMON      B @BASEBOARD_FAB2_LIB.BASEBOARD_FAB2(SCH_1):ISENSE_PVDDQ_ABC_PH2_IMON

RES_0402-150.0,1%,1/16W,CHIP,GA  I28  R7G24
   1 SVID_CLK1_CPU0_R      A @BASEBOARD_FAB2_LIB.BASEBOARD_FAB2(SCH_1):SVID_CLK1_CPU0_R
   2 SVID_CLK_PVDDQ_ABC      B @BASEBOARD_FAB2_LIB.BASEBOARD_FAB2(SCH_1):SVID_CLK_PVDDQ_ABC

RES_0402-100.0K,1%,1/16W,EMPTYA  I29  R7F20
   1 P3V3_STBY      A @BASEBOARD_FAB2_LIB.BASEBOARD_FAB2(SCH_1):P3V3_STBY
   2 VR_PVDDQ_ABC_VREN      B @BASEBOARD_FAB2_LIB.BASEBOARD_FAB2(SCH_1):VR_PVDDQ_ABC_VREN

RES_0402-0.0,5%,1/16W,CHIP,G21A  I33  R3T13
   1 P3V3_STBY      A @BASEBOARD_FAB2_LIB.BASEBOARD_FAB2(SCH_1):P3V3_STBY
   2 VR_PVDDQ_ABC_VDD      B @BASEBOARD_FAB2_LIB.BASEBOARD_FAB2(SCH_1):VR_PVDDQ_ABC_VDD

CAP_A_0402V-0.1UF,16V,10%,X7R,A  I34  C7F17
   1 VR_PVDDQ_ABC_VDD      A @BASEBOARD_FAB2_LIB.BASEBOARD_FAB2(SCH_1):VR_PVDDQ_ABC_VDD
   2    GND      B @BASEBOARD_FAB2_LIB.BASEBOARD_FAB2(SCH_1):GND

CAP_A_0402V-1.0UF,6.3V,10%,X6SA  I35  C7F18
   1 VR_PVDDQ_ABC_VDD      A @BASEBOARD_FAB2_LIB.BASEBOARD_FAB2(SCH_1):VR_PVDDQ_ABC_VDD
   2    GND      B @BASEBOARD_FAB2_LIB.BASEBOARD_FAB2(SCH_1):GND

CAP_A_0402V-0.1UF,16V,10%,X7R,A  I38  C7F15
   1 VR_PVDDQ_ABC_VD12      A @BASEBOARD_FAB2_LIB.BASEBOARD_FAB2(SCH_1):VR_PVDDQ_ABC_VD12
   2    GND      B @BASEBOARD_FAB2_LIB.BASEBOARD_FAB2(SCH_1):GND

CAP_A_0402V-1.0UF,6.3V,10%,X6SA  I40  C7F16
   1 VR_PVDDQ_ABC_VD12      A @BASEBOARD_FAB2_LIB.BASEBOARD_FAB2(SCH_1):VR_PVDDQ_ABC_VD12
   2    GND      B @BASEBOARD_FAB2_LIB.BASEBOARD_FAB2(SCH_1):GND

RES_0402-0.0,5%,1/16W,CHIP,G21A  I41  R7G2
   1 SVID_VDIO_PVDDQ_ABC      A @BASEBOARD_FAB2_LIB.BASEBOARD_FAB2(SCH_1):SVID_VDIO_PVDDQ_ABC
   2 SVID_DIO1_CPU0_R      B @BASEBOARD_FAB2_LIB.BASEBOARD_FAB2(SCH_1):SVID_DIO1_CPU0_R

CAP_0402LF-1000PF,50V,10%,X7R,A  I44  C7F14
   1 PWRGD_PVDDQ_ABC_R      A @BASEBOARD_FAB2_LIB.BASEBOARD_FAB2(SCH_1):PWRGD_PVDDQ_ABC_R
   2    GND      B @BASEBOARD_FAB2_LIB.BASEBOARD_FAB2(SCH_1):GND

RES_0402-0.0,5%,1/16W,EMPTY,G2A  I45  R12W26
   1 TP_PVDDQ_ABC_MP1      A @BASEBOARD_FAB2_LIB.BASEBOARD_FAB2(SCH_1):TP_PVDDQ_ABC_MP1
   2 PWRGD_PVDDQ_ABC      B @BASEBOARD_FAB2_LIB.BASEBOARD_FAB2(SCH_1):PWRGD_PVDDQ_ABC

RES_0402-0.0,5%,1/16W,CHIP,G21A  I49  R7G4
   1 SVID_ALERT_PVDDQ_ABC      A @BASEBOARD_FAB2_LIB.BASEBOARD_FAB2(SCH_1):SVID_ALERT_PVDDQ_ABC
   2 SVID_ALERT1_CPU0_R_N      B @BASEBOARD_FAB2_LIB.BASEBOARD_FAB2(SCH_1):SVID_ALERT1_CPU0_R_N

RES_0402-1.00K,1%,1/16W,CHIP,GA  I50  R7F27
   1 P3V3_STBY      A @BASEBOARD_FAB2_LIB.BASEBOARD_FAB2(SCH_1):P3V3_STBY
   2 IRQ_PVDDQ_ABC_VRHOT_LVT3_R_N      B @BASEBOARD_FAB2_LIB.BASEBOARD_FAB2(SCH_1):IRQ_PVDDQ_ABC_VRHOT_LVT3_R_N

RES_0402-1.00K,1%,1/16W,CHIP,GA  I51  R7F22
   1 P3V3_STBY      A @BASEBOARD_FAB2_LIB.BASEBOARD_FAB2(SCH_1):P3V3_STBY
   2 PWRGD_PVDDQ_ABC_R      B @BASEBOARD_FAB2_LIB.BASEBOARD_FAB2(SCH_1):PWRGD_PVDDQ_ABC_R

RES_0402-33.2,1%,1/16W,CHIP,G2A  I53  R7F23
   1 IRQ_PVDDQ_ABC_VRHOT_LVT3_R_N      A @BASEBOARD_FAB2_LIB.BASEBOARD_FAB2(SCH_1):IRQ_PVDDQ_ABC_VRHOT_LVT3_R_N
   2 IRQ_PVDDQ_ABC_VRHOT_LVT3_N      B @BASEBOARD_FAB2_LIB.BASEBOARD_FAB2(SCH_1):IRQ_PVDDQ_ABC_VRHOT_LVT3_N

RES_0402-0.0,5%,1/16W,EMPTY,G2A  I54  R12W27
   1 TP_PVDDQ_ABC_MP2      A @BASEBOARD_FAB2_LIB.BASEBOARD_FAB2(SCH_1):TP_PVDDQ_ABC_MP2
   2 PWRGD_PVDDQ_ABC      B @BASEBOARD_FAB2_LIB.BASEBOARD_FAB2(SCH_1):PWRGD_PVDDQ_ABC

RES_0402-22.1,1.0%,1/16W,CHIP,A  I56  R7F24
   1 PWRGD_PVDDQ_ABC_R      A @BASEBOARD_FAB2_LIB.BASEBOARD_FAB2(SCH_1):PWRGD_PVDDQ_ABC_R
   2 PWRGD_PVDDQ_ABC      B @BASEBOARD_FAB2_LIB.BASEBOARD_FAB2(SCH_1):PWRGD_PVDDQ_ABC

RES_0402-100.0,1%,1/16W,CHIP,GA  I58  R3U2
   1 PVCCIO_CPU0      A @BASEBOARD_FAB2_LIB.BASEBOARD_FAB2(SCH_1):PVCCIO_CPU0
   2 SVID_DIO1_CPU0_R      B @BASEBOARD_FAB2_LIB.BASEBOARD_FAB2(SCH_1):SVID_DIO1_CPU0_R

PXM1310B_QFN-IC,H89186-001  I69  EU7G1
   1     NC  BPWM1     NC
   2     NC DNC<0>     NC
   3     NC  APWM3     NC
   4 VR_PVDDQ_ABC_PWM2  APWM2 @BASEBOARD_FAB2_LIB.BASEBOARD_FAB2(SCH_1):VR_PVDDQ_ABC_PWM2
   5 VR_PVDDQ_ABC_PWM1  APWM1 @BASEBOARD_FAB2_LIB.BASEBOARD_FAB2(SCH_1):VR_PVDDQ_ABC_PWM1
   6 SMB_VR_STBY_LVC3_SDA    SDA @BASEBOARD_FAB2_LIB.BASEBOARD_FAB2(SCH_1):SMB_VR_STBY_LVC3_SDA
   7 SMB_VR_STBY_LVC3_SCL    SCL @BASEBOARD_FAB2_LIB.BASEBOARD_FAB2(SCH_1):SMB_VR_STBY_LVC3_SCL
   8     NC RESET_N     NC
   9 PWRGD_PVDDQ_ABC_R AVRRDY @BASEBOARD_FAB2_LIB.BASEBOARD_FAB2(SCH_1):PWRGD_PVDDQ_ABC_R
  10 VR_PVDDQ_ABC_VREN  AVREN @BASEBOARD_FAB2_LIB.BASEBOARD_FAB2(SCH_1):VR_PVDDQ_ABC_VREN
  11 IRQ_PVDDQ_ABC_VRHOT_LVT3_R_N VRHOT_N @BASEBOARD_FAB2_LIB.BASEBOARD_FAB2(SCH_1):IRQ_PVDDQ_ABC_VRHOT_LVT3_R_N
  12     NC PINALRT_N     NC
  13 PU_VR_PVDDQ_ABC_FAULT1    MP0 @BASEBOARD_FAB2_LIB.BASEBOARD_FAB2(SCH_1):PU_VR_PVDDQ_ABC_FAULT1
  14 TP_PVDDQ_ABC_MP1    MP1 @BASEBOARD_FAB2_LIB.BASEBOARD_FAB2(SCH_1):TP_PVDDQ_ABC_MP1
  15 SVID_CLK_PVDDQ_ABC   VCLK @BASEBOARD_FAB2_LIB.BASEBOARD_FAB2(SCH_1):SVID_CLK_PVDDQ_ABC
  16 SVID_VDIO_PVDDQ_ABC   VDIO @BASEBOARD_FAB2_LIB.BASEBOARD_FAB2(SCH_1):SVID_VDIO_PVDDQ_ABC
  17 SVID_ALERT_PVDDQ_ABC VALRT_N @BASEBOARD_FAB2_LIB.BASEBOARD_FAB2(SCH_1):SVID_ALERT_PVDDQ_ABC
  18 TP_PVDDQ_ABC_MP2    MP2 @BASEBOARD_FAB2_LIB.BASEBOARD_FAB2(SCH_1):TP_PVDDQ_ABC_MP2
  19 VR_PVDDQ_ABC_AVSP  AVSEN @BASEBOARD_FAB2_LIB.BASEBOARD_FAB2(SCH_1):VR_PVDDQ_ABC_AVSP
  20 VSENSE_PVDDQ_ABC_N  AVREF @BASEBOARD_FAB2_LIB.BASEBOARD_FAB2(SCH_1):VSENSE_PVDDQ_ABC_N
  21 VR_PVDDQ_ABC_AIREF1 AIREF1 @BASEBOARD_FAB2_LIB.BASEBOARD_FAB2(SCH_1):VR_PVDDQ_ABC_AIREF1
  22 ISENSE_PVDDQ_ABC_PH1_IMON AISEN1 @BASEBOARD_FAB2_LIB.BASEBOARD_FAB2(SCH_1):ISENSE_PVDDQ_ABC_PH1_IMON
  23 VR_PVDDQ_ABC_AIREF2 AIREF2 @BASEBOARD_FAB2_LIB.BASEBOARD_FAB2(SCH_1):VR_PVDDQ_ABC_AIREF2
  24 ISENSE_PVDDQ_ABC_PH2_IMON AISEN2 @BASEBOARD_FAB2_LIB.BASEBOARD_FAB2(SCH_1):ISENSE_PVDDQ_ABC_PH2_IMON
  25     NC AIREF3     NC
  26     NC AISEN3     NC
  27    GND    GND @BASEBOARD_FAB2_LIB.BASEBOARD_FAB2(SCH_1):GND
  28     NC DNC<1>     NC
  29     NC  BVSEN     NC
  30     NC  BVREF     NC
  31     NC BIREF1     NC
  32    GND BISEN1 @BASEBOARD_FAB2_LIB.BASEBOARD_FAB2(SCH_1):GND
  33 VR_PVDDQ_ABC_XADDR2 XADDR2 @BASEBOARD_FAB2_LIB.BASEBOARD_FAB2(SCH_1):VR_PVDDQ_ABC_XADDR2
  34     NC  BTSEN     NC
  35 A_TSENSE_PVDDQ_ABC  ATSEN @BASEBOARD_FAB2_LIB.BASEBOARD_FAB2(SCH_1):A_TSENSE_PVDDQ_ABC
  36 VR_PVDDQ_ABC_XADDR1 XADDR1 @BASEBOARD_FAB2_LIB.BASEBOARD_FAB2(SCH_1):VR_PVDDQ_ABC_XADDR1
  37 VR_PVDDQ_ABC_VINSEN VINSEN @BASEBOARD_FAB2_LIB.BASEBOARD_FAB2(SCH_1):VR_PVDDQ_ABC_VINSEN
  38 VR_PVDDQ_ABC_AIINSEN IINSEN @BASEBOARD_FAB2_LIB.BASEBOARD_FAB2(SCH_1):VR_PVDDQ_ABC_AIINSEN
  39 VR_PVDDQ_ABC_VDD    VDD @BASEBOARD_FAB2_LIB.BASEBOARD_FAB2(SCH_1):VR_PVDDQ_ABC_VDD
  40 VR_PVDDQ_ABC_VD12   VD12 @BASEBOARD_FAB2_LIB.BASEBOARD_FAB2(SCH_1):VR_PVDDQ_ABC_VD12
  41    GND  THPAD @BASEBOARD_FAB2_LIB.BASEBOARD_FAB2(SCH_1):GND

RES_0402-49.9,1%,1/16W,CHIP,G2A  I70  R3T11
   1 PVCCIO_CPU0      A @BASEBOARD_FAB2_LIB.BASEBOARD_FAB2(SCH_1):PVCCIO_CPU0
   2 SVID_CLK1_CPU0_R      B @BASEBOARD_FAB2_LIB.BASEBOARD_FAB2(SCH_1):SVID_CLK1_CPU0_R

RES_0402-2.26K,1.0%,1/16W,CHIPA  I72  R7G8
   1 VR_PVDDQ_ABC_XADDR1      A @BASEBOARD_FAB2_LIB.BASEBOARD_FAB2(SCH_1):VR_PVDDQ_ABC_XADDR1
   2    GND      B @BASEBOARD_FAB2_LIB.BASEBOARD_FAB2(SCH_1):GND

RES_0402-2.26K,1.0%,1/16W,CHIPA  I73  R7G10
   1 VR_PVDDQ_ABC_XADDR2      A @BASEBOARD_FAB2_LIB.BASEBOARD_FAB2(SCH_1):VR_PVDDQ_ABC_XADDR2
   2    GND      B @BASEBOARD_FAB2_LIB.BASEBOARD_FAB2(SCH_1):GND

RES_0402-0.0,5%,1/16W,CHIP,G21A  I74  R12W25
   1 PU_VR_PVDDQ_ABC_FAULT1      A @BASEBOARD_FAB2_LIB.BASEBOARD_FAB2(SCH_1):PU_VR_PVDDQ_ABC_FAULT1
   2 PWRGD_PVDDQ_ABC      B @BASEBOARD_FAB2_LIB.BASEBOARD_FAB2(SCH_1):PWRGD_PVDDQ_ABC

RES_0402-2.26K,1.0%,1/16W,CHIPA  I75  R7F36
   1 P3V3_STBY      A @BASEBOARD_FAB2_LIB.BASEBOARD_FAB2(SCH_1):P3V3_STBY
   2 PWRGD_PVDDQ_ABC      B @BASEBOARD_FAB2_LIB.BASEBOARD_FAB2(SCH_1):PWRGD_PVDDQ_ABC


DRAWING: @BASEBOARD_FAB2_LIB.BASEBOARD_FAB2(SCH_1):PAGE197 

CAP_0402LF-47.0PF,50V,5%,COG,AA  I1  C12W2
   1 VR_PVDDQ_DEF_AIINSEN      A @BASEBOARD_FAB2_LIB.BASEBOARD_FAB2(SCH_1):VR_PVDDQ_DEF_AIINSEN
   2 VR_PVDDQ_DEF_VINSEN      B @BASEBOARD_FAB2_LIB.BASEBOARD_FAB2(SCH_1):VR_PVDDQ_DEF_VINSEN

RES_1206-0.002,1%,1W,CHIP,G521A  I6  R4B12
   1 P12V_STBY      A @BASEBOARD_FAB2_LIB.BASEBOARD_FAB2(SCH_1):P12V_STBY
   2 P12V_NVDIMM_DEF      B @BASEBOARD_FAB2_LIB.BASEBOARD_FAB2(SCH_1):P12V_NVDIMM_DEF

CAP_0402LF-47.0PF,50V,5%,COG,AA  I8  C12W1
   1 VR_PVDDQ_ABC_AIINSEN      A @BASEBOARD_FAB2_LIB.BASEBOARD_FAB2(SCH_1):VR_PVDDQ_ABC_AIINSEN
   2 VR_PVDDQ_ABC_VINSEN      B @BASEBOARD_FAB2_LIB.BASEBOARD_FAB2(SCH_1):VR_PVDDQ_ABC_VINSEN

RES_1206-0.002,1%,1W,CHIP,G521A  I14  R4F2
   1 P12V_STBY      A @BASEBOARD_FAB2_LIB.BASEBOARD_FAB2(SCH_1):P12V_STBY
   2 P12V_NVDIMM_ABC      B @BASEBOARD_FAB2_LIB.BASEBOARD_FAB2(SCH_1):P12V_NVDIMM_ABC

CAP_0402LF-47.0PF,50V,5%,COG,AA  I18  C12W4
   1 VR_PVDDQ_KLM_AIINSEN      A @BASEBOARD_FAB2_LIB.BASEBOARD_FAB2(SCH_1):VR_PVDDQ_KLM_AIINSEN
   2 VR_PVDDQ_KLM_VINSEN      B @BASEBOARD_FAB2_LIB.BASEBOARD_FAB2(SCH_1):VR_PVDDQ_KLM_VINSEN

BSL308C-H6327-GP_DISCRET-GB1-BA  I19  Q12W2
   1 PWRGD_PVDDQ_DEF GATE#1 @BASEBOARD_FAB2_LIB.BASEBOARD_FAB2(SCH_1):PWRGD_PVDDQ_DEF
   2 P12V_NVDIMM_DEF SOURCE#2 @BASEBOARD_FAB2_LIB.BASEBOARD_FAB2(SCH_1):P12V_NVDIMM_DEF
   6 PWRGD_PVDDQ_DEF_N DRAIN#6 @BASEBOARD_FAB2_LIB.BASEBOARD_FAB2(SCH_1):PWRGD_PVDDQ_DEF_N
   5    GND SOURCE#5 @BASEBOARD_FAB2_LIB.BASEBOARD_FAB2(SCH_1):GND
   3 PWRGD_PVDDQ_DEF_N GATE#3 @BASEBOARD_FAB2_LIB.BASEBOARD_FAB2(SCH_1):PWRGD_PVDDQ_DEF_N
   4 P12V_NVDIMM_DEF_D DRAIN#4 @BASEBOARD_FAB2_LIB.BASEBOARD_FAB2(SCH_1):P12V_NVDIMM_DEF_D

RES_0603-100.0K,1%,1/10W,CHIP,A  I21  R12W9
   1 P12V_NVDIMM_DEF      A @BASEBOARD_FAB2_LIB.BASEBOARD_FAB2(SCH_1):P12V_NVDIMM_DEF
   2 PWRGD_PVDDQ_DEF_N      B @BASEBOARD_FAB2_LIB.BASEBOARD_FAB2(SCH_1):PWRGD_PVDDQ_DEF_N

RES_1206-0.002,1%,1W,CHIP,G521A  I29  R9M4
   1 P12V_STBY      A @BASEBOARD_FAB2_LIB.BASEBOARD_FAB2(SCH_1):P12V_STBY
   2 P12V_NVDIMM_KLM      B @BASEBOARD_FAB2_LIB.BASEBOARD_FAB2(SCH_1):P12V_NVDIMM_KLM

BSL308C-H6327-GP_DISCRET-GB1-BA  I35  Q12W4
   1 PWRGD_PVDDQ_KLM GATE#1 @BASEBOARD_FAB2_LIB.BASEBOARD_FAB2(SCH_1):PWRGD_PVDDQ_KLM
   2 P12V_NVDIMM_KLM SOURCE#2 @BASEBOARD_FAB2_LIB.BASEBOARD_FAB2(SCH_1):P12V_NVDIMM_KLM
   6 PWRGD_PVDDQ_KLM_N DRAIN#6 @BASEBOARD_FAB2_LIB.BASEBOARD_FAB2(SCH_1):PWRGD_PVDDQ_KLM_N
   5    GND SOURCE#5 @BASEBOARD_FAB2_LIB.BASEBOARD_FAB2(SCH_1):GND
   3 PWRGD_PVDDQ_KLM_N GATE#3 @BASEBOARD_FAB2_LIB.BASEBOARD_FAB2(SCH_1):PWRGD_PVDDQ_KLM_N
   4 P12V_NVDIMM_KLM_D DRAIN#4 @BASEBOARD_FAB2_LIB.BASEBOARD_FAB2(SCH_1):P12V_NVDIMM_KLM_D

RES_0603-100.0K,1%,1/10W,CHIP,A  I37  R12W19
   1 P12V_NVDIMM_KLM      A @BASEBOARD_FAB2_LIB.BASEBOARD_FAB2(SCH_1):P12V_NVDIMM_KLM
   2 PWRGD_PVDDQ_KLM_N      B @BASEBOARD_FAB2_LIB.BASEBOARD_FAB2(SCH_1):PWRGD_PVDDQ_KLM_N

CAP_0402LF-47.0PF,50V,5%,COG,AA  I42  C12W3
   1 VR_PVDDQ_GHJ_AIINSEN      A @BASEBOARD_FAB2_LIB.BASEBOARD_FAB2(SCH_1):VR_PVDDQ_GHJ_AIINSEN
   2 VR_PVDDQ_GHJ_VINSEN      B @BASEBOARD_FAB2_LIB.BASEBOARD_FAB2(SCH_1):VR_PVDDQ_GHJ_VINSEN

BSL308C-H6327-GP_DISCRET-GB1-BA  I43  Q12W1
   1 PWRGD_PVDDQ_ABC GATE#1 @BASEBOARD_FAB2_LIB.BASEBOARD_FAB2(SCH_1):PWRGD_PVDDQ_ABC
   2 P12V_NVDIMM_ABC SOURCE#2 @BASEBOARD_FAB2_LIB.BASEBOARD_FAB2(SCH_1):P12V_NVDIMM_ABC
   6 PWRGD_PVDDQ_ABC_N DRAIN#6 @BASEBOARD_FAB2_LIB.BASEBOARD_FAB2(SCH_1):PWRGD_PVDDQ_ABC_N
   5    GND SOURCE#5 @BASEBOARD_FAB2_LIB.BASEBOARD_FAB2(SCH_1):GND
   3 PWRGD_PVDDQ_ABC_N GATE#3 @BASEBOARD_FAB2_LIB.BASEBOARD_FAB2(SCH_1):PWRGD_PVDDQ_ABC_N
   4 P12V_NVDIMM_ABC_D DRAIN#4 @BASEBOARD_FAB2_LIB.BASEBOARD_FAB2(SCH_1):P12V_NVDIMM_ABC_D

RES_0603-100.0K,1%,1/10W,CHIP,A  I45  R12W4
   1 P12V_NVDIMM_ABC      A @BASEBOARD_FAB2_LIB.BASEBOARD_FAB2(SCH_1):P12V_NVDIMM_ABC
   2 PWRGD_PVDDQ_ABC_N      B @BASEBOARD_FAB2_LIB.BASEBOARD_FAB2(SCH_1):PWRGD_PVDDQ_ABC_N

RES_1206-0.002,1%,1W,CHIP,G521A  I50  R1F3
   1 P12V_STBY      A @BASEBOARD_FAB2_LIB.BASEBOARD_FAB2(SCH_1):P12V_STBY
   2 P12V_NVDIMM_GHJ      B @BASEBOARD_FAB2_LIB.BASEBOARD_FAB2(SCH_1):P12V_NVDIMM_GHJ

RES_0603-100.0K,1%,1/10W,CHIP,A  I53  R12W14
   1 P12V_NVDIMM_GHJ      A @BASEBOARD_FAB2_LIB.BASEBOARD_FAB2(SCH_1):P12V_NVDIMM_GHJ
   2 PWRGD_PVDDQ_GHJ_N      B @BASEBOARD_FAB2_LIB.BASEBOARD_FAB2(SCH_1):PWRGD_PVDDQ_GHJ_N

CAP_0805-10UF,16V,10%,X7R,G106A  I56  C9T8
   1 P12V_NVDIMM_GHJ      A @BASEBOARD_FAB2_LIB.BASEBOARD_FAB2(SCH_1):P12V_NVDIMM_GHJ
   2    GND      B @BASEBOARD_FAB2_LIB.BASEBOARD_FAB2(SCH_1):GND

CAP_0805-10UF,16V,10%,X7R,G106A  I60  C1A4
   1 P12V_NVDIMM_KLM      A @BASEBOARD_FAB2_LIB.BASEBOARD_FAB2(SCH_1):P12V_NVDIMM_KLM
   2    GND      B @BASEBOARD_FAB2_LIB.BASEBOARD_FAB2(SCH_1):GND

CAP_0805-10UF,16V,10%,X7R,G106A  I63  C9U11
   1 P12V_NVDIMM_GHJ      A @BASEBOARD_FAB2_LIB.BASEBOARD_FAB2(SCH_1):P12V_NVDIMM_GHJ
   2    GND      B @BASEBOARD_FAB2_LIB.BASEBOARD_FAB2(SCH_1):GND

CAP_0805-10UF,16V,10%,X7R,G106A  I66  C9U8
   1 P12V_NVDIMM_GHJ      A @BASEBOARD_FAB2_LIB.BASEBOARD_FAB2(SCH_1):P12V_NVDIMM_GHJ
   2    GND      B @BASEBOARD_FAB2_LIB.BASEBOARD_FAB2(SCH_1):GND

CAP_0805-10UF,16V,10%,X7R,G106A  I69  C6U18
   1 P12V_NVDIMM_ABC      A @BASEBOARD_FAB2_LIB.BASEBOARD_FAB2(SCH_1):P12V_NVDIMM_ABC
   2    GND      B @BASEBOARD_FAB2_LIB.BASEBOARD_FAB2(SCH_1):GND

CAP_0805-10UF,16V,10%,X7R,G106A  I71  C6T2
   1 P12V_NVDIMM_ABC      A @BASEBOARD_FAB2_LIB.BASEBOARD_FAB2(SCH_1):P12V_NVDIMM_ABC
   2    GND      B @BASEBOARD_FAB2_LIB.BASEBOARD_FAB2(SCH_1):GND

CAP_0805-10UF,16V,10%,X7R,G106A  I72  C1B7
   1 P12V_NVDIMM_KLM      A @BASEBOARD_FAB2_LIB.BASEBOARD_FAB2(SCH_1):P12V_NVDIMM_KLM
   2    GND      B @BASEBOARD_FAB2_LIB.BASEBOARD_FAB2(SCH_1):GND

CAP_0805-10UF,16V,10%,X7R,G106A  I75  C1A16
   1 P12V_NVDIMM_KLM      A @BASEBOARD_FAB2_LIB.BASEBOARD_FAB2(SCH_1):P12V_NVDIMM_KLM
   2    GND      B @BASEBOARD_FAB2_LIB.BASEBOARD_FAB2(SCH_1):GND

CAP_0805-10UF,16V,10%,X7R,G106A  I78  C4B11
   1 P12V_NVDIMM_DEF      A @BASEBOARD_FAB2_LIB.BASEBOARD_FAB2(SCH_1):P12V_NVDIMM_DEF
   2    GND      B @BASEBOARD_FAB2_LIB.BASEBOARD_FAB2(SCH_1):GND

CAP_0805-10UF,16V,10%,X7R,G106A  I81  C4A4
   1 P12V_NVDIMM_DEF      A @BASEBOARD_FAB2_LIB.BASEBOARD_FAB2(SCH_1):P12V_NVDIMM_DEF
   2    GND      B @BASEBOARD_FAB2_LIB.BASEBOARD_FAB2(SCH_1):GND

CAP_0805-10UF,16V,10%,X7R,G106A  I84  C6U10
   1 P12V_NVDIMM_ABC      A @BASEBOARD_FAB2_LIB.BASEBOARD_FAB2(SCH_1):P12V_NVDIMM_ABC
   2    GND      B @BASEBOARD_FAB2_LIB.BASEBOARD_FAB2(SCH_1):GND

CAP_0805-10UF,16V,10%,X7R,G106A  I88  C4A17
   1 P12V_NVDIMM_DEF      A @BASEBOARD_FAB2_LIB.BASEBOARD_FAB2(SCH_1):P12V_NVDIMM_DEF
   2    GND      B @BASEBOARD_FAB2_LIB.BASEBOARD_FAB2(SCH_1):GND

BSL308C-H6327-GP_DISCRET-GB1-BA  I91  Q12W3
   1 PWRGD_PVDDQ_GHJ GATE#1 @BASEBOARD_FAB2_LIB.BASEBOARD_FAB2(SCH_1):PWRGD_PVDDQ_GHJ
   2 P12V_NVDIMM_GHJ SOURCE#2 @BASEBOARD_FAB2_LIB.BASEBOARD_FAB2(SCH_1):P12V_NVDIMM_GHJ
   6 PWRGD_PVDDQ_GHJ_N DRAIN#6 @BASEBOARD_FAB2_LIB.BASEBOARD_FAB2(SCH_1):PWRGD_PVDDQ_GHJ_N
   5    GND SOURCE#5 @BASEBOARD_FAB2_LIB.BASEBOARD_FAB2(SCH_1):GND
   3 PWRGD_PVDDQ_GHJ_N GATE#3 @BASEBOARD_FAB2_LIB.BASEBOARD_FAB2(SCH_1):PWRGD_PVDDQ_GHJ_N
   4 P12V_NVDIMM_GHJ_D DRAIN#4 @BASEBOARD_FAB2_LIB.BASEBOARD_FAB2(SCH_1):P12V_NVDIMM_GHJ_D

665KR5B-1-GP_SMD-RG3-665KR5B-1A  I101  R12W1
   1 P12V_STBY      1 @BASEBOARD_FAB2_LIB.BASEBOARD_FAB2(SCH_1):P12V_STBY
   2 VR_PVDDQ_ABC_AIINSEN      2 @BASEBOARD_FAB2_LIB.BASEBOARD_FAB2(SCH_1):VR_PVDDQ_ABC_AIINSEN

665KR2B-GP_SMD-RG2-665KR2B-GP,A  I109  R12W10
   1 VR_PVDDQ_DEF_AIINSEN      1 @BASEBOARD_FAB2_LIB.BASEBOARD_FAB2(SCH_1):VR_PVDDQ_DEF_AIINSEN
   2 VR_PVDDQ_DEF_VINSEN      2 @BASEBOARD_FAB2_LIB.BASEBOARD_FAB2(SCH_1):VR_PVDDQ_DEF_VINSEN

665KR2B-GP_SMD-RG2-665KR2B-GP,A  I110  R12W20
   1 VR_PVDDQ_KLM_AIINSEN      1 @BASEBOARD_FAB2_LIB.BASEBOARD_FAB2(SCH_1):VR_PVDDQ_KLM_AIINSEN
   2 VR_PVDDQ_KLM_VINSEN      2 @BASEBOARD_FAB2_LIB.BASEBOARD_FAB2(SCH_1):VR_PVDDQ_KLM_VINSEN

665KR2B-GP_SMD-RG2-665KR2B-GP,A  I111  R12W5
   1 VR_PVDDQ_ABC_AIINSEN      1 @BASEBOARD_FAB2_LIB.BASEBOARD_FAB2(SCH_1):VR_PVDDQ_ABC_AIINSEN
   2 VR_PVDDQ_ABC_VINSEN      2 @BASEBOARD_FAB2_LIB.BASEBOARD_FAB2(SCH_1):VR_PVDDQ_ABC_VINSEN

665KR2B-GP_SMD-RG2-665KR2B-GP,A  I112  R12W15
   1 VR_PVDDQ_GHJ_AIINSEN      1 @BASEBOARD_FAB2_LIB.BASEBOARD_FAB2(SCH_1):VR_PVDDQ_GHJ_AIINSEN
   2 VR_PVDDQ_GHJ_VINSEN      2 @BASEBOARD_FAB2_LIB.BASEBOARD_FAB2(SCH_1):VR_PVDDQ_GHJ_VINSEN

4D02R2F-GP_SMD-RG2-4D02R2F-GP,A  I113  R12W8
   1 P12V_STBY      1 @BASEBOARD_FAB2_LIB.BASEBOARD_FAB2(SCH_1):P12V_STBY
   2 P12V_NVDIMM_DEF_D      2 @BASEBOARD_FAB2_LIB.BASEBOARD_FAB2(SCH_1):P12V_NVDIMM_DEF_D

4D02R2F-GP_SMD-RG2-4D02R2F-GP,A  I114  R12W18
   1 P12V_STBY      1 @BASEBOARD_FAB2_LIB.BASEBOARD_FAB2(SCH_1):P12V_STBY
   2 P12V_NVDIMM_KLM_D      2 @BASEBOARD_FAB2_LIB.BASEBOARD_FAB2(SCH_1):P12V_NVDIMM_KLM_D

4D02R2F-GP_SMD-RG2-4D02R2F-GP,A  I115  R12W3
   1 P12V_STBY      1 @BASEBOARD_FAB2_LIB.BASEBOARD_FAB2(SCH_1):P12V_STBY
   2 P12V_NVDIMM_ABC_D      2 @BASEBOARD_FAB2_LIB.BASEBOARD_FAB2(SCH_1):P12V_NVDIMM_ABC_D

4D02R2F-GP_SMD-RG2-4D02R2F-GP,A  I116  R12W13
   1 P12V_STBY      1 @BASEBOARD_FAB2_LIB.BASEBOARD_FAB2(SCH_1):P12V_STBY
   2 P12V_NVDIMM_GHJ_D      2 @BASEBOARD_FAB2_LIB.BASEBOARD_FAB2(SCH_1):P12V_NVDIMM_GHJ_D

665KR5B-1-GP_SMD-RG3-665KR5B-1A  I117  R12W2
   1 P12V_NVDIMM_ABC_D      1 @BASEBOARD_FAB2_LIB.BASEBOARD_FAB2(SCH_1):P12V_NVDIMM_ABC_D
   2 VR_PVDDQ_ABC_VINSEN      2 @BASEBOARD_FAB2_LIB.BASEBOARD_FAB2(SCH_1):VR_PVDDQ_ABC_VINSEN

665KR5B-1-GP_SMD-RG3-665KR5B-1A  I118  R12W11
   1 P12V_STBY      1 @BASEBOARD_FAB2_LIB.BASEBOARD_FAB2(SCH_1):P12V_STBY
   2 VR_PVDDQ_GHJ_AIINSEN      2 @BASEBOARD_FAB2_LIB.BASEBOARD_FAB2(SCH_1):VR_PVDDQ_GHJ_AIINSEN

665KR5B-1-GP_SMD-RG3-665KR5B-1A  I119  R12W12
   1 P12V_NVDIMM_GHJ_D      1 @BASEBOARD_FAB2_LIB.BASEBOARD_FAB2(SCH_1):P12V_NVDIMM_GHJ_D
   2 VR_PVDDQ_GHJ_VINSEN      2 @BASEBOARD_FAB2_LIB.BASEBOARD_FAB2(SCH_1):VR_PVDDQ_GHJ_VINSEN

665KR5B-1-GP_SMD-RG3-665KR5B-1A  I120  R12W6
   1 P12V_STBY      1 @BASEBOARD_FAB2_LIB.BASEBOARD_FAB2(SCH_1):P12V_STBY
   2 VR_PVDDQ_DEF_AIINSEN      2 @BASEBOARD_FAB2_LIB.BASEBOARD_FAB2(SCH_1):VR_PVDDQ_DEF_AIINSEN

665KR5B-1-GP_SMD-RG3-665KR5B-1A  I121  R12W7
   1 P12V_NVDIMM_DEF_D      1 @BASEBOARD_FAB2_LIB.BASEBOARD_FAB2(SCH_1):P12V_NVDIMM_DEF_D
   2 VR_PVDDQ_DEF_VINSEN      2 @BASEBOARD_FAB2_LIB.BASEBOARD_FAB2(SCH_1):VR_PVDDQ_DEF_VINSEN

665KR5B-1-GP_SMD-RG3-665KR5B-1A  I122  R12W16
   1 P12V_STBY      1 @BASEBOARD_FAB2_LIB.BASEBOARD_FAB2(SCH_1):P12V_STBY
   2 VR_PVDDQ_KLM_AIINSEN      2 @BASEBOARD_FAB2_LIB.BASEBOARD_FAB2(SCH_1):VR_PVDDQ_KLM_AIINSEN

665KR5B-1-GP_SMD-RG3-665KR5B-1A  I123  R12W17
   1 P12V_NVDIMM_KLM_D      1 @BASEBOARD_FAB2_LIB.BASEBOARD_FAB2(SCH_1):P12V_NVDIMM_KLM_D
   2 VR_PVDDQ_KLM_VINSEN      2 @BASEBOARD_FAB2_LIB.BASEBOARD_FAB2(SCH_1):VR_PVDDQ_KLM_VINSEN


DRAWING: @BASEBOARD_FAB2_LIB.BASEBOARD_FAB2(SCH_1):PAGE230 

CAP_0402LF-1000PF,50V,10%,EMPTA  I2  C4A6
   1 FM_PVTT_KLM_EN_R      A @BASEBOARD_FAB2_LIB.BASEBOARD_FAB2(SCH_1):FM_PVTT_KLM_EN_R
   2    GND      B @BASEBOARD_FAB2_LIB.BASEBOARD_FAB2(SCH_1):GND

RES_0402-0.0,5%,1/16W,CHIP,G21A  I4  R4A3
   1 PWRGD_PVDDQ_KLM_R      A @BASEBOARD_FAB2_LIB.BASEBOARD_FAB2(SCH_1):PWRGD_PVDDQ_KLM_R
   2 FM_PVTT_KLM_EN_R      B @BASEBOARD_FAB2_LIB.BASEBOARD_FAB2(SCH_1):FM_PVTT_KLM_EN_R

RES_0402-1.0M,1%,1/16W,EMPTY,GA  I5  R6L5
   1   P3V3      A @BASEBOARD_FAB2_LIB.BASEBOARD_FAB2(SCH_1):P3V3
   2 FM_PVTT_KLM_EN_R      B @BASEBOARD_FAB2_LIB.BASEBOARD_FAB2(SCH_1):FM_PVTT_KLM_EN_R

RES_0402-0.0,5%,1/16W,CHIP,G21A  I6  R6L6
   1 PVDDQ_KLM      A @BASEBOARD_FAB2_LIB.BASEBOARD_FAB2(SCH_1):PVDDQ_KLM
   2 VSENSE_PVDDQ_KLM_VTT      B @BASEBOARD_FAB2_LIB.BASEBOARD_FAB2(SCH_1):VSENSE_PVDDQ_KLM_VTT

CAP_0603-4.7UF,6.3V,10%,X6S,E1A  I10  C4A7
   1 VSENSE_PVDDQ_KLM_VTT      A @BASEBOARD_FAB2_LIB.BASEBOARD_FAB2(SCH_1):VSENSE_PVDDQ_KLM_VTT
   2    GND      B @BASEBOARD_FAB2_LIB.BASEBOARD_FAB2(SCH_1):GND

CAP_0402-1.0UF,16V,10%,X6S,D97A  I12  C4A8
   1 VR_PVTT_KLM_BIAS      A @BASEBOARD_FAB2_LIB.BASEBOARD_FAB2(SCH_1):VR_PVTT_KLM_BIAS
   2    GND      B @BASEBOARD_FAB2_LIB.BASEBOARD_FAB2(SCH_1):GND

RES_0402-0.0,5%,1/16W,CHIP,G21A  I13  R6L8
   1   P3V3      A @BASEBOARD_FAB2_LIB.BASEBOARD_FAB2(SCH_1):P3V3
   2 VR_PVTT_KLM_BIAS      B @BASEBOARD_FAB2_LIB.BASEBOARD_FAB2(SCH_1):VR_PVTT_KLM_BIAS

CAP_0805LF-22UF,4V,20%,X6S,C95A  I20  C4A13
   1 PVTT_KLM      A @BASEBOARD_FAB2_LIB.BASEBOARD_FAB2(SCH_1):PVTT_KLM
   2    GND      B @BASEBOARD_FAB2_LIB.BASEBOARD_FAB2(SCH_1):GND

CAP_0402LF-1000PF,50V,10%,X7R,A  I23  C4A3
   1 PWRGD_PVTT_KLM_CPU1_R      A @BASEBOARD_FAB2_LIB.BASEBOARD_FAB2(SCH_1):PWRGD_PVTT_KLM_CPU1_R
   2    GND      B @BASEBOARD_FAB2_LIB.BASEBOARD_FAB2(SCH_1):GND

CAP_A_0603V-47UF,4V,20%,X5R,60A  I24  C8M12
   1 PVTT_KLM      A @BASEBOARD_FAB2_LIB.BASEBOARD_FAB2(SCH_1):PVTT_KLM
   2    GND      B @BASEBOARD_FAB2_LIB.BASEBOARD_FAB2(SCH_1):GND

RES_0402-33.2,1%,1/16W,CHIP,G2A  I32  R4A4
   1 PWRGD_PVTT_KLM_CPU1_R      A @BASEBOARD_FAB2_LIB.BASEBOARD_FAB2(SCH_1):PWRGD_PVTT_KLM_CPU1_R
   2 PWRGD_PVTT_CPU1      B @BASEBOARD_FAB2_LIB.BASEBOARD_FAB2(SCH_1):PWRGD_PVTT_CPU1

CAP_0603LF-10UF,4V,20%,X6S,E15A  I35  C6L5
   1 PVDDQ_KLM      A @BASEBOARD_FAB2_LIB.BASEBOARD_FAB2(SCH_1):PVDDQ_KLM
   2    GND      B @BASEBOARD_FAB2_LIB.BASEBOARD_FAB2(SCH_1):GND

CAP_0402-1.0UF,16V,10%,X6S,D97A  I36  C4A14
   1 VR_PVTT_KLM_VREF      A @BASEBOARD_FAB2_LIB.BASEBOARD_FAB2(SCH_1):VR_PVTT_KLM_VREF
   2    GND      B @BASEBOARD_FAB2_LIB.BASEBOARD_FAB2(SCH_1):GND

CAP_0603LF-10UF,4V,20%,X6S,E15A  I17  C4A15
   1 PVDDQ_KLM      A @BASEBOARD_FAB2_LIB.BASEBOARD_FAB2(SCH_1):PVDDQ_KLM
   2    GND      B @BASEBOARD_FAB2_LIB.BASEBOARD_FAB2(SCH_1):GND

RES_0402-10.0K,1%,1/16W,CHIP,GA  I21  R4A5
   1   P3V3      A @BASEBOARD_FAB2_LIB.BASEBOARD_FAB2(SCH_1):P3V3
   2 PWRGD_PVTT_KLM_CPU1_R      B @BASEBOARD_FAB2_LIB.BASEBOARD_FAB2(SCH_1):PWRGD_PVTT_KLM_CPU1_R

SHUNT_SH0201-EMPTY,N_A  I30  SH8L1
   1 VR_PVTT_KLM_SNS      A @BASEBOARD_FAB2_LIB.BASEBOARD_FAB2(SCH_1):VR_PVTT_KLM_SNS
   2 PVTT_KLM      B @BASEBOARD_FAB2_LIB.BASEBOARD_FAB2(SCH_1):PVTT_KLM

MIC5166_DFN-IC,H55101-001  I37  EU4A2
   7 FM_PVTT_KLM_EN_R     EN @BASEBOARD_FAB2_LIB.BASEBOARD_FAB2(SCH_1):FM_PVTT_KLM_EN_R
  10 PVDDQ_KLM    VIN @BASEBOARD_FAB2_LIB.BASEBOARD_FAB2(SCH_1):PVDDQ_KLM
   1 VR_PVTT_KLM_VREF   VREF @BASEBOARD_FAB2_LIB.BASEBOARD_FAB2(SCH_1):VR_PVTT_KLM_VREF
   2 VR_PVTT_KLM_BIAS   BIAS @BASEBOARD_FAB2_LIB.BASEBOARD_FAB2(SCH_1):VR_PVTT_KLM_BIAS
   3    GND   AGND @BASEBOARD_FAB2_LIB.BASEBOARD_FAB2(SCH_1):GND
   5 PWRGD_PVTT_KLM_CPU1_R     PG @BASEBOARD_FAB2_LIB.BASEBOARD_FAB2(SCH_1):PWRGD_PVTT_KLM_CPU1_R
   4 VSENSE_PVDDQ_KLM_VTT   VDDQ @BASEBOARD_FAB2_LIB.BASEBOARD_FAB2(SCH_1):VSENSE_PVDDQ_KLM_VTT
   6 VR_PVTT_KLM_SNS    SNS @BASEBOARD_FAB2_LIB.BASEBOARD_FAB2(SCH_1):VR_PVTT_KLM_SNS
   8    GND   PGND @BASEBOARD_FAB2_LIB.BASEBOARD_FAB2(SCH_1):GND
   9 PVTT_KLM    VTT @BASEBOARD_FAB2_LIB.BASEBOARD_FAB2(SCH_1):PVTT_KLM
  11    GND  THPAD @BASEBOARD_FAB2_LIB.BASEBOARD_FAB2(SCH_1):GND

CAP_0805-100UF,4V,20%,X5R,6024A  I41  C8L3
   1 PVTT_KLM      A @BASEBOARD_FAB2_LIB.BASEBOARD_FAB2(SCH_1):PVTT_KLM
   2    GND      B @BASEBOARD_FAB2_LIB.BASEBOARD_FAB2(SCH_1):GND

CAP_0805-100UF,4V,20%,X5R,6024A  I42  C8L4
   1 PVTT_KLM      A @BASEBOARD_FAB2_LIB.BASEBOARD_FAB2(SCH_1):PVTT_KLM
   2    GND      B @BASEBOARD_FAB2_LIB.BASEBOARD_FAB2(SCH_1):GND

CAP_0805-100UF,4V,20%,X5R,6024A  I43  C6W13
   1 PVTT_KLM      A @BASEBOARD_FAB2_LIB.BASEBOARD_FAB2(SCH_1):PVTT_KLM
   2    GND      B @BASEBOARD_FAB2_LIB.BASEBOARD_FAB2(SCH_1):GND


DRAWING: @BASEBOARD_FAB2_LIB.BASEBOARD_FAB2(SCH_1):PAGE181 

RES_0402-4.75K,1%,1/16W,CHIP,GA  I4  R9T9
   1 P12V_PSU      A @BASEBOARD_FAB2_LIB.BASEBOARD_FAB2(SCH_1):P12V_PSU
   2 FM_MATED_IN_N      B @BASEBOARD_FAB2_LIB.BASEBOARD_FAB2(SCH_1):FM_MATED_IN_N

DIODE_SM-SDMK0340L,IC,H71799-0A  I5  CR1F4
   1 FM_MATED_IN_D1_N      C @BASEBOARD_FAB2_LIB.BASEBOARD_FAB2(SCH_1):FM_MATED_IN_D1_N
   2 FM_MATED_IN_N      A @BASEBOARD_FAB2_LIB.BASEBOARD_FAB2(SCH_1):FM_MATED_IN_N

RES_0402-0.0,5%,1/16W,CHIP,G21A  I22  R1F8
   1 FAN_TACH0      A @BASEBOARD_FAB2_LIB.BASEBOARD_FAB2(SCH_1):FAN_TACH0
   2 FAN_TACH0_R      B @BASEBOARD_FAB2_LIB.BASEBOARD_FAB2(SCH_1):FAN_TACH0_R

RES_0402-0.0,5%,1/16W,CHIP,G21A  I26  R9T1
   1 FAN_PWM_OUT_SYS0_R      A @BASEBOARD_FAB2_LIB.BASEBOARD_FAB2(SCH_1):FAN_PWM_OUT_SYS0_R
   2 FAN_PWM_OUT_SYS0_R1      B @BASEBOARD_FAB2_LIB.BASEBOARD_FAB2(SCH_1):FAN_PWM_OUT_SYS0_R1

RES_0402-0.0,5%,1/16W,CHIP,G21A  I27  R9R12
   1 FAN_TACH2      A @BASEBOARD_FAB2_LIB.BASEBOARD_FAB2(SCH_1):FAN_TACH2
   2 FAN_TACH2_R      B @BASEBOARD_FAB2_LIB.BASEBOARD_FAB2(SCH_1):FAN_TACH2_R

RES_0402-0.0,5%,1/16W,EMPTY,G2A  I28  R9F63
   1 SPA_MID_DBG_RX      A @BASEBOARD_FAB2_LIB.BASEBOARD_FAB2(SCH_1):SPA_MID_DBG_RX
   2 SPA_MID_DBG_RX_R      B @BASEBOARD_FAB2_LIB.BASEBOARD_FAB2(SCH_1):SPA_MID_DBG_RX_R

RES_0402-0.0,5%,1/16W,CHIP,G21A  I29  R9F64
   1 SP2_BMC_CM_UART_TX_R1      A @BASEBOARD_FAB2_LIB.BASEBOARD_FAB2(SCH_1):SP2_BMC_CM_UART_TX_R1
   2 SPA_MID_DBG_RX_R      B @BASEBOARD_FAB2_LIB.BASEBOARD_FAB2(SCH_1):SPA_MID_DBG_RX_R

RES_0402-0.0,5%,1/16W,EMPTY,G2A  I30  R9F70
   1 SPA_MID_DBG_TX      A @BASEBOARD_FAB2_LIB.BASEBOARD_FAB2(SCH_1):SPA_MID_DBG_TX
   2 SPA_MID_DBG_TX_R      B @BASEBOARD_FAB2_LIB.BASEBOARD_FAB2(SCH_1):SPA_MID_DBG_TX_R

RES_0402-0.0,5%,1/16W,CHIP,G21A  I31  R9R10
   1 FAN_TACH1      A @BASEBOARD_FAB2_LIB.BASEBOARD_FAB2(SCH_1):FAN_TACH1
   2 FAN_TACH1_R      B @BASEBOARD_FAB2_LIB.BASEBOARD_FAB2(SCH_1):FAN_TACH1_R

RES_0402-0.0,5%,1/16W,CHIP,G21A  I32  R9R9
   1 FAN_TACH3      A @BASEBOARD_FAB2_LIB.BASEBOARD_FAB2(SCH_1):FAN_TACH3
   2 FAN_TACH3_R      B @BASEBOARD_FAB2_LIB.BASEBOARD_FAB2(SCH_1):FAN_TACH3_R

RES_0402-0.0,5%,1/16W,CHIP,G21A  I33  R9F67
   1 SP2_BMC_CM_UART_RX_R1      A @BASEBOARD_FAB2_LIB.BASEBOARD_FAB2(SCH_1):SP2_BMC_CM_UART_RX_R1
   2 SPA_MID_DBG_TX_R      B @BASEBOARD_FAB2_LIB.BASEBOARD_FAB2(SCH_1):SPA_MID_DBG_TX_R

CAP_A_0402V-0.1UF,16V,10%,X7R,A  I34  C8E1
   1 P3V3_STBY      A @BASEBOARD_FAB2_LIB.BASEBOARD_FAB2(SCH_1):P3V3_STBY
   2    GND      B @BASEBOARD_FAB2_LIB.BASEBOARD_FAB2(SCH_1):GND

DIODE_SM-SDMK0340L,IC,H71799-0A  I37  CR1F3
   1 FM_MATED_IN_D2_N      C @BASEBOARD_FAB2_LIB.BASEBOARD_FAB2(SCH_1):FM_MATED_IN_D2_N
   2 FM_MATED_IN_D1_N      A @BASEBOARD_FAB2_LIB.BASEBOARD_FAB2(SCH_1):FM_MATED_IN_D1_N

CAP_0402LF-470PF,50V,10%,EMPTYA  I40  C2R6
   1 FM_PS_EN      A @BASEBOARD_FAB2_LIB.BASEBOARD_FAB2(SCH_1):FM_PS_EN
   2    GND      B @BASEBOARD_FAB2_LIB.BASEBOARD_FAB2(SCH_1):GND

NPN_SM-MMBT3904,IC,C52245-001  I42  Q9T1
   1 FM_MATED_IN_D2_N      B @BASEBOARD_FAB2_LIB.BASEBOARD_FAB2(SCH_1):FM_MATED_IN_D2_N
   3 FM_P12V_HOTSWAP0_EN      C @BASEBOARD_FAB2_LIB.BASEBOARD_FAB2(SCH_1):FM_P12V_HOTSWAP0_EN
   2    GND      E @BASEBOARD_FAB2_LIB.BASEBOARD_FAB2(SCH_1):GND

TTL08_QFN15-74LVC08A,IC,D90404B  I60  U8E1
   8 FM_CTNR_PS_ON_R   Y<0> @BASEBOARD_FAB2_LIB.BASEBOARD_FAB2(SCH_1):FM_CTNR_PS_ON_R
  10 PWRGD_P12V_HSC_DLY   B<0> @BASEBOARD_FAB2_LIB.BASEBOARD_FAB2(SCH_1):PWRGD_P12V_HSC_DLY
   9 FM_PS_EN   A<0> @BASEBOARD_FAB2_LIB.BASEBOARD_FAB2(SCH_1):FM_PS_EN

RES_0402-33.2,1%,1/16W,CHIP,G2A  I63  R8E5
   1 FM_CTNR_PS_ON_R      A @BASEBOARD_FAB2_LIB.BASEBOARD_FAB2(SCH_1):FM_CTNR_PS_ON_R
   2 FM_CTNR_PS_ON      B @BASEBOARD_FAB2_LIB.BASEBOARD_FAB2(SCH_1):FM_CTNR_PS_ON

RES_0402-6.19K,1%,1/16W,CHIP,GA  I64  R9T3
   1 FM_P12V_HOTSWAP0_EN      A @BASEBOARD_FAB2_LIB.BASEBOARD_FAB2(SCH_1):FM_P12V_HOTSWAP0_EN
   2    GND      B @BASEBOARD_FAB2_LIB.BASEBOARD_FAB2(SCH_1):GND

RES_0402-15.0K,1%,1/16W,CHIP,GA  I68  R9T6
   1 P12V_PSU      A @BASEBOARD_FAB2_LIB.BASEBOARD_FAB2(SCH_1):P12V_PSU
   2 FM_P12V_HOTSWAP0_EN      B @BASEBOARD_FAB2_LIB.BASEBOARD_FAB2(SCH_1):FM_P12V_HOTSWAP0_EN

CAP_0402-0.22UF,16V,10%,X7R,A3A  I70  C1F14
   1 P3E_CPU1_PE3_MP_C_TXP<2>      A @BASEBOARD_FAB2_LIB.BASEBOARD_FAB2(SCH_1):P3E_CPU1_PE3_MP_C_TXP(2)
   2 P3E_CPU1_PE3_MP_TXP<2>      B @BASEBOARD_FAB2_LIB.BASEBOARD_FAB2(SCH_1):P3E_CPU1_PE3_MP_TXP(2)

CAP_0402-0.22UF,16V,10%,X7R,A3A  I71  C1F17
   1 P3E_CPU1_PE3_MP_C_TXP<1>      A @BASEBOARD_FAB2_LIB.BASEBOARD_FAB2(SCH_1):P3E_CPU1_PE3_MP_C_TXP(1)
   2 P3E_CPU1_PE3_MP_TXP<1>      B @BASEBOARD_FAB2_LIB.BASEBOARD_FAB2(SCH_1):P3E_CPU1_PE3_MP_TXP(1)

CAP_0402-0.22UF,16V,10%,X7R,A3A  I72  C1F18
   1 P3E_CPU1_PE3_MP_C_TXP<0>      A @BASEBOARD_FAB2_LIB.BASEBOARD_FAB2(SCH_1):P3E_CPU1_PE3_MP_C_TXP(0)
   2 P3E_CPU1_PE3_MP_TXP<0>      B @BASEBOARD_FAB2_LIB.BASEBOARD_FAB2(SCH_1):P3E_CPU1_PE3_MP_TXP(0)

CAP_0402-0.22UF,16V,10%,X7R,A3A  I73  C1F8
   1 P3E_CPU1_PE3_MP_C_TXN<5>      A @BASEBOARD_FAB2_LIB.BASEBOARD_FAB2(SCH_1):P3E_CPU1_PE3_MP_C_TXN(5)
   2 P3E_CPU1_PE3_MP_TXN<5>      B @BASEBOARD_FAB2_LIB.BASEBOARD_FAB2(SCH_1):P3E_CPU1_PE3_MP_TXN(5)

CAP_0402-0.22UF,16V,10%,X7R,A3A  I74  C1F11
   1 P3E_CPU1_PE3_MP_C_TXP<4>      A @BASEBOARD_FAB2_LIB.BASEBOARD_FAB2(SCH_1):P3E_CPU1_PE3_MP_C_TXP(4)
   2 P3E_CPU1_PE3_MP_TXP<4>      B @BASEBOARD_FAB2_LIB.BASEBOARD_FAB2(SCH_1):P3E_CPU1_PE3_MP_TXP(4)

CAP_0402-0.22UF,16V,10%,X7R,A3A  I75  C1F12
   1 P3E_CPU1_PE3_MP_C_TXP<3>      A @BASEBOARD_FAB2_LIB.BASEBOARD_FAB2(SCH_1):P3E_CPU1_PE3_MP_C_TXP(3)
   2 P3E_CPU1_PE3_MP_TXP<3>      B @BASEBOARD_FAB2_LIB.BASEBOARD_FAB2(SCH_1):P3E_CPU1_PE3_MP_TXP(3)

CAP_0402-0.22UF,16V,10%,X7R,A3A  I76  C1F3
   1 P3E_CPU1_PE3_MP_C_TXN<7>      A @BASEBOARD_FAB2_LIB.BASEBOARD_FAB2(SCH_1):P3E_CPU1_PE3_MP_C_TXN(7)
   2 P3E_CPU1_PE3_MP_TXN<7>      B @BASEBOARD_FAB2_LIB.BASEBOARD_FAB2(SCH_1):P3E_CPU1_PE3_MP_TXN(7)

CAP_0402-0.22UF,16V,10%,X7R,A3A  I77  C1F5
   1 P3E_CPU1_PE3_MP_C_TXP<6>      A @BASEBOARD_FAB2_LIB.BASEBOARD_FAB2(SCH_1):P3E_CPU1_PE3_MP_C_TXP(6)
   2 P3E_CPU1_PE3_MP_TXP<6>      B @BASEBOARD_FAB2_LIB.BASEBOARD_FAB2(SCH_1):P3E_CPU1_PE3_MP_TXP(6)

CAP_0402-0.22UF,16V,10%,X7R,A3A  I78  C1F15
   1 P3E_CPU1_PE3_MP_C_TXN<2>      A @BASEBOARD_FAB2_LIB.BASEBOARD_FAB2(SCH_1):P3E_CPU1_PE3_MP_C_TXN(2)
   2 P3E_CPU1_PE3_MP_TXN<2>      B @BASEBOARD_FAB2_LIB.BASEBOARD_FAB2(SCH_1):P3E_CPU1_PE3_MP_TXN(2)

CAP_0402-0.22UF,16V,10%,X7R,A3A  I79  C1F16
   1 P3E_CPU1_PE3_MP_C_TXN<1>      A @BASEBOARD_FAB2_LIB.BASEBOARD_FAB2(SCH_1):P3E_CPU1_PE3_MP_C_TXN(1)
   2 P3E_CPU1_PE3_MP_TXN<1>      B @BASEBOARD_FAB2_LIB.BASEBOARD_FAB2(SCH_1):P3E_CPU1_PE3_MP_TXN(1)

RES_0402-2.26K,1.0%,1/16W,CHIPA  I80  R7D9
   1 P3V3_STBY      A @BASEBOARD_FAB2_LIB.BASEBOARD_FAB2(SCH_1):P3V3_STBY
   2 FM_MB_SLOT_ID1      B @BASEBOARD_FAB2_LIB.BASEBOARD_FAB2(SCH_1):FM_MB_SLOT_ID1

RES_0402-2.26K,1.0%,1/16W,CHIPA  I81  R3P61
   1 P3V3_STBY      A @BASEBOARD_FAB2_LIB.BASEBOARD_FAB2(SCH_1):P3V3_STBY
   2 FM_MB_SLOT_ID2      B @BASEBOARD_FAB2_LIB.BASEBOARD_FAB2(SCH_1):FM_MB_SLOT_ID2

RES_0402-2.26K,1.0%,1/16W,CHIPA  I82  R7D5
   1 P3V3_STBY      A @BASEBOARD_FAB2_LIB.BASEBOARD_FAB2(SCH_1):P3V3_STBY
   2 FM_MB_SLOT_ID0      B @BASEBOARD_FAB2_LIB.BASEBOARD_FAB2(SCH_1):FM_MB_SLOT_ID0

CAP_0402-0.22UF,16V,10%,X7R,A3A  I86  C1F20
   1 P3E_CPU1_PE3_MP_C_TXN<0>      A @BASEBOARD_FAB2_LIB.BASEBOARD_FAB2(SCH_1):P3E_CPU1_PE3_MP_C_TXN(0)
   2 P3E_CPU1_PE3_MP_TXN<0>      B @BASEBOARD_FAB2_LIB.BASEBOARD_FAB2(SCH_1):P3E_CPU1_PE3_MP_TXN(0)

CAP_0402-0.22UF,16V,10%,X7R,A3A  I87  C1F10
   1 P3E_CPU1_PE3_MP_C_TXN<4>      A @BASEBOARD_FAB2_LIB.BASEBOARD_FAB2(SCH_1):P3E_CPU1_PE3_MP_C_TXN(4)
   2 P3E_CPU1_PE3_MP_TXN<4>      B @BASEBOARD_FAB2_LIB.BASEBOARD_FAB2(SCH_1):P3E_CPU1_PE3_MP_TXN(4)

CAP_0402-0.22UF,16V,10%,X7R,A3A  I88  C1F6
   1 P3E_CPU1_PE3_MP_C_TXP<5>      A @BASEBOARD_FAB2_LIB.BASEBOARD_FAB2(SCH_1):P3E_CPU1_PE3_MP_C_TXP(5)
   2 P3E_CPU1_PE3_MP_TXP<5>      B @BASEBOARD_FAB2_LIB.BASEBOARD_FAB2(SCH_1):P3E_CPU1_PE3_MP_TXP(5)

CAP_0402-0.22UF,16V,10%,X7R,A3A  I89  C1F13
   1 P3E_CPU1_PE3_MP_C_TXN<3>      A @BASEBOARD_FAB2_LIB.BASEBOARD_FAB2(SCH_1):P3E_CPU1_PE3_MP_C_TXN(3)
   2 P3E_CPU1_PE3_MP_TXN<3>      B @BASEBOARD_FAB2_LIB.BASEBOARD_FAB2(SCH_1):P3E_CPU1_PE3_MP_TXN(3)

CAP_0402-0.22UF,16V,10%,X7R,A3A  I90  C1F2
   1 P3E_CPU1_PE3_MP_C_TXP<7>      A @BASEBOARD_FAB2_LIB.BASEBOARD_FAB2(SCH_1):P3E_CPU1_PE3_MP_C_TXP(7)
   2 P3E_CPU1_PE3_MP_TXP<7>      B @BASEBOARD_FAB2_LIB.BASEBOARD_FAB2(SCH_1):P3E_CPU1_PE3_MP_TXP(7)

CAP_0402-0.22UF,16V,10%,X7R,A3A  I91  C1F4
   1 P3E_CPU1_PE3_MP_C_TXN<6>      A @BASEBOARD_FAB2_LIB.BASEBOARD_FAB2(SCH_1):P3E_CPU1_PE3_MP_C_TXN(6)
   2 P3E_CPU1_PE3_MP_TXN<6>      B @BASEBOARD_FAB2_LIB.BASEBOARD_FAB2(SCH_1):P3E_CPU1_PE3_MP_TXN(6)

CONN8_H62179001_PIP-CONN,H6217A  I106  J1F3
   1 P3V3_STBY    IO1 @BASEBOARD_FAB2_LIB.BASEBOARD_FAB2(SCH_1):P3V3_STBY
   2 FM_MP_PS_REDUNDANT_LOST_N    IO2 @BASEBOARD_FAB2_LIB.BASEBOARD_FAB2(SCH_1):FM_MP_PS_REDUNDANT_LOST_N
   3 FM_MP_PS_FAIL_N    IO3 @BASEBOARD_FAB2_LIB.BASEBOARD_FAB2(SCH_1):FM_MP_PS_FAIL_N
   4 FM_MATED_IN_N    IO4 @BASEBOARD_FAB2_LIB.BASEBOARD_FAB2(SCH_1):FM_MATED_IN_N
   5 IRQ_SML1_PMBUS_ALERT_R_N    IO5 @BASEBOARD_FAB2_LIB.BASEBOARD_FAB2(SCH_1):IRQ_SML1_PMBUS_ALERT_R_N
   6 SMB_BMC_PMBUS_STBY_LVC3_SDA    IO6 @BASEBOARD_FAB2_LIB.BASEBOARD_FAB2(SCH_1):SMB_BMC_PMBUS_STBY_LVC3_SDA
   7 SMB_BMC_PMBUS_STBY_LVC3_SCL    IO7 @BASEBOARD_FAB2_LIB.BASEBOARD_FAB2(SCH_1):SMB_BMC_PMBUS_STBY_LVC3_SCL
   8    GND    IO8 @BASEBOARD_FAB2_LIB.BASEBOARD_FAB2(SCH_1):GND

DM-FCI-CONN76-8R-GP-U-01_CONN-A  I134  J1F1
  A1 P3E_CPU1_PE3_MP_RXN<0> PCIE_RX_DP0 @BASEBOARD_FAB2_LIB.BASEBOARD_FAB2(SCH_1):P3E_CPU1_PE3_MP_RXN(0)
  A2    GND   GND1 @BASEBOARD_FAB2_LIB.BASEBOARD_FAB2(SCH_1):GND
  A3 P3E_CPU1_PE3_MP_RXP<6> PCIE_RX_DP6 @BASEBOARD_FAB2_LIB.BASEBOARD_FAB2(SCH_1):P3E_CPU1_PE3_MP_RXP(6)
  A4 FAN_TACH3_R FAN_TACH3 @BASEBOARD_FAB2_LIB.BASEBOARD_FAB2(SCH_1):FAN_TACH3_R
  A5 NIC_MDI_MNG_TX_DP MNG_TX_DP @BASEBOARD_FAB2_LIB.BASEBOARD_FAB2(SCH_1):NIC_MDI_MNG_TX_DP
  A6 IRQ_SML1_PMBUS_ALERT_R_N PMBUS_ALERT# @BASEBOARD_FAB2_LIB.BASEBOARD_FAB2(SCH_1):IRQ_SML1_PMBUS_ALERT_R_N
  A7 P3E_CPU1_PE3_MP_C_TXN<3> PCIE_TX_DP3 @BASEBOARD_FAB2_LIB.BASEBOARD_FAB2(SCH_1):P3E_CPU1_PE3_MP_C_TXN(3)
  A8    GND   GND2 @BASEBOARD_FAB2_LIB.BASEBOARD_FAB2(SCH_1):GND
  B1 P3E_CPU1_PE3_MP_RXP<0> PCIE_RX_DN0 @BASEBOARD_FAB2_LIB.BASEBOARD_FAB2(SCH_1):P3E_CPU1_PE3_MP_RXP(0)
  B2 P3E_CPU1_PE3_MP_RXN<3> PCIE_RX_DP3 @BASEBOARD_FAB2_LIB.BASEBOARD_FAB2(SCH_1):P3E_CPU1_PE3_MP_RXN(3)
  B3 P3E_CPU1_PE3_MP_RXN<6> PCIE_RX_DN6 @BASEBOARD_FAB2_LIB.BASEBOARD_FAB2(SCH_1):P3E_CPU1_PE3_MP_RXN(6)
  B4 FAN_TACH2_R FAN_TACH2 @BASEBOARD_FAB2_LIB.BASEBOARD_FAB2(SCH_1):FAN_TACH2_R
  B5 NIC_MDI_MNG_TX_DN MNG_TX_DN @BASEBOARD_FAB2_LIB.BASEBOARD_FAB2(SCH_1):NIC_MDI_MNG_TX_DN
  B6 SMB_BMC_PMBUS_STBY_LVC3_SDA PMBUS_DATA @BASEBOARD_FAB2_LIB.BASEBOARD_FAB2(SCH_1):SMB_BMC_PMBUS_STBY_LVC3_SDA
  B7 P3E_CPU1_PE3_MP_C_TXP<3> PCIE_TX_DN3 @BASEBOARD_FAB2_LIB.BASEBOARD_FAB2(SCH_1):P3E_CPU1_PE3_MP_C_TXP(3)
  B8 P3E_CPU1_PE3_MP_C_TXN<0> PCIE_TX_DP0 @BASEBOARD_FAB2_LIB.BASEBOARD_FAB2(SCH_1):P3E_CPU1_PE3_MP_C_TXN(0)
  C1    GND   GND3 @BASEBOARD_FAB2_LIB.BASEBOARD_FAB2(SCH_1):GND
  C2 P3E_CPU1_PE3_MP_RXP<3> PCIE_RX_DN3 @BASEBOARD_FAB2_LIB.BASEBOARD_FAB2(SCH_1):P3E_CPU1_PE3_MP_RXP(3)
  C3    GND   GND4 @BASEBOARD_FAB2_LIB.BASEBOARD_FAB2(SCH_1):GND
  C4 FAN_TACH1_R FAN_TACH1 @BASEBOARD_FAB2_LIB.BASEBOARD_FAB2(SCH_1):FAN_TACH1_R
  C5    GND   GND5 @BASEBOARD_FAB2_LIB.BASEBOARD_FAB2(SCH_1):GND
  C6 SMB_BMC_PMBUS_STBY_LVC3_SCL PMBUS_CLK @BASEBOARD_FAB2_LIB.BASEBOARD_FAB2(SCH_1):SMB_BMC_PMBUS_STBY_LVC3_SCL
  C7    GND   GND6 @BASEBOARD_FAB2_LIB.BASEBOARD_FAB2(SCH_1):GND
  C8 P3E_CPU1_PE3_MP_C_TXP<0> PCIE_TX_DN0 @BASEBOARD_FAB2_LIB.BASEBOARD_FAB2(SCH_1):P3E_CPU1_PE3_MP_C_TXP(0)
  D1 P3E_CPU1_PE3_MP_RXN<1> PCIE_RX_DP1 @BASEBOARD_FAB2_LIB.BASEBOARD_FAB2(SCH_1):P3E_CPU1_PE3_MP_RXN(1)
  D2    GND   GND7 @BASEBOARD_FAB2_LIB.BASEBOARD_FAB2(SCH_1):GND
  D3 P3E_CPU1_PE3_MP_RXN<7> PCIE_RX_DP7 @BASEBOARD_FAB2_LIB.BASEBOARD_FAB2(SCH_1):P3E_CPU1_PE3_MP_RXN(7)
  D4 FAN_TACH0_R FAN_TACH0 @BASEBOARD_FAB2_LIB.BASEBOARD_FAB2(SCH_1):FAN_TACH0_R
  D5 NIC_MDI_MNG_RX_DP MNG_RX_DP @BASEBOARD_FAB2_LIB.BASEBOARD_FAB2(SCH_1):NIC_MDI_MNG_RX_DP
  D6    GND   GND8 @BASEBOARD_FAB2_LIB.BASEBOARD_FAB2(SCH_1):GND
  D7 P3E_CPU1_PE3_MP_C_TXN<4> PCIE_TX_DP4 @BASEBOARD_FAB2_LIB.BASEBOARD_FAB2(SCH_1):P3E_CPU1_PE3_MP_C_TXN(4)
  D8    GND   GND9 @BASEBOARD_FAB2_LIB.BASEBOARD_FAB2(SCH_1):GND
  E1 P3E_CPU1_PE3_MP_RXP<1> PCIE_RX_DN1 @BASEBOARD_FAB2_LIB.BASEBOARD_FAB2(SCH_1):P3E_CPU1_PE3_MP_RXP(1)
  E2 P3E_CPU1_PE3_MP_RXN<4> PCIE_RX_DP4 @BASEBOARD_FAB2_LIB.BASEBOARD_FAB2(SCH_1):P3E_CPU1_PE3_MP_RXN(4)
  E3 P3E_CPU1_PE3_MP_RXP<7> PCIE_RX_DN7 @BASEBOARD_FAB2_LIB.BASEBOARD_FAB2(SCH_1):P3E_CPU1_PE3_MP_RXP(7)
  E4 FM_MATED_IN_N MATED_IN# @BASEBOARD_FAB2_LIB.BASEBOARD_FAB2(SCH_1):FM_MATED_IN_N
  E5 NIC_MDI_MNG_RX_DN MNG_RX_DN @BASEBOARD_FAB2_LIB.BASEBOARD_FAB2(SCH_1):NIC_MDI_MNG_RX_DN
  E6 P3E_CPU1_PE3_MP_C_TXN<6> PCIE_TX_DP6 @BASEBOARD_FAB2_LIB.BASEBOARD_FAB2(SCH_1):P3E_CPU1_PE3_MP_C_TXN(6)
  E7 P3E_CPU1_PE3_MP_C_TXP<4> PCIE_TX_DN4 @BASEBOARD_FAB2_LIB.BASEBOARD_FAB2(SCH_1):P3E_CPU1_PE3_MP_C_TXP(4)
  E8 P3E_CPU1_PE3_MP_C_TXN<1> PCIE_TX_DP1 @BASEBOARD_FAB2_LIB.BASEBOARD_FAB2(SCH_1):P3E_CPU1_PE3_MP_C_TXN(1)
  F1    GND  GND10 @BASEBOARD_FAB2_LIB.BASEBOARD_FAB2(SCH_1):GND
  F2 P3E_CPU1_PE3_MP_RXP<4> PCIE_RX_DN4 @BASEBOARD_FAB2_LIB.BASEBOARD_FAB2(SCH_1):P3E_CPU1_PE3_MP_RXP(4)
  F3    GND  GND11 @BASEBOARD_FAB2_LIB.BASEBOARD_FAB2(SCH_1):GND
  F4 FAN_PWM_OUT_SYS0_R1 FAN_PWM0 @BASEBOARD_FAB2_LIB.BASEBOARD_FAB2(SCH_1):FAN_PWM_OUT_SYS0_R1
  F5 FM_MB_SLOT_ID0 MB_SLOT_ID0 @BASEBOARD_FAB2_LIB.BASEBOARD_FAB2(SCH_1):FM_MB_SLOT_ID0
  F6 P3E_CPU1_PE3_MP_C_TXP<6> PCIE_TX_DN6 @BASEBOARD_FAB2_LIB.BASEBOARD_FAB2(SCH_1):P3E_CPU1_PE3_MP_C_TXP(6)
  F7    GND  GND12 @BASEBOARD_FAB2_LIB.BASEBOARD_FAB2(SCH_1):GND
  F8 P3E_CPU1_PE3_MP_C_TXP<1> PCIE_TX_DN1 @BASEBOARD_FAB2_LIB.BASEBOARD_FAB2(SCH_1):P3E_CPU1_PE3_MP_C_TXP(1)
  G1 P3E_CPU1_PE3_MP_RXP<2> PCIE_RX_DP2 @BASEBOARD_FAB2_LIB.BASEBOARD_FAB2(SCH_1):P3E_CPU1_PE3_MP_RXP(2)
  G2    GND  GND13 @BASEBOARD_FAB2_LIB.BASEBOARD_FAB2(SCH_1):GND
  G3 SPA_MID_DBG_TX_R COM_TX @BASEBOARD_FAB2_LIB.BASEBOARD_FAB2(SCH_1):SPA_MID_DBG_TX_R
  G4    GND  GND14 @BASEBOARD_FAB2_LIB.BASEBOARD_FAB2(SCH_1):GND
  G5 FM_MB_SLOT_ID1 MB_SLOT_ID1 @BASEBOARD_FAB2_LIB.BASEBOARD_FAB2(SCH_1):FM_MB_SLOT_ID1
  G6    GND  GND15 @BASEBOARD_FAB2_LIB.BASEBOARD_FAB2(SCH_1):GND
  G7 P3E_CPU1_PE3_MP_C_TXP<5> PCIE_TX_DP5 @BASEBOARD_FAB2_LIB.BASEBOARD_FAB2(SCH_1):P3E_CPU1_PE3_MP_C_TXP(5)
  G8    GND  GND16 @BASEBOARD_FAB2_LIB.BASEBOARD_FAB2(SCH_1):GND
  H1 P3E_CPU1_PE3_MP_RXN<2> PCIE_RX_DN2 @BASEBOARD_FAB2_LIB.BASEBOARD_FAB2(SCH_1):P3E_CPU1_PE3_MP_RXN(2)
  H2 P3E_CPU1_PE3_MP_RXP<5> PCIE_RX_DP5 @BASEBOARD_FAB2_LIB.BASEBOARD_FAB2(SCH_1):P3E_CPU1_PE3_MP_RXP(5)
  H3 SPA_MID_DBG_RX_R COM_RX @BASEBOARD_FAB2_LIB.BASEBOARD_FAB2(SCH_1):SPA_MID_DBG_RX_R
  H4 CLK_100M_AIRMAX8_PE1_DP PCIE_CLK_100M_DP @BASEBOARD_FAB2_LIB.BASEBOARD_FAB2(SCH_1):CLK_100M_AIRMAX8_PE1_DP
  H5 FM_MB_SLOT_ID2 MB_SLOT_ID2 @BASEBOARD_FAB2_LIB.BASEBOARD_FAB2(SCH_1):FM_MB_SLOT_ID2
  H6 P3E_CPU1_PE3_MP_C_TXP<7> PCIE_TX_DP7 @BASEBOARD_FAB2_LIB.BASEBOARD_FAB2(SCH_1):P3E_CPU1_PE3_MP_C_TXP(7)
  H7 P3E_CPU1_PE3_MP_C_TXN<5> PCIE_TX_DN5 @BASEBOARD_FAB2_LIB.BASEBOARD_FAB2(SCH_1):P3E_CPU1_PE3_MP_C_TXN(5)
  H8 P3E_CPU1_PE3_MP_C_TXN<2> PCIE_TX_DP2 @BASEBOARD_FAB2_LIB.BASEBOARD_FAB2(SCH_1):P3E_CPU1_PE3_MP_C_TXN(2)
  I1    GND  GND17 @BASEBOARD_FAB2_LIB.BASEBOARD_FAB2(SCH_1):GND
  I2 P3E_CPU1_PE3_MP_RXN<5> PCIE_RX_DN5 @BASEBOARD_FAB2_LIB.BASEBOARD_FAB2(SCH_1):P3E_CPU1_PE3_MP_RXN(5)
  I3 FM_ENABLE_FAN_POWER MB_ON# @BASEBOARD_FAB2_LIB.BASEBOARD_FAB2(SCH_1):FM_ENABLE_FAN_POWER
  I4 CLK_100M_AIRMAX8_PE1_DN PCIE_CLK_100M_DN @BASEBOARD_FAB2_LIB.BASEBOARD_FAB2(SCH_1):CLK_100M_AIRMAX8_PE1_DN
  I5 RST_PCIE_MIDPLANE_N PCIE_PERST# @BASEBOARD_FAB2_LIB.BASEBOARD_FAB2(SCH_1):RST_PCIE_MIDPLANE_N
  I6 P3E_CPU1_PE3_MP_C_TXN<7> PCIE_TX_DN7 @BASEBOARD_FAB2_LIB.BASEBOARD_FAB2(SCH_1):P3E_CPU1_PE3_MP_C_TXN(7)
  I7    GND  GND18 @BASEBOARD_FAB2_LIB.BASEBOARD_FAB2(SCH_1):GND
  I8 P3E_CPU1_PE3_MP_C_TXP<2> PCIE_TX_DN2 @BASEBOARD_FAB2_LIB.BASEBOARD_FAB2(SCH_1):P3E_CPU1_PE3_MP_C_TXP(2)
  J2    GND     J2 @BASEBOARD_FAB2_LIB.BASEBOARD_FAB2(SCH_1):GND
  J4    GND     J4 @BASEBOARD_FAB2_LIB.BASEBOARD_FAB2(SCH_1):GND
  J6    GND     J6 @BASEBOARD_FAB2_LIB.BASEBOARD_FAB2(SCH_1):GND
  J8    GND     J8 @BASEBOARD_FAB2_LIB.BASEBOARD_FAB2(SCH_1):GND

RES_0402-0.0,5%,1/16W,CHIP,G21A  I137  R9T8
   1 FM_MATED_IN_N      A @BASEBOARD_FAB2_LIB.BASEBOARD_FAB2(SCH_1):FM_MATED_IN_N
   2    GND      B @BASEBOARD_FAB2_LIB.BASEBOARD_FAB2(SCH_1):GND


DRAWING: @BASEBOARD_FAB2_LIB.BASEBOARD_FAB2(SCH_1):PAGE182 

RES_0402-0.0,5%,1/16W,EMPTY,G2A  I6  R1C31
   1 FM_XRC_READY_N      A @BASEBOARD_FAB2_LIB.BASEBOARD_FAB2(SCH_1):FM_XRC_READY_N
   2 FAN_TACH0_R      B @BASEBOARD_FAB2_LIB.BASEBOARD_FAB2(SCH_1):FAN_TACH0_R

RES_0402-0.0,5%,1/16W,EMPTY,G2A  I7  R1F9
   1 FM_BMC_READY_N      A @BASEBOARD_FAB2_LIB.BASEBOARD_FAB2(SCH_1):FM_BMC_READY_N
   2 FAN_PWM_OUT_SYS0_R1      B @BASEBOARD_FAB2_LIB.BASEBOARD_FAB2(SCH_1):FAN_PWM_OUT_SYS0_R1

RES_0402-0.0,5%,1/16W,EMPTY,G2A  I8  R1C9
   1 IRQ_BOARD_BMC_ALERT_N      A @BASEBOARD_FAB2_LIB.BASEBOARD_FAB2(SCH_1):IRQ_BOARD_BMC_ALERT_N
   2 FAN_TACH2_R      B @BASEBOARD_FAB2_LIB.BASEBOARD_FAB2(SCH_1):FAN_TACH2_R

RES_0402-0.0,5%,1/16W,EMPTY,G2A  I9  R1C10
   1 SMB_LAN_STBY_LVC3_SDA      A @BASEBOARD_FAB2_LIB.BASEBOARD_FAB2(SCH_1):SMB_LAN_STBY_LVC3_SDA
   2 FAN_TACH3_R      B @BASEBOARD_FAB2_LIB.BASEBOARD_FAB2(SCH_1):FAN_TACH3_R

RES_0402-0.0,5%,1/16W,EMPTY,G2A  I10  R1C11
   1 SMB_LAN_STBY_LVC3_SCL      A @BASEBOARD_FAB2_LIB.BASEBOARD_FAB2(SCH_1):SMB_LAN_STBY_LVC3_SCL
   2 FAN_TACH1_R      B @BASEBOARD_FAB2_LIB.BASEBOARD_FAB2(SCH_1):FAN_TACH1_R

CAP_0402-0.22UF,16V,10%,X7R,A3A  I36  C9N2
   1 P3E_CPU1_PE3_MP_C_TXN<10>      A @BASEBOARD_FAB2_LIB.BASEBOARD_FAB2(SCH_1):P3E_CPU1_PE3_MP_C_TXN(10)
   2 P3E_CPU1_PE3_MP_TXN<10>      B @BASEBOARD_FAB2_LIB.BASEBOARD_FAB2(SCH_1):P3E_CPU1_PE3_MP_TXN(10)

CAP_0402-0.22UF,16V,10%,X7R,A3A  I37  C9N12
   1 P3E_CPU1_PE3_MP_C_TXP<9>      A @BASEBOARD_FAB2_LIB.BASEBOARD_FAB2(SCH_1):P3E_CPU1_PE3_MP_C_TXP(9)
   2 P3E_CPU1_PE3_MP_TXP<9>      B @BASEBOARD_FAB2_LIB.BASEBOARD_FAB2(SCH_1):P3E_CPU1_PE3_MP_TXP(9)

CAP_0402-0.22UF,16V,10%,X7R,A3A  I38  C9N17
   1 P3E_CPU1_PE3_MP_C_TXP<8>      A @BASEBOARD_FAB2_LIB.BASEBOARD_FAB2(SCH_1):P3E_CPU1_PE3_MP_C_TXP(8)
   2 P3E_CPU1_PE3_MP_TXP<8>      B @BASEBOARD_FAB2_LIB.BASEBOARD_FAB2(SCH_1):P3E_CPU1_PE3_MP_TXP(8)

CAP_0402-0.22UF,16V,10%,X7R,A3A  I39  C9N18
   1 P3E_CPU1_PE3_MP_C_TXN<8>      A @BASEBOARD_FAB2_LIB.BASEBOARD_FAB2(SCH_1):P3E_CPU1_PE3_MP_C_TXN(8)
   2 P3E_CPU1_PE3_MP_TXN<8>      B @BASEBOARD_FAB2_LIB.BASEBOARD_FAB2(SCH_1):P3E_CPU1_PE3_MP_TXN(8)

CAP_0402-0.22UF,16V,10%,X7R,A3A  I40  C9N1
   1 P3E_CPU1_PE3_MP_C_TXP<10>      A @BASEBOARD_FAB2_LIB.BASEBOARD_FAB2(SCH_1):P3E_CPU1_PE3_MP_C_TXP(10)
   2 P3E_CPU1_PE3_MP_TXP<10>      B @BASEBOARD_FAB2_LIB.BASEBOARD_FAB2(SCH_1):P3E_CPU1_PE3_MP_TXP(10)

CAP_0402-0.22UF,16V,10%,X7R,A3A  I41  C9N15
   1 P3E_CPU1_PE3_MP_C_TXN<9>      A @BASEBOARD_FAB2_LIB.BASEBOARD_FAB2(SCH_1):P3E_CPU1_PE3_MP_C_TXN(9)
   2 P3E_CPU1_PE3_MP_TXN<9>      B @BASEBOARD_FAB2_LIB.BASEBOARD_FAB2(SCH_1):P3E_CPU1_PE3_MP_TXN(9)

CAP_0402-0.22UF,16V,10%,X7R,A3A  I42  C9N6
   1 P3E_CPU1_PE3_MP_C_TXN<13>      A @BASEBOARD_FAB2_LIB.BASEBOARD_FAB2(SCH_1):P3E_CPU1_PE3_MP_C_TXN(13)
   2 P3E_CPU1_PE3_MP_TXN<13>      B @BASEBOARD_FAB2_LIB.BASEBOARD_FAB2(SCH_1):P3E_CPU1_PE3_MP_TXN(13)

CAP_0402-0.22UF,16V,10%,X7R,A3A  I43  C9N14
   1 P3E_CPU1_PE3_MP_C_TXP<12>      A @BASEBOARD_FAB2_LIB.BASEBOARD_FAB2(SCH_1):P3E_CPU1_PE3_MP_C_TXP(12)
   2 P3E_CPU1_PE3_MP_TXP<12>      B @BASEBOARD_FAB2_LIB.BASEBOARD_FAB2(SCH_1):P3E_CPU1_PE3_MP_TXP(12)

CAP_0402-0.22UF,16V,10%,X7R,A3A  I44  C9N4
   1 P3E_CPU1_PE3_MP_C_TXP<11>      A @BASEBOARD_FAB2_LIB.BASEBOARD_FAB2(SCH_1):P3E_CPU1_PE3_MP_C_TXP(11)
   2 P3E_CPU1_PE3_MP_TXP<11>      B @BASEBOARD_FAB2_LIB.BASEBOARD_FAB2(SCH_1):P3E_CPU1_PE3_MP_TXP(11)

CAP_0402-0.22UF,16V,10%,X7R,A3A  I45  C9N5
   1 P3E_CPU1_PE3_MP_C_TXP<13>      A @BASEBOARD_FAB2_LIB.BASEBOARD_FAB2(SCH_1):P3E_CPU1_PE3_MP_C_TXP(13)
   2 P3E_CPU1_PE3_MP_TXP<13>      B @BASEBOARD_FAB2_LIB.BASEBOARD_FAB2(SCH_1):P3E_CPU1_PE3_MP_TXP(13)

CAP_0402-0.22UF,16V,10%,X7R,A3A  I46  C9N16
   1 P3E_CPU1_PE3_MP_C_TXN<12>      A @BASEBOARD_FAB2_LIB.BASEBOARD_FAB2(SCH_1):P3E_CPU1_PE3_MP_C_TXN(12)
   2 P3E_CPU1_PE3_MP_TXN<12>      B @BASEBOARD_FAB2_LIB.BASEBOARD_FAB2(SCH_1):P3E_CPU1_PE3_MP_TXN(12)

CAP_0402-0.22UF,16V,10%,X7R,A3A  I47  C9N3
   1 P3E_CPU1_PE3_MP_C_TXN<11>      A @BASEBOARD_FAB2_LIB.BASEBOARD_FAB2(SCH_1):P3E_CPU1_PE3_MP_C_TXN(11)
   2 P3E_CPU1_PE3_MP_TXN<11>      B @BASEBOARD_FAB2_LIB.BASEBOARD_FAB2(SCH_1):P3E_CPU1_PE3_MP_TXN(11)

CAP_0402-0.22UF,16V,10%,X7R,A3A  I48  C9N7
   1 P3E_CPU1_PE3_MP_C_TXP<15>      A @BASEBOARD_FAB2_LIB.BASEBOARD_FAB2(SCH_1):P3E_CPU1_PE3_MP_C_TXP(15)
   2 P3E_CPU1_PE3_MP_TXP<15>      B @BASEBOARD_FAB2_LIB.BASEBOARD_FAB2(SCH_1):P3E_CPU1_PE3_MP_TXP(15)

CAP_0402-0.22UF,16V,10%,X7R,A3A  I49  C9N10
   1 P3E_CPU1_PE3_MP_C_TXP<14>      A @BASEBOARD_FAB2_LIB.BASEBOARD_FAB2(SCH_1):P3E_CPU1_PE3_MP_C_TXP(14)
   2 P3E_CPU1_PE3_MP_TXP<14>      B @BASEBOARD_FAB2_LIB.BASEBOARD_FAB2(SCH_1):P3E_CPU1_PE3_MP_TXP(14)

CAP_0402-0.22UF,16V,10%,X7R,A3A  I52  C9N9
   1 P3E_CPU1_PE3_MP_C_TXN<15>      A @BASEBOARD_FAB2_LIB.BASEBOARD_FAB2(SCH_1):P3E_CPU1_PE3_MP_C_TXN(15)
   2 P3E_CPU1_PE3_MP_TXN<15>      B @BASEBOARD_FAB2_LIB.BASEBOARD_FAB2(SCH_1):P3E_CPU1_PE3_MP_TXN(15)

CAP_0402-0.22UF,16V,10%,X7R,A3A  I53  C9N8
   1 P3E_CPU1_PE3_MP_C_TXN<14>      A @BASEBOARD_FAB2_LIB.BASEBOARD_FAB2(SCH_1):P3E_CPU1_PE3_MP_C_TXN(14)
   2 P3E_CPU1_PE3_MP_TXN<14>      B @BASEBOARD_FAB2_LIB.BASEBOARD_FAB2(SCH_1):P3E_CPU1_PE3_MP_TXN(14)

DM-FCI-CONN76-8R-GP-U-01_CONN-A  I79  J1C1
  A1 P3E_CPU1_PE3_MP_RXN<8> PCIE_RX_DP0 @BASEBOARD_FAB2_LIB.BASEBOARD_FAB2(SCH_1):P3E_CPU1_PE3_MP_RXN(8)
  A2    GND   GND1 @BASEBOARD_FAB2_LIB.BASEBOARD_FAB2(SCH_1):GND
  A3 P3E_CPU1_PE3_MP_RXP<14> PCIE_RX_DP6 @BASEBOARD_FAB2_LIB.BASEBOARD_FAB2(SCH_1):P3E_CPU1_PE3_MP_RXP(14)
  A4    GND FAN_TACH3 @BASEBOARD_FAB2_LIB.BASEBOARD_FAB2(SCH_1):GND
  A5 TP_IOA5 MNG_TX_DP @BASEBOARD_FAB2_LIB.BASEBOARD_FAB2(SCH_1):TP_IOA5
  A6    GND PMBUS_ALERT# @BASEBOARD_FAB2_LIB.BASEBOARD_FAB2(SCH_1):GND
  A7 P3E_CPU1_PE3_MP_C_TXN<11> PCIE_TX_DP3 @BASEBOARD_FAB2_LIB.BASEBOARD_FAB2(SCH_1):P3E_CPU1_PE3_MP_C_TXN(11)
  A8    GND   GND2 @BASEBOARD_FAB2_LIB.BASEBOARD_FAB2(SCH_1):GND
  B1 P3E_CPU1_PE3_MP_RXP<8> PCIE_RX_DN0 @BASEBOARD_FAB2_LIB.BASEBOARD_FAB2(SCH_1):P3E_CPU1_PE3_MP_RXP(8)
  B2 P3E_CPU1_PE3_MP_RXN<11> PCIE_RX_DP3 @BASEBOARD_FAB2_LIB.BASEBOARD_FAB2(SCH_1):P3E_CPU1_PE3_MP_RXN(11)
  B3 P3E_CPU1_PE3_MP_RXN<14> PCIE_RX_DN6 @BASEBOARD_FAB2_LIB.BASEBOARD_FAB2(SCH_1):P3E_CPU1_PE3_MP_RXN(14)
  B4 TP_FM_WAKE_N FAN_TACH2 @BASEBOARD_FAB2_LIB.BASEBOARD_FAB2(SCH_1):TP_FM_WAKE_N
  B5 IRQ_BOARD_BMC_ALERT_N MNG_TX_DN @BASEBOARD_FAB2_LIB.BASEBOARD_FAB2(SCH_1):IRQ_BOARD_BMC_ALERT_N
  B6 SMB_PEHPCPU1_STBY_LVC3_SDA PMBUS_DATA @BASEBOARD_FAB2_LIB.BASEBOARD_FAB2(SCH_1):SMB_PEHPCPU1_STBY_LVC3_SDA
  B7 P3E_CPU1_PE3_MP_C_TXP<11> PCIE_TX_DN3 @BASEBOARD_FAB2_LIB.BASEBOARD_FAB2(SCH_1):P3E_CPU1_PE3_MP_C_TXP(11)
  B8 P3E_CPU1_PE3_MP_C_TXN<8> PCIE_TX_DP0 @BASEBOARD_FAB2_LIB.BASEBOARD_FAB2(SCH_1):P3E_CPU1_PE3_MP_C_TXN(8)
  C1    GND   GND3 @BASEBOARD_FAB2_LIB.BASEBOARD_FAB2(SCH_1):GND
  C2 P3E_CPU1_PE3_MP_RXP<11> PCIE_RX_DN3 @BASEBOARD_FAB2_LIB.BASEBOARD_FAB2(SCH_1):P3E_CPU1_PE3_MP_RXP(11)
  C3    GND   GND4 @BASEBOARD_FAB2_LIB.BASEBOARD_FAB2(SCH_1):GND
  C4 FM_BB_BMC_MP_GPIO FAN_TACH1 @BASEBOARD_FAB2_LIB.BASEBOARD_FAB2(SCH_1):FM_BB_BMC_MP_GPIO
  C5    GND   GND5 @BASEBOARD_FAB2_LIB.BASEBOARD_FAB2(SCH_1):GND
  C6 SMB_PEHPCPU1_STBY_LVC3_SCL PMBUS_CLK @BASEBOARD_FAB2_LIB.BASEBOARD_FAB2(SCH_1):SMB_PEHPCPU1_STBY_LVC3_SCL
  C7    GND   GND6 @BASEBOARD_FAB2_LIB.BASEBOARD_FAB2(SCH_1):GND
  C8 P3E_CPU1_PE3_MP_C_TXP<8> PCIE_TX_DN0 @BASEBOARD_FAB2_LIB.BASEBOARD_FAB2(SCH_1):P3E_CPU1_PE3_MP_C_TXP(8)
  D1 P3E_CPU1_PE3_MP_RXN<9> PCIE_RX_DP1 @BASEBOARD_FAB2_LIB.BASEBOARD_FAB2(SCH_1):P3E_CPU1_PE3_MP_RXN(9)
  D2    GND   GND7 @BASEBOARD_FAB2_LIB.BASEBOARD_FAB2(SCH_1):GND
  D3 P3E_CPU1_PE3_MP_RXN<15> PCIE_RX_DP7 @BASEBOARD_FAB2_LIB.BASEBOARD_FAB2(SCH_1):P3E_CPU1_PE3_MP_RXN(15)
  D4    GND FAN_TACH0 @BASEBOARD_FAB2_LIB.BASEBOARD_FAB2(SCH_1):GND
  D5 SMB_LAN_STBY_LVC3_SDA MNG_RX_DP @BASEBOARD_FAB2_LIB.BASEBOARD_FAB2(SCH_1):SMB_LAN_STBY_LVC3_SDA
  D6    GND   GND8 @BASEBOARD_FAB2_LIB.BASEBOARD_FAB2(SCH_1):GND
  D7 P3E_CPU1_PE3_MP_C_TXN<12> PCIE_TX_DP4 @BASEBOARD_FAB2_LIB.BASEBOARD_FAB2(SCH_1):P3E_CPU1_PE3_MP_C_TXN(12)
  D8    GND   GND9 @BASEBOARD_FAB2_LIB.BASEBOARD_FAB2(SCH_1):GND
  E1 P3E_CPU1_PE3_MP_RXP<9> PCIE_RX_DN1 @BASEBOARD_FAB2_LIB.BASEBOARD_FAB2(SCH_1):P3E_CPU1_PE3_MP_RXP(9)
  E2 P3E_CPU1_PE3_MP_RXN<12> PCIE_RX_DP4 @BASEBOARD_FAB2_LIB.BASEBOARD_FAB2(SCH_1):P3E_CPU1_PE3_MP_RXN(12)
  E3 P3E_CPU1_PE3_MP_RXP<15> PCIE_RX_DN7 @BASEBOARD_FAB2_LIB.BASEBOARD_FAB2(SCH_1):P3E_CPU1_PE3_MP_RXP(15)
  E4 TP_IOE4 MATED_IN# @BASEBOARD_FAB2_LIB.BASEBOARD_FAB2(SCH_1):TP_IOE4
  E5 SMB_LAN_STBY_LVC3_SCL MNG_RX_DN @BASEBOARD_FAB2_LIB.BASEBOARD_FAB2(SCH_1):SMB_LAN_STBY_LVC3_SCL
  E6 P3E_CPU1_PE3_MP_C_TXN<14> PCIE_TX_DP6 @BASEBOARD_FAB2_LIB.BASEBOARD_FAB2(SCH_1):P3E_CPU1_PE3_MP_C_TXN(14)
  E7 P3E_CPU1_PE3_MP_C_TXP<12> PCIE_TX_DN4 @BASEBOARD_FAB2_LIB.BASEBOARD_FAB2(SCH_1):P3E_CPU1_PE3_MP_C_TXP(12)
  E8 P3E_CPU1_PE3_MP_C_TXN<9> PCIE_TX_DP1 @BASEBOARD_FAB2_LIB.BASEBOARD_FAB2(SCH_1):P3E_CPU1_PE3_MP_C_TXN(9)
  F1    GND  GND10 @BASEBOARD_FAB2_LIB.BASEBOARD_FAB2(SCH_1):GND
  F2 P3E_CPU1_PE3_MP_RXP<12> PCIE_RX_DN4 @BASEBOARD_FAB2_LIB.BASEBOARD_FAB2(SCH_1):P3E_CPU1_PE3_MP_RXP(12)
  F3    GND  GND11 @BASEBOARD_FAB2_LIB.BASEBOARD_FAB2(SCH_1):GND
  F4 TP_IOF4 FAN_PWM0 @BASEBOARD_FAB2_LIB.BASEBOARD_FAB2(SCH_1):TP_IOF4
  F5    GND MB_SLOT_ID0 @BASEBOARD_FAB2_LIB.BASEBOARD_FAB2(SCH_1):GND
  F6 P3E_CPU1_PE3_MP_C_TXP<14> PCIE_TX_DN6 @BASEBOARD_FAB2_LIB.BASEBOARD_FAB2(SCH_1):P3E_CPU1_PE3_MP_C_TXP(14)
  F7    GND  GND12 @BASEBOARD_FAB2_LIB.BASEBOARD_FAB2(SCH_1):GND
  F8 P3E_CPU1_PE3_MP_C_TXP<9> PCIE_TX_DN1 @BASEBOARD_FAB2_LIB.BASEBOARD_FAB2(SCH_1):P3E_CPU1_PE3_MP_C_TXP(9)
  G1 P3E_CPU1_PE3_MP_RXP<10> PCIE_RX_DP2 @BASEBOARD_FAB2_LIB.BASEBOARD_FAB2(SCH_1):P3E_CPU1_PE3_MP_RXP(10)
  G2    GND  GND13 @BASEBOARD_FAB2_LIB.BASEBOARD_FAB2(SCH_1):GND
  G3 TP_IOG3 COM_TX @BASEBOARD_FAB2_LIB.BASEBOARD_FAB2(SCH_1):TP_IOG3
  G4    GND  GND14 @BASEBOARD_FAB2_LIB.BASEBOARD_FAB2(SCH_1):GND
  G5 FM_XRC_PRESENT_N MB_SLOT_ID1 @BASEBOARD_FAB2_LIB.BASEBOARD_FAB2(SCH_1):FM_XRC_PRESENT_N
  G6    GND  GND15 @BASEBOARD_FAB2_LIB.BASEBOARD_FAB2(SCH_1):GND
  G7 P3E_CPU1_PE3_MP_C_TXN<13> PCIE_TX_DP5 @BASEBOARD_FAB2_LIB.BASEBOARD_FAB2(SCH_1):P3E_CPU1_PE3_MP_C_TXN(13)
  G8    GND  GND16 @BASEBOARD_FAB2_LIB.BASEBOARD_FAB2(SCH_1):GND
  H1 P3E_CPU1_PE3_MP_RXN<10> PCIE_RX_DN2 @BASEBOARD_FAB2_LIB.BASEBOARD_FAB2(SCH_1):P3E_CPU1_PE3_MP_RXN(10)
  H2 P3E_CPU1_PE3_MP_RXP<13> PCIE_RX_DP5 @BASEBOARD_FAB2_LIB.BASEBOARD_FAB2(SCH_1):P3E_CPU1_PE3_MP_RXP(13)
  H3 TP_IOH3 COM_RX @BASEBOARD_FAB2_LIB.BASEBOARD_FAB2(SCH_1):TP_IOH3
  H4 TP_IOH4 PCIE_CLK_100M_DP @BASEBOARD_FAB2_LIB.BASEBOARD_FAB2(SCH_1):TP_IOH4
  H5 FM_XRC_READY_N MB_SLOT_ID2 @BASEBOARD_FAB2_LIB.BASEBOARD_FAB2(SCH_1):FM_XRC_READY_N
  H6 P3E_CPU1_PE3_MP_C_TXN<15> PCIE_TX_DP7 @BASEBOARD_FAB2_LIB.BASEBOARD_FAB2(SCH_1):P3E_CPU1_PE3_MP_C_TXN(15)
  H7 P3E_CPU1_PE3_MP_C_TXP<13> PCIE_TX_DN5 @BASEBOARD_FAB2_LIB.BASEBOARD_FAB2(SCH_1):P3E_CPU1_PE3_MP_C_TXP(13)
  H8 P3E_CPU1_PE3_MP_C_TXP<10> PCIE_TX_DP2 @BASEBOARD_FAB2_LIB.BASEBOARD_FAB2(SCH_1):P3E_CPU1_PE3_MP_C_TXP(10)
  I1    GND  GND17 @BASEBOARD_FAB2_LIB.BASEBOARD_FAB2(SCH_1):GND
  I2 P3E_CPU1_PE3_MP_RXN<13> PCIE_RX_DN5 @BASEBOARD_FAB2_LIB.BASEBOARD_FAB2(SCH_1):P3E_CPU1_PE3_MP_RXN(13)
  I3    GND MB_ON# @BASEBOARD_FAB2_LIB.BASEBOARD_FAB2(SCH_1):GND
  I4 TP_IOI4 PCIE_CLK_100M_DN @BASEBOARD_FAB2_LIB.BASEBOARD_FAB2(SCH_1):TP_IOI4
  I5    GND PCIE_PERST# @BASEBOARD_FAB2_LIB.BASEBOARD_FAB2(SCH_1):GND
  I6 P3E_CPU1_PE3_MP_C_TXP<15> PCIE_TX_DN7 @BASEBOARD_FAB2_LIB.BASEBOARD_FAB2(SCH_1):P3E_CPU1_PE3_MP_C_TXP(15)
  I7    GND  GND18 @BASEBOARD_FAB2_LIB.BASEBOARD_FAB2(SCH_1):GND
  I8 P3E_CPU1_PE3_MP_C_TXN<10> PCIE_TX_DN2 @BASEBOARD_FAB2_LIB.BASEBOARD_FAB2(SCH_1):P3E_CPU1_PE3_MP_C_TXN(10)
  J2    GND     J2 @BASEBOARD_FAB2_LIB.BASEBOARD_FAB2(SCH_1):GND
  J4    GND     J4 @BASEBOARD_FAB2_LIB.BASEBOARD_FAB2(SCH_1):GND
  J6    GND     J6 @BASEBOARD_FAB2_LIB.BASEBOARD_FAB2(SCH_1):GND
  J8    GND     J8 @BASEBOARD_FAB2_LIB.BASEBOARD_FAB2(SCH_1):GND


DRAWING: @BASEBOARD_FAB2_LIB.BASEBOARD_FAB2(SCH_1):PAGE269 

RES_0402-10.0K,1%,1/16W,CHIP,GA  I4  R25W174
   1 P3V3_STBY      A @BASEBOARD_FAB2_LIB.BASEBOARD_FAB2(SCH_1):P3V3_STBY
   2 BMC_JTAG_SEL_N      B @BASEBOARD_FAB2_LIB.BASEBOARD_FAB2(SCH_1):BMC_JTAG_SEL_N

RES_0402-1.00K,1%,1/16W,CHIP,GA  I10  R25W167
   1 BMC_TCK_MUX_SEL      A @BASEBOARD_FAB2_LIB.BASEBOARD_FAB2(SCH_1):BMC_TCK_MUX_SEL
   2    GND      B @BASEBOARD_FAB2_LIB.BASEBOARD_FAB2(SCH_1):GND

RES_0402-1.00K,1%,1/16W,CHIP,GA  I11  R25W168
   1 JTAG_BMC_TCK0      A @BASEBOARD_FAB2_LIB.BASEBOARD_FAB2(SCH_1):JTAG_BMC_TCK0
   2    GND      B @BASEBOARD_FAB2_LIB.BASEBOARD_FAB2(SCH_1):GND

RES_0402-1.00K,1%,1/16W,CHIP,GA  I12  R25W169
   1 JTAG_BMC_TCK1      A @BASEBOARD_FAB2_LIB.BASEBOARD_FAB2(SCH_1):JTAG_BMC_TCK1
   2    GND      B @BASEBOARD_FAB2_LIB.BASEBOARD_FAB2(SCH_1):GND

RES_0402-1.00K,1%,1/16W,CHIP,GA  I13  R25W170
   1 JTAG_BMC_TRST_BUF_N      A @BASEBOARD_FAB2_LIB.BASEBOARD_FAB2(SCH_1):JTAG_BMC_TRST_BUF_N
   2    GND      B @BASEBOARD_FAB2_LIB.BASEBOARD_FAB2(SCH_1):GND

RES_0402-1.00K,1%,1/16W,CHIP,GA  I18  R25W177
   1 P3V3_STBY      A @BASEBOARD_FAB2_LIB.BASEBOARD_FAB2(SCH_1):P3V3_STBY
   2 BMC_PREQ_BUF_N      B @BASEBOARD_FAB2_LIB.BASEBOARD_FAB2(SCH_1):BMC_PREQ_BUF_N

RES_0402-1.00K,1%,1/16W,CHIP,GA  I19  R25W178
   1 P3V3_STBY      A @BASEBOARD_FAB2_LIB.BASEBOARD_FAB2(SCH_1):P3V3_STBY
   2 BMC_PWR_DEBUG_BUF_N      B @BASEBOARD_FAB2_LIB.BASEBOARD_FAB2(SCH_1):BMC_PWR_DEBUG_BUF_N

RES_0402-1.00K,1%,1/16W,CHIP,GA  I20  R25W160
   1 P3V3_STBY      A @BASEBOARD_FAB2_LIB.BASEBOARD_FAB2(SCH_1):P3V3_STBY
   2 JTAG_BMC_BUF_TDI      B @BASEBOARD_FAB2_LIB.BASEBOARD_FAB2(SCH_1):JTAG_BMC_BUF_TDI

RES_0402-1.00K,1%,1/16W,CHIP,GA  I21  R25W161
   1 P3V3_STBY      A @BASEBOARD_FAB2_LIB.BASEBOARD_FAB2(SCH_1):P3V3_STBY
   2 JTAG_BMC_BUF_TMS      B @BASEBOARD_FAB2_LIB.BASEBOARD_FAB2(SCH_1):JTAG_BMC_BUF_TMS

RES_0402-1.00K,1%,1/16W,CHIP,GA  I22  R25W158
   1 P3V3_STBY      A @BASEBOARD_FAB2_LIB.BASEBOARD_FAB2(SCH_1):P3V3_STBY
   2 PU_GTL2014_3_DIR      B @BASEBOARD_FAB2_LIB.BASEBOARD_FAB2(SCH_1):PU_GTL2014_3_DIR

RES_0402-1.00K,1%,1/16W,CHIP,GA  I24  R25W159
   1    GND      A @BASEBOARD_FAB2_LIB.BASEBOARD_FAB2(SCH_1):GND
   2 PD_GTL2014_3_VREF      B @BASEBOARD_FAB2_LIB.BASEBOARD_FAB2(SCH_1):PD_GTL2014_3_VREF

CAP_A_0402V-1.0UF,6.3V,10%,X6SA  I26  C25W91
   1 P3V3_STBY      A @BASEBOARD_FAB2_LIB.BASEBOARD_FAB2(SCH_1):P3V3_STBY
   2    GND      B @BASEBOARD_FAB2_LIB.BASEBOARD_FAB2(SCH_1):GND

CAP_0402-1.0UF,16V,10%,X6S,D97A  I32  C25W94
   1 P3V3_STBY      A @BASEBOARD_FAB2_LIB.BASEBOARD_FAB2(SCH_1):P3V3_STBY
   2    GND      B @BASEBOARD_FAB2_LIB.BASEBOARD_FAB2(SCH_1):GND

TTL3126_QFNLF-74CBTLV3126,IC,DB  I33  SIZE=4  Summary of common pins:

  Section:  I33(3) U25W12
   1 BMC_JTAG_SEL_BUF  OE<3> @BASEBOARD_FAB2_LIB.BASEBOARD_FAB2(SCH_1):BMC_JTAG_SEL_BUF
   2 BMC_PREQ_N   A<3> @BASEBOARD_FAB2_LIB.BASEBOARD_FAB2(SCH_1):BMC_PREQ_N
   3 BMC_PREQ_BUF_N   B<3> @BASEBOARD_FAB2_LIB.BASEBOARD_FAB2(SCH_1):BMC_PREQ_BUF_N

  Section:  I33(2) U25W12
   4 JTAG_BMC_TCK0  OE<2> @BASEBOARD_FAB2_LIB.BASEBOARD_FAB2(SCH_1):JTAG_BMC_TCK0
   5 P1V05_PCH_STBY   A<2> @BASEBOARD_FAB2_LIB.BASEBOARD_FAB2(SCH_1):P1V05_PCH_STBY
   6 XDP_CPU_TCK0_R   B<2> @BASEBOARD_FAB2_LIB.BASEBOARD_FAB2(SCH_1):XDP_CPU_TCK0_R

  Section:  I33(1) U25W12
  10 JTAG_BMC_TCK1  OE<1> @BASEBOARD_FAB2_LIB.BASEBOARD_FAB2(SCH_1):JTAG_BMC_TCK1
   9 P1V05_PCH_STBY   A<1> @BASEBOARD_FAB2_LIB.BASEBOARD_FAB2(SCH_1):P1V05_PCH_STBY
   8 XDP_PCH_TCK1_R   B<1> @BASEBOARD_FAB2_LIB.BASEBOARD_FAB2(SCH_1):XDP_PCH_TCK1_R

  Section:  I33 U25W12
  13 JTAG_BMC_TRST_BUF_N  OE<0> @BASEBOARD_FAB2_LIB.BASEBOARD_FAB2(SCH_1):JTAG_BMC_TRST_BUF_N
  12 P1V05_PCH_STBY   A<0> @BASEBOARD_FAB2_LIB.BASEBOARD_FAB2(SCH_1):P1V05_PCH_STBY
  11 XDP_TRST_R_N   B<0> @BASEBOARD_FAB2_LIB.BASEBOARD_FAB2(SCH_1):XDP_TRST_R_N

GTL2014_SM-IC,D66151-001  I49  U25W10
  13 BMC_PREQ_BUF_N     A0 @BASEBOARD_FAB2_LIB.BASEBOARD_FAB2(SCH_1):BMC_PREQ_BUF_N
  12 BMC_PWR_DEBUG_BUF_N     A1 @BASEBOARD_FAB2_LIB.BASEBOARD_FAB2(SCH_1):BMC_PWR_DEBUG_BUF_N
  10 JTAG_BMC_BUF_TDI     A2 @BASEBOARD_FAB2_LIB.BASEBOARD_FAB2(SCH_1):JTAG_BMC_BUF_TDI
   9 JTAG_BMC_BUF_TMS     A3 @BASEBOARD_FAB2_LIB.BASEBOARD_FAB2(SCH_1):JTAG_BMC_BUF_TMS
   2 XDP_PREQ_N     B0 @BASEBOARD_FAB2_LIB.BASEBOARD_FAB2(SCH_1):XDP_PREQ_N
   3 XDP_CPU_PWR_DEBUG_N     B1 @BASEBOARD_FAB2_LIB.BASEBOARD_FAB2(SCH_1):XDP_CPU_PWR_DEBUG_N
   5 XDP_TDI_R     B2 @BASEBOARD_FAB2_LIB.BASEBOARD_FAB2(SCH_1):XDP_TDI_R
   6 XDP_TMS_R     B3 @BASEBOARD_FAB2_LIB.BASEBOARD_FAB2(SCH_1):XDP_TMS_R
   1 PU_GTL2014_3_DIR    DIR @BASEBOARD_FAB2_LIB.BASEBOARD_FAB2(SCH_1):PU_GTL2014_3_DIR
  11    GND GND<2> @BASEBOARD_FAB2_LIB.BASEBOARD_FAB2(SCH_1):GND
   8    GND GND<1> @BASEBOARD_FAB2_LIB.BASEBOARD_FAB2(SCH_1):GND
   7    GND GND<0> @BASEBOARD_FAB2_LIB.BASEBOARD_FAB2(SCH_1):GND
  14 P3V3_STBY    VCC @BASEBOARD_FAB2_LIB.BASEBOARD_FAB2(SCH_1):P3V3_STBY
   4 PD_GTL2014_3_VREF   VREF @BASEBOARD_FAB2_LIB.BASEBOARD_FAB2(SCH_1):PD_GTL2014_3_VREF

MAX4564EKA-GP_SCRET-GC1-MAX456A  I53  U25W13
   1 JTAG_BMC_TCK0     NC @BASEBOARD_FAB2_LIB.BASEBOARD_FAB2(SCH_1):JTAG_BMC_TCK0
   2 P3V3_STBY     V+ @BASEBOARD_FAB2_LIB.BASEBOARD_FAB2(SCH_1):P3V3_STBY
   3 BMC_TCK_MUX_SEL     IN @BASEBOARD_FAB2_LIB.BASEBOARD_FAB2(SCH_1):BMC_TCK_MUX_SEL
   4 JTAG_BMC_TCK1     NO @BASEBOARD_FAB2_LIB.BASEBOARD_FAB2(SCH_1):JTAG_BMC_TCK1
   5    GND    GND @BASEBOARD_FAB2_LIB.BASEBOARD_FAB2(SCH_1):GND
   6    GND     V- @BASEBOARD_FAB2_LIB.BASEBOARD_FAB2(SCH_1):GND
   7 BMC_JTAG_SEL_N    EN# @BASEBOARD_FAB2_LIB.BASEBOARD_FAB2(SCH_1):BMC_JTAG_SEL_N
   8 JTAG_BMC_TCK_BUF    COM @BASEBOARD_FAB2_LIB.BASEBOARD_FAB2(SCH_1):JTAG_BMC_TCK_BUF

CAP_A_0402V-0.1UF,16V,10%,X7R,A  I56  C25W95
   1 P3V3_STBY      A @BASEBOARD_FAB2_LIB.BASEBOARD_FAB2(SCH_1):P3V3_STBY
   2    GND      B @BASEBOARD_FAB2_LIB.BASEBOARD_FAB2(SCH_1):GND

TTL1G08_SOTLF-NC7SZ08,IC,D1032B  I61  U25W17
   4 JTAG_BMC_TRST_BUF_N   Y<0> @BASEBOARD_FAB2_LIB.BASEBOARD_FAB2(SCH_1):JTAG_BMC_TRST_BUF_N
   1 JTAG_BMC_TRST_N   A<0> @BASEBOARD_FAB2_LIB.BASEBOARD_FAB2(SCH_1):JTAG_BMC_TRST_N
   2 BMC_JTAG_SEL_BUF   B<0> @BASEBOARD_FAB2_LIB.BASEBOARD_FAB2(SCH_1):BMC_JTAG_SEL_BUF

CAP_A_0402V-0.1UF,16V,10%,X7R,A  I62  C25W99
   1 P3V3_STBY      A @BASEBOARD_FAB2_LIB.BASEBOARD_FAB2(SCH_1):P3V3_STBY
   2    GND      B @BASEBOARD_FAB2_LIB.BASEBOARD_FAB2(SCH_1):GND

BLM15AG121SN-1GP_DISCRET-G-BLMA  I71  FB25W1
   1 XDP_CPU_TCK0_R      1 @BASEBOARD_FAB2_LIB.BASEBOARD_FAB2(SCH_1):XDP_CPU_TCK0_R
   2 XDP_CPU_TCK0      2 @BASEBOARD_FAB2_LIB.BASEBOARD_FAB2(SCH_1):XDP_CPU_TCK0

BLM15AG121SN-1GP_DISCRET-G-BLMA  I72  FB25W2
   1 XDP_PCH_TCK1_R      1 @BASEBOARD_FAB2_LIB.BASEBOARD_FAB2(SCH_1):XDP_PCH_TCK1_R
   2 XDP_PCH_TCK1      2 @BASEBOARD_FAB2_LIB.BASEBOARD_FAB2(SCH_1):XDP_PCH_TCK1

BLM15AG121SN-1GP_DISCRET-G-BLMA  I73  FB25W3
   1 XDP_TRST_R_N      1 @BASEBOARD_FAB2_LIB.BASEBOARD_FAB2(SCH_1):XDP_TRST_R_N
   2 XDP_TRST_N      2 @BASEBOARD_FAB2_LIB.BASEBOARD_FAB2(SCH_1):XDP_TRST_N

BLM15AG121SN-1GP_DISCRET-G-BLMA  I74  FB25W5
   1 XDP_TMS_R      1 @BASEBOARD_FAB2_LIB.BASEBOARD_FAB2(SCH_1):XDP_TMS_R
   2 XDP_TMS      2 @BASEBOARD_FAB2_LIB.BASEBOARD_FAB2(SCH_1):XDP_TMS

BLM15AG121SN-1GP_DISCRET-G-BLMA  I75  FB25W4
   1 XDP_TDI_R      1 @BASEBOARD_FAB2_LIB.BASEBOARD_FAB2(SCH_1):XDP_TDI_R
   2 XDP_TDI      2 @BASEBOARD_FAB2_LIB.BASEBOARD_FAB2(SCH_1):XDP_TDI

TTL1G126_A_SOT-74HC1G126,IC,A7B  I76  U25W19
   1 BMC_JTAG_SEL_BUF     OE @BASEBOARD_FAB2_LIB.BASEBOARD_FAB2(SCH_1):BMC_JTAG_SEL_BUF
   2 JTAG_BMC_TCK      A @BASEBOARD_FAB2_LIB.BASEBOARD_FAB2(SCH_1):JTAG_BMC_TCK
   4 JTAG_BMC_TCK_BUF      Y @BASEBOARD_FAB2_LIB.BASEBOARD_FAB2(SCH_1):JTAG_BMC_TCK_BUF

CAP_A_0402V-0.1UF,16V,10%,X7R,A  I79  C25W101
   1 P3V3_STBY      A @BASEBOARD_FAB2_LIB.BASEBOARD_FAB2(SCH_1):P3V3_STBY
   2    GND      B @BASEBOARD_FAB2_LIB.BASEBOARD_FAB2(SCH_1):GND


DRAWING: @BASEBOARD_FAB2_LIB.BASEBOARD_FAB2(SCH_1):PAGE268 

RES_0402-1.00K,1%,1/16W,CHIP,GA  I2  R25W180
   1 P3V3_STBY      A @BASEBOARD_FAB2_LIB.BASEBOARD_FAB2(SCH_1):P3V3_STBY
   2 BMC_DEBUG_EN_N      B @BASEBOARD_FAB2_LIB.BASEBOARD_FAB2(SCH_1):BMC_DEBUG_EN_N

CAP_A_0402V-0.1UF,16V,10%,X7R,A  I4  C25W97
   1 P3V3_STBY      A @BASEBOARD_FAB2_LIB.BASEBOARD_FAB2(SCH_1):P3V3_STBY
   2    GND      B @BASEBOARD_FAB2_LIB.BASEBOARD_FAB2(SCH_1):GND

RES_0402-1.00K,1%,1/16W,CHIP,GA  I7  R25W179
   1 P3V3_STBY      A @BASEBOARD_FAB2_LIB.BASEBOARD_FAB2(SCH_1):P3V3_STBY
   2 XDP_PRESENT_N      B @BASEBOARD_FAB2_LIB.BASEBOARD_FAB2(SCH_1):XDP_PRESENT_N

CAP_A_0402V-0.1UF,16V,10%,X7R,A  I9  C25W96
   1 P3V3_STBY      A @BASEBOARD_FAB2_LIB.BASEBOARD_FAB2(SCH_1):P3V3_STBY
   2    GND      B @BASEBOARD_FAB2_LIB.BASEBOARD_FAB2(SCH_1):GND

TTL1G07_A_SOP-74LVC1G07,IC,C88B  I12  U25W15
   2 BMC_DEBUG_EN_N      A @BASEBOARD_FAB2_LIB.BASEBOARD_FAB2(SCH_1):BMC_DEBUG_EN_N
   4 CPU_XDP_PRESENT_N      Y @BASEBOARD_FAB2_LIB.BASEBOARD_FAB2(SCH_1):CPU_XDP_PRESENT_N

TTL1G07_A_SOP-74LVC1G07,IC,C88B  I13  U25W14
   2 XDP_PRESENT_N      A @BASEBOARD_FAB2_LIB.BASEBOARD_FAB2(SCH_1):XDP_PRESENT_N
   4 CPU_XDP_PRESENT_N      Y @BASEBOARD_FAB2_LIB.BASEBOARD_FAB2(SCH_1):CPU_XDP_PRESENT_N

RES_0402-1.00K,1%,1/16W,CHIP,GA  I14  R25W176
   1 PD_GTL2014_6_B2      A @BASEBOARD_FAB2_LIB.BASEBOARD_FAB2(SCH_1):PD_GTL2014_6_B2
   2    GND      B @BASEBOARD_FAB2_LIB.BASEBOARD_FAB2(SCH_1):GND

RES_0402-1.00K,1%,1/16W,CHIP,GA  I17  R25W175
   1 PD_GTL2014_6_B0      A @BASEBOARD_FAB2_LIB.BASEBOARD_FAB2(SCH_1):PD_GTL2014_6_B0
   2    GND      B @BASEBOARD_FAB2_LIB.BASEBOARD_FAB2(SCH_1):GND

CAP_0402-1.0UF,16V,10%,X6S,D97A  I23  C25W92
   1 P3V3_STBY      A @BASEBOARD_FAB2_LIB.BASEBOARD_FAB2(SCH_1):P3V3_STBY
   2    GND      B @BASEBOARD_FAB2_LIB.BASEBOARD_FAB2(SCH_1):GND

RES_0402-1.00K,1%,1/16W,CHIP,GA  I26  R25W166
   1 PD_GTL2014_DIR_6      A @BASEBOARD_FAB2_LIB.BASEBOARD_FAB2(SCH_1):PD_GTL2014_DIR_6
   2    GND      B @BASEBOARD_FAB2_LIB.BASEBOARD_FAB2(SCH_1):GND

CAP_A_0402V-0.1UF,16V,10%,X7R,A  I27  C25W93
   1 P0V7_GTL2014_VREF_6      A @BASEBOARD_FAB2_LIB.BASEBOARD_FAB2(SCH_1):P0V7_GTL2014_VREF_6
   2    GND      B @BASEBOARD_FAB2_LIB.BASEBOARD_FAB2(SCH_1):GND

RES_0402-100.0,1%,1/16W,CHIP,GA  I28  R25W165
   1 P0V7_GTL2014_VREF_6      A @BASEBOARD_FAB2_LIB.BASEBOARD_FAB2(SCH_1):P0V7_GTL2014_VREF_6
   2    GND      B @BASEBOARD_FAB2_LIB.BASEBOARD_FAB2(SCH_1):GND

RES_0402-49.9,1%,1/16W,CHIP,G2A  I29  R25W164
   1 P1V05_PCH_STBY      A @BASEBOARD_FAB2_LIB.BASEBOARD_FAB2(SCH_1):P1V05_PCH_STBY
   2 P0V7_GTL2014_VREF_6      B @BASEBOARD_FAB2_LIB.BASEBOARD_FAB2(SCH_1):P0V7_GTL2014_VREF_6

GTL2014_SM-IC,D66151-001  I33  U25W11
  13 TP_GTL2014_6_A0     A0 @BASEBOARD_FAB2_LIB.BASEBOARD_FAB2(SCH_1):TP_GTL2014_6_A0
  12 BMC_PRDY_N     A1 @BASEBOARD_FAB2_LIB.BASEBOARD_FAB2(SCH_1):BMC_PRDY_N
  10 TP_GTL2014_6_A2     A2 @BASEBOARD_FAB2_LIB.BASEBOARD_FAB2(SCH_1):TP_GTL2014_6_A2
   9 JTAG_BMC_BUF_TDO_R     A3 @BASEBOARD_FAB2_LIB.BASEBOARD_FAB2(SCH_1):JTAG_BMC_BUF_TDO_R
   2 PD_GTL2014_6_B0     B0 @BASEBOARD_FAB2_LIB.BASEBOARD_FAB2(SCH_1):PD_GTL2014_6_B0
   3 XDP_PRDY_N     B1 @BASEBOARD_FAB2_LIB.BASEBOARD_FAB2(SCH_1):XDP_PRDY_N
   5 PD_GTL2014_6_B2     B2 @BASEBOARD_FAB2_LIB.BASEBOARD_FAB2(SCH_1):PD_GTL2014_6_B2
   6 XDP_TDO     B3 @BASEBOARD_FAB2_LIB.BASEBOARD_FAB2(SCH_1):XDP_TDO
   1 PD_GTL2014_DIR_6    DIR @BASEBOARD_FAB2_LIB.BASEBOARD_FAB2(SCH_1):PD_GTL2014_DIR_6
  11    GND GND<2> @BASEBOARD_FAB2_LIB.BASEBOARD_FAB2(SCH_1):GND
   8    GND GND<1> @BASEBOARD_FAB2_LIB.BASEBOARD_FAB2(SCH_1):GND
   7    GND GND<0> @BASEBOARD_FAB2_LIB.BASEBOARD_FAB2(SCH_1):GND
  14 P3V3_STBY    VCC @BASEBOARD_FAB2_LIB.BASEBOARD_FAB2(SCH_1):P3V3_STBY
   4 P0V7_GTL2014_VREF_6   VREF @BASEBOARD_FAB2_LIB.BASEBOARD_FAB2(SCH_1):P0V7_GTL2014_VREF_6

374R2F-1-GP_SMD-RG-374R2F-1-GPA  I36  R25W183
   1 P3V3_STBY      1 @BASEBOARD_FAB2_LIB.BASEBOARD_FAB2(SCH_1):P3V3_STBY
   2 P0V7_GTL2014_VREF_6      2 @BASEBOARD_FAB2_LIB.BASEBOARD_FAB2(SCH_1):P0V7_GTL2014_VREF_6

TTL3126_QFNLF-74CBTLV3126,IC,DB  I38  SIZE=4  Summary of common pins:

  Section:  I38(3) U25W16
   1 BMC_JTAG_SEL_BUF  OE<3> @BASEBOARD_FAB2_LIB.BASEBOARD_FAB2(SCH_1):BMC_JTAG_SEL_BUF
   2 JTAG_BMC_TDI   A<3> @BASEBOARD_FAB2_LIB.BASEBOARD_FAB2(SCH_1):JTAG_BMC_TDI
   3 JTAG_BMC_BUF_TDI   B<3> @BASEBOARD_FAB2_LIB.BASEBOARD_FAB2(SCH_1):JTAG_BMC_BUF_TDI

  Section:  I38(2) U25W16
   4 BMC_JTAG_SEL_BUF  OE<2> @BASEBOARD_FAB2_LIB.BASEBOARD_FAB2(SCH_1):BMC_JTAG_SEL_BUF
   5 JTAG_BMC_TMS   A<2> @BASEBOARD_FAB2_LIB.BASEBOARD_FAB2(SCH_1):JTAG_BMC_TMS
   6 JTAG_BMC_BUF_TMS   B<2> @BASEBOARD_FAB2_LIB.BASEBOARD_FAB2(SCH_1):JTAG_BMC_BUF_TMS

  Section:  I38(1) U25W16
  10 BMC_JTAG_SEL_BUF  OE<1> @BASEBOARD_FAB2_LIB.BASEBOARD_FAB2(SCH_1):BMC_JTAG_SEL_BUF
   9 JTAG_BMC_TDO   A<1> @BASEBOARD_FAB2_LIB.BASEBOARD_FAB2(SCH_1):JTAG_BMC_TDO
   8 JTAG_BMC_BUF_TDO   B<1> @BASEBOARD_FAB2_LIB.BASEBOARD_FAB2(SCH_1):JTAG_BMC_BUF_TDO

  Section:  I38 U25W16
  13 BMC_JTAG_SEL_BUF  OE<0> @BASEBOARD_FAB2_LIB.BASEBOARD_FAB2(SCH_1):BMC_JTAG_SEL_BUF
  12 BMC_PWR_DEBUG_N   A<0> @BASEBOARD_FAB2_LIB.BASEBOARD_FAB2(SCH_1):BMC_PWR_DEBUG_N
  11 BMC_PWR_DEBUG_BUF_N   B<0> @BASEBOARD_FAB2_LIB.BASEBOARD_FAB2(SCH_1):BMC_PWR_DEBUG_BUF_N

CAP_0402-1.0UF,16V,10%,X6S,D97A  I40  C25W98
   1 P3V3_STBY      A @BASEBOARD_FAB2_LIB.BASEBOARD_FAB2(SCH_1):P3V3_STBY
   2    GND      B @BASEBOARD_FAB2_LIB.BASEBOARD_FAB2(SCH_1):GND

FET_N_SOT23LF-2N7002,FET,C7925A  I51  Q25W5
   1 BMC_JTAG_SEL_N   GATE @BASEBOARD_FAB2_LIB.BASEBOARD_FAB2(SCH_1):BMC_JTAG_SEL_N
   2    GND    SRC @BASEBOARD_FAB2_LIB.BASEBOARD_FAB2(SCH_1):GND
   3 BMC_JTAG_SEL    DRN @BASEBOARD_FAB2_LIB.BASEBOARD_FAB2(SCH_1):BMC_JTAG_SEL

RES_0402-4.75K,1%,1/16W,CHIP,GA  I54  R25W185
   1 P3V3_STBY      A @BASEBOARD_FAB2_LIB.BASEBOARD_FAB2(SCH_1):P3V3_STBY
   2 BMC_JTAG_SEL      B @BASEBOARD_FAB2_LIB.BASEBOARD_FAB2(SCH_1):BMC_JTAG_SEL

TTL1G08_SOTLF-NC7SZ08,IC,D1032B  I57  U25W18
   4 BMC_JTAG_SEL_BUF   Y<0> @BASEBOARD_FAB2_LIB.BASEBOARD_FAB2(SCH_1):BMC_JTAG_SEL_BUF
   1 XDP_PRESENT_N   A<0> @BASEBOARD_FAB2_LIB.BASEBOARD_FAB2(SCH_1):XDP_PRESENT_N
   2 BMC_JTAG_SEL   B<0> @BASEBOARD_FAB2_LIB.BASEBOARD_FAB2(SCH_1):BMC_JTAG_SEL

CAP_A_0402V-0.1UF,16V,10%,X7R,A  I60  C25W100
   1 P3V3_STBY      A @BASEBOARD_FAB2_LIB.BASEBOARD_FAB2(SCH_1):P3V3_STBY
   2    GND      B @BASEBOARD_FAB2_LIB.BASEBOARD_FAB2(SCH_1):GND

SW-SLIDE75-GP_DISCRET-G6-SW-SLA  I63  S9W1
   1     NC      1     NC
   2 BMC_JTAG_SEL      2 @BASEBOARD_FAB2_LIB.BASEBOARD_FAB2(SCH_1):BMC_JTAG_SEL
   3    GND      3 @BASEBOARD_FAB2_LIB.BASEBOARD_FAB2(SCH_1):GND
   4    GND      4 @BASEBOARD_FAB2_LIB.BASEBOARD_FAB2(SCH_1):GND
   5    GND      5 @BASEBOARD_FAB2_LIB.BASEBOARD_FAB2(SCH_1):GND
 NP1     NC    NP1     NC
 NP2     NC    NP2     NC
   6    GND      6 @BASEBOARD_FAB2_LIB.BASEBOARD_FAB2(SCH_1):GND
   7    GND      7 @BASEBOARD_FAB2_LIB.BASEBOARD_FAB2(SCH_1):GND

RES_0402-0.0,5%,1/16W,CHIP,G21A  I66  R25W187
   1 JTAG_BMC_BUF_TDO_R      A @BASEBOARD_FAB2_LIB.BASEBOARD_FAB2(SCH_1):JTAG_BMC_BUF_TDO_R
   2 JTAG_BMC_BUF_TDO      B @BASEBOARD_FAB2_LIB.BASEBOARD_FAB2(SCH_1):JTAG_BMC_BUF_TDO


DRAWING: @BASEBOARD_FAB2_LIB.BASEBOARD_FAB2(SCH_1):PAGE271 

TPAD-DIFF-4P-GP_DISCRET-GB3-TPA  I3  T1P1
   1 L1_85OHM_6INCH_DP      1 @BASEBOARD_FAB2_LIB.BASEBOARD_FAB2(SCH_1):L1_85OHM_6INCH_DP
   2 L1_85OHM_6INCH_DN      2 @BASEBOARD_FAB2_LIB.BASEBOARD_FAB2(SCH_1):L1_85OHM_6INCH_DN
GND1    GND   GND1 @BASEBOARD_FAB2_LIB.BASEBOARD_FAB2(SCH_1):GND
GND2    GND   GND2 @BASEBOARD_FAB2_LIB.BASEBOARD_FAB2(SCH_1):GND

TPAD-DIFF-4P-GP_DISCRET-GB3-TPA  I5  T1P2
   1 L3_85OHM_6INCH_DP      1 @BASEBOARD_FAB2_LIB.BASEBOARD_FAB2(SCH_1):L3_85OHM_6INCH_DP
   2 L3_85OHM_6INCH_DN      2 @BASEBOARD_FAB2_LIB.BASEBOARD_FAB2(SCH_1):L3_85OHM_6INCH_DN
GND1    GND   GND1 @BASEBOARD_FAB2_LIB.BASEBOARD_FAB2(SCH_1):GND
GND2    GND   GND2 @BASEBOARD_FAB2_LIB.BASEBOARD_FAB2(SCH_1):GND

TPAD-DIFF-4P-GP_DISCRET-GB3-TPA  I7  T1P4
   1 L10_85OHM_6INCH_DP      1 @BASEBOARD_FAB2_LIB.BASEBOARD_FAB2(SCH_1):L10_85OHM_6INCH_DP
   2 L10_85OHM_6INCH_DN      2 @BASEBOARD_FAB2_LIB.BASEBOARD_FAB2(SCH_1):L10_85OHM_6INCH_DN
GND1    GND   GND1 @BASEBOARD_FAB2_LIB.BASEBOARD_FAB2(SCH_1):GND
GND2    GND   GND2 @BASEBOARD_FAB2_LIB.BASEBOARD_FAB2(SCH_1):GND

TPAD-DIFF-4P-GP_DISCRET-GB3-TPA  I8  T1P3
   1 L5_85OHM_6INCH_DP      1 @BASEBOARD_FAB2_LIB.BASEBOARD_FAB2(SCH_1):L5_85OHM_6INCH_DP
   2 L5_85OHM_6INCH_DN      2 @BASEBOARD_FAB2_LIB.BASEBOARD_FAB2(SCH_1):L5_85OHM_6INCH_DN
GND1    GND   GND1 @BASEBOARD_FAB2_LIB.BASEBOARD_FAB2(SCH_1):GND
GND2    GND   GND2 @BASEBOARD_FAB2_LIB.BASEBOARD_FAB2(SCH_1):GND

TPAD-DIFF-4P-GP_DISCRET-GB3-TPA  I11  T1P5
   1 L12_85OHM_6INCH_DP      1 @BASEBOARD_FAB2_LIB.BASEBOARD_FAB2(SCH_1):L12_85OHM_6INCH_DP
   2 L12_85OHM_6INCH_DN      2 @BASEBOARD_FAB2_LIB.BASEBOARD_FAB2(SCH_1):L12_85OHM_6INCH_DN
GND1    GND   GND1 @BASEBOARD_FAB2_LIB.BASEBOARD_FAB2(SCH_1):GND
GND2    GND   GND2 @BASEBOARD_FAB2_LIB.BASEBOARD_FAB2(SCH_1):GND

TPAD-DIFF-4P-GP_DISCRET-GB3-TPA  I13  T1P6
   1 L14_85OHM_6INCH_DP      1 @BASEBOARD_FAB2_LIB.BASEBOARD_FAB2(SCH_1):L14_85OHM_6INCH_DP
   2 L14_85OHM_6INCH_DN      2 @BASEBOARD_FAB2_LIB.BASEBOARD_FAB2(SCH_1):L14_85OHM_6INCH_DN
GND1    GND   GND1 @BASEBOARD_FAB2_LIB.BASEBOARD_FAB2(SCH_1):GND
GND2    GND   GND2 @BASEBOARD_FAB2_LIB.BASEBOARD_FAB2(SCH_1):GND

TPAD-DIFF-4P-GP_DISCRET-GB3-TPA  I15  T1P10
   1 L10_73OHM_6INCH_DP      1 @BASEBOARD_FAB2_LIB.BASEBOARD_FAB2(SCH_1):L10_73OHM_6INCH_DP
   2 L10_73OHM_6INCH_DN      2 @BASEBOARD_FAB2_LIB.BASEBOARD_FAB2(SCH_1):L10_73OHM_6INCH_DN
GND1    GND   GND1 @BASEBOARD_FAB2_LIB.BASEBOARD_FAB2(SCH_1):GND
GND2    GND   GND2 @BASEBOARD_FAB2_LIB.BASEBOARD_FAB2(SCH_1):GND

TPAD-DIFF-4P-GP_DISCRET-GB3-TPA  I16  T1P8
   1 L3_73OHM_6INCH_DP      1 @BASEBOARD_FAB2_LIB.BASEBOARD_FAB2(SCH_1):L3_73OHM_6INCH_DP
   2 L3_73OHM_6INCH_DN      2 @BASEBOARD_FAB2_LIB.BASEBOARD_FAB2(SCH_1):L3_73OHM_6INCH_DN
GND1    GND   GND1 @BASEBOARD_FAB2_LIB.BASEBOARD_FAB2(SCH_1):GND
GND2    GND   GND2 @BASEBOARD_FAB2_LIB.BASEBOARD_FAB2(SCH_1):GND

TPAD-DIFF-4P-GP_DISCRET-GB3-TPA  I17  T1P7
   1 L1_73OHM_6INCH_DP      1 @BASEBOARD_FAB2_LIB.BASEBOARD_FAB2(SCH_1):L1_73OHM_6INCH_DP
   2 L1_73OHM_6INCH_DN      2 @BASEBOARD_FAB2_LIB.BASEBOARD_FAB2(SCH_1):L1_73OHM_6INCH_DN
GND1    GND   GND1 @BASEBOARD_FAB2_LIB.BASEBOARD_FAB2(SCH_1):GND
GND2    GND   GND2 @BASEBOARD_FAB2_LIB.BASEBOARD_FAB2(SCH_1):GND

TPAD-DIFF-4P-GP_DISCRET-GB3-TPA  I19  T1P9
   1 L5_73OHM_6INCH_DP      1 @BASEBOARD_FAB2_LIB.BASEBOARD_FAB2(SCH_1):L5_73OHM_6INCH_DP
   2 L5_73OHM_6INCH_DN      2 @BASEBOARD_FAB2_LIB.BASEBOARD_FAB2(SCH_1):L5_73OHM_6INCH_DN
GND1    GND   GND1 @BASEBOARD_FAB2_LIB.BASEBOARD_FAB2(SCH_1):GND
GND2    GND   GND2 @BASEBOARD_FAB2_LIB.BASEBOARD_FAB2(SCH_1):GND

TPAD-DIFF-4P-GP_DISCRET-GB3-TPA  I23  T1P11
   1 L12_73OHM_6INCH_DP      1 @BASEBOARD_FAB2_LIB.BASEBOARD_FAB2(SCH_1):L12_73OHM_6INCH_DP
   2 L12_73OHM_6INCH_DN      2 @BASEBOARD_FAB2_LIB.BASEBOARD_FAB2(SCH_1):L12_73OHM_6INCH_DN
GND1    GND   GND1 @BASEBOARD_FAB2_LIB.BASEBOARD_FAB2(SCH_1):GND
GND2    GND   GND2 @BASEBOARD_FAB2_LIB.BASEBOARD_FAB2(SCH_1):GND

TPAD-DIFF-4P-GP_DISCRET-GB3-TPA  I24  T1P12
   1 L14_73OHM_6INCH_DP      1 @BASEBOARD_FAB2_LIB.BASEBOARD_FAB2(SCH_1):L14_73OHM_6INCH_DP
   2 L14_73OHM_6INCH_DN      2 @BASEBOARD_FAB2_LIB.BASEBOARD_FAB2(SCH_1):L14_73OHM_6INCH_DN
GND1    GND   GND1 @BASEBOARD_FAB2_LIB.BASEBOARD_FAB2(SCH_1):GND
GND2    GND   GND2 @BASEBOARD_FAB2_LIB.BASEBOARD_FAB2(SCH_1):GND

TPAD-DIFF-4P-GP_DISCRET-GB3-TPA  I30  T1P14
   1 L1_95OHM_6INCH_DP      1 @BASEBOARD_FAB2_LIB.BASEBOARD_FAB2(SCH_1):L1_95OHM_6INCH_DP
   2 L1_95OHM_6INCH_DN      2 @BASEBOARD_FAB2_LIB.BASEBOARD_FAB2(SCH_1):L1_95OHM_6INCH_DN
GND1    GND   GND1 @BASEBOARD_FAB2_LIB.BASEBOARD_FAB2(SCH_1):GND
GND2    GND   GND2 @BASEBOARD_FAB2_LIB.BASEBOARD_FAB2(SCH_1):GND

TPAD-DIFF-4P-GP_DISCRET-GB3-TPA  I36  T1P17
   1 L12_95OHM_6INCH_DP      1 @BASEBOARD_FAB2_LIB.BASEBOARD_FAB2(SCH_1):L12_95OHM_6INCH_DP
   2 L12_95OHM_6INCH_DN      2 @BASEBOARD_FAB2_LIB.BASEBOARD_FAB2(SCH_1):L12_95OHM_6INCH_DN
GND1    GND   GND1 @BASEBOARD_FAB2_LIB.BASEBOARD_FAB2(SCH_1):GND
GND2    GND   GND2 @BASEBOARD_FAB2_LIB.BASEBOARD_FAB2(SCH_1):GND

TPAD-DIFF-4P-GP_DISCRET-GB3-TPA  I38  T1P24
   1 L14_100OHM_6INCH_DP      1 @BASEBOARD_FAB2_LIB.BASEBOARD_FAB2(SCH_1):L14_100OHM_6INCH_DP
   2 L14_100OHM_6INCH_DN      2 @BASEBOARD_FAB2_LIB.BASEBOARD_FAB2(SCH_1):L14_100OHM_6INCH_DN
GND1    GND   GND1 @BASEBOARD_FAB2_LIB.BASEBOARD_FAB2(SCH_1):GND
GND2    GND   GND2 @BASEBOARD_FAB2_LIB.BASEBOARD_FAB2(SCH_1):GND

TPAD-DIFF-4P-GP_DISCRET-GB3-TPA  I39  T1P19
   1 L1_100OHM_6INCH_DP      1 @BASEBOARD_FAB2_LIB.BASEBOARD_FAB2(SCH_1):L1_100OHM_6INCH_DP
   2 L1_100OHM_6INCH_DN      2 @BASEBOARD_FAB2_LIB.BASEBOARD_FAB2(SCH_1):L1_100OHM_6INCH_DN
GND1    GND   GND1 @BASEBOARD_FAB2_LIB.BASEBOARD_FAB2(SCH_1):GND
GND2    GND   GND2 @BASEBOARD_FAB2_LIB.BASEBOARD_FAB2(SCH_1):GND

TPAD-DIFF-4P-GP_DISCRET-GB3-TPA  I45  T1P22
   1 L10_100OHM_6INCH_DP      1 @BASEBOARD_FAB2_LIB.BASEBOARD_FAB2(SCH_1):L10_100OHM_6INCH_DP
   2 L10_100OHM_6INCH_DN      2 @BASEBOARD_FAB2_LIB.BASEBOARD_FAB2(SCH_1):L10_100OHM_6INCH_DN
GND1    GND   GND1 @BASEBOARD_FAB2_LIB.BASEBOARD_FAB2(SCH_1):GND
GND2    GND   GND2 @BASEBOARD_FAB2_LIB.BASEBOARD_FAB2(SCH_1):GND

TPAD-DIFF-4P-GP_DISCRET-GB3-TPA  I47  T1P23
   1 L12_100OHM_6INCH_DP      1 @BASEBOARD_FAB2_LIB.BASEBOARD_FAB2(SCH_1):L12_100OHM_6INCH_DP
   2 L12_100OHM_6INCH_DN      2 @BASEBOARD_FAB2_LIB.BASEBOARD_FAB2(SCH_1):L12_100OHM_6INCH_DN
GND1    GND   GND1 @BASEBOARD_FAB2_LIB.BASEBOARD_FAB2(SCH_1):GND
GND2    GND   GND2 @BASEBOARD_FAB2_LIB.BASEBOARD_FAB2(SCH_1):GND

TPAD-SE-2P-GP_DISCRET-GA1-TPADA  I50  T1P25
   1 L1_40OHM_6INCH      1 @BASEBOARD_FAB2_LIB.BASEBOARD_FAB2(SCH_1):L1_40OHM_6INCH
GND1    GND   GND1 @BASEBOARD_FAB2_LIB.BASEBOARD_FAB2(SCH_1):GND

TPAD-SE-2P-GP_DISCRET-GA1-TPADA  I52  T1P26
   1 L3_40OHM_6INCH      1 @BASEBOARD_FAB2_LIB.BASEBOARD_FAB2(SCH_1):L3_40OHM_6INCH
GND1    GND   GND1 @BASEBOARD_FAB2_LIB.BASEBOARD_FAB2(SCH_1):GND

TPAD-SE-2P-GP_DISCRET-GA1-TPADA  I54  T1P27
   1 L5_40OHM_6INCH      1 @BASEBOARD_FAB2_LIB.BASEBOARD_FAB2(SCH_1):L5_40OHM_6INCH
GND1    GND   GND1 @BASEBOARD_FAB2_LIB.BASEBOARD_FAB2(SCH_1):GND

TPAD-SE-2P-GP_DISCRET-GA1-TPADA  I56  T1P29
   1 L12_40OHM_6INCH      1 @BASEBOARD_FAB2_LIB.BASEBOARD_FAB2(SCH_1):L12_40OHM_6INCH
GND1    GND   GND1 @BASEBOARD_FAB2_LIB.BASEBOARD_FAB2(SCH_1):GND

TPAD-SE-2P-GP_DISCRET-GA1-TPADA  I60  T1P28
   1 L10_40OHM_6INCH      1 @BASEBOARD_FAB2_LIB.BASEBOARD_FAB2(SCH_1):L10_40OHM_6INCH
GND1    GND   GND1 @BASEBOARD_FAB2_LIB.BASEBOARD_FAB2(SCH_1):GND

TPAD-SE-2P-GP_DISCRET-GA1-TPADA  I61  T1P30
   1 L14_40OHM_6INCH      1 @BASEBOARD_FAB2_LIB.BASEBOARD_FAB2(SCH_1):L14_40OHM_6INCH
GND1    GND   GND1 @BASEBOARD_FAB2_LIB.BASEBOARD_FAB2(SCH_1):GND

TPAD-SE-2P-GP_DISCRET-GA1-TPADA  I62  T1P34
   1 L10_50OHM_6INCH      1 @BASEBOARD_FAB2_LIB.BASEBOARD_FAB2(SCH_1):L10_50OHM_6INCH
GND1    GND   GND1 @BASEBOARD_FAB2_LIB.BASEBOARD_FAB2(SCH_1):GND

TPAD-SE-2P-GP_DISCRET-GA1-TPADA  I63  T1P36
   1 L14_50OHM_6INCH      1 @BASEBOARD_FAB2_LIB.BASEBOARD_FAB2(SCH_1):L14_50OHM_6INCH
GND1    GND   GND1 @BASEBOARD_FAB2_LIB.BASEBOARD_FAB2(SCH_1):GND

TPAD-SE-2P-GP_DISCRET-GA1-TPADA  I67  T1P35
   1 L12_50OHM_6INCH      1 @BASEBOARD_FAB2_LIB.BASEBOARD_FAB2(SCH_1):L12_50OHM_6INCH
GND1    GND   GND1 @BASEBOARD_FAB2_LIB.BASEBOARD_FAB2(SCH_1):GND

TPAD-SE-2P-GP_DISCRET-GA1-TPADA  I71  T1P31
   1 L1_50OHM_6INCH      1 @BASEBOARD_FAB2_LIB.BASEBOARD_FAB2(SCH_1):L1_50OHM_6INCH
GND1    GND   GND1 @BASEBOARD_FAB2_LIB.BASEBOARD_FAB2(SCH_1):GND

TPAD-SE-2P-GP_DISCRET-GA1-TPADA  I72  T1P32
   1 L3_50OHM_6INCH      1 @BASEBOARD_FAB2_LIB.BASEBOARD_FAB2(SCH_1):L3_50OHM_6INCH
GND1    GND   GND1 @BASEBOARD_FAB2_LIB.BASEBOARD_FAB2(SCH_1):GND

TPAD-SE-2P-GP_DISCRET-GA1-TPADA  I73  T1P33
   1 L5_50OHM_6INCH      1 @BASEBOARD_FAB2_LIB.BASEBOARD_FAB2(SCH_1):L5_50OHM_6INCH
GND1    GND   GND1 @BASEBOARD_FAB2_LIB.BASEBOARD_FAB2(SCH_1):GND


DRAWING: @BASEBOARD_FAB2_LIB.BASEBOARD_FAB2(SCH_1):PAGE270 

TEST-PAD-12P-1-GP-U_DISCRET-GBA  I1  T1D1
   3    GND GND<0> @BASEBOARD_FAB2_LIB.BASEBOARD_FAB2(SCH_1):GND
   4    GND GND<1> @BASEBOARD_FAB2_LIB.BASEBOARD_FAB2(SCH_1):GND
   5    GND GND<2> @BASEBOARD_FAB2_LIB.BASEBOARD_FAB2(SCH_1):GND
   6    GND GND<3> @BASEBOARD_FAB2_LIB.BASEBOARD_FAB2(SCH_1):GND
   7    GND GND<4> @BASEBOARD_FAB2_LIB.BASEBOARD_FAB2(SCH_1):GND
   8    GND GND<5> @BASEBOARD_FAB2_LIB.BASEBOARD_FAB2(SCH_1):GND
   9    GND GND<6> @BASEBOARD_FAB2_LIB.BASEBOARD_FAB2(SCH_1):GND
  10    GND GND<7> @BASEBOARD_FAB2_LIB.BASEBOARD_FAB2(SCH_1):GND
  11    GND GND<8> @BASEBOARD_FAB2_LIB.BASEBOARD_FAB2(SCH_1):GND
  12    GND GND<9> @BASEBOARD_FAB2_LIB.BASEBOARD_FAB2(SCH_1):GND
   1 L1_85OHM_5INCH_DP     DP @BASEBOARD_FAB2_LIB.BASEBOARD_FAB2(SCH_1):L1_85OHM_5INCH_DP
   2 L1_85OHM_5INCH_DN     DN @BASEBOARD_FAB2_LIB.BASEBOARD_FAB2(SCH_1):L1_85OHM_5INCH_DN

TEST-PAD-12P-1-GP-U_DISCRET-GBA  I3  T1D2
   3    GND GND<0> @BASEBOARD_FAB2_LIB.BASEBOARD_FAB2(SCH_1):GND
   4    GND GND<1> @BASEBOARD_FAB2_LIB.BASEBOARD_FAB2(SCH_1):GND
   5    GND GND<2> @BASEBOARD_FAB2_LIB.BASEBOARD_FAB2(SCH_1):GND
   6    GND GND<3> @BASEBOARD_FAB2_LIB.BASEBOARD_FAB2(SCH_1):GND
   7    GND GND<4> @BASEBOARD_FAB2_LIB.BASEBOARD_FAB2(SCH_1):GND
   8    GND GND<5> @BASEBOARD_FAB2_LIB.BASEBOARD_FAB2(SCH_1):GND
   9    GND GND<6> @BASEBOARD_FAB2_LIB.BASEBOARD_FAB2(SCH_1):GND
  10    GND GND<7> @BASEBOARD_FAB2_LIB.BASEBOARD_FAB2(SCH_1):GND
  11    GND GND<8> @BASEBOARD_FAB2_LIB.BASEBOARD_FAB2(SCH_1):GND
  12    GND GND<9> @BASEBOARD_FAB2_LIB.BASEBOARD_FAB2(SCH_1):GND
   1 L1_85OHM_5INCH_DN     DP @BASEBOARD_FAB2_LIB.BASEBOARD_FAB2(SCH_1):L1_85OHM_5INCH_DN
   2 L1_85OHM_5INCH_DP     DN @BASEBOARD_FAB2_LIB.BASEBOARD_FAB2(SCH_1):L1_85OHM_5INCH_DP

TEST-PAD-12P-1-GP-U_DISCRET-GBA  I5  T1D3
   3    GND GND<0> @BASEBOARD_FAB2_LIB.BASEBOARD_FAB2(SCH_1):GND
   4    GND GND<1> @BASEBOARD_FAB2_LIB.BASEBOARD_FAB2(SCH_1):GND
   5    GND GND<2> @BASEBOARD_FAB2_LIB.BASEBOARD_FAB2(SCH_1):GND
   6    GND GND<3> @BASEBOARD_FAB2_LIB.BASEBOARD_FAB2(SCH_1):GND
   7    GND GND<4> @BASEBOARD_FAB2_LIB.BASEBOARD_FAB2(SCH_1):GND
   8    GND GND<5> @BASEBOARD_FAB2_LIB.BASEBOARD_FAB2(SCH_1):GND
   9    GND GND<6> @BASEBOARD_FAB2_LIB.BASEBOARD_FAB2(SCH_1):GND
  10    GND GND<7> @BASEBOARD_FAB2_LIB.BASEBOARD_FAB2(SCH_1):GND
  11    GND GND<8> @BASEBOARD_FAB2_LIB.BASEBOARD_FAB2(SCH_1):GND
  12    GND GND<9> @BASEBOARD_FAB2_LIB.BASEBOARD_FAB2(SCH_1):GND
   1 L3_85OHM_5INCH_DP     DP @BASEBOARD_FAB2_LIB.BASEBOARD_FAB2(SCH_1):L3_85OHM_5INCH_DP
   2 L3_85OHM_5INCH_DN     DN @BASEBOARD_FAB2_LIB.BASEBOARD_FAB2(SCH_1):L3_85OHM_5INCH_DN

TEST-PAD-12P-1-GP-U_DISCRET-GBA  I6  T1D4
   3    GND GND<0> @BASEBOARD_FAB2_LIB.BASEBOARD_FAB2(SCH_1):GND
   4    GND GND<1> @BASEBOARD_FAB2_LIB.BASEBOARD_FAB2(SCH_1):GND
   5    GND GND<2> @BASEBOARD_FAB2_LIB.BASEBOARD_FAB2(SCH_1):GND
   6    GND GND<3> @BASEBOARD_FAB2_LIB.BASEBOARD_FAB2(SCH_1):GND
   7    GND GND<4> @BASEBOARD_FAB2_LIB.BASEBOARD_FAB2(SCH_1):GND
   8    GND GND<5> @BASEBOARD_FAB2_LIB.BASEBOARD_FAB2(SCH_1):GND
   9    GND GND<6> @BASEBOARD_FAB2_LIB.BASEBOARD_FAB2(SCH_1):GND
  10    GND GND<7> @BASEBOARD_FAB2_LIB.BASEBOARD_FAB2(SCH_1):GND
  11    GND GND<8> @BASEBOARD_FAB2_LIB.BASEBOARD_FAB2(SCH_1):GND
  12    GND GND<9> @BASEBOARD_FAB2_LIB.BASEBOARD_FAB2(SCH_1):GND
   1 L3_85OHM_5INCH_DN     DP @BASEBOARD_FAB2_LIB.BASEBOARD_FAB2(SCH_1):L3_85OHM_5INCH_DN
   2 L3_85OHM_5INCH_DP     DN @BASEBOARD_FAB2_LIB.BASEBOARD_FAB2(SCH_1):L3_85OHM_5INCH_DP

TEST-PAD-12P-1-GP-U_DISCRET-GBA  I9  T1D6
   3    GND GND<0> @BASEBOARD_FAB2_LIB.BASEBOARD_FAB2(SCH_1):GND
   4    GND GND<1> @BASEBOARD_FAB2_LIB.BASEBOARD_FAB2(SCH_1):GND
   5    GND GND<2> @BASEBOARD_FAB2_LIB.BASEBOARD_FAB2(SCH_1):GND
   6    GND GND<3> @BASEBOARD_FAB2_LIB.BASEBOARD_FAB2(SCH_1):GND
   7    GND GND<4> @BASEBOARD_FAB2_LIB.BASEBOARD_FAB2(SCH_1):GND
   8    GND GND<5> @BASEBOARD_FAB2_LIB.BASEBOARD_FAB2(SCH_1):GND
   9    GND GND<6> @BASEBOARD_FAB2_LIB.BASEBOARD_FAB2(SCH_1):GND
  10    GND GND<7> @BASEBOARD_FAB2_LIB.BASEBOARD_FAB2(SCH_1):GND
  11    GND GND<8> @BASEBOARD_FAB2_LIB.BASEBOARD_FAB2(SCH_1):GND
  12    GND GND<9> @BASEBOARD_FAB2_LIB.BASEBOARD_FAB2(SCH_1):GND
   1 L5_85OHM_5INCH_DN     DP @BASEBOARD_FAB2_LIB.BASEBOARD_FAB2(SCH_1):L5_85OHM_5INCH_DN
   2 L5_85OHM_5INCH_DP     DN @BASEBOARD_FAB2_LIB.BASEBOARD_FAB2(SCH_1):L5_85OHM_5INCH_DP

TEST-PAD-12P-1-GP-U_DISCRET-GBA  I12  T1D5
   3    GND GND<0> @BASEBOARD_FAB2_LIB.BASEBOARD_FAB2(SCH_1):GND
   4    GND GND<1> @BASEBOARD_FAB2_LIB.BASEBOARD_FAB2(SCH_1):GND
   5    GND GND<2> @BASEBOARD_FAB2_LIB.BASEBOARD_FAB2(SCH_1):GND
   6    GND GND<3> @BASEBOARD_FAB2_LIB.BASEBOARD_FAB2(SCH_1):GND
   7    GND GND<4> @BASEBOARD_FAB2_LIB.BASEBOARD_FAB2(SCH_1):GND
   8    GND GND<5> @BASEBOARD_FAB2_LIB.BASEBOARD_FAB2(SCH_1):GND
   9    GND GND<6> @BASEBOARD_FAB2_LIB.BASEBOARD_FAB2(SCH_1):GND
  10    GND GND<7> @BASEBOARD_FAB2_LIB.BASEBOARD_FAB2(SCH_1):GND
  11    GND GND<8> @BASEBOARD_FAB2_LIB.BASEBOARD_FAB2(SCH_1):GND
  12    GND GND<9> @BASEBOARD_FAB2_LIB.BASEBOARD_FAB2(SCH_1):GND
   1 L5_85OHM_5INCH_DP     DP @BASEBOARD_FAB2_LIB.BASEBOARD_FAB2(SCH_1):L5_85OHM_5INCH_DP
   2 L5_85OHM_5INCH_DN     DN @BASEBOARD_FAB2_LIB.BASEBOARD_FAB2(SCH_1):L5_85OHM_5INCH_DN

TEST-PAD-12P-1-GP-U_DISCRET-GBA  I13  T1D8
   3    GND GND<0> @BASEBOARD_FAB2_LIB.BASEBOARD_FAB2(SCH_1):GND
   4    GND GND<1> @BASEBOARD_FAB2_LIB.BASEBOARD_FAB2(SCH_1):GND
   5    GND GND<2> @BASEBOARD_FAB2_LIB.BASEBOARD_FAB2(SCH_1):GND
   6    GND GND<3> @BASEBOARD_FAB2_LIB.BASEBOARD_FAB2(SCH_1):GND
   7    GND GND<4> @BASEBOARD_FAB2_LIB.BASEBOARD_FAB2(SCH_1):GND
   8    GND GND<5> @BASEBOARD_FAB2_LIB.BASEBOARD_FAB2(SCH_1):GND
   9    GND GND<6> @BASEBOARD_FAB2_LIB.BASEBOARD_FAB2(SCH_1):GND
  10    GND GND<7> @BASEBOARD_FAB2_LIB.BASEBOARD_FAB2(SCH_1):GND
  11    GND GND<8> @BASEBOARD_FAB2_LIB.BASEBOARD_FAB2(SCH_1):GND
  12    GND GND<9> @BASEBOARD_FAB2_LIB.BASEBOARD_FAB2(SCH_1):GND
   1 L10_85OHM_5INCH_DN     DP @BASEBOARD_FAB2_LIB.BASEBOARD_FAB2(SCH_1):L10_85OHM_5INCH_DN
   2 L10_85OHM_5INCH_DP     DN @BASEBOARD_FAB2_LIB.BASEBOARD_FAB2(SCH_1):L10_85OHM_5INCH_DP

TEST-PAD-12P-1-GP-U_DISCRET-GBA  I16  T1D7
   3    GND GND<0> @BASEBOARD_FAB2_LIB.BASEBOARD_FAB2(SCH_1):GND
   4    GND GND<1> @BASEBOARD_FAB2_LIB.BASEBOARD_FAB2(SCH_1):GND
   5    GND GND<2> @BASEBOARD_FAB2_LIB.BASEBOARD_FAB2(SCH_1):GND
   6    GND GND<3> @BASEBOARD_FAB2_LIB.BASEBOARD_FAB2(SCH_1):GND
   7    GND GND<4> @BASEBOARD_FAB2_LIB.BASEBOARD_FAB2(SCH_1):GND
   8    GND GND<5> @BASEBOARD_FAB2_LIB.BASEBOARD_FAB2(SCH_1):GND
   9    GND GND<6> @BASEBOARD_FAB2_LIB.BASEBOARD_FAB2(SCH_1):GND
  10    GND GND<7> @BASEBOARD_FAB2_LIB.BASEBOARD_FAB2(SCH_1):GND
  11    GND GND<8> @BASEBOARD_FAB2_LIB.BASEBOARD_FAB2(SCH_1):GND
  12    GND GND<9> @BASEBOARD_FAB2_LIB.BASEBOARD_FAB2(SCH_1):GND
   1 L10_85OHM_5INCH_DP     DP @BASEBOARD_FAB2_LIB.BASEBOARD_FAB2(SCH_1):L10_85OHM_5INCH_DP
   2 L10_85OHM_5INCH_DN     DN @BASEBOARD_FAB2_LIB.BASEBOARD_FAB2(SCH_1):L10_85OHM_5INCH_DN

TEST-PAD-12P-1-GP-U_DISCRET-GBA  I17  T1D10
   3    GND GND<0> @BASEBOARD_FAB2_LIB.BASEBOARD_FAB2(SCH_1):GND
   4    GND GND<1> @BASEBOARD_FAB2_LIB.BASEBOARD_FAB2(SCH_1):GND
   5    GND GND<2> @BASEBOARD_FAB2_LIB.BASEBOARD_FAB2(SCH_1):GND
   6    GND GND<3> @BASEBOARD_FAB2_LIB.BASEBOARD_FAB2(SCH_1):GND
   7    GND GND<4> @BASEBOARD_FAB2_LIB.BASEBOARD_FAB2(SCH_1):GND
   8    GND GND<5> @BASEBOARD_FAB2_LIB.BASEBOARD_FAB2(SCH_1):GND
   9    GND GND<6> @BASEBOARD_FAB2_LIB.BASEBOARD_FAB2(SCH_1):GND
  10    GND GND<7> @BASEBOARD_FAB2_LIB.BASEBOARD_FAB2(SCH_1):GND
  11    GND GND<8> @BASEBOARD_FAB2_LIB.BASEBOARD_FAB2(SCH_1):GND
  12    GND GND<9> @BASEBOARD_FAB2_LIB.BASEBOARD_FAB2(SCH_1):GND
   1 L12_85OHM_5INCH_DN     DP @BASEBOARD_FAB2_LIB.BASEBOARD_FAB2(SCH_1):L12_85OHM_5INCH_DN
   2 L12_85OHM_5INCH_DP     DN @BASEBOARD_FAB2_LIB.BASEBOARD_FAB2(SCH_1):L12_85OHM_5INCH_DP

TEST-PAD-12P-1-GP-U_DISCRET-GBA  I18  T1D9
   3    GND GND<0> @BASEBOARD_FAB2_LIB.BASEBOARD_FAB2(SCH_1):GND
   4    GND GND<1> @BASEBOARD_FAB2_LIB.BASEBOARD_FAB2(SCH_1):GND
   5    GND GND<2> @BASEBOARD_FAB2_LIB.BASEBOARD_FAB2(SCH_1):GND
   6    GND GND<3> @BASEBOARD_FAB2_LIB.BASEBOARD_FAB2(SCH_1):GND
   7    GND GND<4> @BASEBOARD_FAB2_LIB.BASEBOARD_FAB2(SCH_1):GND
   8    GND GND<5> @BASEBOARD_FAB2_LIB.BASEBOARD_FAB2(SCH_1):GND
   9    GND GND<6> @BASEBOARD_FAB2_LIB.BASEBOARD_FAB2(SCH_1):GND
  10    GND GND<7> @BASEBOARD_FAB2_LIB.BASEBOARD_FAB2(SCH_1):GND
  11    GND GND<8> @BASEBOARD_FAB2_LIB.BASEBOARD_FAB2(SCH_1):GND
  12    GND GND<9> @BASEBOARD_FAB2_LIB.BASEBOARD_FAB2(SCH_1):GND
   1 L12_85OHM_5INCH_DP     DP @BASEBOARD_FAB2_LIB.BASEBOARD_FAB2(SCH_1):L12_85OHM_5INCH_DP
   2 L12_85OHM_5INCH_DN     DN @BASEBOARD_FAB2_LIB.BASEBOARD_FAB2(SCH_1):L12_85OHM_5INCH_DN

TEST-PAD-12P-1-GP-U_DISCRET-GBA  I21  T1D12
   3    GND GND<0> @BASEBOARD_FAB2_LIB.BASEBOARD_FAB2(SCH_1):GND
   4    GND GND<1> @BASEBOARD_FAB2_LIB.BASEBOARD_FAB2(SCH_1):GND
   5    GND GND<2> @BASEBOARD_FAB2_LIB.BASEBOARD_FAB2(SCH_1):GND
   6    GND GND<3> @BASEBOARD_FAB2_LIB.BASEBOARD_FAB2(SCH_1):GND
   7    GND GND<4> @BASEBOARD_FAB2_LIB.BASEBOARD_FAB2(SCH_1):GND
   8    GND GND<5> @BASEBOARD_FAB2_LIB.BASEBOARD_FAB2(SCH_1):GND
   9    GND GND<6> @BASEBOARD_FAB2_LIB.BASEBOARD_FAB2(SCH_1):GND
  10    GND GND<7> @BASEBOARD_FAB2_LIB.BASEBOARD_FAB2(SCH_1):GND
  11    GND GND<8> @BASEBOARD_FAB2_LIB.BASEBOARD_FAB2(SCH_1):GND
  12    GND GND<9> @BASEBOARD_FAB2_LIB.BASEBOARD_FAB2(SCH_1):GND
   1 L14_85OHM_5INCH_DN     DP @BASEBOARD_FAB2_LIB.BASEBOARD_FAB2(SCH_1):L14_85OHM_5INCH_DN
   2 L14_85OHM_5INCH_DP     DN @BASEBOARD_FAB2_LIB.BASEBOARD_FAB2(SCH_1):L14_85OHM_5INCH_DP

TEST-PAD-12P-1-GP-U_DISCRET-GBA  I24  T1D11
   3    GND GND<0> @BASEBOARD_FAB2_LIB.BASEBOARD_FAB2(SCH_1):GND
   4    GND GND<1> @BASEBOARD_FAB2_LIB.BASEBOARD_FAB2(SCH_1):GND
   5    GND GND<2> @BASEBOARD_FAB2_LIB.BASEBOARD_FAB2(SCH_1):GND
   6    GND GND<3> @BASEBOARD_FAB2_LIB.BASEBOARD_FAB2(SCH_1):GND
   7    GND GND<4> @BASEBOARD_FAB2_LIB.BASEBOARD_FAB2(SCH_1):GND
   8    GND GND<5> @BASEBOARD_FAB2_LIB.BASEBOARD_FAB2(SCH_1):GND
   9    GND GND<6> @BASEBOARD_FAB2_LIB.BASEBOARD_FAB2(SCH_1):GND
  10    GND GND<7> @BASEBOARD_FAB2_LIB.BASEBOARD_FAB2(SCH_1):GND
  11    GND GND<8> @BASEBOARD_FAB2_LIB.BASEBOARD_FAB2(SCH_1):GND
  12    GND GND<9> @BASEBOARD_FAB2_LIB.BASEBOARD_FAB2(SCH_1):GND
   1 L14_85OHM_5INCH_DP     DP @BASEBOARD_FAB2_LIB.BASEBOARD_FAB2(SCH_1):L14_85OHM_5INCH_DP
   2 L14_85OHM_5INCH_DN     DN @BASEBOARD_FAB2_LIB.BASEBOARD_FAB2(SCH_1):L14_85OHM_5INCH_DN


DRAWING: @BASEBOARD_FAB2_LIB.BASEBOARD_FAB2(SCH_1):PAGE272 

TEST-PAD-12P-1-GP-U_DISCRET-GBA  I1  T1D17
   3    GND GND<0> @BASEBOARD_FAB2_LIB.BASEBOARD_FAB2(SCH_1):GND
   4    GND GND<1> @BASEBOARD_FAB2_LIB.BASEBOARD_FAB2(SCH_1):GND
   5    GND GND<2> @BASEBOARD_FAB2_LIB.BASEBOARD_FAB2(SCH_1):GND
   6    GND GND<3> @BASEBOARD_FAB2_LIB.BASEBOARD_FAB2(SCH_1):GND
   7    GND GND<4> @BASEBOARD_FAB2_LIB.BASEBOARD_FAB2(SCH_1):GND
   8    GND GND<5> @BASEBOARD_FAB2_LIB.BASEBOARD_FAB2(SCH_1):GND
   9    GND GND<6> @BASEBOARD_FAB2_LIB.BASEBOARD_FAB2(SCH_1):GND
  10    GND GND<7> @BASEBOARD_FAB2_LIB.BASEBOARD_FAB2(SCH_1):GND
  11    GND GND<8> @BASEBOARD_FAB2_LIB.BASEBOARD_FAB2(SCH_1):GND
  12    GND GND<9> @BASEBOARD_FAB2_LIB.BASEBOARD_FAB2(SCH_1):GND
   1 L5_85OHM_10INCH_DP     DP @BASEBOARD_FAB2_LIB.BASEBOARD_FAB2(SCH_1):L5_85OHM_10INCH_DP
   2 L5_85OHM_10INCH_DN     DN @BASEBOARD_FAB2_LIB.BASEBOARD_FAB2(SCH_1):L5_85OHM_10INCH_DN

TEST-PAD-12P-1-GP-U_DISCRET-GBA  I3  T1D15
   3    GND GND<0> @BASEBOARD_FAB2_LIB.BASEBOARD_FAB2(SCH_1):GND
   4    GND GND<1> @BASEBOARD_FAB2_LIB.BASEBOARD_FAB2(SCH_1):GND
   5    GND GND<2> @BASEBOARD_FAB2_LIB.BASEBOARD_FAB2(SCH_1):GND
   6    GND GND<3> @BASEBOARD_FAB2_LIB.BASEBOARD_FAB2(SCH_1):GND
   7    GND GND<4> @BASEBOARD_FAB2_LIB.BASEBOARD_FAB2(SCH_1):GND
   8    GND GND<5> @BASEBOARD_FAB2_LIB.BASEBOARD_FAB2(SCH_1):GND
   9    GND GND<6> @BASEBOARD_FAB2_LIB.BASEBOARD_FAB2(SCH_1):GND
  10    GND GND<7> @BASEBOARD_FAB2_LIB.BASEBOARD_FAB2(SCH_1):GND
  11    GND GND<8> @BASEBOARD_FAB2_LIB.BASEBOARD_FAB2(SCH_1):GND
  12    GND GND<9> @BASEBOARD_FAB2_LIB.BASEBOARD_FAB2(SCH_1):GND
   1 L3_85OHM_10INCH_DP     DP @BASEBOARD_FAB2_LIB.BASEBOARD_FAB2(SCH_1):L3_85OHM_10INCH_DP
   2 L3_85OHM_10INCH_DN     DN @BASEBOARD_FAB2_LIB.BASEBOARD_FAB2(SCH_1):L3_85OHM_10INCH_DN

TEST-PAD-12P-1-GP-U_DISCRET-GBA  I5  T1D13
   3    GND GND<0> @BASEBOARD_FAB2_LIB.BASEBOARD_FAB2(SCH_1):GND
   4    GND GND<1> @BASEBOARD_FAB2_LIB.BASEBOARD_FAB2(SCH_1):GND
   5    GND GND<2> @BASEBOARD_FAB2_LIB.BASEBOARD_FAB2(SCH_1):GND
   6    GND GND<3> @BASEBOARD_FAB2_LIB.BASEBOARD_FAB2(SCH_1):GND
   7    GND GND<4> @BASEBOARD_FAB2_LIB.BASEBOARD_FAB2(SCH_1):GND
   8    GND GND<5> @BASEBOARD_FAB2_LIB.BASEBOARD_FAB2(SCH_1):GND
   9    GND GND<6> @BASEBOARD_FAB2_LIB.BASEBOARD_FAB2(SCH_1):GND
  10    GND GND<7> @BASEBOARD_FAB2_LIB.BASEBOARD_FAB2(SCH_1):GND
  11    GND GND<8> @BASEBOARD_FAB2_LIB.BASEBOARD_FAB2(SCH_1):GND
  12    GND GND<9> @BASEBOARD_FAB2_LIB.BASEBOARD_FAB2(SCH_1):GND
   1 L1_85OHM_10INCH_DP     DP @BASEBOARD_FAB2_LIB.BASEBOARD_FAB2(SCH_1):L1_85OHM_10INCH_DP
   2 L1_85OHM_10INCH_DN     DN @BASEBOARD_FAB2_LIB.BASEBOARD_FAB2(SCH_1):L1_85OHM_10INCH_DN

TEST-PAD-12P-1-GP-U_DISCRET-GBA  I8  T1D18
   3    GND GND<0> @BASEBOARD_FAB2_LIB.BASEBOARD_FAB2(SCH_1):GND
   4    GND GND<1> @BASEBOARD_FAB2_LIB.BASEBOARD_FAB2(SCH_1):GND
   5    GND GND<2> @BASEBOARD_FAB2_LIB.BASEBOARD_FAB2(SCH_1):GND
   6    GND GND<3> @BASEBOARD_FAB2_LIB.BASEBOARD_FAB2(SCH_1):GND
   7    GND GND<4> @BASEBOARD_FAB2_LIB.BASEBOARD_FAB2(SCH_1):GND
   8    GND GND<5> @BASEBOARD_FAB2_LIB.BASEBOARD_FAB2(SCH_1):GND
   9    GND GND<6> @BASEBOARD_FAB2_LIB.BASEBOARD_FAB2(SCH_1):GND
  10    GND GND<7> @BASEBOARD_FAB2_LIB.BASEBOARD_FAB2(SCH_1):GND
  11    GND GND<8> @BASEBOARD_FAB2_LIB.BASEBOARD_FAB2(SCH_1):GND
  12    GND GND<9> @BASEBOARD_FAB2_LIB.BASEBOARD_FAB2(SCH_1):GND
   1 L5_85OHM_10INCH_DN     DP @BASEBOARD_FAB2_LIB.BASEBOARD_FAB2(SCH_1):L5_85OHM_10INCH_DN
   2 L5_85OHM_10INCH_DP     DN @BASEBOARD_FAB2_LIB.BASEBOARD_FAB2(SCH_1):L5_85OHM_10INCH_DP

TEST-PAD-12P-1-GP-U_DISCRET-GBA  I9  T1D23
   3    GND GND<0> @BASEBOARD_FAB2_LIB.BASEBOARD_FAB2(SCH_1):GND
   4    GND GND<1> @BASEBOARD_FAB2_LIB.BASEBOARD_FAB2(SCH_1):GND
   5    GND GND<2> @BASEBOARD_FAB2_LIB.BASEBOARD_FAB2(SCH_1):GND
   6    GND GND<3> @BASEBOARD_FAB2_LIB.BASEBOARD_FAB2(SCH_1):GND
   7    GND GND<4> @BASEBOARD_FAB2_LIB.BASEBOARD_FAB2(SCH_1):GND
   8    GND GND<5> @BASEBOARD_FAB2_LIB.BASEBOARD_FAB2(SCH_1):GND
   9    GND GND<6> @BASEBOARD_FAB2_LIB.BASEBOARD_FAB2(SCH_1):GND
  10    GND GND<7> @BASEBOARD_FAB2_LIB.BASEBOARD_FAB2(SCH_1):GND
  11    GND GND<8> @BASEBOARD_FAB2_LIB.BASEBOARD_FAB2(SCH_1):GND
  12    GND GND<9> @BASEBOARD_FAB2_LIB.BASEBOARD_FAB2(SCH_1):GND
   1 L14_85OHM_10INCH_DP     DP @BASEBOARD_FAB2_LIB.BASEBOARD_FAB2(SCH_1):L14_85OHM_10INCH_DP
   2 L14_85OHM_10INCH_DN     DN @BASEBOARD_FAB2_LIB.BASEBOARD_FAB2(SCH_1):L14_85OHM_10INCH_DN

TEST-PAD-12P-1-GP-U_DISCRET-GBA  I12  T1D24
   3    GND GND<0> @BASEBOARD_FAB2_LIB.BASEBOARD_FAB2(SCH_1):GND
   4    GND GND<1> @BASEBOARD_FAB2_LIB.BASEBOARD_FAB2(SCH_1):GND
   5    GND GND<2> @BASEBOARD_FAB2_LIB.BASEBOARD_FAB2(SCH_1):GND
   6    GND GND<3> @BASEBOARD_FAB2_LIB.BASEBOARD_FAB2(SCH_1):GND
   7    GND GND<4> @BASEBOARD_FAB2_LIB.BASEBOARD_FAB2(SCH_1):GND
   8    GND GND<5> @BASEBOARD_FAB2_LIB.BASEBOARD_FAB2(SCH_1):GND
   9    GND GND<6> @BASEBOARD_FAB2_LIB.BASEBOARD_FAB2(SCH_1):GND
  10    GND GND<7> @BASEBOARD_FAB2_LIB.BASEBOARD_FAB2(SCH_1):GND
  11    GND GND<8> @BASEBOARD_FAB2_LIB.BASEBOARD_FAB2(SCH_1):GND
  12    GND GND<9> @BASEBOARD_FAB2_LIB.BASEBOARD_FAB2(SCH_1):GND
   1 L14_85OHM_10INCH_DN     DP @BASEBOARD_FAB2_LIB.BASEBOARD_FAB2(SCH_1):L14_85OHM_10INCH_DN
   2 L14_85OHM_10INCH_DP     DN @BASEBOARD_FAB2_LIB.BASEBOARD_FAB2(SCH_1):L14_85OHM_10INCH_DP

TEST-PAD-12P-1-GP-U_DISCRET-GBA  I14  T1D16
   3    GND GND<0> @BASEBOARD_FAB2_LIB.BASEBOARD_FAB2(SCH_1):GND
   4    GND GND<1> @BASEBOARD_FAB2_LIB.BASEBOARD_FAB2(SCH_1):GND
   5    GND GND<2> @BASEBOARD_FAB2_LIB.BASEBOARD_FAB2(SCH_1):GND
   6    GND GND<3> @BASEBOARD_FAB2_LIB.BASEBOARD_FAB2(SCH_1):GND
   7    GND GND<4> @BASEBOARD_FAB2_LIB.BASEBOARD_FAB2(SCH_1):GND
   8    GND GND<5> @BASEBOARD_FAB2_LIB.BASEBOARD_FAB2(SCH_1):GND
   9    GND GND<6> @BASEBOARD_FAB2_LIB.BASEBOARD_FAB2(SCH_1):GND
  10    GND GND<7> @BASEBOARD_FAB2_LIB.BASEBOARD_FAB2(SCH_1):GND
  11    GND GND<8> @BASEBOARD_FAB2_LIB.BASEBOARD_FAB2(SCH_1):GND
  12    GND GND<9> @BASEBOARD_FAB2_LIB.BASEBOARD_FAB2(SCH_1):GND
   1 L3_85OHM_10INCH_DN     DP @BASEBOARD_FAB2_LIB.BASEBOARD_FAB2(SCH_1):L3_85OHM_10INCH_DN
   2 L3_85OHM_10INCH_DP     DN @BASEBOARD_FAB2_LIB.BASEBOARD_FAB2(SCH_1):L3_85OHM_10INCH_DP

TEST-PAD-12P-1-GP-U_DISCRET-GBA  I16  T1D21
   3    GND GND<0> @BASEBOARD_FAB2_LIB.BASEBOARD_FAB2(SCH_1):GND
   4    GND GND<1> @BASEBOARD_FAB2_LIB.BASEBOARD_FAB2(SCH_1):GND
   5    GND GND<2> @BASEBOARD_FAB2_LIB.BASEBOARD_FAB2(SCH_1):GND
   6    GND GND<3> @BASEBOARD_FAB2_LIB.BASEBOARD_FAB2(SCH_1):GND
   7    GND GND<4> @BASEBOARD_FAB2_LIB.BASEBOARD_FAB2(SCH_1):GND
   8    GND GND<5> @BASEBOARD_FAB2_LIB.BASEBOARD_FAB2(SCH_1):GND
   9    GND GND<6> @BASEBOARD_FAB2_LIB.BASEBOARD_FAB2(SCH_1):GND
  10    GND GND<7> @BASEBOARD_FAB2_LIB.BASEBOARD_FAB2(SCH_1):GND
  11    GND GND<8> @BASEBOARD_FAB2_LIB.BASEBOARD_FAB2(SCH_1):GND
  12    GND GND<9> @BASEBOARD_FAB2_LIB.BASEBOARD_FAB2(SCH_1):GND
   1 L12_85OHM_10INCH_DP     DP @BASEBOARD_FAB2_LIB.BASEBOARD_FAB2(SCH_1):L12_85OHM_10INCH_DP
   2 L12_85OHM_10INCH_DN     DN @BASEBOARD_FAB2_LIB.BASEBOARD_FAB2(SCH_1):L12_85OHM_10INCH_DN

TEST-PAD-12P-1-GP-U_DISCRET-GBA  I21  T1D22
   3    GND GND<0> @BASEBOARD_FAB2_LIB.BASEBOARD_FAB2(SCH_1):GND
   4    GND GND<1> @BASEBOARD_FAB2_LIB.BASEBOARD_FAB2(SCH_1):GND
   5    GND GND<2> @BASEBOARD_FAB2_LIB.BASEBOARD_FAB2(SCH_1):GND
   6    GND GND<3> @BASEBOARD_FAB2_LIB.BASEBOARD_FAB2(SCH_1):GND
   7    GND GND<4> @BASEBOARD_FAB2_LIB.BASEBOARD_FAB2(SCH_1):GND
   8    GND GND<5> @BASEBOARD_FAB2_LIB.BASEBOARD_FAB2(SCH_1):GND
   9    GND GND<6> @BASEBOARD_FAB2_LIB.BASEBOARD_FAB2(SCH_1):GND
  10    GND GND<7> @BASEBOARD_FAB2_LIB.BASEBOARD_FAB2(SCH_1):GND
  11    GND GND<8> @BASEBOARD_FAB2_LIB.BASEBOARD_FAB2(SCH_1):GND
  12    GND GND<9> @BASEBOARD_FAB2_LIB.BASEBOARD_FAB2(SCH_1):GND
   1 L12_85OHM_10INCH_DN     DP @BASEBOARD_FAB2_LIB.BASEBOARD_FAB2(SCH_1):L12_85OHM_10INCH_DN
   2 L12_85OHM_10INCH_DP     DN @BASEBOARD_FAB2_LIB.BASEBOARD_FAB2(SCH_1):L12_85OHM_10INCH_DP

TEST-PAD-12P-1-GP-U_DISCRET-GBA  I22  T1D14
   3    GND GND<0> @BASEBOARD_FAB2_LIB.BASEBOARD_FAB2(SCH_1):GND
   4    GND GND<1> @BASEBOARD_FAB2_LIB.BASEBOARD_FAB2(SCH_1):GND
   5    GND GND<2> @BASEBOARD_FAB2_LIB.BASEBOARD_FAB2(SCH_1):GND
   6    GND GND<3> @BASEBOARD_FAB2_LIB.BASEBOARD_FAB2(SCH_1):GND
   7    GND GND<4> @BASEBOARD_FAB2_LIB.BASEBOARD_FAB2(SCH_1):GND
   8    GND GND<5> @BASEBOARD_FAB2_LIB.BASEBOARD_FAB2(SCH_1):GND
   9    GND GND<6> @BASEBOARD_FAB2_LIB.BASEBOARD_FAB2(SCH_1):GND
  10    GND GND<7> @BASEBOARD_FAB2_LIB.BASEBOARD_FAB2(SCH_1):GND
  11    GND GND<8> @BASEBOARD_FAB2_LIB.BASEBOARD_FAB2(SCH_1):GND
  12    GND GND<9> @BASEBOARD_FAB2_LIB.BASEBOARD_FAB2(SCH_1):GND
   1 L1_85OHM_10INCH_DN     DP @BASEBOARD_FAB2_LIB.BASEBOARD_FAB2(SCH_1):L1_85OHM_10INCH_DN
   2 L1_85OHM_10INCH_DP     DN @BASEBOARD_FAB2_LIB.BASEBOARD_FAB2(SCH_1):L1_85OHM_10INCH_DP

TEST-PAD-12P-1-GP-U_DISCRET-GBA  I23  T1D19
   3    GND GND<0> @BASEBOARD_FAB2_LIB.BASEBOARD_FAB2(SCH_1):GND
   4    GND GND<1> @BASEBOARD_FAB2_LIB.BASEBOARD_FAB2(SCH_1):GND
   5    GND GND<2> @BASEBOARD_FAB2_LIB.BASEBOARD_FAB2(SCH_1):GND
   6    GND GND<3> @BASEBOARD_FAB2_LIB.BASEBOARD_FAB2(SCH_1):GND
   7    GND GND<4> @BASEBOARD_FAB2_LIB.BASEBOARD_FAB2(SCH_1):GND
   8    GND GND<5> @BASEBOARD_FAB2_LIB.BASEBOARD_FAB2(SCH_1):GND
   9    GND GND<6> @BASEBOARD_FAB2_LIB.BASEBOARD_FAB2(SCH_1):GND
  10    GND GND<7> @BASEBOARD_FAB2_LIB.BASEBOARD_FAB2(SCH_1):GND
  11    GND GND<8> @BASEBOARD_FAB2_LIB.BASEBOARD_FAB2(SCH_1):GND
  12    GND GND<9> @BASEBOARD_FAB2_LIB.BASEBOARD_FAB2(SCH_1):GND
   1 L10_85OHM_10INCH_DP     DP @BASEBOARD_FAB2_LIB.BASEBOARD_FAB2(SCH_1):L10_85OHM_10INCH_DP
   2 L10_85OHM_10INCH_DN     DN @BASEBOARD_FAB2_LIB.BASEBOARD_FAB2(SCH_1):L10_85OHM_10INCH_DN

TEST-PAD-12P-1-GP-U_DISCRET-GBA  I24  T1D20
   3    GND GND<0> @BASEBOARD_FAB2_LIB.BASEBOARD_FAB2(SCH_1):GND
   4    GND GND<1> @BASEBOARD_FAB2_LIB.BASEBOARD_FAB2(SCH_1):GND
   5    GND GND<2> @BASEBOARD_FAB2_LIB.BASEBOARD_FAB2(SCH_1):GND
   6    GND GND<3> @BASEBOARD_FAB2_LIB.BASEBOARD_FAB2(SCH_1):GND
   7    GND GND<4> @BASEBOARD_FAB2_LIB.BASEBOARD_FAB2(SCH_1):GND
   8    GND GND<5> @BASEBOARD_FAB2_LIB.BASEBOARD_FAB2(SCH_1):GND
   9    GND GND<6> @BASEBOARD_FAB2_LIB.BASEBOARD_FAB2(SCH_1):GND
  10    GND GND<7> @BASEBOARD_FAB2_LIB.BASEBOARD_FAB2(SCH_1):GND
  11    GND GND<8> @BASEBOARD_FAB2_LIB.BASEBOARD_FAB2(SCH_1):GND
  12    GND GND<9> @BASEBOARD_FAB2_LIB.BASEBOARD_FAB2(SCH_1):GND
   1 L10_85OHM_10INCH_DN     DP @BASEBOARD_FAB2_LIB.BASEBOARD_FAB2(SCH_1):L10_85OHM_10INCH_DN
   2 L10_85OHM_10INCH_DP     DN @BASEBOARD_FAB2_LIB.BASEBOARD_FAB2(SCH_1):L10_85OHM_10INCH_DP

END LOGICAL PART CROSS REFERENCE
GLOBAL SIGNAL CROSS REFERENCE - 16-Jun-2017 AT 17:50:48
AGND_HSC @BASEBOARD_FAB2_LIB.BASEBOARD_FAB2(SCH_1):AGND_HSC
 C1D25    2      B CAP_0402-1.0UF,16V,10%,X6S,D97A     I3 @BASEBOARD_FAB2_LIB.BASEBOARD_FAB2(SCH_1):PAGE199
 C1D27    2      B CAP_A_0402V-0.1UF,16V,10%,X7R,A     I7 @BASEBOARD_FAB2_LIB.BASEBOARD_FAB2(SCH_1):PAGE199
 R1D43    2      B RES_0402-7.5K,1%,1/16W,CHIP,G2A     I9 @BASEBOARD_FAB2_LIB.BASEBOARD_FAB2(SCH_1):PAGE199
 EU1D2   33     EP ADM1278_SM-IC,G99251-001    I10 @BASEBOARD_FAB2_LIB.BASEBOARD_FAB2(SCH_1):PAGE199
 EU1D2   22    GND ADM1278_SM-IC,G99251-001    I10 @BASEBOARD_FAB2_LIB.BASEBOARD_FAB2(SCH_1):PAGE199
 R1D42    2      B RES_0402-11K,1%,1/16W,CHIP,G21A    I13 @BASEBOARD_FAB2_LIB.BASEBOARD_FAB2(SCH_1):PAGE199
 R1D41    2      B RES_0805-0.0,5%,1/8W,CHIP,G221A    I19 @BASEBOARD_FAB2_LIB.BASEBOARD_FAB2(SCH_1):PAGE199
 C9P14    2      B CAP_0603LF-0.033UF,50V,10%,X7RA    I24 @BASEBOARD_FAB2_LIB.BASEBOARD_FAB2(SCH_1):PAGE199
 R1D28    2      B RES_0402-100.0,1%,1/16W,EMPTY,A    I26 @BASEBOARD_FAB2_LIB.BASEBOARD_FAB2(SCH_1):PAGE199
 R9P17    2      B RES_0402-150.0K,1%,1/16W,CHIP,A    I33 @BASEBOARD_FAB2_LIB.BASEBOARD_FAB2(SCH_1):PAGE199
 R9P16    2      B RES_0402-0.0,5%,1/16W,CHIP,G21A    I36 @BASEBOARD_FAB2_LIB.BASEBOARD_FAB2(SCH_1):PAGE199
 C1D11    2      B CAP_A_0402V-0.1UF,16V,10%,X7R,A    I53 @BASEBOARD_FAB2_LIB.BASEBOARD_FAB2(SCH_1):PAGE199
 R9P24    2      B RES_0402-12.1K,1%,1/16W,CHIP,GA    I55 @BASEBOARD_FAB2_LIB.BASEBOARD_FAB2(SCH_1):PAGE199
 C9P12    2      B CAP_A_0402V-0.1UF,16V,10%,EMPTA    I67 @BASEBOARD_FAB2_LIB.BASEBOARD_FAB2(SCH_1):PAGE199
  Q1D1    4 SOURCE<0> FET_N_DUAL_SMLF-2N7002DW,FET,DA    I82 @BASEBOARD_FAB2_LIB.BASEBOARD_FAB2(SCH_1):PAGE199
  Q1D1    1 SOURCE<0> FET_N_DUAL_SMLF-2N7002DW,FET,DA    I86 @BASEBOARD_FAB2_LIB.BASEBOARD_FAB2(SCH_1):PAGE199
 R1D40    2      B RES_0402-40.2K,1%,1/16W,CHIP,GA   I100 @BASEBOARD_FAB2_LIB.BASEBOARD_FAB2(SCH_1):PAGE199
 R1D34    2      B RES_0402-16K,1.0%,1/16W,CHIP,GA   I102 @BASEBOARD_FAB2_LIB.BASEBOARD_FAB2(SCH_1):PAGE199
 C9P15    2      B CAP_A_0402V-0.1UF,16V,10%,X7R,A   I105 @BASEBOARD_FAB2_LIB.BASEBOARD_FAB2(SCH_1):PAGE199
 C1D26    2      B CAP_A_0402V-0.1UF,16V,10%,X7R,A   I107 @BASEBOARD_FAB2_LIB.BASEBOARD_FAB2(SCH_1):PAGE199
 C1D19    2      B CAP_0402-1.0UF,16V,10%,X6S,D97A   I119 @BASEBOARD_FAB2_LIB.BASEBOARD_FAB2(SCH_1):PAGE199
 C1D21    2      B CAP_A_0402V-0.1UF,16V,10%,X7R,A   I121 @BASEBOARD_FAB2_LIB.BASEBOARD_FAB2(SCH_1):PAGE199
 C9P17    2      B CAP_A_0402V-0.1UF,16V,10%,EMPTA    I36 @BASEBOARD_FAB2_LIB.BASEBOARD_FAB2(SCH_1):PAGE200
 C9P16    2      B CAP_A_0402V-0.1UF,16V,10%,EMPTA    I40 @BASEBOARD_FAB2_LIB.BASEBOARD_FAB2(SCH_1):PAGE200
 R9P19    2      B RES_0402-10.0K,1%,1/16W,EMPTY,A    I70 @BASEBOARD_FAB2_LIB.BASEBOARD_FAB2(SCH_1):PAGE200
 R9P11    2      B RES_0402-10.0K,1%,1/16W,CHIP,GA   I108 @BASEBOARD_FAB2_LIB.BASEBOARD_FAB2(SCH_1):PAGE200
 R1D12    2      B RES_0402-10.0K,1%,1/16W,CHIP,GA   I174 @BASEBOARD_FAB2_LIB.BASEBOARD_FAB2(SCH_1):PAGE200
 R1D19    2      B RES_0402-10.0K,1%,1/16W,CHIP,GA   I175 @BASEBOARD_FAB2_LIB.BASEBOARD_FAB2(SCH_1):PAGE200
  C9P6    2      B CAP_A_0402V-0.1UF,16V,10%,X7R,A   I185 @BASEBOARD_FAB2_LIB.BASEBOARD_FAB2(SCH_1):PAGE200
  C1D9    2      B CAP_A_0402V-0.1UF,16V,10%,X7R,A   I187 @BASEBOARD_FAB2_LIB.BASEBOARD_FAB2(SCH_1):PAGE200
 R9P12    2      B RES_0402-4.99K,1%,1/16W,CHIP,GA   I218 @BASEBOARD_FAB2_LIB.BASEBOARD_FAB2(SCH_1):PAGE200
  C9W1    2      2 SC22P50V2JN-4GP_SMD-BCG-SC22P5A   I235 @BASEBOARD_FAB2_LIB.BASEBOARD_FAB2(SCH_1):PAGE200
  C9W2    2      2 SC22P50V2JN-4GP_SMD-BCG-SC22P5A   I236 @BASEBOARD_FAB2_LIB.BASEBOARD_FAB2(SCH_1):PAGE200
 R1D18    2      B RES_0402-100.0K,1%,1/16W,CHIP,A    I87 @BASEBOARD_FAB2_LIB.BASEBOARD_FAB2(SCH_1):PAGE199
 R1D11    2      B RES_0402-100.0K,1%,1/16W,CHIP,A    I88 @BASEBOARD_FAB2_LIB.BASEBOARD_FAB2(SCH_1):PAGE199
  R9P9    2      B RES_0402-3.74K,1%,1/16W,CHIP,GA   I251 @BASEBOARD_FAB2_LIB.BASEBOARD_FAB2(SCH_1):PAGE200

AGND_P3V3_STBY @BASEBOARD_FAB2_LIB.BASEBOARD_FAB2(SCH_1):AGND_P3V3_STBY
 C8E17    2      B CAP_0402LF-1000PF,50V,10%,EMPTA   I113 @BASEBOARD_FAB2_LIB.BASEBOARD_FAB2(SCH_1):PAGE240
 EU8F1   11     G0 RT8240_QFN-IC,H66262-001   I125 @BASEBOARD_FAB2_LIB.BASEBOARD_FAB2(SCH_1):PAGE240
 EU8F1   12 GND<0> RT8240_QFN-IC,H66262-001   I125 @BASEBOARD_FAB2_LIB.BASEBOARD_FAB2(SCH_1):PAGE240
 EU8F1   13 GND<1> RT8240_QFN-IC,H66262-001   I125 @BASEBOARD_FAB2_LIB.BASEBOARD_FAB2(SCH_1):PAGE240
 R8E38    2      B RES_0402-0.0,5%,1/16W,CHIP,G21A   I140 @BASEBOARD_FAB2_LIB.BASEBOARD_FAB2(SCH_1):PAGE240
 R8E34    2      B RES_0402-10.0K,1%,1/16W,CHIP,GA   I142 @BASEBOARD_FAB2_LIB.BASEBOARD_FAB2(SCH_1):PAGE240
 R8F11    2      B RES_0402-0.0,5%,1/16W,CHIP,G21A   I146 @BASEBOARD_FAB2_LIB.BASEBOARD_FAB2(SCH_1):PAGE240
 C2R11    2      2 SC4D7U16V3KX-GP_SMD-BCG5-SC4D7A   I191 @BASEBOARD_FAB2_LIB.BASEBOARD_FAB2(SCH_1):PAGE240
  R8F9    2      B RES_0402-49.9K,1%,1/16W,CHIP,GA   I195 @BASEBOARD_FAB2_LIB.BASEBOARD_FAB2(SCH_1):PAGE240

AGND_P5V_STBY @BASEBOARD_FAB2_LIB.BASEBOARD_FAB2(SCH_1):AGND_P5V_STBY
 R7E14    2      B RES_0402-75K,1%,1/16W,CHIP,G21A    I18 @BASEBOARD_FAB2_LIB.BASEBOARD_FAB2(SCH_1):PAGE241
 C8E13    2      B CAP_0402LF-1000PF,50V,10%,EMPTA    I41 @BASEBOARD_FAB2_LIB.BASEBOARD_FAB2(SCH_1):PAGE241
 R7E16    2      B RES_0402-1.37K,1%,1/16W,CHIP,GA    I51 @BASEBOARD_FAB2_LIB.BASEBOARD_FAB2(SCH_1):PAGE241
 C8E16    2      B CAP_0402LF-270PF,50V,10%,X7R,AA    I53 @BASEBOARD_FAB2_LIB.BASEBOARD_FAB2(SCH_1):PAGE241
  C8F1    2      B CAP_0402LF-2200PF,50V,10%,X7R,A    I57 @BASEBOARD_FAB2_LIB.BASEBOARD_FAB2(SCH_1):PAGE241
 R7E13    2      B RES_0402-0.0,5%,1/16W,CHIP,G21A    I58 @BASEBOARD_FAB2_LIB.BASEBOARD_FAB2(SCH_1):PAGE241
 C8E15    2      B CAP_0402LF-0.022UF,16V,10%,X7RA    I63 @BASEBOARD_FAB2_LIB.BASEBOARD_FAB2(SCH_1):PAGE241

AGND_PVPP_ABC @BASEBOARD_FAB2_LIB.BASEBOARD_FAB2(SCH_1):AGND_PVPP_ABC
 R7F15    2      B RES_0402-7.87K,1.0%,1/16W,CHIPA   I134 @BASEBOARD_FAB2_LIB.BASEBOARD_FAB2(SCH_1):PAGE231
  C7F8    2      B CAP_0402LF-1000PF,50V,10%,EMPTA   I140 @BASEBOARD_FAB2_LIB.BASEBOARD_FAB2(SCH_1):PAGE231
 R7F35    2      B RES_0402-0.0,5%,1/16W,CHIP,G21A   I170 @BASEBOARD_FAB2_LIB.BASEBOARD_FAB2(SCH_1):PAGE231
 EU7F1    5   AGND NCP3232L_SM-IC,H86355-001   I193 @BASEBOARD_FAB2_LIB.BASEBOARD_FAB2(SCH_1):PAGE231
 EU7F1    6    OTS NCP3232L_SM-IC,H86355-001   I193 @BASEBOARD_FAB2_LIB.BASEBOARD_FAB2(SCH_1):PAGE231
 C7F10    2      B CAP_0402-0.027UF,16V,10%,X7R,AA   I194 @BASEBOARD_FAB2_LIB.BASEBOARD_FAB2(SCH_1):PAGE231
 C3T11    2      B CAP_0603-4.7UF,6.3V,10%,X6S,E1A   I202 @BASEBOARD_FAB2_LIB.BASEBOARD_FAB2(SCH_1):PAGE231
 R7F11    2      B RES_0402-6.19K,1%,1/16W,CHIP,GA   I230 @BASEBOARD_FAB2_LIB.BASEBOARD_FAB2(SCH_1):PAGE231

AGND_PVPP_DEF @BASEBOARD_FAB2_LIB.BASEBOARD_FAB2(SCH_1):AGND_PVPP_DEF
 R7B20    2      B RES_0402-0.0,5%,1/16W,CHIP,G21A   I150 @BASEBOARD_FAB2_LIB.BASEBOARD_FAB2(SCH_1):PAGE232
  C7B9    2      B CAP_0402LF-1000PF,50V,10%,EMPTA   I185 @BASEBOARD_FAB2_LIB.BASEBOARD_FAB2(SCH_1):PAGE232
 C7B11    2      B CAP_0402-0.027UF,16V,10%,X7R,AA   I197 @BASEBOARD_FAB2_LIB.BASEBOARD_FAB2(SCH_1):PAGE232
 EU7B1    5   AGND NCP3232L_SM-IC,H86355-001   I214 @BASEBOARD_FAB2_LIB.BASEBOARD_FAB2(SCH_1):PAGE232
 EU7B1    6    OTS NCP3232L_SM-IC,H86355-001   I214 @BASEBOARD_FAB2_LIB.BASEBOARD_FAB2(SCH_1):PAGE232
 C3M10    2      B CAP_0603-4.7UF,6.3V,10%,X6S,E1A   I253 @BASEBOARD_FAB2_LIB.BASEBOARD_FAB2(SCH_1):PAGE232
 R7B13    2      B RES_0402-6.19K,1%,1/16W,CHIP,GA   I314 @BASEBOARD_FAB2_LIB.BASEBOARD_FAB2(SCH_1):PAGE232
 R7B14    2      B RES_0402-7.87K,1.0%,1/16W,CHIPA   I315 @BASEBOARD_FAB2_LIB.BASEBOARD_FAB2(SCH_1):PAGE232

AGND_PVPP_GHJ @BASEBOARD_FAB2_LIB.BASEBOARD_FAB2(SCH_1):AGND_PVPP_GHJ
 R4G25    2      B RES_0402-0.0,5%,1/16W,CHIP,G21A   I157 @BASEBOARD_FAB2_LIB.BASEBOARD_FAB2(SCH_1):PAGE233
  C4G7    2      B CAP_0402LF-1000PF,50V,10%,EMPTA   I183 @BASEBOARD_FAB2_LIB.BASEBOARD_FAB2(SCH_1):PAGE233
  C6U6    2      B CAP_0603-4.7UF,6.3V,10%,X6S,E1A   I187 @BASEBOARD_FAB2_LIB.BASEBOARD_FAB2(SCH_1):PAGE233
  C4G8    2      B CAP_0402-0.027UF,16V,10%,X7R,AA   I194 @BASEBOARD_FAB2_LIB.BASEBOARD_FAB2(SCH_1):PAGE233
 EU4G1    5   AGND NCP3232L_SM-IC,H86355-001   I225 @BASEBOARD_FAB2_LIB.BASEBOARD_FAB2(SCH_1):PAGE233
 EU4G1    6    OTS NCP3232L_SM-IC,H86355-001   I225 @BASEBOARD_FAB2_LIB.BASEBOARD_FAB2(SCH_1):PAGE233
  R4G9    2      B RES_0402-6.19K,1%,1/16W,CHIP,GA   I283 @BASEBOARD_FAB2_LIB.BASEBOARD_FAB2(SCH_1):PAGE233
 R4G11    2      B RES_0402-7.87K,1.0%,1/16W,CHIPA   I284 @BASEBOARD_FAB2_LIB.BASEBOARD_FAB2(SCH_1):PAGE233

AGND_PVPP_KLM @BASEBOARD_FAB2_LIB.BASEBOARD_FAB2(SCH_1):AGND_PVPP_KLM
 R4B14    2      B RES_0402-0.0,5%,1/16W,CHIP,G21A    I29 @BASEBOARD_FAB2_LIB.BASEBOARD_FAB2(SCH_1):PAGE234
  C4B5    2      B CAP_0402LF-1000PF,50V,10%,EMPTA   I129 @BASEBOARD_FAB2_LIB.BASEBOARD_FAB2(SCH_1):PAGE234
 C6L12    2      B CAP_0603-4.7UF,6.3V,10%,X6S,E1A   I144 @BASEBOARD_FAB2_LIB.BASEBOARD_FAB2(SCH_1):PAGE234
  C4B6    2      B CAP_0402-0.027UF,16V,10%,X7R,AA   I146 @BASEBOARD_FAB2_LIB.BASEBOARD_FAB2(SCH_1):PAGE234
 EU4A3    5   AGND NCP3232L_SM-IC,H86355-001   I184 @BASEBOARD_FAB2_LIB.BASEBOARD_FAB2(SCH_1):PAGE234
 EU4A3    6    OTS NCP3232L_SM-IC,H86355-001   I184 @BASEBOARD_FAB2_LIB.BASEBOARD_FAB2(SCH_1):PAGE234
  R4B4    2      B RES_0402-6.19K,1%,1/16W,CHIP,GA   I227 @BASEBOARD_FAB2_LIB.BASEBOARD_FAB2(SCH_1):PAGE234
  R4B6    2      B RES_0402-7.87K,1.0%,1/16W,CHIPA   I228 @BASEBOARD_FAB2_LIB.BASEBOARD_FAB2(SCH_1):PAGE234

A_1P8_3P3_RCOMP @BASEBOARD_FAB2_LIB.BASEBOARD_FAB2(SCH_1):A_1P8_3P3_RCOMP
  U7C1  AM4 GPIO_RCOMP_1P8_3P3 LBG_CORE_QAT_EXT_D_BGA1-IC,H91A    I34 @BASEBOARD_FAB2_LIB.BASEBOARD_FAB2(SCH_1):PAGE121
 R8C26    1      A RES_0402-100.0,1%,1/16W,CHIP,GA    I35 @BASEBOARD_FAB2_LIB.BASEBOARD_FAB2(SCH_1):PAGE121

A_ADM1085_CEXT @BASEBOARD_FAB2_LIB.BASEBOARD_FAB2(SCH_1):A_ADM1085_CEXT
 C3P45    1      A CAP_0402-0.047UF,25V,10%,X7R,AA    I60 @BASEBOARD_FAB2_LIB.BASEBOARD_FAB2(SCH_1):PAGE196
  U7D3    5   CEXT ADM1085_SMT-IC,H46130-001    I70 @BASEBOARD_FAB2_LIB.BASEBOARD_FAB2(SCH_1):PAGE196

A_CBOT @BASEBOARD_FAB2_LIB.BASEBOARD_FAB2(SCH_1):A_CBOT
 EU9E1   37   CBOT SPRINGVILLE_SM1-IC,G47144-004    I72 @BASEBOARD_FAB2_LIB.BASEBOARD_FAB2(SCH_1):PAGE139
  C9E7    2      B CAP_0402LF-0.039UF,25V,10%,X7RA    I76 @BASEBOARD_FAB2_LIB.BASEBOARD_FAB2(SCH_1):PAGE139

A_COMP_CKMNG @BASEBOARD_FAB2_LIB.BASEBOARD_FAB2(SCH_1):A_COMP_CKMNG
 R8F25    1      A RES_0402-475.0,1%,1/16W,CHIP,GA    I28 @BASEBOARD_FAB2_LIB.BASEBOARD_FAB2(SCH_1):PAGE101
 EU8F2   11   IREF ICS9FGP204_MLFP-IC,E95226-001    I34 @BASEBOARD_FAB2_LIB.BASEBOARD_FAB2(SCH_1):PAGE101

A_CPU0_ABC_RCOMP0 @BASEBOARD_FAB2_LIB.BASEBOARD_FAB2(SCH_1):A_CPU0_ABC_RCOMP0
  R4P8    1      A RES_0402-90.9,1%,1/16W,CHIP,G2A   I180 @BASEBOARD_FAB2_LIB.BASEBOARD_FAB2(SCH_1):PAGE21
  U5D1  Y43 DDR012_RCOMP<0> SKX_EXT_B_BGA1-IC,TBD   I259 @BASEBOARD_FAB2_LIB.BASEBOARD_FAB2(SCH_1):PAGE21

A_CPU0_ABC_RCOMP1 @BASEBOARD_FAB2_LIB.BASEBOARD_FAB2(SCH_1):A_CPU0_ABC_RCOMP1
 R4P10    1      A RES_0402-90.9,1%,1/16W,CHIP,G2A   I181 @BASEBOARD_FAB2_LIB.BASEBOARD_FAB2(SCH_1):PAGE21
  U5D1 AB43 DDR012_RCOMP<1> SKX_EXT_B_BGA1-IC,TBD   I259 @BASEBOARD_FAB2_LIB.BASEBOARD_FAB2(SCH_1):PAGE21

A_CPU0_ABC_RCOMP2 @BASEBOARD_FAB2_LIB.BASEBOARD_FAB2(SCH_1):A_CPU0_ABC_RCOMP2
 R4P11    1      A RES_0402-100.0,1%,1/16W,CHIP,GA   I182 @BASEBOARD_FAB2_LIB.BASEBOARD_FAB2(SCH_1):PAGE21
  U5D1 AC42 DDR012_RCOMP<2> SKX_EXT_B_BGA1-IC,TBD   I259 @BASEBOARD_FAB2_LIB.BASEBOARD_FAB2(SCH_1):PAGE21

A_CPU0_DEF_RCOMP0 @BASEBOARD_FAB2_LIB.BASEBOARD_FAB2(SCH_1):A_CPU0_DEF_RCOMP0
  R5D1    1      A RES_0402-90.9,1%,1/16W,CHIP,G2A   I177 @BASEBOARD_FAB2_LIB.BASEBOARD_FAB2(SCH_1):PAGE21
  U5D1 DC48 DDR345_RCOMP<0> SKX_EXT_B_BGA1-IC,TBD   I259 @BASEBOARD_FAB2_LIB.BASEBOARD_FAB2(SCH_1):PAGE21

A_CPU0_DEF_RCOMP1 @BASEBOARD_FAB2_LIB.BASEBOARD_FAB2(SCH_1):A_CPU0_DEF_RCOMP1
  R5D2    1      A RES_0402-90.9,1%,1/16W,CHIP,G2A   I178 @BASEBOARD_FAB2_LIB.BASEBOARD_FAB2(SCH_1):PAGE21
  U5D1 DD47 DDR345_RCOMP<1> SKX_EXT_B_BGA1-IC,TBD   I259 @BASEBOARD_FAB2_LIB.BASEBOARD_FAB2(SCH_1):PAGE21

A_CPU0_DEF_RCOMP2 @BASEBOARD_FAB2_LIB.BASEBOARD_FAB2(SCH_1):A_CPU0_DEF_RCOMP2
  R6D1    1      A RES_0402-100.0,1%,1/16W,CHIP,GA   I179 @BASEBOARD_FAB2_LIB.BASEBOARD_FAB2(SCH_1):PAGE21
  U5D1 DD49 DDR345_RCOMP<2> SKX_EXT_B_BGA1-IC,TBD   I259 @BASEBOARD_FAB2_LIB.BASEBOARD_FAB2(SCH_1):PAGE21

A_CPU0_MCP01_RBIAS @BASEBOARD_FAB2_LIB.BASEBOARD_FAB2(SCH_1):A_CPU0_MCP01_RBIAS
  R6D2    1      A RES_0402-49.9,1%,1/16W,CHIP,G2A   I204 @BASEBOARD_FAB2_LIB.BASEBOARD_FAB2(SCH_1):PAGE21
  U5D1 CU32 MCP01_RBIAS<0> SKX_EXT_B_BGA1-IC,TBD   I259 @BASEBOARD_FAB2_LIB.BASEBOARD_FAB2(SCH_1):PAGE21
  U5D1 CT31 MCP01_RBIAS<1> SKX_EXT_B_BGA1-IC,TBD   I259 @BASEBOARD_FAB2_LIB.BASEBOARD_FAB2(SCH_1):PAGE21

A_CPU0_PE012_RBIAS @BASEBOARD_FAB2_LIB.BASEBOARD_FAB2(SCH_1):A_CPU0_PE012_RBIAS
  R4P3    1      A RES_0402-49.9,1%,1/16W,CHIP,G2A   I186 @BASEBOARD_FAB2_LIB.BASEBOARD_FAB2(SCH_1):PAGE21
  U5D1 CN30 PE012_RBIAS<0> SKX_EXT_B_BGA1-IC,TBD   I259 @BASEBOARD_FAB2_LIB.BASEBOARD_FAB2(SCH_1):PAGE21
  U5D1 CL30 PE012_RBIAS<1> SKX_EXT_B_BGA1-IC,TBD   I259 @BASEBOARD_FAB2_LIB.BASEBOARD_FAB2(SCH_1):PAGE21

A_CPU0_PE3_RBIAS @BASEBOARD_FAB2_LIB.BASEBOARD_FAB2(SCH_1):A_CPU0_PE3_RBIAS
  R4P2    1      A RES_0402-49.9,1%,1/16W,CHIP,G2A   I188 @BASEBOARD_FAB2_LIB.BASEBOARD_FAB2(SCH_1):PAGE21
  U5D1 CP29 PE3_RBIAS<0> SKX_EXT_B_BGA1-IC,TBD   I259 @BASEBOARD_FAB2_LIB.BASEBOARD_FAB2(SCH_1):PAGE21
  U5D1 CR30 PE3_RBIAS<1> SKX_EXT_B_BGA1-IC,TBD   I259 @BASEBOARD_FAB2_LIB.BASEBOARD_FAB2(SCH_1):PAGE21

A_CPU0_UPI01_RBIAS @BASEBOARD_FAB2_LIB.BASEBOARD_FAB2(SCH_1):A_CPU0_UPI01_RBIAS
 R6D11    1      A RES_0402-49.9,1%,1/16W,CHIP,G2A   I184 @BASEBOARD_FAB2_LIB.BASEBOARD_FAB2(SCH_1):PAGE21
  U5D1 AT29 UPI01_RBIAS<0> SKX_EXT_B_BGA1-IC,TBD   I259 @BASEBOARD_FAB2_LIB.BASEBOARD_FAB2(SCH_1):PAGE21
  U5D1 AP29 UPI01_RBIAS<1> SKX_EXT_B_BGA1-IC,TBD   I259 @BASEBOARD_FAB2_LIB.BASEBOARD_FAB2(SCH_1):PAGE21

A_CPU0_UPI2_RBIAS @BASEBOARD_FAB2_LIB.BASEBOARD_FAB2(SCH_1):A_CPU0_UPI2_RBIAS
  R4P4    1      A RES_0402-49.9,1%,1/16W,CHIP,G2A   I189 @BASEBOARD_FAB2_LIB.BASEBOARD_FAB2(SCH_1):PAGE21
  U5D1 CL28 UPI2_RBIAS<0> SKX_EXT_B_BGA1-IC,TBD   I259 @BASEBOARD_FAB2_LIB.BASEBOARD_FAB2(SCH_1):PAGE21
  U5D1 CK29 UPI2_RBIAS<1> SKX_EXT_B_BGA1-IC,TBD   I259 @BASEBOARD_FAB2_LIB.BASEBOARD_FAB2(SCH_1):PAGE21

A_CPU1_GHJ_RCOMP0 @BASEBOARD_FAB2_LIB.BASEBOARD_FAB2(SCH_1):A_CPU1_GHJ_RCOMP0
 R7P16    1      A RES_0402-90.9,1%,1/16W,CHIP,G2A   I119 @BASEBOARD_FAB2_LIB.BASEBOARD_FAB2(SCH_1):PAGE55
  U2D1  Y43 DDR012_RCOMP<0> SKX_EXT_B_BGA1-IC,TBD   I172 @BASEBOARD_FAB2_LIB.BASEBOARD_FAB2(SCH_1):PAGE55

A_CPU1_GHJ_RCOMP1 @BASEBOARD_FAB2_LIB.BASEBOARD_FAB2(SCH_1):A_CPU1_GHJ_RCOMP1
 R7P17    1      A RES_0402-90.9,1%,1/16W,CHIP,G2A   I140 @BASEBOARD_FAB2_LIB.BASEBOARD_FAB2(SCH_1):PAGE55
  U2D1 AB43 DDR012_RCOMP<1> SKX_EXT_B_BGA1-IC,TBD   I172 @BASEBOARD_FAB2_LIB.BASEBOARD_FAB2(SCH_1):PAGE55

A_CPU1_GHJ_RCOMP2 @BASEBOARD_FAB2_LIB.BASEBOARD_FAB2(SCH_1):A_CPU1_GHJ_RCOMP2
 R7P19    1      A RES_0402-100.0,1%,1/16W,CHIP,GA   I115 @BASEBOARD_FAB2_LIB.BASEBOARD_FAB2(SCH_1):PAGE55
  U2D1 AC42 DDR012_RCOMP<2> SKX_EXT_B_BGA1-IC,TBD   I172 @BASEBOARD_FAB2_LIB.BASEBOARD_FAB2(SCH_1):PAGE55

A_CPU1_KLM_RCOMP0 @BASEBOARD_FAB2_LIB.BASEBOARD_FAB2(SCH_1):A_CPU1_KLM_RCOMP0
  R3D1    1      A RES_0402-90.9,1%,1/16W,CHIP,G2A   I116 @BASEBOARD_FAB2_LIB.BASEBOARD_FAB2(SCH_1):PAGE55
  U2D1 DC48 DDR345_RCOMP<0> SKX_EXT_B_BGA1-IC,TBD   I172 @BASEBOARD_FAB2_LIB.BASEBOARD_FAB2(SCH_1):PAGE55

A_CPU1_KLM_RCOMP1 @BASEBOARD_FAB2_LIB.BASEBOARD_FAB2(SCH_1):A_CPU1_KLM_RCOMP1
  R3D2    1      A RES_0402-90.9,1%,1/16W,CHIP,G2A   I117 @BASEBOARD_FAB2_LIB.BASEBOARD_FAB2(SCH_1):PAGE55
  U2D1 DD47 DDR345_RCOMP<1> SKX_EXT_B_BGA1-IC,TBD   I172 @BASEBOARD_FAB2_LIB.BASEBOARD_FAB2(SCH_1):PAGE55

A_CPU1_KLM_RCOMP2 @BASEBOARD_FAB2_LIB.BASEBOARD_FAB2(SCH_1):A_CPU1_KLM_RCOMP2
  R3D3    1      A RES_0402-100.0,1%,1/16W,CHIP,GA   I118 @BASEBOARD_FAB2_LIB.BASEBOARD_FAB2(SCH_1):PAGE55
  U2D1 DD49 DDR345_RCOMP<2> SKX_EXT_B_BGA1-IC,TBD   I172 @BASEBOARD_FAB2_LIB.BASEBOARD_FAB2(SCH_1):PAGE55

A_CPU1_MCP01_RBIAS @BASEBOARD_FAB2_LIB.BASEBOARD_FAB2(SCH_1):A_CPU1_MCP01_RBIAS
  R3D4    1      A RES_0402-49.9,1%,1/16W,CHIP,G2A   I155 @BASEBOARD_FAB2_LIB.BASEBOARD_FAB2(SCH_1):PAGE55
  U2D1 CU32 MCP01_RBIAS<0> SKX_EXT_B_BGA1-IC,TBD   I172 @BASEBOARD_FAB2_LIB.BASEBOARD_FAB2(SCH_1):PAGE55
  U2D1 CT31 MCP01_RBIAS<1> SKX_EXT_B_BGA1-IC,TBD   I172 @BASEBOARD_FAB2_LIB.BASEBOARD_FAB2(SCH_1):PAGE55

A_CPU1_PE012_RBIAS @BASEBOARD_FAB2_LIB.BASEBOARD_FAB2(SCH_1):A_CPU1_PE012_RBIAS
 R7P10    1      A RES_0402-49.9,1%,1/16W,CHIP,G2A   I124 @BASEBOARD_FAB2_LIB.BASEBOARD_FAB2(SCH_1):PAGE55
  U2D1 CN30 PE012_RBIAS<0> SKX_EXT_B_BGA1-IC,TBD   I172 @BASEBOARD_FAB2_LIB.BASEBOARD_FAB2(SCH_1):PAGE55
  U2D1 CL30 PE012_RBIAS<1> SKX_EXT_B_BGA1-IC,TBD   I172 @BASEBOARD_FAB2_LIB.BASEBOARD_FAB2(SCH_1):PAGE55

A_CPU1_PE3_RBIAS @BASEBOARD_FAB2_LIB.BASEBOARD_FAB2(SCH_1):A_CPU1_PE3_RBIAS
  R7P8    1      A RES_0402-49.9,1%,1/16W,CHIP,G2A   I123 @BASEBOARD_FAB2_LIB.BASEBOARD_FAB2(SCH_1):PAGE55
  U2D1 CP29 PE3_RBIAS<0> SKX_EXT_B_BGA1-IC,TBD   I172 @BASEBOARD_FAB2_LIB.BASEBOARD_FAB2(SCH_1):PAGE55
  U2D1 CR30 PE3_RBIAS<1> SKX_EXT_B_BGA1-IC,TBD   I172 @BASEBOARD_FAB2_LIB.BASEBOARD_FAB2(SCH_1):PAGE55

A_CPU1_UPI01_RBIAS @BASEBOARD_FAB2_LIB.BASEBOARD_FAB2(SCH_1):A_CPU1_UPI01_RBIAS
 R3D19    1      A RES_0402-49.9,1%,1/16W,CHIP,G2A   I125 @BASEBOARD_FAB2_LIB.BASEBOARD_FAB2(SCH_1):PAGE55
  U2D1 AT29 UPI01_RBIAS<0> SKX_EXT_B_BGA1-IC,TBD   I172 @BASEBOARD_FAB2_LIB.BASEBOARD_FAB2(SCH_1):PAGE55
  U2D1 AP29 UPI01_RBIAS<1> SKX_EXT_B_BGA1-IC,TBD   I172 @BASEBOARD_FAB2_LIB.BASEBOARD_FAB2(SCH_1):PAGE55

A_CPU1_UPI2_RBIAS @BASEBOARD_FAB2_LIB.BASEBOARD_FAB2(SCH_1):A_CPU1_UPI2_RBIAS
 R7P11    1      A RES_0402-49.9,1%,1/16W,CHIP,G2A   I126 @BASEBOARD_FAB2_LIB.BASEBOARD_FAB2(SCH_1):PAGE55
  U2D1 CL28 UPI2_RBIAS<0> SKX_EXT_B_BGA1-IC,TBD   I172 @BASEBOARD_FAB2_LIB.BASEBOARD_FAB2(SCH_1):PAGE55
  U2D1 CK29 UPI2_RBIAS<1> SKX_EXT_B_BGA1-IC,TBD   I172 @BASEBOARD_FAB2_LIB.BASEBOARD_FAB2(SCH_1):PAGE55

A_CTOP @BASEBOARD_FAB2_LIB.BASEBOARD_FAB2(SCH_1):A_CTOP
 EU9E1   40   CTOP SPRINGVILLE_SM1-IC,G47144-004    I72 @BASEBOARD_FAB2_LIB.BASEBOARD_FAB2(SCH_1):PAGE139
  C9E7    1      A CAP_0402LF-0.039UF,25V,10%,X7RA    I76 @BASEBOARD_FAB2_LIB.BASEBOARD_FAB2(SCH_1):PAGE139

A_DACRSET @BASEBOARD_FAB2_LIB.BASEBOARD_FAB2(SCH_1):A_DACRSET
 U25W4   K4 DACRSET AST2520A1-GP-GP_ASIC2-GB1-AST2A    I95 @BASEBOARD_FAB2_LIB.BASEBOARD_FAB2(SCH_1):PAGE144
R25W58    1      1 18KR2F-GP_RCL_GP-18KR2F-GP,64.A   I150 @BASEBOARD_FAB2_LIB.BASEBOARD_FAB2(SCH_1):PAGE144

A_EXTCLKN @BASEBOARD_FAB2_LIB.BASEBOARD_FAB2(SCH_1):A_EXTCLKN
  U7C1  D66 EXTCLKN LBG_CORE_QAT_EXT_D_BGA1-IC,H91A   I220 @BASEBOARD_FAB2_LIB.BASEBOARD_FAB2(SCH_1):PAGE116
  R7B8    1      A RES_0402-10.0K,1%,1/16W,EMPTY,A   I229 @BASEBOARD_FAB2_LIB.BASEBOARD_FAB2(SCH_1):PAGE116

A_EXTCLKP @BASEBOARD_FAB2_LIB.BASEBOARD_FAB2(SCH_1):A_EXTCLKP
  U7C1  E67 EXTCLKP LBG_CORE_QAT_EXT_D_BGA1-IC,H91A   I220 @BASEBOARD_FAB2_LIB.BASEBOARD_FAB2(SCH_1):PAGE116
  R7B7    1      A RES_0402-10.0K,1%,1/16W,EMPTY,A   I230 @BASEBOARD_FAB2_LIB.BASEBOARD_FAB2(SCH_1):PAGE116

A_HSC_C @BASEBOARD_FAB2_LIB.BASEBOARD_FAB2(SCH_1):A_HSC_C
 R1D51    1      A RES_0402-10.0,1%,1/16W,CHIP,G2A   I154 @BASEBOARD_FAB2_LIB.BASEBOARD_FAB2(SCH_1):PAGE200
  C1E2    1      A CAP_1206-0.068UF,50V,20%,X7R,1A   I155 @BASEBOARD_FAB2_LIB.BASEBOARD_FAB2(SCH_1):PAGE200

A_HSC_CSOUT @BASEBOARD_FAB2_LIB.BASEBOARD_FAB2(SCH_1):A_HSC_CSOUT
 EU1D2   19  CSOUT ADM1278_SM-IC,G99251-001    I10 @BASEBOARD_FAB2_LIB.BASEBOARD_FAB2(SCH_1):PAGE199
 R1D14    1      A RES_0402-105.0K,1%,1/16W,CHIP,A   I246 @BASEBOARD_FAB2_LIB.BASEBOARD_FAB2(SCH_1):PAGE200
 R1D20    1      A RES_0402-200.0K,1%,1/16W,CHIP,A   I253 @BASEBOARD_FAB2_LIB.BASEBOARD_FAB2(SCH_1):PAGE200

A_HSC_GATE @BASEBOARD_FAB2_LIB.BASEBOARD_FAB2(SCH_1):A_HSC_GATE
 EU1D2   24   GATE ADM1278_SM-IC,G99251-001    I10 @BASEBOARD_FAB2_LIB.BASEBOARD_FAB2(SCH_1):PAGE199
  R1E1    1      A RES_0402-10.0,1%,1/16W,CHIP,G2A    I56 @BASEBOARD_FAB2_LIB.BASEBOARD_FAB2(SCH_1):PAGE200
  R9R4    1      A RES_0402-10.0,1%,1/16W,CHIP,G2A    I58 @BASEBOARD_FAB2_LIB.BASEBOARD_FAB2(SCH_1):PAGE200
 R1D48    1      A RES_0402-10.0,1%,1/16W,CHIP,G2A    I60 @BASEBOARD_FAB2_LIB.BASEBOARD_FAB2(SCH_1):PAGE200
 R1D51    2      B RES_0402-10.0,1%,1/16W,CHIP,G2A   I154 @BASEBOARD_FAB2_LIB.BASEBOARD_FAB2(SCH_1):PAGE200

A_HSC_GATE1_R @BASEBOARD_FAB2_LIB.BASEBOARD_FAB2(SCH_1):A_HSC_GATE1_R
 EU1E3    4      G MOSFETN_1D3S_SOT5-IC,G68777-001    I54 @BASEBOARD_FAB2_LIB.BASEBOARD_FAB2(SCH_1):PAGE200
  R1E1    2      B RES_0402-10.0,1%,1/16W,CHIP,G2A    I56 @BASEBOARD_FAB2_LIB.BASEBOARD_FAB2(SCH_1):PAGE200

A_HSC_GATE2_R @BASEBOARD_FAB2_LIB.BASEBOARD_FAB2(SCH_1):A_HSC_GATE2_R
 EU9R1    4      G MOSFETN_1D3S_SOT5-IC,G68777-001    I57 @BASEBOARD_FAB2_LIB.BASEBOARD_FAB2(SCH_1):PAGE200
  R9R4    2      B RES_0402-10.0,1%,1/16W,CHIP,G2A    I58 @BASEBOARD_FAB2_LIB.BASEBOARD_FAB2(SCH_1):PAGE200

A_HSC_GATE3_R @BASEBOARD_FAB2_LIB.BASEBOARD_FAB2(SCH_1):A_HSC_GATE3_R
 EU1E1    4      G MOSFETN_1D3S_SOT5-IC,G68777-001    I59 @BASEBOARD_FAB2_LIB.BASEBOARD_FAB2(SCH_1):PAGE200
 R1D48    2      B RES_0402-10.0,1%,1/16W,CHIP,G2A    I60 @BASEBOARD_FAB2_LIB.BASEBOARD_FAB2(SCH_1):PAGE200

A_HSC_HIGH @BASEBOARD_FAB2_LIB.BASEBOARD_FAB2(SCH_1):A_HSC_HIGH
  U1D2    3   INBN TPS3700_SM-IC,H69492-001   I170 @BASEBOARD_FAB2_LIB.BASEBOARD_FAB2(SCH_1):PAGE200
 R1D19    1      A RES_0402-10.0K,1%,1/16W,CHIP,GA   I175 @BASEBOARD_FAB2_LIB.BASEBOARD_FAB2(SCH_1):PAGE200
 R1D20    2      B RES_0402-200.0K,1%,1/16W,CHIP,A   I253 @BASEBOARD_FAB2_LIB.BASEBOARD_FAB2(SCH_1):PAGE200

A_HSC_HIGH_EN @BASEBOARD_FAB2_LIB.BASEBOARD_FAB2(SCH_1):A_HSC_HIGH_EN
  Q1D1    5 GATE<0> FET_N_DUAL_SMLF-2N7002DW,FET,DA    I82 @BASEBOARD_FAB2_LIB.BASEBOARD_FAB2(SCH_1):PAGE199
 R1D18    1      A RES_0402-100.0K,1%,1/16W,CHIP,A    I87 @BASEBOARD_FAB2_LIB.BASEBOARD_FAB2(SCH_1):PAGE199
  Q1W5    1   GATE FET_N_SOT23LF-2N7002,FET,C7925A   I130 @BASEBOARD_FAB2_LIB.BASEBOARD_FAB2(SCH_1):PAGE199
  J1B4    1      1 CLX-CONN3A-1-GP_CONN-G3-CLX-COA   I131 @BASEBOARD_FAB2_LIB.BASEBOARD_FAB2(SCH_1):PAGE199

A_HSC_HSN @BASEBOARD_FAB2_LIB.BASEBOARD_FAB2(SCH_1):A_HSC_HSN
 EU1D2   27    HSN ADM1278_SM-IC,G99251-001    I10 @BASEBOARD_FAB2_LIB.BASEBOARD_FAB2(SCH_1):PAGE199
 R1D45    2      B RES_0402-0.0,5%,1/16W,CHIP,G21A    I43 @BASEBOARD_FAB2_LIB.BASEBOARD_FAB2(SCH_1):PAGE200
 R9P26    2      B RES_0402-10.0,1%,1/16W,CHIP,G2A    I51 @BASEBOARD_FAB2_LIB.BASEBOARD_FAB2(SCH_1):PAGE200
 R1D47    2      B RES_0402-10.0,1%,1/16W,CHIP,G2A    I52 @BASEBOARD_FAB2_LIB.BASEBOARD_FAB2(SCH_1):PAGE200

A_HSC_HSP @BASEBOARD_FAB2_LIB.BASEBOARD_FAB2(SCH_1):A_HSC_HSP
 EU1D2   28    HSP ADM1278_SM-IC,G99251-001    I10 @BASEBOARD_FAB2_LIB.BASEBOARD_FAB2(SCH_1):PAGE199
 R1D44    2      B RES_0402-0.0,5%,1/16W,CHIP,G21A    I44 @BASEBOARD_FAB2_LIB.BASEBOARD_FAB2(SCH_1):PAGE200
 R9P27    2      B RES_0402-10.0,1%,1/16W,CHIP,G2A    I47 @BASEBOARD_FAB2_LIB.BASEBOARD_FAB2(SCH_1):PAGE200
 R1D46    2      B RES_0402-10.0,1%,1/16W,CHIP,G2A    I48 @BASEBOARD_FAB2_LIB.BASEBOARD_FAB2(SCH_1):PAGE200

A_HSC_INAP @BASEBOARD_FAB2_LIB.BASEBOARD_FAB2(SCH_1):A_HSC_INAP
  U9P2    4   INAP TPS3700_SM-IC,H69492-001   I200 @BASEBOARD_FAB2_LIB.BASEBOARD_FAB2(SCH_1):PAGE200
 R9P12    1      A RES_0402-4.99K,1%,1/16W,CHIP,GA   I218 @BASEBOARD_FAB2_LIB.BASEBOARD_FAB2(SCH_1):PAGE200
 R9P33    2      B RES_0402-100.0K,1%,1/16W,CHIP,A   I222 @BASEBOARD_FAB2_LIB.BASEBOARD_FAB2(SCH_1):PAGE200

A_HSC_ISET @BASEBOARD_FAB2_LIB.BASEBOARD_FAB2(SCH_1):A_HSC_ISET
 EU1D2    3   ISET ADM1278_SM-IC,G99251-001    I10 @BASEBOARD_FAB2_LIB.BASEBOARD_FAB2(SCH_1):PAGE199
 R1D37    2      B RES_0402-100.0K,1%,1/16W,CHIP,A    I15 @BASEBOARD_FAB2_LIB.BASEBOARD_FAB2(SCH_1):PAGE199
 R1D13    2      B RES_0402-90.9K,1%,1/16W,CHIP,GA    I84 @BASEBOARD_FAB2_LIB.BASEBOARD_FAB2(SCH_1):PAGE199
 R1D16    1      A RES_0402-69.8K,1%,1/16W,CHIP,GA    I85 @BASEBOARD_FAB2_LIB.BASEBOARD_FAB2(SCH_1):PAGE199
 C9P15    1      A CAP_A_0402V-0.1UF,16V,10%,X7R,A   I105 @BASEBOARD_FAB2_LIB.BASEBOARD_FAB2(SCH_1):PAGE199

A_HSC_ISET_S @BASEBOARD_FAB2_LIB.BASEBOARD_FAB2(SCH_1):A_HSC_ISET_S
  Q1D1    3 DRAIN<0> FET_N_DUAL_SMLF-2N7002DW,FET,DA    I82 @BASEBOARD_FAB2_LIB.BASEBOARD_FAB2(SCH_1):PAGE199
 R1D13    1      A RES_0402-90.9K,1%,1/16W,CHIP,GA    I84 @BASEBOARD_FAB2_LIB.BASEBOARD_FAB2(SCH_1):PAGE199

A_HSC_ISET_S2 @BASEBOARD_FAB2_LIB.BASEBOARD_FAB2(SCH_1):A_HSC_ISET_S2
 R1D16    2      B RES_0402-69.8K,1%,1/16W,CHIP,GA    I85 @BASEBOARD_FAB2_LIB.BASEBOARD_FAB2(SCH_1):PAGE199
  Q1D1    6 DRAIN<0> FET_N_DUAL_SMLF-2N7002DW,FET,DA    I86 @BASEBOARD_FAB2_LIB.BASEBOARD_FAB2(SCH_1):PAGE199

A_HSC_ISTART @BASEBOARD_FAB2_LIB.BASEBOARD_FAB2(SCH_1):A_HSC_ISTART
 EU1D2    4 ISTART ADM1278_SM-IC,G99251-001    I10 @BASEBOARD_FAB2_LIB.BASEBOARD_FAB2(SCH_1):PAGE199
 R1D32    2      B RES_0402-100.0K,1%,1/16W,CHIP,A    I17 @BASEBOARD_FAB2_LIB.BASEBOARD_FAB2(SCH_1):PAGE199
 R1D34    1      A RES_0402-16K,1.0%,1/16W,CHIP,GA   I102 @BASEBOARD_FAB2_LIB.BASEBOARD_FAB2(SCH_1):PAGE199

A_HSC_LOW @BASEBOARD_FAB2_LIB.BASEBOARD_FAB2(SCH_1):A_HSC_LOW
  U1D2    4   INAP TPS3700_SM-IC,H69492-001   I170 @BASEBOARD_FAB2_LIB.BASEBOARD_FAB2(SCH_1):PAGE200
 R1D12    1      A RES_0402-10.0K,1%,1/16W,CHIP,GA   I174 @BASEBOARD_FAB2_LIB.BASEBOARD_FAB2(SCH_1):PAGE200
 R1D14    2      B RES_0402-105.0K,1%,1/16W,CHIP,A   I246 @BASEBOARD_FAB2_LIB.BASEBOARD_FAB2(SCH_1):PAGE200

A_HSC_LOW_DRAIN @BASEBOARD_FAB2_LIB.BASEBOARD_FAB2(SCH_1):A_HSC_LOW_DRAIN
  Q9P1    6 DRAIN<0> FET_N_DUAL_SMLF-2N7002DW,FET,DA   I196 @BASEBOARD_FAB2_LIB.BASEBOARD_FAB2(SCH_1):PAGE200
 R9P15    1      A RES_0402-0.0,5%,1/16W,CHIP,G21A   I243 @BASEBOARD_FAB2_LIB.BASEBOARD_FAB2(SCH_1):PAGE200

A_HSC_LOW_EN @BASEBOARD_FAB2_LIB.BASEBOARD_FAB2(SCH_1):A_HSC_LOW_EN
  Q1D1    2 GATE<0> FET_N_DUAL_SMLF-2N7002DW,FET,DA    I86 @BASEBOARD_FAB2_LIB.BASEBOARD_FAB2(SCH_1):PAGE199
 R1D11    1      A RES_0402-100.0K,1%,1/16W,CHIP,A    I88 @BASEBOARD_FAB2_LIB.BASEBOARD_FAB2(SCH_1):PAGE199
  J1B4    3      3 CLX-CONN3A-1-GP_CONN-G3-CLX-COA   I131 @BASEBOARD_FAB2_LIB.BASEBOARD_FAB2(SCH_1):PAGE199

A_HSC_LOW_GATE @BASEBOARD_FAB2_LIB.BASEBOARD_FAB2(SCH_1):A_HSC_LOW_GATE
  U1D2    6   OUTA TPS3700_SM-IC,H69492-001   I170 @BASEBOARD_FAB2_LIB.BASEBOARD_FAB2(SCH_1):PAGE200
  Q9P1    2 GATE<0> FET_N_DUAL_SMLF-2N7002DW,FET,DA   I196 @BASEBOARD_FAB2_LIB.BASEBOARD_FAB2(SCH_1):PAGE200
 R1D10    2      B RES_0402-10.0K,1%,1/16W,CHIP,GA   I244 @BASEBOARD_FAB2_LIB.BASEBOARD_FAB2(SCH_1):PAGE200
  Q1W5    3    DRN FET_N_SOT23LF-2N7002,FET,C7925A   I130 @BASEBOARD_FAB2_LIB.BASEBOARD_FAB2(SCH_1):PAGE199

A_HSC_MON @BASEBOARD_FAB2_LIB.BASEBOARD_FAB2(SCH_1):A_HSC_MON
 EU1D2   26    MON ADM1278_SM-IC,G99251-001    I10 @BASEBOARD_FAB2_LIB.BASEBOARD_FAB2(SCH_1):PAGE199
 C9P17    1      A CAP_A_0402V-0.1UF,16V,10%,EMPTA    I36 @BASEBOARD_FAB2_LIB.BASEBOARD_FAB2(SCH_1):PAGE200
 C1D22    1      A CAP_A_0402V-0.1UF,16V,10%,EMPTA    I42 @BASEBOARD_FAB2_LIB.BASEBOARD_FAB2(SCH_1):PAGE200
 R1D45    1      A RES_0402-0.0,5%,1/16W,CHIP,G21A    I43 @BASEBOARD_FAB2_LIB.BASEBOARD_FAB2(SCH_1):PAGE200

A_HSC_MOP @BASEBOARD_FAB2_LIB.BASEBOARD_FAB2(SCH_1):A_HSC_MOP
 EU1D2   29    MOP ADM1278_SM-IC,G99251-001    I10 @BASEBOARD_FAB2_LIB.BASEBOARD_FAB2(SCH_1):PAGE199
 C9P16    1      A CAP_A_0402V-0.1UF,16V,10%,EMPTA    I40 @BASEBOARD_FAB2_LIB.BASEBOARD_FAB2(SCH_1):PAGE200
 C1D22    2      B CAP_A_0402V-0.1UF,16V,10%,EMPTA    I42 @BASEBOARD_FAB2_LIB.BASEBOARD_FAB2(SCH_1):PAGE200
 R1D44    1      A RES_0402-0.0,5%,1/16W,CHIP,G21A    I44 @BASEBOARD_FAB2_LIB.BASEBOARD_FAB2(SCH_1):PAGE200

A_HSC_OCP_SEL @BASEBOARD_FAB2_LIB.BASEBOARD_FAB2(SCH_1):A_HSC_OCP_SEL
 R1D15    2      B RES_0402-100.0K,1%,1/16W,CHIP,A    I92 @BASEBOARD_FAB2_LIB.BASEBOARD_FAB2(SCH_1):PAGE199
  J1B4    2      2 CLX-CONN3A-1-GP_CONN-G3-CLX-COA   I131 @BASEBOARD_FAB2_LIB.BASEBOARD_FAB2(SCH_1):PAGE199

A_HSC_OV @BASEBOARD_FAB2_LIB.BASEBOARD_FAB2(SCH_1):A_HSC_OV
 C1D27    1      A CAP_A_0402V-0.1UF,16V,10%,X7R,A     I7 @BASEBOARD_FAB2_LIB.BASEBOARD_FAB2(SCH_1):PAGE199
 R1D43    1      A RES_0402-7.5K,1%,1/16W,CHIP,G2A     I9 @BASEBOARD_FAB2_LIB.BASEBOARD_FAB2(SCH_1):PAGE199
 EU1D2   32     OV ADM1278_SM-IC,G99251-001    I10 @BASEBOARD_FAB2_LIB.BASEBOARD_FAB2(SCH_1):PAGE199
 R9P28    2      B RES_0402-100.0K,1%,1/16W,CHIP,A   I138 @BASEBOARD_FAB2_LIB.BASEBOARD_FAB2(SCH_1):PAGE199

A_HSC_PSET @BASEBOARD_FAB2_LIB.BASEBOARD_FAB2(SCH_1):A_HSC_PSET
 EU1D2    1   PSET ADM1278_SM-IC,G99251-001    I10 @BASEBOARD_FAB2_LIB.BASEBOARD_FAB2(SCH_1):PAGE199
 R1D39    2      B RES_0402-100.0K,1%,1/16W,CHIP,A    I16 @BASEBOARD_FAB2_LIB.BASEBOARD_FAB2(SCH_1):PAGE199
 R1D40    1      A RES_0402-40.2K,1%,1/16W,CHIP,GA   I100 @BASEBOARD_FAB2_LIB.BASEBOARD_FAB2(SCH_1):PAGE199
 C1D21    1      A CAP_A_0402V-0.1UF,16V,10%,X7R,A   I121 @BASEBOARD_FAB2_LIB.BASEBOARD_FAB2(SCH_1):PAGE199

A_HSC_PWGIN @BASEBOARD_FAB2_LIB.BASEBOARD_FAB2(SCH_1):A_HSC_PWGIN
 EU1D2   21  PWGIN ADM1278_SM-IC,G99251-001    I10 @BASEBOARD_FAB2_LIB.BASEBOARD_FAB2(SCH_1):PAGE199
 R9P23    2      B RES_0402-100.0K,1%,1/16W,CHIP,A    I54 @BASEBOARD_FAB2_LIB.BASEBOARD_FAB2(SCH_1):PAGE199
 R9P24    1      A RES_0402-12.1K,1%,1/16W,CHIP,GA    I55 @BASEBOARD_FAB2_LIB.BASEBOARD_FAB2(SCH_1):PAGE199

A_HSC_TEMP @BASEBOARD_FAB2_LIB.BASEBOARD_FAB2(SCH_1):A_HSC_TEMP
 EU1D2   25   TEMP ADM1278_SM-IC,G99251-001    I10 @BASEBOARD_FAB2_LIB.BASEBOARD_FAB2(SCH_1):PAGE199
 C1W16    1      A CAP_0402LF-1000PF,50V,10%,X7R,A   I132 @BASEBOARD_FAB2_LIB.BASEBOARD_FAB2(SCH_1):PAGE199
 R1W20    1      A RES_0402-0.0,5%,1/16W,CHIP,G21A   I134 @BASEBOARD_FAB2_LIB.BASEBOARD_FAB2(SCH_1):PAGE199

A_HSC_TIMER @BASEBOARD_FAB2_LIB.BASEBOARD_FAB2(SCH_1):A_HSC_TIMER
 EU1D2    5  TIMER ADM1278_SM-IC,G99251-001    I10 @BASEBOARD_FAB2_LIB.BASEBOARD_FAB2(SCH_1):PAGE199
 C9P14    1      A CAP_0603LF-0.033UF,50V,10%,X7RA    I24 @BASEBOARD_FAB2_LIB.BASEBOARD_FAB2(SCH_1):PAGE199
 R9P21    1      A RES_0402-0.0,5%,1/16W,CHIP,G21A    I71 @BASEBOARD_FAB2_LIB.BASEBOARD_FAB2(SCH_1):PAGE200

A_HSC_TIMER_R @BASEBOARD_FAB2_LIB.BASEBOARD_FAB2(SCH_1):A_HSC_TIMER_R
 R9P19    1      A RES_0402-10.0K,1%,1/16W,EMPTY,A    I70 @BASEBOARD_FAB2_LIB.BASEBOARD_FAB2(SCH_1):PAGE200
 R9P21    2      B RES_0402-0.0,5%,1/16W,CHIP,G21A    I71 @BASEBOARD_FAB2_LIB.BASEBOARD_FAB2(SCH_1):PAGE200
  U9P2    3   INBN TPS3700_SM-IC,H69492-001   I200 @BASEBOARD_FAB2_LIB.BASEBOARD_FAB2(SCH_1):PAGE200

A_HSC_UV @BASEBOARD_FAB2_LIB.BASEBOARD_FAB2(SCH_1):A_HSC_UV
 EU1D2   31     UV ADM1278_SM-IC,G99251-001    I10 @BASEBOARD_FAB2_LIB.BASEBOARD_FAB2(SCH_1):PAGE199
 R9P29    2      B RES_0402-100.0K,1%,1/16W,CHIP,A    I12 @BASEBOARD_FAB2_LIB.BASEBOARD_FAB2(SCH_1):PAGE199
 R1D42    1      A RES_0402-11K,1%,1/16W,CHIP,G21A    I13 @BASEBOARD_FAB2_LIB.BASEBOARD_FAB2(SCH_1):PAGE199
 C1D26    1      A CAP_A_0402V-0.1UF,16V,10%,X7R,A   I107 @BASEBOARD_FAB2_LIB.BASEBOARD_FAB2(SCH_1):PAGE199

A_HSC_VCAP @BASEBOARD_FAB2_LIB.BASEBOARD_FAB2(SCH_1):A_HSC_VCAP
 EU1D2    2   VCAP ADM1278_SM-IC,G99251-001    I10 @BASEBOARD_FAB2_LIB.BASEBOARD_FAB2(SCH_1):PAGE199
 R1D37    1      A RES_0402-100.0K,1%,1/16W,CHIP,A    I15 @BASEBOARD_FAB2_LIB.BASEBOARD_FAB2(SCH_1):PAGE199
 R1D39    1      A RES_0402-100.0K,1%,1/16W,CHIP,A    I16 @BASEBOARD_FAB2_LIB.BASEBOARD_FAB2(SCH_1):PAGE199
 R1D32    1      A RES_0402-100.0K,1%,1/16W,CHIP,A    I17 @BASEBOARD_FAB2_LIB.BASEBOARD_FAB2(SCH_1):PAGE199
 R1D27    1      A RES_0402-4.75K,1%,1/16W,EMPTY,A    I38 @BASEBOARD_FAB2_LIB.BASEBOARD_FAB2(SCH_1):PAGE199
 C1D19    1      A CAP_0402-1.0UF,16V,10%,X6S,D97A   I119 @BASEBOARD_FAB2_LIB.BASEBOARD_FAB2(SCH_1):PAGE199
 R1D29    1      A RES_0402-4.75K,1%,1/16W,CHIP,GA   I137 @BASEBOARD_FAB2_LIB.BASEBOARD_FAB2(SCH_1):PAGE199

A_HSC_VOUT @BASEBOARD_FAB2_LIB.BASEBOARD_FAB2(SCH_1):A_HSC_VOUT
 EU1D2   20   VOUT ADM1278_SM-IC,G99251-001    I10 @BASEBOARD_FAB2_LIB.BASEBOARD_FAB2(SCH_1):PAGE199
 R1D36    2      B RES_0402-1.00K,1%,1/16W,CHIP,GA    I65 @BASEBOARD_FAB2_LIB.BASEBOARD_FAB2(SCH_1):PAGE199
 C9P12    1      A CAP_A_0402V-0.1UF,16V,10%,EMPTA    I67 @BASEBOARD_FAB2_LIB.BASEBOARD_FAB2(SCH_1):PAGE199

A_KR0_RBIAS @BASEBOARD_FAB2_LIB.BASEBOARD_FAB2(SCH_1):A_KR0_RBIAS
  U7C1 BB29 LAN_RBIAS_0 LBG_CORE_QAT_EXT_D_BGA1-IC,H91A    I73 @BASEBOARD_FAB2_LIB.BASEBOARD_FAB2(SCH_1):PAGE118
  R2N4    2      B RES_0402-1.0K,0.1%,1/16W,CHIP,A    I96 @BASEBOARD_FAB2_LIB.BASEBOARD_FAB2(SCH_1):PAGE118

A_KR1_RBIAS @BASEBOARD_FAB2_LIB.BASEBOARD_FAB2(SCH_1):A_KR1_RBIAS
  U7C1 BD42 LAN_RBIAS_1 LBG_CORE_QAT_EXT_D_BGA1-IC,H91A    I73 @BASEBOARD_FAB2_LIB.BASEBOARD_FAB2(SCH_1):PAGE118
  R2M6    1      A RES_0402-1.0K,0.1%,1/16W,CHIP,A    I99 @BASEBOARD_FAB2_LIB.BASEBOARD_FAB2(SCH_1):PAGE118

A_P12V_STBY_ADR_TRIGGER @BASEBOARD_FAB2_LIB.BASEBOARD_FAB2(SCH_1):A_P12V_STBY_ADR_TRIGGER
  U9P1    4   INAP TPS3700_SM-IC,H69492-001   I163 @BASEBOARD_FAB2_LIB.BASEBOARD_FAB2(SCH_1):PAGE200
  C9W2    1      1 SC22P50V2JN-4GP_SMD-BCG-SC22P5A   I236 @BASEBOARD_FAB2_LIB.BASEBOARD_FAB2(SCH_1):PAGE200
  R9P9    1      A RES_0402-3.74K,1%,1/16W,CHIP,GA   I251 @BASEBOARD_FAB2_LIB.BASEBOARD_FAB2(SCH_1):PAGE200
  R9P7    2      B RES_0402-100.0K,1%,1/16W,CHIP,A   I252 @BASEBOARD_FAB2_LIB.BASEBOARD_FAB2(SCH_1):PAGE200

A_P12V_STBY_FPH_GATE @BASEBOARD_FAB2_LIB.BASEBOARD_FAB2(SCH_1):A_P12V_STBY_FPH_GATE
  U9P1    1   OUTB TPS3700_SM-IC,H69492-001   I163 @BASEBOARD_FAB2_LIB.BASEBOARD_FAB2(SCH_1):PAGE200
 R9P10    2      B RES_0402-10.0K,1%,1/16W,CHIP,GA   I192 @BASEBOARD_FAB2_LIB.BASEBOARD_FAB2(SCH_1):PAGE200
  Q9P1    5 GATE<0> FET_N_DUAL_SMLF-2N7002DW,FET,DA   I199 @BASEBOARD_FAB2_LIB.BASEBOARD_FAB2(SCH_1):PAGE200

A_P12V_STBY_FP_TRIGGER @BASEBOARD_FAB2_LIB.BASEBOARD_FAB2(SCH_1):A_P12V_STBY_FP_TRIGGER
 R9P11    1      A RES_0402-10.0K,1%,1/16W,CHIP,GA   I108 @BASEBOARD_FAB2_LIB.BASEBOARD_FAB2(SCH_1):PAGE200
  U9P1    3   INBN TPS3700_SM-IC,H69492-001   I163 @BASEBOARD_FAB2_LIB.BASEBOARD_FAB2(SCH_1):PAGE200
  C9W1    1      1 SC22P50V2JN-4GP_SMD-BCG-SC22P5A   I235 @BASEBOARD_FAB2_LIB.BASEBOARD_FAB2(SCH_1):PAGE200
 R9P13    2      2 270KR2F-GP_RCL_GP-270KR2F-GP,6A   I249 @BASEBOARD_FAB2_LIB.BASEBOARD_FAB2(SCH_1):PAGE200
  R6W3    2      2 232KR2F-2-GP_SMD-RG1-232KR2F-2A   I250 @BASEBOARD_FAB2_LIB.BASEBOARD_FAB2(SCH_1):PAGE200

A_P12V_STBY_SCALED @BASEBOARD_FAB2_LIB.BASEBOARD_FAB2(SCH_1):A_P12V_STBY_SCALED
 C9G17    1      A CAP_0402LF-47.0PF,50V,5%,COG,AA    I80 @BASEBOARD_FAB2_LIB.BASEBOARD_FAB2(SCH_1):PAGE169
 R1U32    2      B RES_0402-5.11K,1%,1/16W,CHIP,GA    I82 @BASEBOARD_FAB2_LIB.BASEBOARD_FAB2(SCH_1):PAGE169
 U25W4   E2 ADC2_GPIW2 AST2520A1-GP-GP_ASIC2-GB1-AST2A   I106 @BASEBOARD_FAB2_LIB.BASEBOARD_FAB2(SCH_1):PAGE147
 R1U33    1      1 649R2F-GP_RCL_GP-649R2F-GP,64.A   I171 @BASEBOARD_FAB2_LIB.BASEBOARD_FAB2(SCH_1):PAGE169

A_P1V05_STBY_PCH_SENSOR @BASEBOARD_FAB2_LIB.BASEBOARD_FAB2(SCH_1):A_P1V05_STBY_PCH_SENSOR
 C1U21    1      A CAP_0402LF-47.0PF,50V,5%,COG,AA    I56 @BASEBOARD_FAB2_LIB.BASEBOARD_FAB2(SCH_1):PAGE169
 FB1U3    1      A FERRITE_SMLF-30,FB,693286-021    I57 @BASEBOARD_FAB2_LIB.BASEBOARD_FAB2(SCH_1):PAGE169
 U25W4   E1 ADC3_GPIW3 AST2520A1-GP-GP_ASIC2-GB1-AST2A   I106 @BASEBOARD_FAB2_LIB.BASEBOARD_FAB2(SCH_1):PAGE147

A_P3V3_SCALED @BASEBOARD_FAB2_LIB.BASEBOARD_FAB2(SCH_1):A_P3V3_SCALED
 C9G14    1      A CAP_0402LF-47.0PF,50V,5%,COG,AA   I146 @BASEBOARD_FAB2_LIB.BASEBOARD_FAB2(SCH_1):PAGE169
 R1U26    2      B RES_0402-5.11K,1%,1/16W,CHIP,GA   I148 @BASEBOARD_FAB2_LIB.BASEBOARD_FAB2(SCH_1):PAGE169
 U25W4   F4 ADC0_GPIW0 AST2520A1-GP-GP_ASIC2-GB1-AST2A   I106 @BASEBOARD_FAB2_LIB.BASEBOARD_FAB2(SCH_1):PAGE147
 R1U27    1      A RES_0402-3.48K,1.0%,1/16W,CHIPA   I173 @BASEBOARD_FAB2_LIB.BASEBOARD_FAB2(SCH_1):PAGE169

A_P3V3_STBY_SCALED @BASEBOARD_FAB2_LIB.BASEBOARD_FAB2(SCH_1):A_P3V3_STBY_SCALED
 C9G20    1      A CAP_0402LF-47.0PF,50V,5%,COG,AA    I86 @BASEBOARD_FAB2_LIB.BASEBOARD_FAB2(SCH_1):PAGE169
 R1U39    2      B RES_0402-5.11K,1%,1/16W,CHIP,GA    I88 @BASEBOARD_FAB2_LIB.BASEBOARD_FAB2(SCH_1):PAGE169
 U25W4   E3 ADC5_GPIW5 AST2520A1-GP-GP_ASIC2-GB1-AST2A   I106 @BASEBOARD_FAB2_LIB.BASEBOARD_FAB2(SCH_1):PAGE147
 R1U38    1      A RES_0402-3.48K,1.0%,1/16W,CHIPA   I172 @BASEBOARD_FAB2_LIB.BASEBOARD_FAB2(SCH_1):PAGE169

A_P3V_BAT_R @BASEBOARD_FAB2_LIB.BASEBOARD_FAB2(SCH_1):A_P3V_BAT_R
 R1U50    1      A RES_0402-200.0K,1%,1/16W,CHIP,A   I126 @BASEBOARD_FAB2_LIB.BASEBOARD_FAB2(SCH_1):PAGE169
 R2U43    2      B RES_0402-1.00K,1%,1/16W,CHIP,GA    I46 @BASEBOARD_FAB2_LIB.BASEBOARD_FAB2(SCH_1):PAGE196
 CR2U1    2     A2 DIODE2A_DUAL_SMLF-BAS70-05,DIOA    I53 @BASEBOARD_FAB2_LIB.BASEBOARD_FAB2(SCH_1):PAGE196

A_P3V_BAT_SCALED @BASEBOARD_FAB2_LIB.BASEBOARD_FAB2(SCH_1):A_P3V_BAT_SCALED
 R9G26    1      A RES_0402-100.0K,1%,1/16W,CHIP,A   I106 @BASEBOARD_FAB2_LIB.BASEBOARD_FAB2(SCH_1):PAGE169
 C9G22    1      A CAP_0402LF-10.0PF,50V,5%,COG,AA   I108 @BASEBOARD_FAB2_LIB.BASEBOARD_FAB2(SCH_1):PAGE169
  Q9G1    4 SOURCE<0> FET_N_DUAL_SMLF-NTJD4001N,FET,A   I157 @BASEBOARD_FAB2_LIB.BASEBOARD_FAB2(SCH_1):PAGE169
 U25W4   G4 ADC7_GPIW7 AST2520A1-GP-GP_ASIC2-GB1-AST2A   I106 @BASEBOARD_FAB2_LIB.BASEBOARD_FAB2(SCH_1):PAGE147

A_P5V_SCALED @BASEBOARD_FAB2_LIB.BASEBOARD_FAB2(SCH_1):A_P5V_SCALED
 C9G15    1      A CAP_0402LF-47.0PF,50V,5%,COG,AA   I139 @BASEBOARD_FAB2_LIB.BASEBOARD_FAB2(SCH_1):PAGE169
 R1U29    2      B RES_0402-5.11K,1%,1/16W,CHIP,GA   I141 @BASEBOARD_FAB2_LIB.BASEBOARD_FAB2(SCH_1):PAGE169
 U25W4   F5 ADC1_GPIW1 AST2520A1-GP-GP_ASIC2-GB1-AST2A   I106 @BASEBOARD_FAB2_LIB.BASEBOARD_FAB2(SCH_1):PAGE147
 R1U28    1      1 1K82R2F-1-GP_SMD-RG-1K82R2F-1-A   I169 @BASEBOARD_FAB2_LIB.BASEBOARD_FAB2(SCH_1):PAGE169

A_P5V_STBY_SCALED @BASEBOARD_FAB2_LIB.BASEBOARD_FAB2(SCH_1):A_P5V_STBY_SCALED
 C9G21    1      A CAP_0402LF-47.0PF,50V,5%,COG,AA    I68 @BASEBOARD_FAB2_LIB.BASEBOARD_FAB2(SCH_1):PAGE169
 R1U47    2      B RES_0402-5.11K,1%,1/16W,CHIP,GA   I115 @BASEBOARD_FAB2_LIB.BASEBOARD_FAB2(SCH_1):PAGE169
 U25W4   G5 ADC6_GPIW6 AST2520A1-GP-GP_ASIC2-GB1-AST2A   I106 @BASEBOARD_FAB2_LIB.BASEBOARD_FAB2(SCH_1):PAGE147
 R1U44    1      1 1K82R2F-1-GP_SMD-RG-1K82R2F-1-A   I170 @BASEBOARD_FAB2_LIB.BASEBOARD_FAB2(SCH_1):PAGE169

A_PCH_XCLK_BIASREF @BASEBOARD_FAB2_LIB.BASEBOARD_FAB2(SCH_1):A_PCH_XCLK_BIASREF
  U7C1  G44 XCLK_BIASREF LBG_CORE_QAT_EXT_D_BGA1-IC,H91A    I40 @BASEBOARD_FAB2_LIB.BASEBOARD_FAB2(SCH_1):PAGE114
  R3N1    1      A RES_0402-169,1.0%,1/16W,CHIP,GA   I149 @BASEBOARD_FAB2_LIB.BASEBOARD_FAB2(SCH_1):PAGE114
  C3W1    1      A CAP_0402-1.0UF,6.3V,10%,EMPTY,A   I193 @BASEBOARD_FAB2_LIB.BASEBOARD_FAB2(SCH_1):PAGE114

A_PCIEUP_RCOMP_N @BASEBOARD_FAB2_LIB.BASEBOARD_FAB2(SCH_1):A_PCIEUP_RCOMP_N
 R3M12    2      B RES_0402-100.0,1%,1/16W,CHIP,GA   I181 @BASEBOARD_FAB2_LIB.BASEBOARD_FAB2(SCH_1):PAGE116
  U7C1 AF58 PCIEUP_RCOMPN LBG_CORE_QAT_EXT_D_BGA1-IC,H91A   I220 @BASEBOARD_FAB2_LIB.BASEBOARD_FAB2(SCH_1):PAGE116

A_PCIEUP_RCOMP_P @BASEBOARD_FAB2_LIB.BASEBOARD_FAB2(SCH_1):A_PCIEUP_RCOMP_P
 R3M12    1      A RES_0402-100.0,1%,1/16W,CHIP,GA   I181 @BASEBOARD_FAB2_LIB.BASEBOARD_FAB2(SCH_1):PAGE116
  U7C1 AH58 PCIEUP_RCOMPP LBG_CORE_QAT_EXT_D_BGA1-IC,H91A   I220 @BASEBOARD_FAB2_LIB.BASEBOARD_FAB2(SCH_1):PAGE116

A_PCIE_RCOMP_N @BASEBOARD_FAB2_LIB.BASEBOARD_FAB2(SCH_1):A_PCIE_RCOMP_N
 R3M11    2      B RES_0402-100.0,1%,1/16W,CHIP,GA   I108 @BASEBOARD_FAB2_LIB.BASEBOARD_FAB2(SCH_1):PAGE116
  U7C1 BD58 PCIE_RCOMPN LBG_CORE_QAT_EXT_D_BGA1-IC,H91A   I220 @BASEBOARD_FAB2_LIB.BASEBOARD_FAB2(SCH_1):PAGE116

A_PCIE_RCOMP_P @BASEBOARD_FAB2_LIB.BASEBOARD_FAB2(SCH_1):A_PCIE_RCOMP_P
 R3M11    1      A RES_0402-100.0,1%,1/16W,CHIP,GA   I108 @BASEBOARD_FAB2_LIB.BASEBOARD_FAB2(SCH_1):PAGE116
  U7C1 BB56 PCIE_RCOMPP LBG_CORE_QAT_EXT_D_BGA1-IC,H91A   I220 @BASEBOARD_FAB2_LIB.BASEBOARD_FAB2(SCH_1):PAGE116

A_PG_P12V_MAIN @BASEBOARD_FAB2_LIB.BASEBOARD_FAB2(SCH_1):A_PG_P12V_MAIN
  U8D8    4   INAP TPS3700_SM-IC,H69492-001   I104 @BASEBOARD_FAB2_LIB.BASEBOARD_FAB2(SCH_1):PAGE196
 R8D38    2      B RES_0402-100.0K,1%,1/16W,CHIP,A   I112 @BASEBOARD_FAB2_LIB.BASEBOARD_FAB2(SCH_1):PAGE196
 R8D40    1      A RES_0402-20.0K,1%,1/16W,CHIP,GA   I130 @BASEBOARD_FAB2_LIB.BASEBOARD_FAB2(SCH_1):PAGE196

A_PG_P5V @BASEBOARD_FAB2_LIB.BASEBOARD_FAB2(SCH_1):A_PG_P5V
  U8D8    3   INBN TPS3700_SM-IC,H69492-001   I104 @BASEBOARD_FAB2_LIB.BASEBOARD_FAB2(SCH_1):PAGE196
 R8D39    2      B RES_0402-49.9K,1%,1/16W,CHIP,GA   I114 @BASEBOARD_FAB2_LIB.BASEBOARD_FAB2(SCH_1):PAGE196
 R8D37    1      A RES_0402-4.75K,1%,1/16W,CHIP,GA   I115 @BASEBOARD_FAB2_LIB.BASEBOARD_FAB2(SCH_1):PAGE196

A_PVCCRTC_EXT_CAP @BASEBOARD_FAB2_LIB.BASEBOARD_FAB2(SCH_1):A_PVCCRTC_EXT_CAP
  U7C1 AG22 VCCRTCEXT LBG_CORE_QAT_EXT_D_BGA1-IC,H91A    I63 @BASEBOARD_FAB2_LIB.BASEBOARD_FAB2(SCH_1):PAGE122
 C3N29    1      A CAP_A_0402V-0.1UF,16V,10%,X7R,A    I16 @BASEBOARD_FAB2_LIB.BASEBOARD_FAB2(SCH_1):PAGE130

A_PVNN_STBY_PCH_SENSOR @BASEBOARD_FAB2_LIB.BASEBOARD_FAB2(SCH_1):A_PVNN_STBY_PCH_SENSOR
 C9G18    1      A CAP_0402LF-47.0PF,50V,5%,COG,AA   I153 @BASEBOARD_FAB2_LIB.BASEBOARD_FAB2(SCH_1):PAGE169
 FB1U4    1      A FERRITE_SMLF-30,FB,693286-021   I155 @BASEBOARD_FAB2_LIB.BASEBOARD_FAB2(SCH_1):PAGE169
 U25W4   F3 ADC4_GPIW4 AST2520A1-GP-GP_ASIC2-GB1-AST2A   I106 @BASEBOARD_FAB2_LIB.BASEBOARD_FAB2(SCH_1):PAGE147

A_RCOMP_3P3 @BASEBOARD_FAB2_LIB.BASEBOARD_FAB2(SCH_1):A_RCOMP_3P3
  U7C1 BY25 GPIO_RCOMP_3P3 LBG_CORE_QAT_EXT_D_BGA1-IC,H91A   I147 @BASEBOARD_FAB2_LIB.BASEBOARD_FAB2(SCH_1):PAGE120
 R8C21    1      A RES_0402-100.0,1%,1/16W,CHIP,GA   I275 @BASEBOARD_FAB2_LIB.BASEBOARD_FAB2(SCH_1):PAGE120

A_TSENSE_P1V05_PCH_STBY_TMON @BASEBOARD_FAB2_LIB.BASEBOARD_FAB2(SCH_1):A_TSENSE_P1V05_PCH_STBY_TMON
 EU8A1   34  BTSEN PXE1110B_QFN-IC,H89187-001   I229 @BASEBOARD_FAB2_LIB.BASEBOARD_FAB2(SCH_1):PAGE235
 EU7A2   36 TOUT_FLT IR354XX_SM-IR35412,IC,H73684-0A   I117 @BASEBOARD_FAB2_LIB.BASEBOARD_FAB2(SCH_1):PAGE236
  CT69    1      A CAP_0402LF-1000PF,50V,10%,X7R,A   I134 @BASEBOARD_FAB2_LIB.BASEBOARD_FAB2(SCH_1):PAGE236
  C4W4    1      A CAP_0402LF-220PF,50V,10%,X7R,AA   I246 @BASEBOARD_FAB2_LIB.BASEBOARD_FAB2(SCH_1):PAGE235

A_TSENSE_PVCCIN_CPU0 @BASEBOARD_FAB2_LIB.BASEBOARD_FAB2(SCH_1):A_TSENSE_PVCCIN_CPU0
 C4D17    1      A CAP_0402LF-220PF,50V,10%,X7R,AA    I66 @BASEBOARD_FAB2_LIB.BASEBOARD_FAB2(SCH_1):PAGE201
 EU4D4   43  ATSEN PXE1610B_QFN-IC,H79206-001   I155 @BASEBOARD_FAB2_LIB.BASEBOARD_FAB2(SCH_1):PAGE201
 EU4E1   36 TOUT_FLT IR354XX_SM-IR35411,IC,H73688-0A    I63 @BASEBOARD_FAB2_LIB.BASEBOARD_FAB2(SCH_1):PAGE202
 EU4D6   36 TOUT_FLT IR354XX_SM-IR35411,IC,H73688-0A    I64 @BASEBOARD_FAB2_LIB.BASEBOARD_FAB2(SCH_1):PAGE202
 EU4D3   36 TOUT_FLT IR354XX_SM-IR35411,IC,H73688-0A    I70 @BASEBOARD_FAB2_LIB.BASEBOARD_FAB2(SCH_1):PAGE203
 EU4D1   36 TOUT_FLT IR354XX_SM-IR35411,IC,H73688-0A    I71 @BASEBOARD_FAB2_LIB.BASEBOARD_FAB2(SCH_1):PAGE203
 EU4C2   36 TOUT_FLT IR354XX_SM-IR35411,IC,H73688-0A    I71 @BASEBOARD_FAB2_LIB.BASEBOARD_FAB2(SCH_1):PAGE204
   CT2    1      A CAP_0402LF-1000PF,50V,10%,X7R,A    I78 @BASEBOARD_FAB2_LIB.BASEBOARD_FAB2(SCH_1):PAGE202
  CT34    1      A CAP_0402LF-1000PF,50V,10%,X7R,A    I88 @BASEBOARD_FAB2_LIB.BASEBOARD_FAB2(SCH_1):PAGE204
  CT37    1      A CAP_0402LF-1000PF,50V,10%,X7R,A    I99 @BASEBOARD_FAB2_LIB.BASEBOARD_FAB2(SCH_1):PAGE203
  CT42    1      A CAP_0402LF-1000PF,50V,10%,X7R,A   I108 @BASEBOARD_FAB2_LIB.BASEBOARD_FAB2(SCH_1):PAGE203
   CT4    1      A CAP_0402LF-1000PF,50V,10%,X7R,A    I87 @BASEBOARD_FAB2_LIB.BASEBOARD_FAB2(SCH_1):PAGE202

A_TSENSE_PVCCIN_CPU1 @BASEBOARD_FAB2_LIB.BASEBOARD_FAB2(SCH_1):A_TSENSE_PVCCIN_CPU1
 C1C10    1      A CAP_0402LF-220PF,50V,10%,X7R,AA    I69 @BASEBOARD_FAB2_LIB.BASEBOARD_FAB2(SCH_1):PAGE206
 EU1C2   43  ATSEN PXE1610B_QFN-IC,H79206-001   I130 @BASEBOARD_FAB2_LIB.BASEBOARD_FAB2(SCH_1):PAGE206
 EU1E2   36 TOUT_FLT IR354XX_SM-IR35411,IC,H73688-0A    I20 @BASEBOARD_FAB2_LIB.BASEBOARD_FAB2(SCH_1):PAGE207
 EU1D3   36 TOUT_FLT IR354XX_SM-IR35411,IC,H73688-0A    I27 @BASEBOARD_FAB2_LIB.BASEBOARD_FAB2(SCH_1):PAGE208
 EU1D1   36 TOUT_FLT IR354XX_SM-IR35411,IC,H73688-0A    I71 @BASEBOARD_FAB2_LIB.BASEBOARD_FAB2(SCH_1):PAGE208
 EU1C3   36 TOUT_FLT IR354XX_SM-IR35411,IC,H73688-0A    I56 @BASEBOARD_FAB2_LIB.BASEBOARD_FAB2(SCH_1):PAGE209
  CT15    1      A CAP_0402LF-1000PF,50V,10%,X7R,A    I67 @BASEBOARD_FAB2_LIB.BASEBOARD_FAB2(SCH_1):PAGE209
  CTI7    1      A CAP_0402LF-1000PF,50V,10%,X7R,A    I82 @BASEBOARD_FAB2_LIB.BASEBOARD_FAB2(SCH_1):PAGE208
  CT19    1      A CAP_0402LF-1000PF,50V,10%,X7R,A    I90 @BASEBOARD_FAB2_LIB.BASEBOARD_FAB2(SCH_1):PAGE208
  CT22    1      A CAP_0402LF-1000PF,50V,10%,X7R,A    I74 @BASEBOARD_FAB2_LIB.BASEBOARD_FAB2(SCH_1):PAGE207
  CT26    1      A CAP_0402LF-1000PF,50V,10%,X7R,A    I82 @BASEBOARD_FAB2_LIB.BASEBOARD_FAB2(SCH_1):PAGE207
 EU1D4   36 TOUT_FLT IR354XX_SM-IR35411,IC,H73688-0A   I113 @BASEBOARD_FAB2_LIB.BASEBOARD_FAB2(SCH_1):PAGE207

A_TSENSE_PVCCIO_CPU0 @BASEBOARD_FAB2_LIB.BASEBOARD_FAB2(SCH_1):A_TSENSE_PVCCIO_CPU0
 EU3P1   35  ATSEN PXE1110B_QFN-IC,H89187-001    I93 @BASEBOARD_FAB2_LIB.BASEBOARD_FAB2(SCH_1):PAGE211
 EU7C1   36 TOUT_FLT IR354XX_SM-IR35412,IC,H73684-0A   I101 @BASEBOARD_FAB2_LIB.BASEBOARD_FAB2(SCH_1):PAGE212
  CT71    1      A CAP_0402LF-1000PF,50V,10%,X7R,A   I109 @BASEBOARD_FAB2_LIB.BASEBOARD_FAB2(SCH_1):PAGE212
  C4W1    1      A CAP_0402LF-220PF,50V,10%,X7R,AA    I97 @BASEBOARD_FAB2_LIB.BASEBOARD_FAB2(SCH_1):PAGE211

A_TSENSE_PVCCIO_CPU1 @BASEBOARD_FAB2_LIB.BASEBOARD_FAB2(SCH_1):A_TSENSE_PVCCIO_CPU1
 EU4D5   35  ATSEN PXE1110B_QFN-IC,H89187-001    I96 @BASEBOARD_FAB2_LIB.BASEBOARD_FAB2(SCH_1):PAGE213
 EU4E2   36 TOUT_FLT IR354XX_SM-IR35412,IC,H73684-0A   I126 @BASEBOARD_FAB2_LIB.BASEBOARD_FAB2(SCH_1):PAGE214
  CT61    1      A CAP_0402LF-1000PF,50V,10%,X7R,A   I134 @BASEBOARD_FAB2_LIB.BASEBOARD_FAB2(SCH_1):PAGE214
  C4W2    1      A CAP_0402LF-220PF,50V,10%,X7R,AA   I101 @BASEBOARD_FAB2_LIB.BASEBOARD_FAB2(SCH_1):PAGE213

A_TSENSE_PVDDQ_ABC @BASEBOARD_FAB2_LIB.BASEBOARD_FAB2(SCH_1):A_TSENSE_PVDDQ_ABC
 EU7G2   36 TOUT_FLT IR354XX_SM-IR35411,IC,H73688-0A   I102 @BASEBOARD_FAB2_LIB.BASEBOARD_FAB2(SCH_1):PAGE216
 EU7G3   36 TOUT_FLT IR354XX_SM-IR35411,IC,H73688-0A   I103 @BASEBOARD_FAB2_LIB.BASEBOARD_FAB2(SCH_1):PAGE216
  CT49    1      A CAP_0402LF-1000PF,50V,10%,X7R,A   I118 @BASEBOARD_FAB2_LIB.BASEBOARD_FAB2(SCH_1):PAGE216
  CT54    1      A CAP_0402LF-1000PF,50V,10%,X7R,A   I121 @BASEBOARD_FAB2_LIB.BASEBOARD_FAB2(SCH_1):PAGE216
  C7G3    1      A CAP_0402LF-220PF,50V,10%,X7R,AA    I22 @BASEBOARD_FAB2_LIB.BASEBOARD_FAB2(SCH_1):PAGE215
 EU7G1   35  ATSEN PXM1310B_QFN-IC,H89186-001    I69 @BASEBOARD_FAB2_LIB.BASEBOARD_FAB2(SCH_1):PAGE215

A_TSENSE_PVDDQ_DEF @BASEBOARD_FAB2_LIB.BASEBOARD_FAB2(SCH_1):A_TSENSE_PVDDQ_DEF
 EU7A1   36 TOUT_FLT IR354XX_SM-IR35411,IC,H73688-0A   I106 @BASEBOARD_FAB2_LIB.BASEBOARD_FAB2(SCH_1):PAGE219
 EU7A4   36 TOUT_FLT IR354XX_SM-IR35411,IC,H73688-0A   I107 @BASEBOARD_FAB2_LIB.BASEBOARD_FAB2(SCH_1):PAGE219
  CT48    1      A CAP_0402LF-1000PF,50V,10%,X7R,A   I119 @BASEBOARD_FAB2_LIB.BASEBOARD_FAB2(SCH_1):PAGE219
  CT43    1      A CAP_0402LF-1000PF,50V,10%,X7R,A   I124 @BASEBOARD_FAB2_LIB.BASEBOARD_FAB2(SCH_1):PAGE219
 EU7A5   35  ATSEN PXM1310B_QFN-IC,H89186-001    I69 @BASEBOARD_FAB2_LIB.BASEBOARD_FAB2(SCH_1):PAGE218
 C7A29    1      A CAP_0402LF-220PF,50V,10%,X7R,AA    I16 @BASEBOARD_FAB2_LIB.BASEBOARD_FAB2(SCH_1):PAGE218

A_TSENSE_PVDDQ_GHJ @BASEBOARD_FAB2_LIB.BASEBOARD_FAB2(SCH_1):A_TSENSE_PVDDQ_GHJ
 EU1G1   36 TOUT_FLT IR354XX_SM-IR35411,IC,H73688-0A   I110 @BASEBOARD_FAB2_LIB.BASEBOARD_FAB2(SCH_1):PAGE224
 EU1F1   36 TOUT_FLT IR354XX_SM-IR35411,IC,H73688-0A   I111 @BASEBOARD_FAB2_LIB.BASEBOARD_FAB2(SCH_1):PAGE224
  CT28    1      A CAP_0402LF-1000PF,50V,10%,X7R,A   I122 @BASEBOARD_FAB2_LIB.BASEBOARD_FAB2(SCH_1):PAGE224
  CT32    1      A CAP_0402LF-1000PF,50V,10%,X7R,A   I130 @BASEBOARD_FAB2_LIB.BASEBOARD_FAB2(SCH_1):PAGE224
 EU1G2   35  ATSEN PXM1310B_QFN-IC,H89186-001    I69 @BASEBOARD_FAB2_LIB.BASEBOARD_FAB2(SCH_1):PAGE223
 C1G24    1      A CAP_0402LF-220PF,50V,10%,X7R,AA    I27 @BASEBOARD_FAB2_LIB.BASEBOARD_FAB2(SCH_1):PAGE223

A_TSENSE_PVDDQ_KLM @BASEBOARD_FAB2_LIB.BASEBOARD_FAB2(SCH_1):A_TSENSE_PVDDQ_KLM
 EU1A2   36 TOUT_FLT IR354XX_SM-IR35411,IC,H73688-0A   I101 @BASEBOARD_FAB2_LIB.BASEBOARD_FAB2(SCH_1):PAGE227
 EU1A1   36 TOUT_FLT IR354XX_SM-IR35411,IC,H73688-0A   I102 @BASEBOARD_FAB2_LIB.BASEBOARD_FAB2(SCH_1):PAGE227
   CT8    1      A CAP_0402LF-1000PF,50V,10%,X7R,A   I114 @BASEBOARD_FAB2_LIB.BASEBOARD_FAB2(SCH_1):PAGE227
  CT10    1      A CAP_0402LF-1000PF,50V,10%,X7R,A   I119 @BASEBOARD_FAB2_LIB.BASEBOARD_FAB2(SCH_1):PAGE227
 EU1B1   35  ATSEN PXM1310B_QFN-IC,H89186-001    I69 @BASEBOARD_FAB2_LIB.BASEBOARD_FAB2(SCH_1):PAGE226
 C1B11    1      A CAP_0402LF-220PF,50V,10%,X7R,AA    I23 @BASEBOARD_FAB2_LIB.BASEBOARD_FAB2(SCH_1):PAGE226

A_TSENSE_PVNN_PCH_TMON @BASEBOARD_FAB2_LIB.BASEBOARD_FAB2(SCH_1):A_TSENSE_PVNN_PCH_TMON
 EU8A1   35  ATSEN PXE1110B_QFN-IC,H89187-001   I229 @BASEBOARD_FAB2_LIB.BASEBOARD_FAB2(SCH_1):PAGE235
 EU7A3   36 TOUT_FLT IR354XX_SM-IR35412,IC,H73684-0A   I116 @BASEBOARD_FAB2_LIB.BASEBOARD_FAB2(SCH_1):PAGE236
  CT64    1      A CAP_0402LF-1000PF,50V,10%,X7R,A   I136 @BASEBOARD_FAB2_LIB.BASEBOARD_FAB2(SCH_1):PAGE236
  C4W3    1      A CAP_0402LF-220PF,50V,10%,X7R,AA   I244 @BASEBOARD_FAB2_LIB.BASEBOARD_FAB2(SCH_1):PAGE235

A_TSENSE_PVSA_CPU0 @BASEBOARD_FAB2_LIB.BASEBOARD_FAB2(SCH_1):A_TSENSE_PVSA_CPU0
 C4D18    1      A CAP_0402LF-220PF,50V,10%,X7R,AA    I68 @BASEBOARD_FAB2_LIB.BASEBOARD_FAB2(SCH_1):PAGE201
 EU4D4   42  BTSEN PXE1610B_QFN-IC,H79206-001   I155 @BASEBOARD_FAB2_LIB.BASEBOARD_FAB2(SCH_1):PAGE201
 EU4C1   36 TOUT_FLT IR354XX_SM-IR35412,IC,H73684-0A    I46 @BASEBOARD_FAB2_LIB.BASEBOARD_FAB2(SCH_1):PAGE205
  CT58    1      A CAP_0402LF-1000PF,50V,10%,X7R,A    I65 @BASEBOARD_FAB2_LIB.BASEBOARD_FAB2(SCH_1):PAGE205

A_TSENSE_PVSA_CPU1 @BASEBOARD_FAB2_LIB.BASEBOARD_FAB2(SCH_1):A_TSENSE_PVSA_CPU1
 C1C11    1      A CAP_0402LF-220PF,50V,10%,X7R,AA    I71 @BASEBOARD_FAB2_LIB.BASEBOARD_FAB2(SCH_1):PAGE206
 EU1C2   42  BTSEN PXE1610B_QFN-IC,H79206-001   I130 @BASEBOARD_FAB2_LIB.BASEBOARD_FAB2(SCH_1):PAGE206
 EU1C1   36 TOUT_FLT IR354XX_SM-IR35412,IC,H73684-0A    I51 @BASEBOARD_FAB2_LIB.BASEBOARD_FAB2(SCH_1):PAGE210
  CT55    1      A CAP_0402LF-1000PF,50V,10%,X7R,A    I60 @BASEBOARD_FAB2_LIB.BASEBOARD_FAB2(SCH_1):PAGE210

A_USB2AVRES @BASEBOARD_FAB2_LIB.BASEBOARD_FAB2(SCH_1):A_USB2AVRES
 R1T26    1      A RES_0402-8.2K,1%,1/16W,CHIP,G2A    I37 @BASEBOARD_FAB2_LIB.BASEBOARD_FAB2(SCH_1):PAGE146
 U25W4   B8 USB2AVRES AST2520A1-GP-GP_ASIC2-GB1-AST2A   I104 @BASEBOARD_FAB2_LIB.BASEBOARD_FAB2(SCH_1):PAGE146
 C1W21    1      A CAP_0603LF-0.033UF,50V,10%,X7RA   I160 @BASEBOARD_FAB2_LIB.BASEBOARD_FAB2(SCH_1):PAGE146

A_USB2BVRES @BASEBOARD_FAB2_LIB.BASEBOARD_FAB2(SCH_1):A_USB2BVRES
 R1T25    1      A RES_0402-8.2K,1%,1/16W,CHIP,G2A    I35 @BASEBOARD_FAB2_LIB.BASEBOARD_FAB2(SCH_1):PAGE146
 U25W4   B7 USB2BVRES AST2520A1-GP-GP_ASIC2-GB1-AST2A   I104 @BASEBOARD_FAB2_LIB.BASEBOARD_FAB2(SCH_1):PAGE146

A_USB2_COMP @BASEBOARD_FAB2_LIB.BASEBOARD_FAB2(SCH_1):A_USB2_COMP
  U7C1 BN70 USB2_COMP LBG_CORE_QAT_EXT_D_BGA1-IC,H91A    I74 @BASEBOARD_FAB2_LIB.BASEBOARD_FAB2(SCH_1):PAGE115
  R8B9    1      A RES_0402-113,1%,1/16W,CHIP,G21A    I90 @BASEBOARD_FAB2_LIB.BASEBOARD_FAB2(SCH_1):PAGE115

A_USB2_VBUS @BASEBOARD_FAB2_LIB.BASEBOARD_FAB2(SCH_1):A_USB2_VBUS
  U7C1 BR67 USB2_VBUS LBG_CORE_QAT_EXT_D_BGA1-IC,H91A    I74 @BASEBOARD_FAB2_LIB.BASEBOARD_FAB2(SCH_1):PAGE115
 R8B32    1      A RES_0402-10.0K,1%,1/16W,CHIP,GA   I114 @BASEBOARD_FAB2_LIB.BASEBOARD_FAB2(SCH_1):PAGE115

BMC_DEBUG_EN_N @BASEBOARD_FAB2_LIB.BASEBOARD_FAB2(SCH_1):BMC_DEBUG_EN_N
 U25W4  L19 GPIOB1 AST2520A1-GP-GP_ASIC2-GB1-AST2A    I95 @BASEBOARD_FAB2_LIB.BASEBOARD_FAB2(SCH_1):PAGE144
R25W180    2      B RES_0402-1.00K,1%,1/16W,CHIP,GA     I2 @BASEBOARD_FAB2_LIB.BASEBOARD_FAB2(SCH_1):PAGE268
U25W15    2      A TTL1G07_A_SOP-74LVC1G07,IC,C88B    I12 @BASEBOARD_FAB2_LIB.BASEBOARD_FAB2(SCH_1):PAGE268

BMC_JTAG_SEL @BASEBOARD_FAB2_LIB.BASEBOARD_FAB2(SCH_1):BMC_JTAG_SEL
 Q25W5    3    DRN FET_N_SOT23LF-2N7002,FET,C7925A    I51 @BASEBOARD_FAB2_LIB.BASEBOARD_FAB2(SCH_1):PAGE268
R25W185    2      B RES_0402-4.75K,1%,1/16W,CHIP,GA    I54 @BASEBOARD_FAB2_LIB.BASEBOARD_FAB2(SCH_1):PAGE268
U25W18    2   B<0> TTL1G08_SOTLF-NC7SZ08,IC,D1032B    I57 @BASEBOARD_FAB2_LIB.BASEBOARD_FAB2(SCH_1):PAGE268
  S9W1    2      2 SW-SLIDE75-GP_DISCRET-G6-SW-SLA    I63 @BASEBOARD_FAB2_LIB.BASEBOARD_FAB2(SCH_1):PAGE268

BMC_JTAG_SEL_BUF @BASEBOARD_FAB2_LIB.BASEBOARD_FAB2(SCH_1):BMC_JTAG_SEL_BUF
U25W12    1  OE<3> TTL3126_QFNLF-74CBTLV3126,IC,DB    I33 @BASEBOARD_FAB2_LIB.BASEBOARD_FAB2(SCH_1):PAGE269
U25W16   13  OE<0> TTL3126_QFNLF-74CBTLV3126,IC,DB    I38 @BASEBOARD_FAB2_LIB.BASEBOARD_FAB2(SCH_1):PAGE268
U25W16   10  OE<1> TTL3126_QFNLF-74CBTLV3126,IC,DB    I38 @BASEBOARD_FAB2_LIB.BASEBOARD_FAB2(SCH_1):PAGE268
U25W16    4  OE<2> TTL3126_QFNLF-74CBTLV3126,IC,DB    I38 @BASEBOARD_FAB2_LIB.BASEBOARD_FAB2(SCH_1):PAGE268
U25W16    1  OE<3> TTL3126_QFNLF-74CBTLV3126,IC,DB    I38 @BASEBOARD_FAB2_LIB.BASEBOARD_FAB2(SCH_1):PAGE268
U25W17    2   B<0> TTL1G08_SOTLF-NC7SZ08,IC,D1032B    I61 @BASEBOARD_FAB2_LIB.BASEBOARD_FAB2(SCH_1):PAGE269
U25W18    4   Y<0> TTL1G08_SOTLF-NC7SZ08,IC,D1032B    I57 @BASEBOARD_FAB2_LIB.BASEBOARD_FAB2(SCH_1):PAGE268
U25W19    1     OE TTL1G126_A_SOT-74HC1G126,IC,A7B    I76 @BASEBOARD_FAB2_LIB.BASEBOARD_FAB2(SCH_1):PAGE269

BMC_JTAG_SEL_N @BASEBOARD_FAB2_LIB.BASEBOARD_FAB2(SCH_1):BMC_JTAG_SEL_N
 U25W4  P22 GPIOY2_SIOPWREQ# AST2520A1-GP-GP_ASIC2-GB1-AST2A    I28 @BASEBOARD_FAB2_LIB.BASEBOARD_FAB2(SCH_1):PAGE148
R25W174    2      B RES_0402-10.0K,1%,1/16W,CHIP,GA     I4 @BASEBOARD_FAB2_LIB.BASEBOARD_FAB2(SCH_1):PAGE269
U25W13    7    EN# MAX4564EKA-GP_SCRET-GC1-MAX456A    I53 @BASEBOARD_FAB2_LIB.BASEBOARD_FAB2(SCH_1):PAGE269
R7G114    1      A RES_0402-0.0,5%,1/16W,CHIP,G21A    I76 @BASEBOARD_FAB2_LIB.BASEBOARD_FAB2(SCH_1):PAGE189
 Q25W5    1   GATE FET_N_SOT23LF-2N7002,FET,C7925A    I51 @BASEBOARD_FAB2_LIB.BASEBOARD_FAB2(SCH_1):PAGE268
R25W186    1      A RES_0402-0.0,5%,1/16W,CHIP,G21A    I77 @BASEBOARD_FAB2_LIB.BASEBOARD_FAB2(SCH_1):PAGE189

BMC_JTAG_SEL_N_MUX @BASEBOARD_FAB2_LIB.BASEBOARD_FAB2(SCH_1):BMC_JTAG_SEL_N_MUX
 U1L10   13  OE<0> TTL3126_QFNLF-74CBTLV3126,IC,DB    I67 @BASEBOARD_FAB2_LIB.BASEBOARD_FAB2(SCH_1):PAGE189
 U1L10   10  OE<1> TTL3126_QFNLF-74CBTLV3126,IC,DB    I67 @BASEBOARD_FAB2_LIB.BASEBOARD_FAB2(SCH_1):PAGE189
 U1L10    4  OE<2> TTL3126_QFNLF-74CBTLV3126,IC,DB    I67 @BASEBOARD_FAB2_LIB.BASEBOARD_FAB2(SCH_1):PAGE189
 U1L10    1  OE<3> TTL3126_QFNLF-74CBTLV3126,IC,DB    I67 @BASEBOARD_FAB2_LIB.BASEBOARD_FAB2(SCH_1):PAGE189
R7G114    2      B RES_0402-0.0,5%,1/16W,CHIP,G21A    I76 @BASEBOARD_FAB2_LIB.BASEBOARD_FAB2(SCH_1):PAGE189

BMC_MIOZ @BASEBOARD_FAB2_LIB.BASEBOARD_FAB2(SCH_1):BMC_MIOZ
 R1T27    2      B RES_0402-240,1.0%,1/16W,CHIP,GA    I58 @BASEBOARD_FAB2_LIB.BASEBOARD_FAB2(SCH_1):PAGE143
 U25W4  W11   MIOZ AST2520A1-GP-GP_ASIC2-GB1-AST2A    I63 @BASEBOARD_FAB2_LIB.BASEBOARD_FAB2(SCH_1):PAGE143

BMC_M_A0 @BASEBOARD_FAB2_LIB.BASEBOARD_FAB2(SCH_1):BMC_M_A0
 U25W4  V13    MA0 AST2520A1-GP-GP_ASIC2-GB1-AST2A    I63 @BASEBOARD_FAB2_LIB.BASEBOARD_FAB2(SCH_1):PAGE143
 U25W5   P3     A0 H5AN4G6NAFR-TFC-GP_MEMORY-G2-HA    I49 @BASEBOARD_FAB2_LIB.BASEBOARD_FAB2(SCH_1):PAGE151
R25W38    1      1 120R2F-GP_RCL_GP-120R2F-GP,64.A   I233 @BASEBOARD_FAB2_LIB.BASEBOARD_FAB2(SCH_1):PAGE151
R25W12    2      2 120R2F-GP_RCL_GP-120R2F-GP,64.A   I256 @BASEBOARD_FAB2_LIB.BASEBOARD_FAB2(SCH_1):PAGE151

BMC_M_A1 @BASEBOARD_FAB2_LIB.BASEBOARD_FAB2(SCH_1):BMC_M_A1
 U25W4 AB14    MA1 AST2520A1-GP-GP_ASIC2-GB1-AST2A    I63 @BASEBOARD_FAB2_LIB.BASEBOARD_FAB2(SCH_1):PAGE143
 U25W5   P7     A1 H5AN4G6NAFR-TFC-GP_MEMORY-G2-HA    I49 @BASEBOARD_FAB2_LIB.BASEBOARD_FAB2(SCH_1):PAGE151
R25W39    1      1 120R2F-GP_RCL_GP-120R2F-GP,64.A   I234 @BASEBOARD_FAB2_LIB.BASEBOARD_FAB2(SCH_1):PAGE151
R25W13    2      2 120R2F-GP_RCL_GP-120R2F-GP,64.A   I260 @BASEBOARD_FAB2_LIB.BASEBOARD_FAB2(SCH_1):PAGE151

BMC_M_A10 @BASEBOARD_FAB2_LIB.BASEBOARD_FAB2(SCH_1):BMC_M_A10
 U25W4  U13   MA10 AST2520A1-GP-GP_ASIC2-GB1-AST2A    I63 @BASEBOARD_FAB2_LIB.BASEBOARD_FAB2(SCH_1):PAGE143
 U25W5   M3 A10/AP H5AN4G6NAFR-TFC-GP_MEMORY-G2-HA    I49 @BASEBOARD_FAB2_LIB.BASEBOARD_FAB2(SCH_1):PAGE151
R25W48    1      1 120R2F-GP_RCL_GP-120R2F-GP,64.A   I240 @BASEBOARD_FAB2_LIB.BASEBOARD_FAB2(SCH_1):PAGE151
R25W22    2      2 120R2F-GP_RCL_GP-120R2F-GP,64.A   I270 @BASEBOARD_FAB2_LIB.BASEBOARD_FAB2(SCH_1):PAGE151

BMC_M_A11 @BASEBOARD_FAB2_LIB.BASEBOARD_FAB2(SCH_1):BMC_M_A11
 U25W4 AA14   MA11 AST2520A1-GP-GP_ASIC2-GB1-AST2A    I63 @BASEBOARD_FAB2_LIB.BASEBOARD_FAB2(SCH_1):PAGE143
 U25W5   T2    A11 H5AN4G6NAFR-TFC-GP_MEMORY-G2-HA    I49 @BASEBOARD_FAB2_LIB.BASEBOARD_FAB2(SCH_1):PAGE151
R25W49    1      1 120R2F-GP_RCL_GP-120R2F-GP,64.A   I243 @BASEBOARD_FAB2_LIB.BASEBOARD_FAB2(SCH_1):PAGE151
R25W23    2      2 120R2F-GP_RCL_GP-120R2F-GP,64.A   I269 @BASEBOARD_FAB2_LIB.BASEBOARD_FAB2(SCH_1):PAGE151

BMC_M_A12 @BASEBOARD_FAB2_LIB.BASEBOARD_FAB2(SCH_1):BMC_M_A12
 U25W4  Y14   MA12 AST2520A1-GP-GP_ASIC2-GB1-AST2A    I63 @BASEBOARD_FAB2_LIB.BASEBOARD_FAB2(SCH_1):PAGE143
 U25W5   M7 A12/BC# H5AN4G6NAFR-TFC-GP_MEMORY-G2-HA    I49 @BASEBOARD_FAB2_LIB.BASEBOARD_FAB2(SCH_1):PAGE151
R25W50    1      1 120R2F-GP_RCL_GP-120R2F-GP,64.A   I244 @BASEBOARD_FAB2_LIB.BASEBOARD_FAB2(SCH_1):PAGE151
R25W24    2      2 120R2F-GP_RCL_GP-120R2F-GP,64.A   I268 @BASEBOARD_FAB2_LIB.BASEBOARD_FAB2(SCH_1):PAGE151

BMC_M_A13 @BASEBOARD_FAB2_LIB.BASEBOARD_FAB2(SCH_1):BMC_M_A13
 U25W4 AB15   MA13 AST2520A1-GP-GP_ASIC2-GB1-AST2A    I63 @BASEBOARD_FAB2_LIB.BASEBOARD_FAB2(SCH_1):PAGE143
 U25W5   T8    A13 H5AN4G6NAFR-TFC-GP_MEMORY-G2-HA    I49 @BASEBOARD_FAB2_LIB.BASEBOARD_FAB2(SCH_1):PAGE151
R25W51    1      1 120R2F-GP_RCL_GP-120R2F-GP,64.A   I245 @BASEBOARD_FAB2_LIB.BASEBOARD_FAB2(SCH_1):PAGE151
R25W25    2      2 120R2F-GP_RCL_GP-120R2F-GP,64.A   I275 @BASEBOARD_FAB2_LIB.BASEBOARD_FAB2(SCH_1):PAGE151

BMC_M_A2 @BASEBOARD_FAB2_LIB.BASEBOARD_FAB2(SCH_1):BMC_M_A2
 U25W4  W14    MA2 AST2520A1-GP-GP_ASIC2-GB1-AST2A    I63 @BASEBOARD_FAB2_LIB.BASEBOARD_FAB2(SCH_1):PAGE143
 U25W5   R3     A2 H5AN4G6NAFR-TFC-GP_MEMORY-G2-HA    I49 @BASEBOARD_FAB2_LIB.BASEBOARD_FAB2(SCH_1):PAGE151
R25W40    1      1 120R2F-GP_RCL_GP-120R2F-GP,64.A   I247 @BASEBOARD_FAB2_LIB.BASEBOARD_FAB2(SCH_1):PAGE151
R25W14    2      2 120R2F-GP_RCL_GP-120R2F-GP,64.A   I263 @BASEBOARD_FAB2_LIB.BASEBOARD_FAB2(SCH_1):PAGE151

BMC_M_A3 @BASEBOARD_FAB2_LIB.BASEBOARD_FAB2(SCH_1):BMC_M_A3
 U25W4  U14    MA3 AST2520A1-GP-GP_ASIC2-GB1-AST2A    I63 @BASEBOARD_FAB2_LIB.BASEBOARD_FAB2(SCH_1):PAGE143
 U25W5   N7     A3 H5AN4G6NAFR-TFC-GP_MEMORY-G2-HA    I49 @BASEBOARD_FAB2_LIB.BASEBOARD_FAB2(SCH_1):PAGE151
R25W41    1      1 120R2F-GP_RCL_GP-120R2F-GP,64.A   I235 @BASEBOARD_FAB2_LIB.BASEBOARD_FAB2(SCH_1):PAGE151
R25W15    2      2 120R2F-GP_RCL_GP-120R2F-GP,64.A   I262 @BASEBOARD_FAB2_LIB.BASEBOARD_FAB2(SCH_1):PAGE151

BMC_M_A4 @BASEBOARD_FAB2_LIB.BASEBOARD_FAB2(SCH_1):BMC_M_A4
 U25W4  W15    MA4 AST2520A1-GP-GP_ASIC2-GB1-AST2A    I63 @BASEBOARD_FAB2_LIB.BASEBOARD_FAB2(SCH_1):PAGE143
 U25W5   N3     A4 H5AN4G6NAFR-TFC-GP_MEMORY-G2-HA    I49 @BASEBOARD_FAB2_LIB.BASEBOARD_FAB2(SCH_1):PAGE151
R25W42    1      1 120R2F-GP_RCL_GP-120R2F-GP,64.A   I236 @BASEBOARD_FAB2_LIB.BASEBOARD_FAB2(SCH_1):PAGE151
R25W16    2      2 120R2F-GP_RCL_GP-120R2F-GP,64.A   I261 @BASEBOARD_FAB2_LIB.BASEBOARD_FAB2(SCH_1):PAGE151

BMC_M_A5 @BASEBOARD_FAB2_LIB.BASEBOARD_FAB2(SCH_1):BMC_M_A5
 U25W4  V15    MA5 AST2520A1-GP-GP_ASIC2-GB1-AST2A    I63 @BASEBOARD_FAB2_LIB.BASEBOARD_FAB2(SCH_1):PAGE143
 U25W5   P8     A5 H5AN4G6NAFR-TFC-GP_MEMORY-G2-HA    I49 @BASEBOARD_FAB2_LIB.BASEBOARD_FAB2(SCH_1):PAGE151
R25W43    1      1 120R2F-GP_RCL_GP-120R2F-GP,64.A   I238 @BASEBOARD_FAB2_LIB.BASEBOARD_FAB2(SCH_1):PAGE151
R25W17    2      2 120R2F-GP_RCL_GP-120R2F-GP,64.A   I264 @BASEBOARD_FAB2_LIB.BASEBOARD_FAB2(SCH_1):PAGE151

BMC_M_A6 @BASEBOARD_FAB2_LIB.BASEBOARD_FAB2(SCH_1):BMC_M_A6
 U25W4 AB16    MA6 AST2520A1-GP-GP_ASIC2-GB1-AST2A    I63 @BASEBOARD_FAB2_LIB.BASEBOARD_FAB2(SCH_1):PAGE143
 U25W5   P2     A6 H5AN4G6NAFR-TFC-GP_MEMORY-G2-HA    I49 @BASEBOARD_FAB2_LIB.BASEBOARD_FAB2(SCH_1):PAGE151
R25W44    1      1 120R2F-GP_RCL_GP-120R2F-GP,64.A   I237 @BASEBOARD_FAB2_LIB.BASEBOARD_FAB2(SCH_1):PAGE151
R25W18    2      2 120R2F-GP_RCL_GP-120R2F-GP,64.A   I265 @BASEBOARD_FAB2_LIB.BASEBOARD_FAB2(SCH_1):PAGE151

BMC_M_A7 @BASEBOARD_FAB2_LIB.BASEBOARD_FAB2(SCH_1):BMC_M_A7
 U25W4 AA16    MA7 AST2520A1-GP-GP_ASIC2-GB1-AST2A    I63 @BASEBOARD_FAB2_LIB.BASEBOARD_FAB2(SCH_1):PAGE143
 U25W5   R8     A7 H5AN4G6NAFR-TFC-GP_MEMORY-G2-HA    I49 @BASEBOARD_FAB2_LIB.BASEBOARD_FAB2(SCH_1):PAGE151
R25W45    1      1 120R2F-GP_RCL_GP-120R2F-GP,64.A   I242 @BASEBOARD_FAB2_LIB.BASEBOARD_FAB2(SCH_1):PAGE151
R25W19    2      2 120R2F-GP_RCL_GP-120R2F-GP,64.A   I267 @BASEBOARD_FAB2_LIB.BASEBOARD_FAB2(SCH_1):PAGE151

BMC_M_A8 @BASEBOARD_FAB2_LIB.BASEBOARD_FAB2(SCH_1):BMC_M_A8
 U25W4  W16    MA8 AST2520A1-GP-GP_ASIC2-GB1-AST2A    I63 @BASEBOARD_FAB2_LIB.BASEBOARD_FAB2(SCH_1):PAGE143
 U25W5   R2     A8 H5AN4G6NAFR-TFC-GP_MEMORY-G2-HA    I49 @BASEBOARD_FAB2_LIB.BASEBOARD_FAB2(SCH_1):PAGE151
R25W46    1      1 120R2F-GP_RCL_GP-120R2F-GP,64.A   I241 @BASEBOARD_FAB2_LIB.BASEBOARD_FAB2(SCH_1):PAGE151
R25W20    2      2 120R2F-GP_RCL_GP-120R2F-GP,64.A   I266 @BASEBOARD_FAB2_LIB.BASEBOARD_FAB2(SCH_1):PAGE151

BMC_M_A9 @BASEBOARD_FAB2_LIB.BASEBOARD_FAB2(SCH_1):BMC_M_A9
 U25W4  Y16    MA9 AST2520A1-GP-GP_ASIC2-GB1-AST2A    I63 @BASEBOARD_FAB2_LIB.BASEBOARD_FAB2(SCH_1):PAGE143
 U25W5   R7     A9 H5AN4G6NAFR-TFC-GP_MEMORY-G2-HA    I49 @BASEBOARD_FAB2_LIB.BASEBOARD_FAB2(SCH_1):PAGE151
R25W47    1      1 120R2F-GP_RCL_GP-120R2F-GP,64.A   I239 @BASEBOARD_FAB2_LIB.BASEBOARD_FAB2(SCH_1):PAGE151
R25W21    2      2 120R2F-GP_RCL_GP-120R2F-GP,64.A   I271 @BASEBOARD_FAB2_LIB.BASEBOARD_FAB2(SCH_1):PAGE151

BMC_M_BA0 @BASEBOARD_FAB2_LIB.BASEBOARD_FAB2(SCH_1):BMC_M_BA0
 U25W4  U12   MBA0 AST2520A1-GP-GP_ASIC2-GB1-AST2A    I63 @BASEBOARD_FAB2_LIB.BASEBOARD_FAB2(SCH_1):PAGE143
 U25W5   N2    BA0 H5AN4G6NAFR-TFC-GP_MEMORY-G2-HA    I49 @BASEBOARD_FAB2_LIB.BASEBOARD_FAB2(SCH_1):PAGE151
R25W35    1      1 120R2F-GP_RCL_GP-120R2F-GP,64.A   I230 @BASEBOARD_FAB2_LIB.BASEBOARD_FAB2(SCH_1):PAGE151
 R25W9    2      2 120R2F-GP_RCL_GP-120R2F-GP,64.A   I258 @BASEBOARD_FAB2_LIB.BASEBOARD_FAB2(SCH_1):PAGE151

BMC_M_BA1 @BASEBOARD_FAB2_LIB.BASEBOARD_FAB2(SCH_1):BMC_M_BA1
 U25W4  Y13   MBA1 AST2520A1-GP-GP_ASIC2-GB1-AST2A    I63 @BASEBOARD_FAB2_LIB.BASEBOARD_FAB2(SCH_1):PAGE143
 U25W5   N8    BA1 H5AN4G6NAFR-TFC-GP_MEMORY-G2-HA    I49 @BASEBOARD_FAB2_LIB.BASEBOARD_FAB2(SCH_1):PAGE151
R25W36    1      1 120R2F-GP_RCL_GP-120R2F-GP,64.A   I231 @BASEBOARD_FAB2_LIB.BASEBOARD_FAB2(SCH_1):PAGE151
R25W10    2      2 120R2F-GP_RCL_GP-120R2F-GP,64.A   I259 @BASEBOARD_FAB2_LIB.BASEBOARD_FAB2(SCH_1):PAGE151

BMC_M_BG0 @BASEBOARD_FAB2_LIB.BASEBOARD_FAB2(SCH_1):BMC_M_BG0
 U25W4  W13 MBA2_MBG0 AST2520A1-GP-GP_ASIC2-GB1-AST2A    I63 @BASEBOARD_FAB2_LIB.BASEBOARD_FAB2(SCH_1):PAGE143
 U25W5   M2    BG0 H5AN4G6NAFR-TFC-GP_MEMORY-G2-HA    I49 @BASEBOARD_FAB2_LIB.BASEBOARD_FAB2(SCH_1):PAGE151
R25W37    1      1 120R2F-GP_RCL_GP-120R2F-GP,64.A   I232 @BASEBOARD_FAB2_LIB.BASEBOARD_FAB2(SCH_1):PAGE151
R25W11    2      2 120R2F-GP_RCL_GP-120R2F-GP,64.A   I257 @BASEBOARD_FAB2_LIB.BASEBOARD_FAB2(SCH_1):PAGE151

BMC_M_CAS_N @BASEBOARD_FAB2_LIB.BASEBOARD_FAB2(SCH_1):BMC_M_CAS_N
 U25W4 AB13  MCAS# AST2520A1-GP-GP_ASIC2-GB1-AST2A    I63 @BASEBOARD_FAB2_LIB.BASEBOARD_FAB2(SCH_1):PAGE143
 U25W5   M8 CAS#/A15 H5AN4G6NAFR-TFC-GP_MEMORY-G2-HA    I49 @BASEBOARD_FAB2_LIB.BASEBOARD_FAB2(SCH_1):PAGE151
R25W33    1      1 120R2F-GP_RCL_GP-120R2F-GP,64.A   I228 @BASEBOARD_FAB2_LIB.BASEBOARD_FAB2(SCH_1):PAGE151
 R25W7    2      2 120R2F-GP_RCL_GP-120R2F-GP,64.A   I254 @BASEBOARD_FAB2_LIB.BASEBOARD_FAB2(SCH_1):PAGE151

BMC_M_CKE @BASEBOARD_FAB2_LIB.BASEBOARD_FAB2(SCH_1):BMC_M_CKE
 U25W4  Y11   MCKE AST2520A1-GP-GP_ASIC2-GB1-AST2A    I63 @BASEBOARD_FAB2_LIB.BASEBOARD_FAB2(SCH_1):PAGE143
 U25W5   K2    CKE H5AN4G6NAFR-TFC-GP_MEMORY-G2-HA    I49 @BASEBOARD_FAB2_LIB.BASEBOARD_FAB2(SCH_1):PAGE151
R25W27    1      1 120R2F-GP_RCL_GP-120R2F-GP,64.A   I223 @BASEBOARD_FAB2_LIB.BASEBOARD_FAB2(SCH_1):PAGE151
 R25W1    2      2 120R2F-GP_RCL_GP-120R2F-GP,64.A   I248 @BASEBOARD_FAB2_LIB.BASEBOARD_FAB2(SCH_1):PAGE151

BMC_M_CLK @BASEBOARD_FAB2_LIB.BASEBOARD_FAB2(SCH_1):BMC_M_CLK
 C1W20    1      A CAP_0402-0.22UF,16V,10%,X7R,A3A   I220 @BASEBOARD_FAB2_LIB.BASEBOARD_FAB2(SCH_1):PAGE151
 R1T40    2      B RES_0402-49.9,1%,1/16W,CHIP,G2A   I278 @BASEBOARD_FAB2_LIB.BASEBOARD_FAB2(SCH_1):PAGE151
 R1T28    2      B RES_0402-49.9,1%,1/16W,CHIP,G2A   I279 @BASEBOARD_FAB2_LIB.BASEBOARD_FAB2(SCH_1):PAGE151

BMC_M_CLK_DN @BASEBOARD_FAB2_LIB.BASEBOARD_FAB2(SCH_1):BMC_M_CLK_DN
 U25W4 AB12   MCKN AST2520A1-GP-GP_ASIC2-GB1-AST2A    I63 @BASEBOARD_FAB2_LIB.BASEBOARD_FAB2(SCH_1):PAGE143
 U25W5   K8   CK_C H5AN4G6NAFR-TFC-GP_MEMORY-G2-HA    I49 @BASEBOARD_FAB2_LIB.BASEBOARD_FAB2(SCH_1):PAGE151
 R1T28    1      A RES_0402-49.9,1%,1/16W,CHIP,G2A   I279 @BASEBOARD_FAB2_LIB.BASEBOARD_FAB2(SCH_1):PAGE151

BMC_M_CLK_DP @BASEBOARD_FAB2_LIB.BASEBOARD_FAB2(SCH_1):BMC_M_CLK_DP
 U25W4 AB11   MCKP AST2520A1-GP-GP_ASIC2-GB1-AST2A    I63 @BASEBOARD_FAB2_LIB.BASEBOARD_FAB2(SCH_1):PAGE143
 U25W5   K7   CK_T H5AN4G6NAFR-TFC-GP_MEMORY-G2-HA    I49 @BASEBOARD_FAB2_LIB.BASEBOARD_FAB2(SCH_1):PAGE151
 R1T40    1      A RES_0402-49.9,1%,1/16W,CHIP,G2A   I278 @BASEBOARD_FAB2_LIB.BASEBOARD_FAB2(SCH_1):PAGE151

BMC_M_CS_N @BASEBOARD_FAB2_LIB.BASEBOARD_FAB2(SCH_1):BMC_M_CS_N
 U25W4 AA12   MCS# AST2520A1-GP-GP_ASIC2-GB1-AST2A    I63 @BASEBOARD_FAB2_LIB.BASEBOARD_FAB2(SCH_1):PAGE143
 U25W5   L7    CS# H5AN4G6NAFR-TFC-GP_MEMORY-G2-HA    I49 @BASEBOARD_FAB2_LIB.BASEBOARD_FAB2(SCH_1):PAGE151
R25W31    1      1 120R2F-GP_RCL_GP-120R2F-GP,64.A   I226 @BASEBOARD_FAB2_LIB.BASEBOARD_FAB2(SCH_1):PAGE151
 R25W5    2      2 120R2F-GP_RCL_GP-120R2F-GP,64.A   I252 @BASEBOARD_FAB2_LIB.BASEBOARD_FAB2(SCH_1):PAGE151

BMC_M_DM0 @BASEBOARD_FAB2_LIB.BASEBOARD_FAB2(SCH_1):BMC_M_DM0
 U25W4   U8   MDM0 AST2520A1-GP-GP_ASIC2-GB1-AST2A    I63 @BASEBOARD_FAB2_LIB.BASEBOARD_FAB2(SCH_1):PAGE143
 U25W5   E7 DML#/DBIL# H5AN4G6NAFR-TFC-GP_MEMORY-G2-HA    I49 @BASEBOARD_FAB2_LIB.BASEBOARD_FAB2(SCH_1):PAGE151

BMC_M_DM1 @BASEBOARD_FAB2_LIB.BASEBOARD_FAB2(SCH_1):BMC_M_DM1
 U25W4  AB8   MDM1 AST2520A1-GP-GP_ASIC2-GB1-AST2A    I63 @BASEBOARD_FAB2_LIB.BASEBOARD_FAB2(SCH_1):PAGE143
 U25W5   E2 DMU#/DBIU# H5AN4G6NAFR-TFC-GP_MEMORY-G2-HA    I49 @BASEBOARD_FAB2_LIB.BASEBOARD_FAB2(SCH_1):PAGE151

BMC_M_DQ0 @BASEBOARD_FAB2_LIB.BASEBOARD_FAB2(SCH_1):BMC_M_DQ0
 U25W4  U10   MDQ0 AST2520A1-GP-GP_ASIC2-GB1-AST2A    I63 @BASEBOARD_FAB2_LIB.BASEBOARD_FAB2(SCH_1):PAGE143
 U25W5   G2   DQL0 H5AN4G6NAFR-TFC-GP_MEMORY-G2-HA    I49 @BASEBOARD_FAB2_LIB.BASEBOARD_FAB2(SCH_1):PAGE151

BMC_M_DQ1 @BASEBOARD_FAB2_LIB.BASEBOARD_FAB2(SCH_1):BMC_M_DQ1
 U25W4  W10   MDQ1 AST2520A1-GP-GP_ASIC2-GB1-AST2A    I63 @BASEBOARD_FAB2_LIB.BASEBOARD_FAB2(SCH_1):PAGE143
 U25W5   F7   DQL1 H5AN4G6NAFR-TFC-GP_MEMORY-G2-HA    I49 @BASEBOARD_FAB2_LIB.BASEBOARD_FAB2(SCH_1):PAGE151

BMC_M_DQ10 @BASEBOARD_FAB2_LIB.BASEBOARD_FAB2(SCH_1):BMC_M_DQ10
 U25W4   Y7  MDQ10 AST2520A1-GP-GP_ASIC2-GB1-AST2A    I63 @BASEBOARD_FAB2_LIB.BASEBOARD_FAB2(SCH_1):PAGE143
 U25W5   C3   DQU2 H5AN4G6NAFR-TFC-GP_MEMORY-G2-HA    I49 @BASEBOARD_FAB2_LIB.BASEBOARD_FAB2(SCH_1):PAGE151

BMC_M_DQ11 @BASEBOARD_FAB2_LIB.BASEBOARD_FAB2(SCH_1):BMC_M_DQ11
 U25W4   W8  MDQ11 AST2520A1-GP-GP_ASIC2-GB1-AST2A    I63 @BASEBOARD_FAB2_LIB.BASEBOARD_FAB2(SCH_1):PAGE143
 U25W5   C7   DQU3 H5AN4G6NAFR-TFC-GP_MEMORY-G2-HA    I49 @BASEBOARD_FAB2_LIB.BASEBOARD_FAB2(SCH_1):PAGE151

BMC_M_DQ12 @BASEBOARD_FAB2_LIB.BASEBOARD_FAB2(SCH_1):BMC_M_DQ12
 U25W4  AA6  MDQ12 AST2520A1-GP-GP_ASIC2-GB1-AST2A    I63 @BASEBOARD_FAB2_LIB.BASEBOARD_FAB2(SCH_1):PAGE143
 U25W5   C2   DQU4 H5AN4G6NAFR-TFC-GP_MEMORY-G2-HA    I49 @BASEBOARD_FAB2_LIB.BASEBOARD_FAB2(SCH_1):PAGE151

BMC_M_DQ13 @BASEBOARD_FAB2_LIB.BASEBOARD_FAB2(SCH_1):BMC_M_DQ13
 U25W4   W7  MDQ13 AST2520A1-GP-GP_ASIC2-GB1-AST2A    I63 @BASEBOARD_FAB2_LIB.BASEBOARD_FAB2(SCH_1):PAGE143
 U25W5   C8   DQU5 H5AN4G6NAFR-TFC-GP_MEMORY-G2-HA    I49 @BASEBOARD_FAB2_LIB.BASEBOARD_FAB2(SCH_1):PAGE151

BMC_M_DQ14 @BASEBOARD_FAB2_LIB.BASEBOARD_FAB2(SCH_1):BMC_M_DQ14
 U25W4   V7  MDQ14 AST2520A1-GP-GP_ASIC2-GB1-AST2A    I63 @BASEBOARD_FAB2_LIB.BASEBOARD_FAB2(SCH_1):PAGE143
 U25W5   D3   DQU6 H5AN4G6NAFR-TFC-GP_MEMORY-G2-HA    I49 @BASEBOARD_FAB2_LIB.BASEBOARD_FAB2(SCH_1):PAGE151

BMC_M_DQ15 @BASEBOARD_FAB2_LIB.BASEBOARD_FAB2(SCH_1):BMC_M_DQ15
 U25W4   U7  MDQ15 AST2520A1-GP-GP_ASIC2-GB1-AST2A    I63 @BASEBOARD_FAB2_LIB.BASEBOARD_FAB2(SCH_1):PAGE143
 U25W5   D7   DQU7 H5AN4G6NAFR-TFC-GP_MEMORY-G2-HA    I49 @BASEBOARD_FAB2_LIB.BASEBOARD_FAB2(SCH_1):PAGE151

BMC_M_DQ2 @BASEBOARD_FAB2_LIB.BASEBOARD_FAB2(SCH_1):BMC_M_DQ2
 U25W4  Y10   MDQ2 AST2520A1-GP-GP_ASIC2-GB1-AST2A    I63 @BASEBOARD_FAB2_LIB.BASEBOARD_FAB2(SCH_1):PAGE143
 U25W5   H3   DQL2 H5AN4G6NAFR-TFC-GP_MEMORY-G2-HA    I49 @BASEBOARD_FAB2_LIB.BASEBOARD_FAB2(SCH_1):PAGE151

BMC_M_DQ3 @BASEBOARD_FAB2_LIB.BASEBOARD_FAB2(SCH_1):BMC_M_DQ3
 U25W4 AA10   MDQ3 AST2520A1-GP-GP_ASIC2-GB1-AST2A    I63 @BASEBOARD_FAB2_LIB.BASEBOARD_FAB2(SCH_1):PAGE143
 U25W5   H7   DQL3 H5AN4G6NAFR-TFC-GP_MEMORY-G2-HA    I49 @BASEBOARD_FAB2_LIB.BASEBOARD_FAB2(SCH_1):PAGE151

BMC_M_DQ4 @BASEBOARD_FAB2_LIB.BASEBOARD_FAB2(SCH_1):BMC_M_DQ4
 U25W4   U9   MDQ4 AST2520A1-GP-GP_ASIC2-GB1-AST2A    I63 @BASEBOARD_FAB2_LIB.BASEBOARD_FAB2(SCH_1):PAGE143
 U25W5   H2   DQL4 H5AN4G6NAFR-TFC-GP_MEMORY-G2-HA    I49 @BASEBOARD_FAB2_LIB.BASEBOARD_FAB2(SCH_1):PAGE151

BMC_M_DQ5 @BASEBOARD_FAB2_LIB.BASEBOARD_FAB2(SCH_1):BMC_M_DQ5
 U25W4   Y9   MDQ5 AST2520A1-GP-GP_ASIC2-GB1-AST2A    I63 @BASEBOARD_FAB2_LIB.BASEBOARD_FAB2(SCH_1):PAGE143
 U25W5   H8   DQL5 H5AN4G6NAFR-TFC-GP_MEMORY-G2-HA    I49 @BASEBOARD_FAB2_LIB.BASEBOARD_FAB2(SCH_1):PAGE151

BMC_M_DQ6 @BASEBOARD_FAB2_LIB.BASEBOARD_FAB2(SCH_1):BMC_M_DQ6
 U25W4   W9   MDQ6 AST2520A1-GP-GP_ASIC2-GB1-AST2A    I63 @BASEBOARD_FAB2_LIB.BASEBOARD_FAB2(SCH_1):PAGE143
 U25W5   J3   DQL6 H5AN4G6NAFR-TFC-GP_MEMORY-G2-HA    I49 @BASEBOARD_FAB2_LIB.BASEBOARD_FAB2(SCH_1):PAGE151

BMC_M_DQ7 @BASEBOARD_FAB2_LIB.BASEBOARD_FAB2(SCH_1):BMC_M_DQ7
 U25W4   V9   MDQ7 AST2520A1-GP-GP_ASIC2-GB1-AST2A    I63 @BASEBOARD_FAB2_LIB.BASEBOARD_FAB2(SCH_1):PAGE143
 U25W5   J7   DQL7 H5AN4G6NAFR-TFC-GP_MEMORY-G2-HA    I49 @BASEBOARD_FAB2_LIB.BASEBOARD_FAB2(SCH_1):PAGE151

BMC_M_DQ8 @BASEBOARD_FAB2_LIB.BASEBOARD_FAB2(SCH_1):BMC_M_DQ8
 U25W4  AA8   MDQ8 AST2520A1-GP-GP_ASIC2-GB1-AST2A    I63 @BASEBOARD_FAB2_LIB.BASEBOARD_FAB2(SCH_1):PAGE143
 U25W5   A3   DQU0 H5AN4G6NAFR-TFC-GP_MEMORY-G2-HA    I49 @BASEBOARD_FAB2_LIB.BASEBOARD_FAB2(SCH_1):PAGE151

BMC_M_DQ9 @BASEBOARD_FAB2_LIB.BASEBOARD_FAB2(SCH_1):BMC_M_DQ9
 U25W4   Y8   MDQ9 AST2520A1-GP-GP_ASIC2-GB1-AST2A    I63 @BASEBOARD_FAB2_LIB.BASEBOARD_FAB2(SCH_1):PAGE143
 U25W5   B8   DQU1 H5AN4G6NAFR-TFC-GP_MEMORY-G2-HA    I49 @BASEBOARD_FAB2_LIB.BASEBOARD_FAB2(SCH_1):PAGE151

BMC_M_DQS0_DN @BASEBOARD_FAB2_LIB.BASEBOARD_FAB2(SCH_1):BMC_M_DQS0_DN
 U25W4 AB10 MDQS0N AST2520A1-GP-GP_ASIC2-GB1-AST2A    I63 @BASEBOARD_FAB2_LIB.BASEBOARD_FAB2(SCH_1):PAGE143
 U25W5   F3 DQSL_C H5AN4G6NAFR-TFC-GP_MEMORY-G2-HA    I49 @BASEBOARD_FAB2_LIB.BASEBOARD_FAB2(SCH_1):PAGE151

BMC_M_DQS0_DP @BASEBOARD_FAB2_LIB.BASEBOARD_FAB2(SCH_1):BMC_M_DQS0_DP
 U25W4  AB9 MDQS0P AST2520A1-GP-GP_ASIC2-GB1-AST2A    I63 @BASEBOARD_FAB2_LIB.BASEBOARD_FAB2(SCH_1):PAGE143
 U25W5   G3 DQSL_T H5AN4G6NAFR-TFC-GP_MEMORY-G2-HA    I49 @BASEBOARD_FAB2_LIB.BASEBOARD_FAB2(SCH_1):PAGE151

BMC_M_DQS1_DN @BASEBOARD_FAB2_LIB.BASEBOARD_FAB2(SCH_1):BMC_M_DQS1_DN
 U25W4  AB6 MDQS1N AST2520A1-GP-GP_ASIC2-GB1-AST2A    I63 @BASEBOARD_FAB2_LIB.BASEBOARD_FAB2(SCH_1):PAGE143
 U25W5   A7 DQSU_C H5AN4G6NAFR-TFC-GP_MEMORY-G2-HA    I49 @BASEBOARD_FAB2_LIB.BASEBOARD_FAB2(SCH_1):PAGE151

BMC_M_DQS1_DP @BASEBOARD_FAB2_LIB.BASEBOARD_FAB2(SCH_1):BMC_M_DQS1_DP
 U25W4  AB7 MDQS1P AST2520A1-GP-GP_ASIC2-GB1-AST2A    I63 @BASEBOARD_FAB2_LIB.BASEBOARD_FAB2(SCH_1):PAGE143
 U25W5   B7 DQSU_T H5AN4G6NAFR-TFC-GP_MEMORY-G2-HA    I49 @BASEBOARD_FAB2_LIB.BASEBOARD_FAB2(SCH_1):PAGE151

BMC_M_MACT_N @BASEBOARD_FAB2_LIB.BASEBOARD_FAB2(SCH_1):BMC_M_MACT_N
 U25W4  Y15 MA14_MACT# AST2520A1-GP-GP_ASIC2-GB1-AST2A    I63 @BASEBOARD_FAB2_LIB.BASEBOARD_FAB2(SCH_1):PAGE143
 U25W5   L3   ACT# H5AN4G6NAFR-TFC-GP_MEMORY-G2-HA    I49 @BASEBOARD_FAB2_LIB.BASEBOARD_FAB2(SCH_1):PAGE151
R25W52    1      1 120R2F-GP_RCL_GP-120R2F-GP,64.A   I246 @BASEBOARD_FAB2_LIB.BASEBOARD_FAB2(SCH_1):PAGE151
R25W26    2      2 120R2F-GP_RCL_GP-120R2F-GP,64.A   I274 @BASEBOARD_FAB2_LIB.BASEBOARD_FAB2(SCH_1):PAGE151

BMC_M_MALERT_N @BASEBOARD_FAB2_LIB.BASEBOARD_FAB2(SCH_1):BMC_M_MALERT_N
 U25W4  U16 MALERT# AST2520A1-GP-GP_ASIC2-GB1-AST2A   I105 @BASEBOARD_FAB2_LIB.BASEBOARD_FAB2(SCH_1):PAGE146
 U25W5   P9 ALERT# H5AN4G6NAFR-TFC-GP_MEMORY-G2-HA    I49 @BASEBOARD_FAB2_LIB.BASEBOARD_FAB2(SCH_1):PAGE151
R25W30    1      A RES_0402-2.7K,1%,1/16W,CHIP,G2A   I222 @BASEBOARD_FAB2_LIB.BASEBOARD_FAB2(SCH_1):PAGE151
 R25W4    2      2 120R2F-GP_RCL_GP-120R2F-GP,64.A   I251 @BASEBOARD_FAB2_LIB.BASEBOARD_FAB2(SCH_1):PAGE151

BMC_M_ODT @BASEBOARD_FAB2_LIB.BASEBOARD_FAB2(SCH_1):BMC_M_ODT
 U25W4  V11   MODT AST2520A1-GP-GP_ASIC2-GB1-AST2A    I63 @BASEBOARD_FAB2_LIB.BASEBOARD_FAB2(SCH_1):PAGE143
 U25W5   K3    ODT H5AN4G6NAFR-TFC-GP_MEMORY-G2-HA    I49 @BASEBOARD_FAB2_LIB.BASEBOARD_FAB2(SCH_1):PAGE151
R25W28    1      1 120R2F-GP_RCL_GP-120R2F-GP,64.A   I224 @BASEBOARD_FAB2_LIB.BASEBOARD_FAB2(SCH_1):PAGE151
 R25W2    2      2 120R2F-GP_RCL_GP-120R2F-GP,64.A   I249 @BASEBOARD_FAB2_LIB.BASEBOARD_FAB2(SCH_1):PAGE151

BMC_M_PAR @BASEBOARD_FAB2_LIB.BASEBOARD_FAB2(SCH_1):BMC_M_PAR
 U25W5   T3    PAR H5AN4G6NAFR-TFC-GP_MEMORY-G2-HA    I49 @BASEBOARD_FAB2_LIB.BASEBOARD_FAB2(SCH_1):PAGE151
R25W119    2      B RES_0402-4.75K,1%,1/16W,EMPTY,A   I210 @BASEBOARD_FAB2_LIB.BASEBOARD_FAB2(SCH_1):PAGE151
R25W118    1      A RES_0402-0.0,5%,1/16W,CHIP,G21A   I211 @BASEBOARD_FAB2_LIB.BASEBOARD_FAB2(SCH_1):PAGE151

BMC_M_RAS_N @BASEBOARD_FAB2_LIB.BASEBOARD_FAB2(SCH_1):BMC_M_RAS_N
 U25W4  W12  MRAS# AST2520A1-GP-GP_ASIC2-GB1-AST2A    I63 @BASEBOARD_FAB2_LIB.BASEBOARD_FAB2(SCH_1):PAGE143
 U25W5   L8 RAS#/A16 H5AN4G6NAFR-TFC-GP_MEMORY-G2-HA    I49 @BASEBOARD_FAB2_LIB.BASEBOARD_FAB2(SCH_1):PAGE151
R25W32    1      1 120R2F-GP_RCL_GP-120R2F-GP,64.A   I227 @BASEBOARD_FAB2_LIB.BASEBOARD_FAB2(SCH_1):PAGE151
 R25W6    2      2 120R2F-GP_RCL_GP-120R2F-GP,64.A   I253 @BASEBOARD_FAB2_LIB.BASEBOARD_FAB2(SCH_1):PAGE151

BMC_M_RST_N @BASEBOARD_FAB2_LIB.BASEBOARD_FAB2(SCH_1):BMC_M_RST_N
 U25W4 AB17 MRESET# AST2520A1-GP-GP_ASIC2-GB1-AST2A   I105 @BASEBOARD_FAB2_LIB.BASEBOARD_FAB2(SCH_1):PAGE146
 U25W5   P1 RESET# H5AN4G6NAFR-TFC-GP_MEMORY-G2-HA    I49 @BASEBOARD_FAB2_LIB.BASEBOARD_FAB2(SCH_1):PAGE151
 R9F34    2      B RES_0402-33.2,1%,1/16W,EMPTY,GA   I209 @BASEBOARD_FAB2_LIB.BASEBOARD_FAB2(SCH_1):PAGE151
R25W29    1      1 120R2F-GP_RCL_GP-120R2F-GP,64.A   I225 @BASEBOARD_FAB2_LIB.BASEBOARD_FAB2(SCH_1):PAGE151
 R25W3    2      2 120R2F-GP_RCL_GP-120R2F-GP,64.A   I250 @BASEBOARD_FAB2_LIB.BASEBOARD_FAB2(SCH_1):PAGE151

BMC_M_VREFCA @BASEBOARD_FAB2_LIB.BASEBOARD_FAB2(SCH_1):BMC_M_VREFCA
 U25W4   T9  MVREF AST2520A1-GP-GP_ASIC2-GB1-AST2A    I63 @BASEBOARD_FAB2_LIB.BASEBOARD_FAB2(SCH_1):PAGE143
 U25W5   M1 VREFCA H5AN4G6NAFR-TFC-GP_MEMORY-G2-HA    I49 @BASEBOARD_FAB2_LIB.BASEBOARD_FAB2(SCH_1):PAGE151
 R1T30    2      B RES_0402-1.00K,1%,1/16W,CHIP,GA   I201 @BASEBOARD_FAB2_LIB.BASEBOARD_FAB2(SCH_1):PAGE151
 R1T29    1      A RES_0402-1.00K,1%,1/16W,CHIP,GA   I202 @BASEBOARD_FAB2_LIB.BASEBOARD_FAB2(SCH_1):PAGE151
C25W12    1      A CAP_A_0402V-1.0UF,6.3V,10%,X6SA   I212 @BASEBOARD_FAB2_LIB.BASEBOARD_FAB2(SCH_1):PAGE151
C25W10    2      B CAP_A_0402V-0.01UF,25V,10%,X7RA   I213 @BASEBOARD_FAB2_LIB.BASEBOARD_FAB2(SCH_1):PAGE151
C25W11    1      A CAP_A_0402V-0.01UF,25V,10%,X7RA   I214 @BASEBOARD_FAB2_LIB.BASEBOARD_FAB2(SCH_1):PAGE151
C25W22    1      A CAP_A_0402V-0.1UF,16V,10%,X7R,A    I67 @BASEBOARD_FAB2_LIB.BASEBOARD_FAB2(SCH_1):PAGE143
C25W13    1      A CAP_A_0402V-0.1UF,16V,10%,X7R,A   I217 @BASEBOARD_FAB2_LIB.BASEBOARD_FAB2(SCH_1):PAGE151

BMC_M_WE_N @BASEBOARD_FAB2_LIB.BASEBOARD_FAB2(SCH_1):BMC_M_WE_N
 U25W4  Y12   MWE# AST2520A1-GP-GP_ASIC2-GB1-AST2A    I63 @BASEBOARD_FAB2_LIB.BASEBOARD_FAB2(SCH_1):PAGE143
 U25W5   L2 WE#/A14 H5AN4G6NAFR-TFC-GP_MEMORY-G2-HA    I49 @BASEBOARD_FAB2_LIB.BASEBOARD_FAB2(SCH_1):PAGE151
R25W34    1      1 120R2F-GP_RCL_GP-120R2F-GP,64.A   I229 @BASEBOARD_FAB2_LIB.BASEBOARD_FAB2(SCH_1):PAGE151
 R25W8    2      2 120R2F-GP_RCL_GP-120R2F-GP,64.A   I255 @BASEBOARD_FAB2_LIB.BASEBOARD_FAB2(SCH_1):PAGE151

BMC_PRDY_N @BASEBOARD_FAB2_LIB.BASEBOARD_FAB2(SCH_1):BMC_PRDY_N
 U25W4  Y19 GPIOR3_SPI2CK AST2520A1-GP-GP_ASIC2-GB1-AST2A   I105 @BASEBOARD_FAB2_LIB.BASEBOARD_FAB2(SCH_1):PAGE146
U25W11   12     A1 GTL2014_SM-IC,D66151-001    I33 @BASEBOARD_FAB2_LIB.BASEBOARD_FAB2(SCH_1):PAGE268

BMC_PREQ_BUF_N @BASEBOARD_FAB2_LIB.BASEBOARD_FAB2(SCH_1):BMC_PREQ_BUF_N
R25W177    2      B RES_0402-1.00K,1%,1/16W,CHIP,GA    I18 @BASEBOARD_FAB2_LIB.BASEBOARD_FAB2(SCH_1):PAGE269
U25W12    3   B<3> TTL3126_QFNLF-74CBTLV3126,IC,DB    I33 @BASEBOARD_FAB2_LIB.BASEBOARD_FAB2(SCH_1):PAGE269
U25W10   13     A0 GTL2014_SM-IC,D66151-001    I49 @BASEBOARD_FAB2_LIB.BASEBOARD_FAB2(SCH_1):PAGE269

BMC_PREQ_N @BASEBOARD_FAB2_LIB.BASEBOARD_FAB2(SCH_1):BMC_PREQ_N
 U25W4   Y5 GPIOP5_TACH13 AST2520A1-GP-GP_ASIC2-GB1-AST2A   I106 @BASEBOARD_FAB2_LIB.BASEBOARD_FAB2(SCH_1):PAGE147
U25W12    2   A<3> TTL3126_QFNLF-74CBTLV3126,IC,DB    I33 @BASEBOARD_FAB2_LIB.BASEBOARD_FAB2(SCH_1):PAGE269

BMC_PWR_DEBUG_BUF_N @BASEBOARD_FAB2_LIB.BASEBOARD_FAB2(SCH_1):BMC_PWR_DEBUG_BUF_N
R25W178    2      B RES_0402-1.00K,1%,1/16W,CHIP,GA    I19 @BASEBOARD_FAB2_LIB.BASEBOARD_FAB2(SCH_1):PAGE269
U25W10   12     A1 GTL2014_SM-IC,D66151-001    I49 @BASEBOARD_FAB2_LIB.BASEBOARD_FAB2(SCH_1):PAGE269
U25W16   11   B<0> TTL3126_QFNLF-74CBTLV3126,IC,DB    I38 @BASEBOARD_FAB2_LIB.BASEBOARD_FAB2(SCH_1):PAGE268

BMC_PWR_DEBUG_N @BASEBOARD_FAB2_LIB.BASEBOARD_FAB2(SCH_1):BMC_PWR_DEBUG_N
 U25W4   W6 GPIOP6_TACH14 AST2520A1-GP-GP_ASIC2-GB1-AST2A   I106 @BASEBOARD_FAB2_LIB.BASEBOARD_FAB2(SCH_1):PAGE147
U25W16   12   A<0> TTL3126_QFNLF-74CBTLV3126,IC,DB    I38 @BASEBOARD_FAB2_LIB.BASEBOARD_FAB2(SCH_1):PAGE268

BMC_RSMRST_B_N @BASEBOARD_FAB2_LIB.BASEBOARD_FAB2(SCH_1):BMC_RSMRST_B_N
 U25W4   V6 GPIOP7_TACH15 AST2520A1-GP-GP_ASIC2-GB1-AST2A   I106 @BASEBOARD_FAB2_LIB.BASEBOARD_FAB2(SCH_1):PAGE147
R25W181    2      B RES_0402-0.0,5%,1/16W,CHIP,G21A   I173 @BASEBOARD_FAB2_LIB.BASEBOARD_FAB2(SCH_1):PAGE147

BMC_SELF_HW_D_RST @BASEBOARD_FAB2_LIB.BASEBOARD_FAB2(SCH_1):BMC_SELF_HW_D_RST
  R3W1    1      A RES_0402-1.00K,1%,1/16W,CHIP,GA     I2 @BASEBOARD_FAB2_LIB.BASEBOARD_FAB2(SCH_1):PAGE249
  R8W1    1      A RES_0402-0.0,5%,1/16W,CHIP,G21A    I34 @BASEBOARD_FAB2_LIB.BASEBOARD_FAB2(SCH_1):PAGE249
  C8W1    1      1 SC1U16V3KX-2GP_SMD-BCG-SC1U16VA    I52 @BASEBOARD_FAB2_LIB.BASEBOARD_FAB2(SCH_1):PAGE249
 CR3W1    1      C DIODE_SMLF-BAT54WS,IC,C73510-0A    I55 @BASEBOARD_FAB2_LIB.BASEBOARD_FAB2(SCH_1):PAGE249

BMC_SELF_HW_RST @BASEBOARD_FAB2_LIB.BASEBOARD_FAB2(SCH_1):BMC_SELF_HW_RST
 U25W4  T22 GPIOAB2_VPOVS_WDTRST1 AST2520A1-GP-GP_ASIC2-GB1-AST2A   I105 @BASEBOARD_FAB2_LIB.BASEBOARD_FAB2(SCH_1):PAGE146
 CR3W1    2      A DIODE_SMLF-BAT54WS,IC,C73510-0A    I55 @BASEBOARD_FAB2_LIB.BASEBOARD_FAB2(SCH_1):PAGE249

BMC_STRAP_BIT17 @BASEBOARD_FAB2_LIB.BASEBOARD_FAB2(SCH_1):BMC_STRAP_BIT17
 U25W4  U21 GPIOZ4_VPOG6_NORA4 AST2520A1-GP-GP_ASIC2-GB1-AST2A   I104 @BASEBOARD_FAB2_LIB.BASEBOARD_FAB2(SCH_1):PAGE146
R25W101    2      B RES_0402-4.75K,1%,1/16W,EMPTY,A   I241 @BASEBOARD_FAB2_LIB.BASEBOARD_FAB2(SCH_1):PAGE150

BMC_STRAP_BIT18 @BASEBOARD_FAB2_LIB.BASEBOARD_FAB2(SCH_1):BMC_STRAP_BIT18
 U25W4  W22 GPIOZ5_VPOG7_NORA5 AST2520A1-GP-GP_ASIC2-GB1-AST2A   I104 @BASEBOARD_FAB2_LIB.BASEBOARD_FAB2(SCH_1):PAGE146
R25W102    2      B RES_0402-4.75K,1%,1/16W,EMPTY,A   I239 @BASEBOARD_FAB2_LIB.BASEBOARD_FAB2(SCH_1):PAGE150

BMC_STRAP_BIT20 @BASEBOARD_FAB2_LIB.BASEBOARD_FAB2(SCH_1):BMC_STRAP_BIT20
 U25W4  V22 GPIOZ6_VPOG8_NORA6 AST2520A1-GP-GP_ASIC2-GB1-AST2A   I104 @BASEBOARD_FAB2_LIB.BASEBOARD_FAB2(SCH_1):PAGE146
R25W103    2      B RES_0402-4.75K,1%,1/16W,EMPTY,A   I214 @BASEBOARD_FAB2_LIB.BASEBOARD_FAB2(SCH_1):PAGE150

BMC_STRAP_BIT27 @BASEBOARD_FAB2_LIB.BASEBOARD_FAB2(SCH_1):BMC_STRAP_BIT27
 U25W4  W21 GPIOZ7_VPOG9_NORA7 AST2520A1-GP-GP_ASIC2-GB1-AST2A   I104 @BASEBOARD_FAB2_LIB.BASEBOARD_FAB2(SCH_1):PAGE146
R25W104    2      B RES_0402-4.75K,1%,1/16W,CHIP,GA   I215 @BASEBOARD_FAB2_LIB.BASEBOARD_FAB2(SCH_1):PAGE150

BMC_STRAP_BIT3 @BASEBOARD_FAB2_LIB.BASEBOARD_FAB2(SCH_1):BMC_STRAP_BIT3
 U25W4  R19 GPIOS4_VPOB6 AST2520A1-GP-GP_ASIC2-GB1-AST2A   I104 @BASEBOARD_FAB2_LIB.BASEBOARD_FAB2(SCH_1):PAGE146
R25W98    2      B RES_0402-4.75K,1%,1/16W,EMPTY,A   I209 @BASEBOARD_FAB2_LIB.BASEBOARD_FAB2(SCH_1):PAGE150

BMC_STRAP_BIT5 @BASEBOARD_FAB2_LIB.BASEBOARD_FAB2(SCH_1):BMC_STRAP_BIT5
 U25W4  U20 GPIOS6_VPOB8 AST2520A1-GP-GP_ASIC2-GB1-AST2A   I104 @BASEBOARD_FAB2_LIB.BASEBOARD_FAB2(SCH_1):PAGE146
R25W99    2      B RES_0402-4.75K,1%,1/16W,EMPTY,A   I210 @BASEBOARD_FAB2_LIB.BASEBOARD_FAB2(SCH_1):PAGE150

BMC_TCK_MUX_SEL @BASEBOARD_FAB2_LIB.BASEBOARD_FAB2(SCH_1):BMC_TCK_MUX_SEL
 U25W4  T17 GPIOR2_SPI2CS0# AST2520A1-GP-GP_ASIC2-GB1-AST2A   I105 @BASEBOARD_FAB2_LIB.BASEBOARD_FAB2(SCH_1):PAGE146
R25W167    1      A RES_0402-1.00K,1%,1/16W,CHIP,GA    I10 @BASEBOARD_FAB2_LIB.BASEBOARD_FAB2(SCH_1):PAGE269
U25W13    3     IN MAX4564EKA-GP_SCRET-GC1-MAX456A    I53 @BASEBOARD_FAB2_LIB.BASEBOARD_FAB2(SCH_1):PAGE269

BMC_TPM_HW_C_RST @BASEBOARD_FAB2_LIB.BASEBOARD_FAB2(SCH_1):BMC_TPM_HW_C_RST
  Q9W1    1   GATE FET_N_SOT23LF-2N7002,FET,C7925A    I30 @BASEBOARD_FAB2_LIB.BASEBOARD_FAB2(SCH_1):PAGE249
  C8W1    2      2 SC1U16V3KX-2GP_SMD-BCG-SC1U16VA    I52 @BASEBOARD_FAB2_LIB.BASEBOARD_FAB2(SCH_1):PAGE249
  R3W2    1      A RES_0402-100.0K,1%,1/16W,CHIP,A    I56 @BASEBOARD_FAB2_LIB.BASEBOARD_FAB2(SCH_1):PAGE249
  C3W2    1      A CAP_A_0402V-0.1UF,16V,10%,X7R,A    I57 @BASEBOARD_FAB2_LIB.BASEBOARD_FAB2(SCH_1):PAGE249

BMC_VGA_BLUE @BASEBOARD_FAB2_LIB.BASEBOARD_FAB2(SCH_1):BMC_VGA_BLUE
 U25W4   J2   DACB AST2520A1-GP-GP_ASIC2-GB1-AST2A    I95 @BASEBOARD_FAB2_LIB.BASEBOARD_FAB2(SCH_1):PAGE144
R25W123    1      A RES_0402-150.0,1%,1/16W,CHIP,GA   I139 @BASEBOARD_FAB2_LIB.BASEBOARD_FAB2(SCH_1):PAGE144
C25W72    1      A CAP_0402LF-12.0PF,50V,5%,COG,AA     I7 @BASEBOARD_FAB2_LIB.BASEBOARD_FAB2(SCH_1):PAGE255
 L25W1    1      1 IND-68NH-15-GP_DISCRET-GC1-INDA    I76 @BASEBOARD_FAB2_LIB.BASEBOARD_FAB2(SCH_1):PAGE255

BMC_VGA_GREEN @BASEBOARD_FAB2_LIB.BASEBOARD_FAB2(SCH_1):BMC_VGA_GREEN
 U25W4   J3   DACG AST2520A1-GP-GP_ASIC2-GB1-AST2A    I95 @BASEBOARD_FAB2_LIB.BASEBOARD_FAB2(SCH_1):PAGE144
R25W124    1      A RES_0402-150.0,1%,1/16W,CHIP,GA   I140 @BASEBOARD_FAB2_LIB.BASEBOARD_FAB2(SCH_1):PAGE144
C25W73    1      A CAP_0402LF-12.0PF,50V,5%,COG,AA    I11 @BASEBOARD_FAB2_LIB.BASEBOARD_FAB2(SCH_1):PAGE255
 L25W2    1      1 IND-68NH-15-GP_DISCRET-GC1-INDA    I77 @BASEBOARD_FAB2_LIB.BASEBOARD_FAB2(SCH_1):PAGE255

BMC_VGA_HSYNC @BASEBOARD_FAB2_LIB.BASEBOARD_FAB2(SCH_1):BMC_VGA_HSYNC
 U25W4   N5 GPIOJ4_VGAHS AST2520A1-GP-GP_ASIC2-GB1-AST2A   I105 @BASEBOARD_FAB2_LIB.BASEBOARD_FAB2(SCH_1):PAGE146
 U25W7    2      A U74AHCT1G125G-AL5-R-GP-U_TTL-GA   I111 @BASEBOARD_FAB2_LIB.BASEBOARD_FAB2(SCH_1):PAGE255

BMC_VGA_RED @BASEBOARD_FAB2_LIB.BASEBOARD_FAB2(SCH_1):BMC_VGA_RED
 U25W4   J4   DACR AST2520A1-GP-GP_ASIC2-GB1-AST2A    I95 @BASEBOARD_FAB2_LIB.BASEBOARD_FAB2(SCH_1):PAGE144
R25W125    1      A RES_0402-150.0,1%,1/16W,CHIP,GA   I141 @BASEBOARD_FAB2_LIB.BASEBOARD_FAB2(SCH_1):PAGE144
C25W74    1      A CAP_0402LF-12.0PF,50V,5%,COG,AA    I12 @BASEBOARD_FAB2_LIB.BASEBOARD_FAB2(SCH_1):PAGE255
 L25W3    1      1 IND-68NH-15-GP_DISCRET-GC1-INDA    I78 @BASEBOARD_FAB2_LIB.BASEBOARD_FAB2(SCH_1):PAGE255

BMC_VGA_VSYNC @BASEBOARD_FAB2_LIB.BASEBOARD_FAB2(SCH_1):BMC_VGA_VSYNC
 U25W4   R4 GPIOJ5_VGAVS AST2520A1-GP-GP_ASIC2-GB1-AST2A   I105 @BASEBOARD_FAB2_LIB.BASEBOARD_FAB2(SCH_1):PAGE146
 U25W8    2      A U74AHCT1G125G-AL5-R-GP-U_TTL-GA   I112 @BASEBOARD_FAB2_LIB.BASEBOARD_FAB2(SCH_1):PAGE255

BMC_ZQ @BASEBOARD_FAB2_LIB.BASEBOARD_FAB2(SCH_1):BMC_ZQ
 U25W5   F9     ZQ H5AN4G6NAFR-TFC-GP_MEMORY-G2-HA    I49 @BASEBOARD_FAB2_LIB.BASEBOARD_FAB2(SCH_1):PAGE151
R25W117    1      A RES_0402-240,1.0%,1/16W,CHIP,GA   I101 @BASEBOARD_FAB2_LIB.BASEBOARD_FAB2(SCH_1):PAGE151

CLK_100M_AIRMAX8_PE1_DN @BASEBOARD_FAB2_LIB.BASEBOARD_FAB2(SCH_1):CLK_100M_AIRMAX8_PE1_DN
  U7C1  K38 CLKOUT_SRCN<0> LBG_CORE_QAT_EXT_D_BGA1-IC,H91A    I40 @BASEBOARD_FAB2_LIB.BASEBOARD_FAB2(SCH_1):PAGE114
  J1F1   I4 PCIE_CLK_100M_DN DM-FCI-CONN76-8R-GP-U-01_CONN-A   I134 @BASEBOARD_FAB2_LIB.BASEBOARD_FAB2(SCH_1):PAGE181

CLK_100M_AIRMAX8_PE1_DP @BASEBOARD_FAB2_LIB.BASEBOARD_FAB2(SCH_1):CLK_100M_AIRMAX8_PE1_DP
  U7C1  H38 CLKOUT_SRCP<0> LBG_CORE_QAT_EXT_D_BGA1-IC,H91A    I40 @BASEBOARD_FAB2_LIB.BASEBOARD_FAB2(SCH_1):PAGE114
  J1F1   H4 PCIE_CLK_100M_DP DM-FCI-CONN76-8R-GP-U-01_CONN-A   I134 @BASEBOARD_FAB2_LIB.BASEBOARD_FAB2(SCH_1):PAGE181

CLK_100M_BMC_PE_DN @BASEBOARD_FAB2_LIB.BASEBOARD_FAB2(SCH_1):CLK_100M_BMC_PE_DN
  U7C1  B29 CLKOUT_PLAT0N LBG_CORE_QAT_EXT_D_BGA1-IC,H91A    I40 @BASEBOARD_FAB2_LIB.BASEBOARD_FAB2(SCH_1):PAGE114
  R7C2    2      B RES_0402-0.0,5%,1/16W,CHIP,G21A   I192 @BASEBOARD_FAB2_LIB.BASEBOARD_FAB2(SCH_1):PAGE114

CLK_100M_BMC_PE_DP @BASEBOARD_FAB2_LIB.BASEBOARD_FAB2(SCH_1):CLK_100M_BMC_PE_DP
  U7C1  D29 CLKOUT_PLAT0P LBG_CORE_QAT_EXT_D_BGA1-IC,H91A    I40 @BASEBOARD_FAB2_LIB.BASEBOARD_FAB2(SCH_1):PAGE114
  R7C4    2      B RES_0402-0.0,5%,1/16W,CHIP,G21A   I191 @BASEBOARD_FAB2_LIB.BASEBOARD_FAB2(SCH_1):PAGE114

CLK_100M_BMC_PE_R_DN @BASEBOARD_FAB2_LIB.BASEBOARD_FAB2(SCH_1):CLK_100M_BMC_PE_R_DN
R25W60    1      A RES_0402-100.0K,1%,1/16W,CHIP,A    I34 @BASEBOARD_FAB2_LIB.BASEBOARD_FAB2(SCH_1):PAGE145
 U25W4  K22 PEREFCLKN AST2520A1-GP-GP_ASIC2-GB1-AST2A   I117 @BASEBOARD_FAB2_LIB.BASEBOARD_FAB2(SCH_1):PAGE145
  R7C2    1      A RES_0402-0.0,5%,1/16W,CHIP,G21A   I192 @BASEBOARD_FAB2_LIB.BASEBOARD_FAB2(SCH_1):PAGE114

CLK_100M_BMC_PE_R_DP @BASEBOARD_FAB2_LIB.BASEBOARD_FAB2(SCH_1):CLK_100M_BMC_PE_R_DP
R25W61    1      A RES_0402-100.0K,1%,1/16W,CHIP,A    I30 @BASEBOARD_FAB2_LIB.BASEBOARD_FAB2(SCH_1):PAGE145
 U25W4  K21 PEREFCLKP AST2520A1-GP-GP_ASIC2-GB1-AST2A   I117 @BASEBOARD_FAB2_LIB.BASEBOARD_FAB2(SCH_1):PAGE145
  R7C4    1      A RES_0402-0.0,5%,1/16W,CHIP,G21A   I191 @BASEBOARD_FAB2_LIB.BASEBOARD_FAB2(SCH_1):PAGE114

CLK_100M_CPU0_BCLK0_DN @BASEBOARD_FAB2_LIB.BASEBOARD_FAB2(SCH_1):CLK_100M_CPU0_BCLK0_DN
  U5D1 AU24 BCLK0_DN SKX_EXT_B_BGA1-IC,TBD   I259 @BASEBOARD_FAB2_LIB.BASEBOARD_FAB2(SCH_1):PAGE21
 R4D25    2      B RES_0402-27.4,1%,1/16W,CHIP,G2A     I1 @BASEBOARD_FAB2_LIB.BASEBOARD_FAB2(SCH_1):PAGE103
 R6P15    1      A RES_0402-42.2,1.0%,1/16W,EMPTYA   I167 @BASEBOARD_FAB2_LIB.BASEBOARD_FAB2(SCH_1):PAGE103

CLK_100M_CPU0_BCLK0_DP @BASEBOARD_FAB2_LIB.BASEBOARD_FAB2(SCH_1):CLK_100M_CPU0_BCLK0_DP
  U5D1 AW24 BCLK0_DP SKX_EXT_B_BGA1-IC,TBD   I259 @BASEBOARD_FAB2_LIB.BASEBOARD_FAB2(SCH_1):PAGE21
 R4D29    2      B RES_0402-27.4,1%,1/16W,CHIP,G2A    I69 @BASEBOARD_FAB2_LIB.BASEBOARD_FAB2(SCH_1):PAGE103
 R6P17    1      A RES_0402-42.2,1.0%,1/16W,EMPTYA   I165 @BASEBOARD_FAB2_LIB.BASEBOARD_FAB2(SCH_1):PAGE103

CLK_100M_CPU0_BCLK0_R_DN @BASEBOARD_FAB2_LIB.BASEBOARD_FAB2(SCH_1):CLK_100M_CPU0_BCLK0_R_DN
 EU4D2   18 DIF_0N NB3W1200L_LCC-IC,H13585-001     I1 @BASEBOARD_FAB2_LIB.BASEBOARD_FAB2(SCH_1):PAGE102
 R4D25    1      A RES_0402-27.4,1%,1/16W,CHIP,G2A     I1 @BASEBOARD_FAB2_LIB.BASEBOARD_FAB2(SCH_1):PAGE103

CLK_100M_CPU0_BCLK0_R_DP @BASEBOARD_FAB2_LIB.BASEBOARD_FAB2(SCH_1):CLK_100M_CPU0_BCLK0_R_DP
 EU4D2   17 DIF_0P NB3W1200L_LCC-IC,H13585-001     I1 @BASEBOARD_FAB2_LIB.BASEBOARD_FAB2(SCH_1):PAGE102
 R4D29    1      A RES_0402-27.4,1%,1/16W,CHIP,G2A    I69 @BASEBOARD_FAB2_LIB.BASEBOARD_FAB2(SCH_1):PAGE103

CLK_100M_CPU0_BCLK1_DN @BASEBOARD_FAB2_LIB.BASEBOARD_FAB2(SCH_1):CLK_100M_CPU0_BCLK1_DN
  U5D1 CR26 BCLK1_DN SKX_EXT_B_BGA1-IC,TBD   I259 @BASEBOARD_FAB2_LIB.BASEBOARD_FAB2(SCH_1):PAGE21
 R4D20    2      B RES_0402-27.4,1%,1/16W,CHIP,G2A   I119 @BASEBOARD_FAB2_LIB.BASEBOARD_FAB2(SCH_1):PAGE103
 R4D18    1      A RES_0402-42.2,1.0%,1/16W,EMPTYA   I163 @BASEBOARD_FAB2_LIB.BASEBOARD_FAB2(SCH_1):PAGE103

CLK_100M_CPU0_BCLK1_DP @BASEBOARD_FAB2_LIB.BASEBOARD_FAB2(SCH_1):CLK_100M_CPU0_BCLK1_DP
  U5D1 CP27 BCLK1_DP SKX_EXT_B_BGA1-IC,TBD   I259 @BASEBOARD_FAB2_LIB.BASEBOARD_FAB2(SCH_1):PAGE21
 R4D22    2      B RES_0402-27.4,1%,1/16W,CHIP,G2A   I114 @BASEBOARD_FAB2_LIB.BASEBOARD_FAB2(SCH_1):PAGE103
 R4D24    1      A RES_0402-42.2,1.0%,1/16W,EMPTYA   I161 @BASEBOARD_FAB2_LIB.BASEBOARD_FAB2(SCH_1):PAGE103

CLK_100M_CPU0_BCLK1_R_DN @BASEBOARD_FAB2_LIB.BASEBOARD_FAB2(SCH_1):CLK_100M_CPU0_BCLK1_R_DN
 EU4D2   22 DIF_1N NB3W1200L_LCC-IC,H13585-001     I1 @BASEBOARD_FAB2_LIB.BASEBOARD_FAB2(SCH_1):PAGE102
 R4D20    1      A RES_0402-27.4,1%,1/16W,CHIP,G2A   I119 @BASEBOARD_FAB2_LIB.BASEBOARD_FAB2(SCH_1):PAGE103

CLK_100M_CPU0_BCLK1_R_DP @BASEBOARD_FAB2_LIB.BASEBOARD_FAB2(SCH_1):CLK_100M_CPU0_BCLK1_R_DP
 EU4D2   21 DIF_1P NB3W1200L_LCC-IC,H13585-001     I1 @BASEBOARD_FAB2_LIB.BASEBOARD_FAB2(SCH_1):PAGE102
 R4D22    1      A RES_0402-27.4,1%,1/16W,CHIP,G2A   I114 @BASEBOARD_FAB2_LIB.BASEBOARD_FAB2(SCH_1):PAGE103

CLK_100M_CPU0_BCLK2_DN @BASEBOARD_FAB2_LIB.BASEBOARD_FAB2(SCH_1):CLK_100M_CPU0_BCLK2_DN
  U5D1 CT25 BCLK2_DN SKX_EXT_B_BGA1-IC,TBD   I259 @BASEBOARD_FAB2_LIB.BASEBOARD_FAB2(SCH_1):PAGE21
 R4D14    2      B RES_0402-27.4,1%,1/16W,CHIP,G2A   I109 @BASEBOARD_FAB2_LIB.BASEBOARD_FAB2(SCH_1):PAGE103
 R6P12    1      A RES_0402-42.2,1.0%,1/16W,EMPTYA   I159 @BASEBOARD_FAB2_LIB.BASEBOARD_FAB2(SCH_1):PAGE103

CLK_100M_CPU0_BCLK2_DP @BASEBOARD_FAB2_LIB.BASEBOARD_FAB2(SCH_1):CLK_100M_CPU0_BCLK2_DP
  U5D1 CU26 BCLK2_DP SKX_EXT_B_BGA1-IC,TBD   I259 @BASEBOARD_FAB2_LIB.BASEBOARD_FAB2(SCH_1):PAGE21
 R4D17    2      B RES_0402-27.4,1%,1/16W,CHIP,G2A   I104 @BASEBOARD_FAB2_LIB.BASEBOARD_FAB2(SCH_1):PAGE103
 R6P13    1      A RES_0402-42.2,1.0%,1/16W,EMPTYA   I157 @BASEBOARD_FAB2_LIB.BASEBOARD_FAB2(SCH_1):PAGE103

CLK_100M_CPU0_BCLK2_R_DN @BASEBOARD_FAB2_LIB.BASEBOARD_FAB2(SCH_1):CLK_100M_CPU0_BCLK2_R_DN
 EU4D2   27 DIF_2N NB3W1200L_LCC-IC,H13585-001     I1 @BASEBOARD_FAB2_LIB.BASEBOARD_FAB2(SCH_1):PAGE102
 R4D14    1      A RES_0402-27.4,1%,1/16W,CHIP,G2A   I109 @BASEBOARD_FAB2_LIB.BASEBOARD_FAB2(SCH_1):PAGE103

CLK_100M_CPU0_BCLK2_R_DP @BASEBOARD_FAB2_LIB.BASEBOARD_FAB2(SCH_1):CLK_100M_CPU0_BCLK2_R_DP
 EU4D2   26 DIF_2P NB3W1200L_LCC-IC,H13585-001     I1 @BASEBOARD_FAB2_LIB.BASEBOARD_FAB2(SCH_1):PAGE102
 R4D17    1      A RES_0402-27.4,1%,1/16W,CHIP,G2A   I104 @BASEBOARD_FAB2_LIB.BASEBOARD_FAB2(SCH_1):PAGE103

CLK_100M_CPU0_PE_REFCLK_DN @BASEBOARD_FAB2_LIB.BASEBOARD_FAB2(SCH_1):CLK_100M_CPU0_PE_REFCLK_DN
  U5D1 BU24 CD_PE_REFCLK_DN SKX_EXT_B_BGA1-IC,TBD    I61 @BASEBOARD_FAB2_LIB.BASEBOARD_FAB2(SCH_1):PAGE29
 R4D10    2      B RES_0402-27.4,1%,1/16W,CHIP,G2A    I99 @BASEBOARD_FAB2_LIB.BASEBOARD_FAB2(SCH_1):PAGE103
  R6P9    1      A RES_0402-42.2,1.0%,1/16W,EMPTYA   I155 @BASEBOARD_FAB2_LIB.BASEBOARD_FAB2(SCH_1):PAGE103

CLK_100M_CPU0_PE_REFCLK_DP @BASEBOARD_FAB2_LIB.BASEBOARD_FAB2(SCH_1):CLK_100M_CPU0_PE_REFCLK_DP
  U5D1 BW24 CD_PE_REFCLK_DP SKX_EXT_B_BGA1-IC,TBD    I61 @BASEBOARD_FAB2_LIB.BASEBOARD_FAB2(SCH_1):PAGE29
 R4D12    2      B RES_0402-27.4,1%,1/16W,CHIP,G2A    I94 @BASEBOARD_FAB2_LIB.BASEBOARD_FAB2(SCH_1):PAGE103
 R6P11    1      A RES_0402-42.2,1.0%,1/16W,EMPTYA   I153 @BASEBOARD_FAB2_LIB.BASEBOARD_FAB2(SCH_1):PAGE103

CLK_100M_CPU0_PE_REFCLK_R_DN @BASEBOARD_FAB2_LIB.BASEBOARD_FAB2(SCH_1):CLK_100M_CPU0_PE_REFCLK_R_DN
 EU4D2   31 DIF_3N NB3W1200L_LCC-IC,H13585-001     I1 @BASEBOARD_FAB2_LIB.BASEBOARD_FAB2(SCH_1):PAGE102
 R4D10    1      A RES_0402-27.4,1%,1/16W,CHIP,G2A    I99 @BASEBOARD_FAB2_LIB.BASEBOARD_FAB2(SCH_1):PAGE103

CLK_100M_CPU0_PE_REFCLK_R_DP @BASEBOARD_FAB2_LIB.BASEBOARD_FAB2(SCH_1):CLK_100M_CPU0_PE_REFCLK_R_DP
 EU4D2   30 DIF_3P NB3W1200L_LCC-IC,H13585-001     I1 @BASEBOARD_FAB2_LIB.BASEBOARD_FAB2(SCH_1):PAGE102
 R4D12    1      A RES_0402-27.4,1%,1/16W,CHIP,G2A    I94 @BASEBOARD_FAB2_LIB.BASEBOARD_FAB2(SCH_1):PAGE103

CLK_100M_CPU0_RC_REFCLK0_DN @BASEBOARD_FAB2_LIB.BASEBOARD_FAB2(SCH_1):CLK_100M_CPU0_RC_REFCLK0_DN
  U5D1 AP27 RSVD<195> SKX_EXT_B_BGA1-IC,TBD   I204 @BASEBOARD_FAB2_LIB.BASEBOARD_FAB2(SCH_1):PAGE22
  R4D7    2      B RES_0402-27.4,1%,1/16W,CHIP,G2A    I89 @BASEBOARD_FAB2_LIB.BASEBOARD_FAB2(SCH_1):PAGE103
  R6P2    1      A RES_0402-42.2,1.0%,1/16W,EMPTYA   I151 @BASEBOARD_FAB2_LIB.BASEBOARD_FAB2(SCH_1):PAGE103

CLK_100M_CPU0_RC_REFCLK0_DP @BASEBOARD_FAB2_LIB.BASEBOARD_FAB2(SCH_1):CLK_100M_CPU0_RC_REFCLK0_DP
  U5D1 AM27 RSVD<206> SKX_EXT_B_BGA1-IC,TBD   I204 @BASEBOARD_FAB2_LIB.BASEBOARD_FAB2(SCH_1):PAGE22
  R4D8    2      B RES_0402-27.4,1%,1/16W,CHIP,G2A    I84 @BASEBOARD_FAB2_LIB.BASEBOARD_FAB2(SCH_1):PAGE103
  R6P1    1      A RES_0402-42.2,1.0%,1/16W,EMPTYA   I149 @BASEBOARD_FAB2_LIB.BASEBOARD_FAB2(SCH_1):PAGE103

CLK_100M_CPU0_RC_REFCLK0_R_DN @BASEBOARD_FAB2_LIB.BASEBOARD_FAB2(SCH_1):CLK_100M_CPU0_RC_REFCLK0_R_DN
 EU4D2   35 DIF_4N NB3W1200L_LCC-IC,H13585-001     I1 @BASEBOARD_FAB2_LIB.BASEBOARD_FAB2(SCH_1):PAGE102
  R4D7    1      A RES_0402-27.4,1%,1/16W,CHIP,G2A    I89 @BASEBOARD_FAB2_LIB.BASEBOARD_FAB2(SCH_1):PAGE103

CLK_100M_CPU0_RC_REFCLK0_R_DP @BASEBOARD_FAB2_LIB.BASEBOARD_FAB2(SCH_1):CLK_100M_CPU0_RC_REFCLK0_R_DP
 EU4D2   34 DIF_4P NB3W1200L_LCC-IC,H13585-001     I1 @BASEBOARD_FAB2_LIB.BASEBOARD_FAB2(SCH_1):PAGE102
  R4D8    1      A RES_0402-27.4,1%,1/16W,CHIP,G2A    I84 @BASEBOARD_FAB2_LIB.BASEBOARD_FAB2(SCH_1):PAGE103

CLK_100M_CPU0_RC_REFCLK1_DN @BASEBOARD_FAB2_LIB.BASEBOARD_FAB2(SCH_1):CLK_100M_CPU0_RC_REFCLK1_DN
  U5D1 BB25 RSVD<165> SKX_EXT_B_BGA1-IC,TBD    I15 @BASEBOARD_FAB2_LIB.BASEBOARD_FAB2(SCH_1):PAGE36
  R4D5    2      B RES_0402-27.4,1%,1/16W,CHIP,G2A    I79 @BASEBOARD_FAB2_LIB.BASEBOARD_FAB2(SCH_1):PAGE103
  R6P4    1      A RES_0402-42.2,1.0%,1/16W,EMPTYA   I147 @BASEBOARD_FAB2_LIB.BASEBOARD_FAB2(SCH_1):PAGE103

CLK_100M_CPU0_RC_REFCLK1_DP @BASEBOARD_FAB2_LIB.BASEBOARD_FAB2(SCH_1):CLK_100M_CPU0_RC_REFCLK1_DP
  U5D1 BD25 RSVD<153> SKX_EXT_B_BGA1-IC,TBD    I15 @BASEBOARD_FAB2_LIB.BASEBOARD_FAB2(SCH_1):PAGE36
  R4D6    2      B RES_0402-27.4,1%,1/16W,CHIP,G2A    I74 @BASEBOARD_FAB2_LIB.BASEBOARD_FAB2(SCH_1):PAGE103
  R6P3    1      A RES_0402-42.2,1.0%,1/16W,EMPTYA   I145 @BASEBOARD_FAB2_LIB.BASEBOARD_FAB2(SCH_1):PAGE103

CLK_100M_CPU0_RC_REFCLK1_R_DN @BASEBOARD_FAB2_LIB.BASEBOARD_FAB2(SCH_1):CLK_100M_CPU0_RC_REFCLK1_R_DN
 EU4D2   39 DIF_5N NB3W1200L_LCC-IC,H13585-001     I1 @BASEBOARD_FAB2_LIB.BASEBOARD_FAB2(SCH_1):PAGE102
  R4D5    1      A RES_0402-27.4,1%,1/16W,CHIP,G2A    I79 @BASEBOARD_FAB2_LIB.BASEBOARD_FAB2(SCH_1):PAGE103

CLK_100M_CPU0_RC_REFCLK1_R_DP @BASEBOARD_FAB2_LIB.BASEBOARD_FAB2(SCH_1):CLK_100M_CPU0_RC_REFCLK1_R_DP
 EU4D2   38 DIF_5P NB3W1200L_LCC-IC,H13585-001     I1 @BASEBOARD_FAB2_LIB.BASEBOARD_FAB2(SCH_1):PAGE102
  R4D6    1      A RES_0402-27.4,1%,1/16W,CHIP,G2A    I74 @BASEBOARD_FAB2_LIB.BASEBOARD_FAB2(SCH_1):PAGE103

CLK_100M_CPU1_BCLK0_DN @BASEBOARD_FAB2_LIB.BASEBOARD_FAB2(SCH_1):CLK_100M_CPU1_BCLK0_DN
  U2D1 AU24 BCLK0_DN SKX_EXT_B_BGA1-IC,TBD   I172 @BASEBOARD_FAB2_LIB.BASEBOARD_FAB2(SCH_1):PAGE55
  R4D3    2      B RES_0402-27.4,1%,1/16W,CHIP,G2A    I64 @BASEBOARD_FAB2_LIB.BASEBOARD_FAB2(SCH_1):PAGE103
  R6P6    1      A RES_0402-42.2,1.0%,1/16W,EMPTYA   I143 @BASEBOARD_FAB2_LIB.BASEBOARD_FAB2(SCH_1):PAGE103

CLK_100M_CPU1_BCLK0_DP @BASEBOARD_FAB2_LIB.BASEBOARD_FAB2(SCH_1):CLK_100M_CPU1_BCLK0_DP
  U2D1 AW24 BCLK0_DP SKX_EXT_B_BGA1-IC,TBD   I172 @BASEBOARD_FAB2_LIB.BASEBOARD_FAB2(SCH_1):PAGE55
  R4D4    2      B RES_0402-27.4,1%,1/16W,CHIP,G2A    I59 @BASEBOARD_FAB2_LIB.BASEBOARD_FAB2(SCH_1):PAGE103
  R6P5    1      A RES_0402-42.2,1.0%,1/16W,EMPTYA   I141 @BASEBOARD_FAB2_LIB.BASEBOARD_FAB2(SCH_1):PAGE103

CLK_100M_CPU1_BCLK0_R_DN @BASEBOARD_FAB2_LIB.BASEBOARD_FAB2(SCH_1):CLK_100M_CPU1_BCLK0_R_DN
 EU4D2   43 DIF_6N NB3W1200L_LCC-IC,H13585-001     I1 @BASEBOARD_FAB2_LIB.BASEBOARD_FAB2(SCH_1):PAGE102
  R4D3    1      A RES_0402-27.4,1%,1/16W,CHIP,G2A    I64 @BASEBOARD_FAB2_LIB.BASEBOARD_FAB2(SCH_1):PAGE103

CLK_100M_CPU1_BCLK0_R_DP @BASEBOARD_FAB2_LIB.BASEBOARD_FAB2(SCH_1):CLK_100M_CPU1_BCLK0_R_DP
 EU4D2   42 DIF_6P NB3W1200L_LCC-IC,H13585-001     I1 @BASEBOARD_FAB2_LIB.BASEBOARD_FAB2(SCH_1):PAGE102
  R4D4    1      A RES_0402-27.4,1%,1/16W,CHIP,G2A    I59 @BASEBOARD_FAB2_LIB.BASEBOARD_FAB2(SCH_1):PAGE103

CLK_100M_CPU1_BCLK1_DN @BASEBOARD_FAB2_LIB.BASEBOARD_FAB2(SCH_1):CLK_100M_CPU1_BCLK1_DN
  U2D1 CR26 BCLK1_DN SKX_EXT_B_BGA1-IC,TBD   I172 @BASEBOARD_FAB2_LIB.BASEBOARD_FAB2(SCH_1):PAGE55
  R4D1    2      B RES_0402-27.4,1%,1/16W,CHIP,G2A    I54 @BASEBOARD_FAB2_LIB.BASEBOARD_FAB2(SCH_1):PAGE103
  R6P8    1      A RES_0402-42.2,1.0%,1/16W,EMPTYA   I139 @BASEBOARD_FAB2_LIB.BASEBOARD_FAB2(SCH_1):PAGE103

CLK_100M_CPU1_BCLK1_DP @BASEBOARD_FAB2_LIB.BASEBOARD_FAB2(SCH_1):CLK_100M_CPU1_BCLK1_DP
  U2D1 CP27 BCLK1_DP SKX_EXT_B_BGA1-IC,TBD   I172 @BASEBOARD_FAB2_LIB.BASEBOARD_FAB2(SCH_1):PAGE55
  R4D2    2      B RES_0402-27.4,1%,1/16W,CHIP,G2A    I49 @BASEBOARD_FAB2_LIB.BASEBOARD_FAB2(SCH_1):PAGE103
  R6P7    1      A RES_0402-42.2,1.0%,1/16W,EMPTYA   I137 @BASEBOARD_FAB2_LIB.BASEBOARD_FAB2(SCH_1):PAGE103

CLK_100M_CPU1_BCLK1_R_DN @BASEBOARD_FAB2_LIB.BASEBOARD_FAB2(SCH_1):CLK_100M_CPU1_BCLK1_R_DN
 EU4D2   47 DIF_7N NB3W1200L_LCC-IC,H13585-001     I1 @BASEBOARD_FAB2_LIB.BASEBOARD_FAB2(SCH_1):PAGE102
  R4D1    1      A RES_0402-27.4,1%,1/16W,CHIP,G2A    I54 @BASEBOARD_FAB2_LIB.BASEBOARD_FAB2(SCH_1):PAGE103

CLK_100M_CPU1_BCLK1_R_DP @BASEBOARD_FAB2_LIB.BASEBOARD_FAB2(SCH_1):CLK_100M_CPU1_BCLK1_R_DP
 EU4D2   46 DIF_7P NB3W1200L_LCC-IC,H13585-001     I1 @BASEBOARD_FAB2_LIB.BASEBOARD_FAB2(SCH_1):PAGE102
  R4D2    1      A RES_0402-27.4,1%,1/16W,CHIP,G2A    I49 @BASEBOARD_FAB2_LIB.BASEBOARD_FAB2(SCH_1):PAGE103

CLK_100M_CPU1_BCLK2_DN @BASEBOARD_FAB2_LIB.BASEBOARD_FAB2(SCH_1):CLK_100M_CPU1_BCLK2_DN
  U2D1 CT25 BCLK2_DN SKX_EXT_B_BGA1-IC,TBD   I172 @BASEBOARD_FAB2_LIB.BASEBOARD_FAB2(SCH_1):PAGE55
 R4D11    2      B RES_0402-27.4,1%,1/16W,CHIP,G2A    I44 @BASEBOARD_FAB2_LIB.BASEBOARD_FAB2(SCH_1):PAGE103
  R7P2    1      A RES_0402-42.2,1.0%,1/16W,EMPTYA   I135 @BASEBOARD_FAB2_LIB.BASEBOARD_FAB2(SCH_1):PAGE103

CLK_100M_CPU1_BCLK2_DP @BASEBOARD_FAB2_LIB.BASEBOARD_FAB2(SCH_1):CLK_100M_CPU1_BCLK2_DP
  U2D1 CU26 BCLK2_DP SKX_EXT_B_BGA1-IC,TBD   I172 @BASEBOARD_FAB2_LIB.BASEBOARD_FAB2(SCH_1):PAGE55
  R4D9    2      B RES_0402-27.4,1%,1/16W,CHIP,G2A    I39 @BASEBOARD_FAB2_LIB.BASEBOARD_FAB2(SCH_1):PAGE103
  R7P1    1      A RES_0402-42.2,1.0%,1/16W,EMPTYA   I133 @BASEBOARD_FAB2_LIB.BASEBOARD_FAB2(SCH_1):PAGE103

CLK_100M_CPU1_BCLK2_R_DN @BASEBOARD_FAB2_LIB.BASEBOARD_FAB2(SCH_1):CLK_100M_CPU1_BCLK2_R_DN
 EU4D2   51 DIF_8N NB3W1200L_LCC-IC,H13585-001     I1 @BASEBOARD_FAB2_LIB.BASEBOARD_FAB2(SCH_1):PAGE102
 R4D11    1      A RES_0402-27.4,1%,1/16W,CHIP,G2A    I44 @BASEBOARD_FAB2_LIB.BASEBOARD_FAB2(SCH_1):PAGE103

CLK_100M_CPU1_BCLK2_R_DP @BASEBOARD_FAB2_LIB.BASEBOARD_FAB2(SCH_1):CLK_100M_CPU1_BCLK2_R_DP
 EU4D2   50 DIF_8P NB3W1200L_LCC-IC,H13585-001     I1 @BASEBOARD_FAB2_LIB.BASEBOARD_FAB2(SCH_1):PAGE102
  R4D9    1      A RES_0402-27.4,1%,1/16W,CHIP,G2A    I39 @BASEBOARD_FAB2_LIB.BASEBOARD_FAB2(SCH_1):PAGE103

CLK_100M_CPU1_PE_REFCLK_DN @BASEBOARD_FAB2_LIB.BASEBOARD_FAB2(SCH_1):CLK_100M_CPU1_PE_REFCLK_DN
  U2D1 BU24 CD_PE_REFCLK_DN SKX_EXT_B_BGA1-IC,TBD    I23 @BASEBOARD_FAB2_LIB.BASEBOARD_FAB2(SCH_1):PAGE63
 R4D16    2      B RES_0402-27.4,1%,1/16W,CHIP,G2A    I34 @BASEBOARD_FAB2_LIB.BASEBOARD_FAB2(SCH_1):PAGE103
  R7P4    1      A RES_0402-42.2,1.0%,1/16W,EMPTYA   I131 @BASEBOARD_FAB2_LIB.BASEBOARD_FAB2(SCH_1):PAGE103

CLK_100M_CPU1_PE_REFCLK_DP @BASEBOARD_FAB2_LIB.BASEBOARD_FAB2(SCH_1):CLK_100M_CPU1_PE_REFCLK_DP
  U2D1 BW24 CD_PE_REFCLK_DP SKX_EXT_B_BGA1-IC,TBD    I23 @BASEBOARD_FAB2_LIB.BASEBOARD_FAB2(SCH_1):PAGE63
 R4D13    2      B RES_0402-27.4,1%,1/16W,CHIP,G2A    I29 @BASEBOARD_FAB2_LIB.BASEBOARD_FAB2(SCH_1):PAGE103
  R7P3    1      A RES_0402-42.2,1.0%,1/16W,EMPTYA   I129 @BASEBOARD_FAB2_LIB.BASEBOARD_FAB2(SCH_1):PAGE103

CLK_100M_CPU1_PE_REFCLK_R_DN @BASEBOARD_FAB2_LIB.BASEBOARD_FAB2(SCH_1):CLK_100M_CPU1_PE_REFCLK_R_DN
 EU4D2   55 DIF_9N NB3W1200L_LCC-IC,H13585-001     I1 @BASEBOARD_FAB2_LIB.BASEBOARD_FAB2(SCH_1):PAGE102
 R4D16    1      A RES_0402-27.4,1%,1/16W,CHIP,G2A    I34 @BASEBOARD_FAB2_LIB.BASEBOARD_FAB2(SCH_1):PAGE103

CLK_100M_CPU1_PE_REFCLK_R_DP @BASEBOARD_FAB2_LIB.BASEBOARD_FAB2(SCH_1):CLK_100M_CPU1_PE_REFCLK_R_DP
 EU4D2   54 DIF_9P NB3W1200L_LCC-IC,H13585-001     I1 @BASEBOARD_FAB2_LIB.BASEBOARD_FAB2(SCH_1):PAGE102
 R4D13    1      A RES_0402-27.4,1%,1/16W,CHIP,G2A    I29 @BASEBOARD_FAB2_LIB.BASEBOARD_FAB2(SCH_1):PAGE103

CLK_100M_CPU1_RC_REFCLK0_DN @BASEBOARD_FAB2_LIB.BASEBOARD_FAB2(SCH_1):CLK_100M_CPU1_RC_REFCLK0_DN
  U2D1 AP27 RSVD<195> SKX_EXT_B_BGA1-IC,TBD   I169 @BASEBOARD_FAB2_LIB.BASEBOARD_FAB2(SCH_1):PAGE56
 R4D21    2      B RES_0402-27.4,1%,1/16W,CHIP,G2A    I24 @BASEBOARD_FAB2_LIB.BASEBOARD_FAB2(SCH_1):PAGE103
  R7P7    1      A RES_0402-42.2,1.0%,1/16W,EMPTYA   I127 @BASEBOARD_FAB2_LIB.BASEBOARD_FAB2(SCH_1):PAGE103

CLK_100M_CPU1_RC_REFCLK0_DP @BASEBOARD_FAB2_LIB.BASEBOARD_FAB2(SCH_1):CLK_100M_CPU1_RC_REFCLK0_DP
  U2D1 AM27 RSVD<206> SKX_EXT_B_BGA1-IC,TBD   I169 @BASEBOARD_FAB2_LIB.BASEBOARD_FAB2(SCH_1):PAGE56
 R4D19    2      B RES_0402-27.4,1%,1/16W,CHIP,G2A    I19 @BASEBOARD_FAB2_LIB.BASEBOARD_FAB2(SCH_1):PAGE103
  R7P6    1      A RES_0402-42.2,1.0%,1/16W,EMPTYA   I125 @BASEBOARD_FAB2_LIB.BASEBOARD_FAB2(SCH_1):PAGE103

CLK_100M_CPU1_RC_REFCLK0_R_DN @BASEBOARD_FAB2_LIB.BASEBOARD_FAB2(SCH_1):CLK_100M_CPU1_RC_REFCLK0_R_DN
 EU4D2   60 DIF_10N NB3W1200L_LCC-IC,H13585-001     I1 @BASEBOARD_FAB2_LIB.BASEBOARD_FAB2(SCH_1):PAGE102
 R4D21    1      A RES_0402-27.4,1%,1/16W,CHIP,G2A    I24 @BASEBOARD_FAB2_LIB.BASEBOARD_FAB2(SCH_1):PAGE103

CLK_100M_CPU1_RC_REFCLK0_R_DP @BASEBOARD_FAB2_LIB.BASEBOARD_FAB2(SCH_1):CLK_100M_CPU1_RC_REFCLK0_R_DP
 EU4D2   59 DIF_10P NB3W1200L_LCC-IC,H13585-001     I1 @BASEBOARD_FAB2_LIB.BASEBOARD_FAB2(SCH_1):PAGE102
 R4D19    1      A RES_0402-27.4,1%,1/16W,CHIP,G2A    I19 @BASEBOARD_FAB2_LIB.BASEBOARD_FAB2(SCH_1):PAGE103

CLK_100M_CPU1_RC_REFCLK1_DN @BASEBOARD_FAB2_LIB.BASEBOARD_FAB2(SCH_1):CLK_100M_CPU1_RC_REFCLK1_DN
  U2D1 BB25 RSVD<165> SKX_EXT_B_BGA1-IC,TBD     I9 @BASEBOARD_FAB2_LIB.BASEBOARD_FAB2(SCH_1):PAGE70
 R4D28    2      B RES_0402-27.4,1%,1/16W,CHIP,G2A    I14 @BASEBOARD_FAB2_LIB.BASEBOARD_FAB2(SCH_1):PAGE103
 R7P12    1      A RES_0402-42.2,1.0%,1/16W,EMPTYA   I123 @BASEBOARD_FAB2_LIB.BASEBOARD_FAB2(SCH_1):PAGE103

CLK_100M_CPU1_RC_REFCLK1_DP @BASEBOARD_FAB2_LIB.BASEBOARD_FAB2(SCH_1):CLK_100M_CPU1_RC_REFCLK1_DP
  U2D1 BD25 RSVD<153> SKX_EXT_B_BGA1-IC,TBD     I9 @BASEBOARD_FAB2_LIB.BASEBOARD_FAB2(SCH_1):PAGE70
 R4D23    2      B RES_0402-27.4,1%,1/16W,CHIP,G2A     I9 @BASEBOARD_FAB2_LIB.BASEBOARD_FAB2(SCH_1):PAGE103
  R7P9    1      A RES_0402-42.2,1.0%,1/16W,EMPTYA   I121 @BASEBOARD_FAB2_LIB.BASEBOARD_FAB2(SCH_1):PAGE103

CLK_100M_CPU1_RC_REFCLK1_R_DN @BASEBOARD_FAB2_LIB.BASEBOARD_FAB2(SCH_1):CLK_100M_CPU1_RC_REFCLK1_R_DN
 EU4D2   64 DIF_11N NB3W1200L_LCC-IC,H13585-001     I1 @BASEBOARD_FAB2_LIB.BASEBOARD_FAB2(SCH_1):PAGE102
 R4D28    1      A RES_0402-27.4,1%,1/16W,CHIP,G2A    I14 @BASEBOARD_FAB2_LIB.BASEBOARD_FAB2(SCH_1):PAGE103

CLK_100M_CPU1_RC_REFCLK1_R_DP @BASEBOARD_FAB2_LIB.BASEBOARD_FAB2(SCH_1):CLK_100M_CPU1_RC_REFCLK1_R_DP
 EU4D2   63 DIF_11P NB3W1200L_LCC-IC,H13585-001     I1 @BASEBOARD_FAB2_LIB.BASEBOARD_FAB2(SCH_1):PAGE102
 R4D23    1      A RES_0402-27.4,1%,1/16W,CHIP,G2A     I9 @BASEBOARD_FAB2_LIB.BASEBOARD_FAB2(SCH_1):PAGE103

CLK_100M_DB1200_DN @BASEBOARD_FAB2_LIB.BASEBOARD_FAB2(SCH_1):CLK_100M_DB1200_DN
 EU4D2   10 CLK_INN NB3W1200L_LCC-IC,H13585-001     I1 @BASEBOARD_FAB2_LIB.BASEBOARD_FAB2(SCH_1):PAGE102
  U7C1  K35 CLKOUT_SRCN<1> LBG_CORE_QAT_EXT_D_BGA1-IC,H91A    I40 @BASEBOARD_FAB2_LIB.BASEBOARD_FAB2(SCH_1):PAGE114

CLK_100M_DB1200_DP @BASEBOARD_FAB2_LIB.BASEBOARD_FAB2(SCH_1):CLK_100M_DB1200_DP
 EU4D2    9 CLK_INP NB3W1200L_LCC-IC,H13585-001     I1 @BASEBOARD_FAB2_LIB.BASEBOARD_FAB2(SCH_1):PAGE102
  U7C1  H35 CLKOUT_SRCP<1> LBG_CORE_QAT_EXT_D_BGA1-IC,H91A    I40 @BASEBOARD_FAB2_LIB.BASEBOARD_FAB2(SCH_1):PAGE114

CLK_100M_M2_DN @BASEBOARD_FAB2_LIB.BASEBOARD_FAB2(SCH_1):CLK_100M_M2_DN
  U7C1  K27 CLKOUT_SRCN<15> LBG_CORE_QAT_EXT_D_BGA1-IC,H91A    I40 @BASEBOARD_FAB2_LIB.BASEBOARD_FAB2(SCH_1):PAGE114
  J8F1   53     53 SKT-MINI67P-41-GP_SOCKET-G4-SKA   I143 @BASEBOARD_FAB2_LIB.BASEBOARD_FAB2(SCH_1):PAGE185

CLK_100M_M2_DP @BASEBOARD_FAB2_LIB.BASEBOARD_FAB2(SCH_1):CLK_100M_M2_DP
  U7C1  H27 CLKOUT_SRCP<15> LBG_CORE_QAT_EXT_D_BGA1-IC,H91A    I40 @BASEBOARD_FAB2_LIB.BASEBOARD_FAB2(SCH_1):PAGE114
  J8F1   55     55 SKT-MINI67P-41-GP_SOCKET-G4-SKA   I143 @BASEBOARD_FAB2_LIB.BASEBOARD_FAB2(SCH_1):PAGE185

CLK_100M_MEZZ1_DN @BASEBOARD_FAB2_LIB.BASEBOARD_FAB2(SCH_1):CLK_100M_MEZZ1_DN
  U7C1  D31 CLKOUT_SRCN<8> LBG_CORE_QAT_EXT_D_BGA1-IC,H91A    I40 @BASEBOARD_FAB2_LIB.BASEBOARD_FAB2(SCH_1):PAGE114
  J9B3   50   IO50 SCONN120_A28699018_SM-SCONN,A2A   I336 @BASEBOARD_FAB2_LIB.BASEBOARD_FAB2(SCH_1):PAGE186

CLK_100M_MEZZ1_DP @BASEBOARD_FAB2_LIB.BASEBOARD_FAB2(SCH_1):CLK_100M_MEZZ1_DP
  U7C1  B31 CLKOUT_SRCP<8> LBG_CORE_QAT_EXT_D_BGA1-IC,H91A    I40 @BASEBOARD_FAB2_LIB.BASEBOARD_FAB2(SCH_1):PAGE114
  J9B3   48   IO48 SCONN120_A28699018_SM-SCONN,A2A   I336 @BASEBOARD_FAB2_LIB.BASEBOARD_FAB2(SCH_1):PAGE186

CLK_100M_MEZZ2_DN @BASEBOARD_FAB2_LIB.BASEBOARD_FAB2(SCH_1):CLK_100M_MEZZ2_DN
  U7C1  J26 CLKOUT_SRCN<9> LBG_CORE_QAT_EXT_D_BGA1-IC,H91A    I40 @BASEBOARD_FAB2_LIB.BASEBOARD_FAB2(SCH_1):PAGE114
  J9B3   53   IO53 SCONN120_A28699018_SM-SCONN,A2A   I336 @BASEBOARD_FAB2_LIB.BASEBOARD_FAB2(SCH_1):PAGE186

CLK_100M_MEZZ2_DP @BASEBOARD_FAB2_LIB.BASEBOARD_FAB2(SCH_1):CLK_100M_MEZZ2_DP
  U7C1  G26 CLKOUT_SRCP<9> LBG_CORE_QAT_EXT_D_BGA1-IC,H91A    I40 @BASEBOARD_FAB2_LIB.BASEBOARD_FAB2(SCH_1):PAGE114
  J9B3   51   IO51 SCONN120_A28699018_SM-SCONN,A2A   I336 @BASEBOARD_FAB2_LIB.BASEBOARD_FAB2(SCH_1):PAGE186

CLK_100M_MEZZ3_DN @BASEBOARD_FAB2_LIB.BASEBOARD_FAB2(SCH_1):CLK_100M_MEZZ3_DN
  U7C1  B23 CLKOUT_SRCN<10> LBG_CORE_QAT_EXT_D_BGA1-IC,H91A    I40 @BASEBOARD_FAB2_LIB.BASEBOARD_FAB2(SCH_1):PAGE114
  J8E3   71   IO71 SCONN80_E67482007_SM-CONN,E674A   I119 @BASEBOARD_FAB2_LIB.BASEBOARD_FAB2(SCH_1):PAGE187

CLK_100M_MEZZ3_DP @BASEBOARD_FAB2_LIB.BASEBOARD_FAB2(SCH_1):CLK_100M_MEZZ3_DP
  U7C1  D23 CLKOUT_SRCP<10> LBG_CORE_QAT_EXT_D_BGA1-IC,H91A    I40 @BASEBOARD_FAB2_LIB.BASEBOARD_FAB2(SCH_1):PAGE114
  J8E3   69   IO69 SCONN80_E67482007_SM-CONN,E674A   I119 @BASEBOARD_FAB2_LIB.BASEBOARD_FAB2(SCH_1):PAGE187

CLK_100M_MEZZ4_DN @BASEBOARD_FAB2_LIB.BASEBOARD_FAB2(SCH_1):CLK_100M_MEZZ4_DN
  U7C1  B21 CLKOUT_SRCN<11> LBG_CORE_QAT_EXT_D_BGA1-IC,H91A    I40 @BASEBOARD_FAB2_LIB.BASEBOARD_FAB2(SCH_1):PAGE114
  J8E3   76   IO76 SCONN80_E67482007_SM-CONN,E674A   I119 @BASEBOARD_FAB2_LIB.BASEBOARD_FAB2(SCH_1):PAGE187

CLK_100M_MEZZ4_DP @BASEBOARD_FAB2_LIB.BASEBOARD_FAB2(SCH_1):CLK_100M_MEZZ4_DP
  U7C1  D21 CLKOUT_SRCP<11> LBG_CORE_QAT_EXT_D_BGA1-IC,H91A    I40 @BASEBOARD_FAB2_LIB.BASEBOARD_FAB2(SCH_1):PAGE114
  J8E3   74   IO74 SCONN80_E67482007_SM-CONN,E674A   I119 @BASEBOARD_FAB2_LIB.BASEBOARD_FAB2(SCH_1):PAGE187

CLK_100M_PCH_SLOTX24_S0_DN @BASEBOARD_FAB2_LIB.BASEBOARD_FAB2(SCH_1):CLK_100M_PCH_SLOTX24_S0_DN
  J8G1   41   IO41 SCONN200_H68296001_SM-CONN,H68A   I258 @BASEBOARD_FAB2_LIB.BASEBOARD_FAB2(SCH_1):PAGE108
  U7C1  J33 CLKOUT_SRCN<2> LBG_CORE_QAT_EXT_D_BGA1-IC,H91A    I40 @BASEBOARD_FAB2_LIB.BASEBOARD_FAB2(SCH_1):PAGE114

CLK_100M_PCH_SLOTX24_S0_DP @BASEBOARD_FAB2_LIB.BASEBOARD_FAB2(SCH_1):CLK_100M_PCH_SLOTX24_S0_DP
  J8G1   39   IO39 SCONN200_H68296001_SM-CONN,H68A   I258 @BASEBOARD_FAB2_LIB.BASEBOARD_FAB2(SCH_1):PAGE108
  U7C1  G33 CLKOUT_SRCP<2> LBG_CORE_QAT_EXT_D_BGA1-IC,H91A    I40 @BASEBOARD_FAB2_LIB.BASEBOARD_FAB2(SCH_1):PAGE114

CLK_100M_PCH_SLOTX24_S1_DN @BASEBOARD_FAB2_LIB.BASEBOARD_FAB2(SCH_1):CLK_100M_PCH_SLOTX24_S1_DN
  J8G1   44   IO44 SCONN200_H68296001_SM-CONN,H68A   I258 @BASEBOARD_FAB2_LIB.BASEBOARD_FAB2(SCH_1):PAGE108
  U7C1  K42 CLKOUT_SRCN<3> LBG_CORE_QAT_EXT_D_BGA1-IC,H91A    I40 @BASEBOARD_FAB2_LIB.BASEBOARD_FAB2(SCH_1):PAGE114

CLK_100M_PCH_SLOTX24_S1_DP @BASEBOARD_FAB2_LIB.BASEBOARD_FAB2(SCH_1):CLK_100M_PCH_SLOTX24_S1_DP
  J8G1   42   IO42 SCONN200_H68296001_SM-CONN,H68A   I258 @BASEBOARD_FAB2_LIB.BASEBOARD_FAB2(SCH_1):PAGE108
  U7C1  H42 CLKOUT_SRCP<3> LBG_CORE_QAT_EXT_D_BGA1-IC,H91A    I40 @BASEBOARD_FAB2_LIB.BASEBOARD_FAB2(SCH_1):PAGE114

CLK_100M_PCH_SLOTX24_S2_DN @BASEBOARD_FAB2_LIB.BASEBOARD_FAB2(SCH_1):CLK_100M_PCH_SLOTX24_S2_DN
  J8G1   50   IO50 SCONN200_H68296001_SM-CONN,H68A   I258 @BASEBOARD_FAB2_LIB.BASEBOARD_FAB2(SCH_1):PAGE108
  U7C1  A28 CLKOUT_SRCN<4> LBG_CORE_QAT_EXT_D_BGA1-IC,H91A    I40 @BASEBOARD_FAB2_LIB.BASEBOARD_FAB2(SCH_1):PAGE114

CLK_100M_PCH_SLOTX24_S2_DP @BASEBOARD_FAB2_LIB.BASEBOARD_FAB2(SCH_1):CLK_100M_PCH_SLOTX24_S2_DP
  J8G1   48   IO48 SCONN200_H68296001_SM-CONN,H68A   I258 @BASEBOARD_FAB2_LIB.BASEBOARD_FAB2(SCH_1):PAGE108
  U7C1  C28 CLKOUT_SRCP<4> LBG_CORE_QAT_EXT_D_BGA1-IC,H91A    I40 @BASEBOARD_FAB2_LIB.BASEBOARD_FAB2(SCH_1):PAGE114

CLK_100M_PCH_SLOTX24_S3_DN @BASEBOARD_FAB2_LIB.BASEBOARD_FAB2(SCH_1):CLK_100M_PCH_SLOTX24_S3_DN
  J8G1   47   IO47 SCONN200_H68296001_SM-CONN,H68A   I258 @BASEBOARD_FAB2_LIB.BASEBOARD_FAB2(SCH_1):PAGE108
  U7C1  J40 CLKOUT_SRCN<5> LBG_CORE_QAT_EXT_D_BGA1-IC,H91A    I40 @BASEBOARD_FAB2_LIB.BASEBOARD_FAB2(SCH_1):PAGE114

CLK_100M_PCH_SLOTX24_S3_DP @BASEBOARD_FAB2_LIB.BASEBOARD_FAB2(SCH_1):CLK_100M_PCH_SLOTX24_S3_DP
  J8G1   45   IO45 SCONN200_H68296001_SM-CONN,H68A   I258 @BASEBOARD_FAB2_LIB.BASEBOARD_FAB2(SCH_1):PAGE108
  U7C1  G40 CLKOUT_SRCP<5> LBG_CORE_QAT_EXT_D_BGA1-IC,H91A    I40 @BASEBOARD_FAB2_LIB.BASEBOARD_FAB2(SCH_1):PAGE114

CLK_100M_PCH_SLOTX24_S4_DN @BASEBOARD_FAB2_LIB.BASEBOARD_FAB2(SCH_1):CLK_100M_PCH_SLOTX24_S4_DN
  J8G1   38   IO38 SCONN200_H68296001_SM-CONN,H68A   I258 @BASEBOARD_FAB2_LIB.BASEBOARD_FAB2(SCH_1):PAGE108
  U7C1  D33 CLKOUT_SRCN<6> LBG_CORE_QAT_EXT_D_BGA1-IC,H91A    I40 @BASEBOARD_FAB2_LIB.BASEBOARD_FAB2(SCH_1):PAGE114

CLK_100M_PCH_SLOTX24_S4_DP @BASEBOARD_FAB2_LIB.BASEBOARD_FAB2(SCH_1):CLK_100M_PCH_SLOTX24_S4_DP
  J8G1   36   IO36 SCONN200_H68296001_SM-CONN,H68A   I258 @BASEBOARD_FAB2_LIB.BASEBOARD_FAB2(SCH_1):PAGE108
  U7C1  B33 CLKOUT_SRCP<6> LBG_CORE_QAT_EXT_D_BGA1-IC,H91A    I40 @BASEBOARD_FAB2_LIB.BASEBOARD_FAB2(SCH_1):PAGE114

CLK_100M_PCH_SLOTX24_S5_DN @BASEBOARD_FAB2_LIB.BASEBOARD_FAB2(SCH_1):CLK_100M_PCH_SLOTX24_S5_DN
  J8G1   35   IO35 SCONN200_H68296001_SM-CONN,H68A   I258 @BASEBOARD_FAB2_LIB.BASEBOARD_FAB2(SCH_1):PAGE108
  U7C1  H31 CLKOUT_SRCN<7> LBG_CORE_QAT_EXT_D_BGA1-IC,H91A    I40 @BASEBOARD_FAB2_LIB.BASEBOARD_FAB2(SCH_1):PAGE114

CLK_100M_PCH_SLOTX24_S5_DP @BASEBOARD_FAB2_LIB.BASEBOARD_FAB2(SCH_1):CLK_100M_PCH_SLOTX24_S5_DP
  J8G1   33   IO33 SCONN200_H68296001_SM-CONN,H68A   I258 @BASEBOARD_FAB2_LIB.BASEBOARD_FAB2(SCH_1):PAGE108
  U7C1  K31 CLKOUT_SRCP<7> LBG_CORE_QAT_EXT_D_BGA1-IC,H91A    I40 @BASEBOARD_FAB2_LIB.BASEBOARD_FAB2(SCH_1):PAGE114

CLK_100M_PCH_XDP_DN @BASEBOARD_FAB2_LIB.BASEBOARD_FAB2(SCH_1):CLK_100M_PCH_XDP_DN
  J9A3   42   IO42 SCONN60_C21100002_SMLF-CONN,C2A    I26 @BASEBOARD_FAB2_LIB.BASEBOARD_FAB2(SCH_1):PAGE111
  U7C1  A39 CLKOUT_ITPXDPN LBG_CORE_QAT_EXT_D_BGA1-IC,H91A    I40 @BASEBOARD_FAB2_LIB.BASEBOARD_FAB2(SCH_1):PAGE114

CLK_100M_PCH_XDP_DP @BASEBOARD_FAB2_LIB.BASEBOARD_FAB2(SCH_1):CLK_100M_PCH_XDP_DP
  J9A3   40   IO40 SCONN60_C21100002_SMLF-CONN,C2A    I26 @BASEBOARD_FAB2_LIB.BASEBOARD_FAB2(SCH_1):PAGE111
  U7C1  C39 CLKOUT_ITPXDPP LBG_CORE_QAT_EXT_D_BGA1-IC,H91A    I40 @BASEBOARD_FAB2_LIB.BASEBOARD_FAB2(SCH_1):PAGE114

CLK_100M_SPRV_DN @BASEBOARD_FAB2_LIB.BASEBOARD_FAB2(SCH_1):CLK_100M_SPRV_DN
  U7C1  C20 CLKOUT_SRCN<14> LBG_CORE_QAT_EXT_D_BGA1-IC,H91A    I40 @BASEBOARD_FAB2_LIB.BASEBOARD_FAB2(SCH_1):PAGE114
 EU9E1   25 PECLKN SPRINGVILLE_SM1-IC,G47144-004    I72 @BASEBOARD_FAB2_LIB.BASEBOARD_FAB2(SCH_1):PAGE139

CLK_100M_SPRV_DP @BASEBOARD_FAB2_LIB.BASEBOARD_FAB2(SCH_1):CLK_100M_SPRV_DP
  U7C1  A20 CLKOUT_SRCP<14> LBG_CORE_QAT_EXT_D_BGA1-IC,H91A    I40 @BASEBOARD_FAB2_LIB.BASEBOARD_FAB2(SCH_1):PAGE114
 EU9E1   26 PECLKP SPRINGVILLE_SM1-IC,G47144-004    I72 @BASEBOARD_FAB2_LIB.BASEBOARD_FAB2(SCH_1):PAGE139

CLK_156M_OSC_BRD_CPU0_DN @BASEBOARD_FAB2_LIB.BASEBOARD_FAB2(SCH_1):CLK_156M_OSC_BRD_CPU0_DN
  R6F7    1      A RES_0402-0.0,5%,1/16W,CHIP,G21A    I67 @BASEBOARD_FAB2_LIB.BASEBOARD_FAB2(SCH_1):PAGE104
  Y6F1    5  OUT_N OSC_C_6P10-156.25MHZ,OSC,G6383A    I71 @BASEBOARD_FAB2_LIB.BASEBOARD_FAB2(SCH_1):PAGE104

CLK_156M_OSC_BRD_CPU0_DP @BASEBOARD_FAB2_LIB.BASEBOARD_FAB2(SCH_1):CLK_156M_OSC_BRD_CPU0_DP
  R6F9    1      A RES_0402-0.0,5%,1/16W,CHIP,G21A    I68 @BASEBOARD_FAB2_LIB.BASEBOARD_FAB2(SCH_1):PAGE104
  Y6F1    4    OUT OSC_C_6P10-156.25MHZ,OSC,G6383A    I71 @BASEBOARD_FAB2_LIB.BASEBOARD_FAB2(SCH_1):PAGE104

CLK_156M_OSC_BRD_CPU1_DN @BASEBOARD_FAB2_LIB.BASEBOARD_FAB2(SCH_1):CLK_156M_OSC_BRD_CPU1_DN
  R3F2    1      A RES_0402-0.0,5%,1/16W,CHIP,G21A    I69 @BASEBOARD_FAB2_LIB.BASEBOARD_FAB2(SCH_1):PAGE104
  Y3F1    5  OUT_N OSC_C_6P10-156.25MHZ,OSC,G6383A    I72 @BASEBOARD_FAB2_LIB.BASEBOARD_FAB2(SCH_1):PAGE104

CLK_156M_OSC_BRD_CPU1_DP @BASEBOARD_FAB2_LIB.BASEBOARD_FAB2(SCH_1):CLK_156M_OSC_BRD_CPU1_DP
  R3F4    1      A RES_0402-0.0,5%,1/16W,CHIP,G21A    I70 @BASEBOARD_FAB2_LIB.BASEBOARD_FAB2(SCH_1):PAGE104
  Y3F1    4    OUT OSC_C_6P10-156.25MHZ,OSC,G6383A    I72 @BASEBOARD_FAB2_LIB.BASEBOARD_FAB2(SCH_1):PAGE104

CLK_156M_OSC_CPU0_HFI_DN @BASEBOARD_FAB2_LIB.BASEBOARD_FAB2(SCH_1):CLK_156M_OSC_CPU0_HFI_DN
  U5D1 BE16 CD_HFI_REFCLK_DN SKX_EXT_B_BGA1-IC,TBD    I61 @BASEBOARD_FAB2_LIB.BASEBOARD_FAB2(SCH_1):PAGE29
  R6F6    2      B RES_0402-0.0,5%,1/16W,EMPTY,G2A    I41 @BASEBOARD_FAB2_LIB.BASEBOARD_FAB2(SCH_1):PAGE104
  R6F7    2      B RES_0402-0.0,5%,1/16W,CHIP,G21A    I67 @BASEBOARD_FAB2_LIB.BASEBOARD_FAB2(SCH_1):PAGE104

CLK_156M_OSC_CPU0_HFI_DP @BASEBOARD_FAB2_LIB.BASEBOARD_FAB2(SCH_1):CLK_156M_OSC_CPU0_HFI_DP
  U5D1 BG16 CD_HFI_REFCLK_DP SKX_EXT_B_BGA1-IC,TBD    I61 @BASEBOARD_FAB2_LIB.BASEBOARD_FAB2(SCH_1):PAGE29
  R6F8    2      B RES_0402-0.0,5%,1/16W,EMPTY,G2A    I37 @BASEBOARD_FAB2_LIB.BASEBOARD_FAB2(SCH_1):PAGE104
  R6F9    2      B RES_0402-0.0,5%,1/16W,CHIP,G21A    I68 @BASEBOARD_FAB2_LIB.BASEBOARD_FAB2(SCH_1):PAGE104

CLK_156M_OSC_CPU1_HFI_DN @BASEBOARD_FAB2_LIB.BASEBOARD_FAB2(SCH_1):CLK_156M_OSC_CPU1_HFI_DN
  U2D1 BE16 CD_HFI_REFCLK_DN SKX_EXT_B_BGA1-IC,TBD    I23 @BASEBOARD_FAB2_LIB.BASEBOARD_FAB2(SCH_1):PAGE63
  R3F1    2      B RES_0402-0.0,5%,1/16W,EMPTY,G2A    I51 @BASEBOARD_FAB2_LIB.BASEBOARD_FAB2(SCH_1):PAGE104
  R3F2    2      B RES_0402-0.0,5%,1/16W,CHIP,G21A    I69 @BASEBOARD_FAB2_LIB.BASEBOARD_FAB2(SCH_1):PAGE104

CLK_156M_OSC_CPU1_HFI_DP @BASEBOARD_FAB2_LIB.BASEBOARD_FAB2(SCH_1):CLK_156M_OSC_CPU1_HFI_DP
  U2D1 BG16 CD_HFI_REFCLK_DP SKX_EXT_B_BGA1-IC,TBD    I23 @BASEBOARD_FAB2_LIB.BASEBOARD_FAB2(SCH_1):PAGE63
  R3F3    2      B RES_0402-0.0,5%,1/16W,EMPTY,G2A    I53 @BASEBOARD_FAB2_LIB.BASEBOARD_FAB2(SCH_1):PAGE104
  R3F4    2      B RES_0402-0.0,5%,1/16W,CHIP,G21A    I70 @BASEBOARD_FAB2_LIB.BASEBOARD_FAB2(SCH_1):PAGE104

CLK_24M_25M_BMC_CLKIN @BASEBOARD_FAB2_LIB.BASEBOARD_FAB2(SCH_1):CLK_24M_25M_BMC_CLKIN
 R9F60    2      B RES_0402-0.0,5%,1/16W,EMPTY,G2A    I10 @BASEBOARD_FAB2_LIB.BASEBOARD_FAB2(SCH_1):PAGE145
 R9F62    2      B RES_0402-0.0,5%,1/16W,CHIP,G21A    I11 @BASEBOARD_FAB2_LIB.BASEBOARD_FAB2(SCH_1):PAGE145
 U25W4  W18  CLKIN AST2520A1-GP-GP_ASIC2-GB1-AST2A   I117 @BASEBOARD_FAB2_LIB.BASEBOARD_FAB2(SCH_1):PAGE145

CLK_24M_BMC_CLKIN_R @BASEBOARD_FAB2_LIB.BASEBOARD_FAB2(SCH_1):CLK_24M_BMC_CLKIN_R
  Y9F2    3    OUT OSC_C_SM4-24MHZ,OSC,D34520-021     I8 @BASEBOARD_FAB2_LIB.BASEBOARD_FAB2(SCH_1):PAGE145
 R9F62    1      A RES_0402-0.0,5%,1/16W,CHIP,G21A    I11 @BASEBOARD_FAB2_LIB.BASEBOARD_FAB2(SCH_1):PAGE145

CLK_24M_BMC_LPC @BASEBOARD_FAB2_LIB.BASEBOARD_FAB2(SCH_1):CLK_24M_BMC_LPC
 R7C26    1      A RES_0402-33.2,1%,1/16W,CHIP,G2A   I189 @BASEBOARD_FAB2_LIB.BASEBOARD_FAB2(SCH_1):PAGE119
R25W66    1      A RES_0402-100.0K,1%,1/16W,CHIP,A    I76 @BASEBOARD_FAB2_LIB.BASEBOARD_FAB2(SCH_1):PAGE146
 U25W4  C22 GPIOAC4_ESPICK_LCLK AST2520A1-GP-GP_ASIC2-GB1-AST2A   I105 @BASEBOARD_FAB2_LIB.BASEBOARD_FAB2(SCH_1):PAGE146

CLK_24M_BMC_LPC_R @BASEBOARD_FAB2_LIB.BASEBOARD_FAB2(SCH_1):CLK_24M_BMC_LPC_R
  U7C1   R3 GPP_A9_CLKOUT_LPC0_ESPI_CLK LBG_CORE_QAT_EXT_D_BGA1-IC,H91A   I115 @BASEBOARD_FAB2_LIB.BASEBOARD_FAB2(SCH_1):PAGE119
 R7C26    2      B RES_0402-33.2,1%,1/16W,CHIP,G2A   I189 @BASEBOARD_FAB2_LIB.BASEBOARD_FAB2(SCH_1):PAGE119

CLK_25M_BMC @BASEBOARD_FAB2_LIB.BASEBOARD_FAB2(SCH_1):CLK_25M_BMC
 R8F29    2      B RES_0402-33.2,1%,1/16W,CHIP,G2A    I20 @BASEBOARD_FAB2_LIB.BASEBOARD_FAB2(SCH_1):PAGE101
 R9F60    1      A RES_0402-0.0,5%,1/16W,EMPTY,G2A    I10 @BASEBOARD_FAB2_LIB.BASEBOARD_FAB2(SCH_1):PAGE145

CLK_25M_BMC_R @BASEBOARD_FAB2_LIB.BASEBOARD_FAB2(SCH_1):CLK_25M_BMC_R
 R8F29    1      A RES_0402-33.2,1%,1/16W,CHIP,G2A    I20 @BASEBOARD_FAB2_LIB.BASEBOARD_FAB2(SCH_1):PAGE101
 EU8F2   16 25MHZ_0 ICS9FGP204_MLFP-IC,E95226-001    I34 @BASEBOARD_FAB2_LIB.BASEBOARD_FAB2(SCH_1):PAGE101

CLK_25M_CPLD @BASEBOARD_FAB2_LIB.BASEBOARD_FAB2(SCH_1):CLK_25M_CPLD
 R2T47    2      B RES_0402-33.2,1%,1/16W,CHIP,G2A   I130 @BASEBOARD_FAB2_LIB.BASEBOARD_FAB2(SCH_1):PAGE101
  U8D7   L2 PL12A_PCLKT3_0 LCMXO2_A_256BGA-IC,H63395-001   I179 @BASEBOARD_FAB2_LIB.BASEBOARD_FAB2(SCH_1):PAGE190

CLK_25M_CPLD_R @BASEBOARD_FAB2_LIB.BASEBOARD_FAB2(SCH_1):CLK_25M_CPLD_R
 EU8F2   17 25MHZ_1 ICS9FGP204_MLFP-IC,E95226-001    I34 @BASEBOARD_FAB2_LIB.BASEBOARD_FAB2(SCH_1):PAGE101
 R2T47    1      A RES_0402-33.2,1%,1/16W,CHIP,G2A   I130 @BASEBOARD_FAB2_LIB.BASEBOARD_FAB2(SCH_1):PAGE101

CLK_322M_156M_CPU0_OSC_VRM_DN @BASEBOARD_FAB2_LIB.BASEBOARD_FAB2(SCH_1):CLK_322M_156M_CPU0_OSC_VRM_DN
  R6F6    1      A RES_0402-0.0,5%,1/16W,EMPTY,G2A    I41 @BASEBOARD_FAB2_LIB.BASEBOARD_FAB2(SCH_1):PAGE104
 R6F10    1      A RES_0402-0.0,5%,1/16W,EMPTY,G2A    I78 @BASEBOARD_FAB2_LIB.BASEBOARD_FAB2(SCH_1):PAGE104
  J6E1   F5   IOF5 SCONN120_H61426002_SM-CONN,H61A    I55 @BASEBOARD_FAB2_LIB.BASEBOARD_FAB2(SCH_1):PAGE194

CLK_322M_156M_CPU0_OSC_VRM_DP @BASEBOARD_FAB2_LIB.BASEBOARD_FAB2(SCH_1):CLK_322M_156M_CPU0_OSC_VRM_DP
  R6F8    1      A RES_0402-0.0,5%,1/16W,EMPTY,G2A    I37 @BASEBOARD_FAB2_LIB.BASEBOARD_FAB2(SCH_1):PAGE104
 R6F11    1      A RES_0402-0.0,5%,1/16W,EMPTY,G2A    I79 @BASEBOARD_FAB2_LIB.BASEBOARD_FAB2(SCH_1):PAGE104
  J6E1   E5   IOE5 SCONN120_H61426002_SM-CONN,H61A    I55 @BASEBOARD_FAB2_LIB.BASEBOARD_FAB2(SCH_1):PAGE194

CLK_322M_156M_CPU1_OSC_VRM_DN @BASEBOARD_FAB2_LIB.BASEBOARD_FAB2(SCH_1):CLK_322M_156M_CPU1_OSC_VRM_DN
  R3F1    1      A RES_0402-0.0,5%,1/16W,EMPTY,G2A    I51 @BASEBOARD_FAB2_LIB.BASEBOARD_FAB2(SCH_1):PAGE104
  R3F5    1      A RES_0402-0.0,5%,1/16W,EMPTY,G2A    I84 @BASEBOARD_FAB2_LIB.BASEBOARD_FAB2(SCH_1):PAGE104
  J4E1   F5   IOF5 SCONN120_H61426002_SM-CONN,H61A    I45 @BASEBOARD_FAB2_LIB.BASEBOARD_FAB2(SCH_1):PAGE193

CLK_322M_156M_CPU1_OSC_VRM_DP @BASEBOARD_FAB2_LIB.BASEBOARD_FAB2(SCH_1):CLK_322M_156M_CPU1_OSC_VRM_DP
  R3F3    1      A RES_0402-0.0,5%,1/16W,EMPTY,G2A    I53 @BASEBOARD_FAB2_LIB.BASEBOARD_FAB2(SCH_1):PAGE104
  R3F6    1      A RES_0402-0.0,5%,1/16W,EMPTY,G2A    I88 @BASEBOARD_FAB2_LIB.BASEBOARD_FAB2(SCH_1):PAGE104
  J4E1   E5   IOE5 SCONN120_H61426002_SM-CONN,H61A    I45 @BASEBOARD_FAB2_LIB.BASEBOARD_FAB2(SCH_1):PAGE193

CLK_322M_OSC_CPU0_RC_DN @BASEBOARD_FAB2_LIB.BASEBOARD_FAB2(SCH_1):CLK_322M_OSC_CPU0_RC_DN
  U5D1 AL26 RSVD<213> SKX_EXT_B_BGA1-IC,TBD   I204 @BASEBOARD_FAB2_LIB.BASEBOARD_FAB2(SCH_1):PAGE22
 R6F10    2      B RES_0402-0.0,5%,1/16W,EMPTY,G2A    I78 @BASEBOARD_FAB2_LIB.BASEBOARD_FAB2(SCH_1):PAGE104

CLK_322M_OSC_CPU0_RC_DP @BASEBOARD_FAB2_LIB.BASEBOARD_FAB2(SCH_1):CLK_322M_OSC_CPU0_RC_DP
  U5D1 AK27 RSVD<220> SKX_EXT_B_BGA1-IC,TBD   I204 @BASEBOARD_FAB2_LIB.BASEBOARD_FAB2(SCH_1):PAGE22
 R6F11    2      B RES_0402-0.0,5%,1/16W,EMPTY,G2A    I79 @BASEBOARD_FAB2_LIB.BASEBOARD_FAB2(SCH_1):PAGE104

CLK_322M_OSC_CPU1_RC_DN @BASEBOARD_FAB2_LIB.BASEBOARD_FAB2(SCH_1):CLK_322M_OSC_CPU1_RC_DN
  U2D1 AL26 RSVD<213> SKX_EXT_B_BGA1-IC,TBD   I169 @BASEBOARD_FAB2_LIB.BASEBOARD_FAB2(SCH_1):PAGE56
  R3F5    2      B RES_0402-0.0,5%,1/16W,EMPTY,G2A    I84 @BASEBOARD_FAB2_LIB.BASEBOARD_FAB2(SCH_1):PAGE104

CLK_322M_OSC_CPU1_RC_DP @BASEBOARD_FAB2_LIB.BASEBOARD_FAB2(SCH_1):CLK_322M_OSC_CPU1_RC_DP
  U2D1 AK27 RSVD<220> SKX_EXT_B_BGA1-IC,TBD   I169 @BASEBOARD_FAB2_LIB.BASEBOARD_FAB2(SCH_1):PAGE56
  R3F6    2      B RES_0402-0.0,5%,1/16W,EMPTY,G2A    I88 @BASEBOARD_FAB2_LIB.BASEBOARD_FAB2(SCH_1):PAGE104

CLK_32K_SUSCLK_PLD @BASEBOARD_FAB2_LIB.BASEBOARD_FAB2(SCH_1):CLK_32K_SUSCLK_PLD
  U8D7   E1 PL3A_PCLKT5_0 LCMXO2_A_256BGA-IC,H63395-001   I179 @BASEBOARD_FAB2_LIB.BASEBOARD_FAB2(SCH_1):PAGE190
 R8F27    2      B RES_0402-33.2,1%,1/16W,CHIP,G2A   I142 @BASEBOARD_FAB2_LIB.BASEBOARD_FAB2(SCH_1):PAGE101

CLK_32K_SUSCLK_PLD_R @BASEBOARD_FAB2_LIB.BASEBOARD_FAB2(SCH_1):CLK_32K_SUSCLK_PLD_R
 EU8F2   13  32KHZ ICS9FGP204_MLFP-IC,E95226-001    I34 @BASEBOARD_FAB2_LIB.BASEBOARD_FAB2(SCH_1):PAGE101
 R8F27    1      A RES_0402-33.2,1%,1/16W,CHIP,G2A   I142 @BASEBOARD_FAB2_LIB.BASEBOARD_FAB2(SCH_1):PAGE101

CLK_48M_USB_BMC @BASEBOARD_FAB2_LIB.BASEBOARD_FAB2(SCH_1):CLK_48M_USB_BMC
  U7C1 BW50 CLOCKSE_BMCCLK LBG_CORE_QAT_EXT_D_BGA1-IC,H91A    I40 @BASEBOARD_FAB2_LIB.BASEBOARD_FAB2(SCH_1):PAGE114
R25W140    1      A RES_0402-0.0,5%,1/16W,EMPTY,G2A   I148 @BASEBOARD_FAB2_LIB.BASEBOARD_FAB2(SCH_1):PAGE144

CLK_48M_USB_BMC_R @BASEBOARD_FAB2_LIB.BASEBOARD_FAB2(SCH_1):CLK_48M_USB_BMC_R
 U25W4  J20 GPIOB4_USBCKI AST2520A1-GP-GP_ASIC2-GB1-AST2A    I95 @BASEBOARD_FAB2_LIB.BASEBOARD_FAB2(SCH_1):PAGE144
R25W140    2      B RES_0402-0.0,5%,1/16W,EMPTY,G2A   I148 @BASEBOARD_FAB2_LIB.BASEBOARD_FAB2(SCH_1):PAGE144

CLK_50M_CKMNG_BMC_1 @BASEBOARD_FAB2_LIB.BASEBOARD_FAB2(SCH_1):CLK_50M_CKMNG_BMC_1
 R2T46    2      B RES_0402-22.1,1.0%,1/16W,CHIP,A   I125 @BASEBOARD_FAB2_LIB.BASEBOARD_FAB2(SCH_1):PAGE101
 U25W4   B4 RGMII1RXCK_RMII1RCLKI_GPIOU4 AST2520A1-GP-GP_ASIC2-GB1-AST2A   I106 @BASEBOARD_FAB2_LIB.BASEBOARD_FAB2(SCH_1):PAGE147

CLK_50M_CKMNG_BMC_1_R @BASEBOARD_FAB2_LIB.BASEBOARD_FAB2(SCH_1):CLK_50M_CKMNG_BMC_1_R
 EU8F2   32 RMII<1> ICS9FGP204_MLFP-IC,E95226-001    I34 @BASEBOARD_FAB2_LIB.BASEBOARD_FAB2(SCH_1):PAGE101
 R2T46    1      A RES_0402-22.1,1.0%,1/16W,CHIP,A   I125 @BASEBOARD_FAB2_LIB.BASEBOARD_FAB2(SCH_1):PAGE101

CLK_50M_CKMNG_BMC_2 @BASEBOARD_FAB2_LIB.BASEBOARD_FAB2(SCH_1):CLK_50M_CKMNG_BMC_2
 U25W4   C2 RGMII2RXCK_RMII2RCLKI_GPIOV2 AST2520A1-GP-GP_ASIC2-GB1-AST2A   I106 @BASEBOARD_FAB2_LIB.BASEBOARD_FAB2(SCH_1):PAGE147
  R8G1    2      B RES_0402-22.1,1.0%,1/16W,CHIP,A   I145 @BASEBOARD_FAB2_LIB.BASEBOARD_FAB2(SCH_1):PAGE101

CLK_50M_CKMNG_BMC_2_R @BASEBOARD_FAB2_LIB.BASEBOARD_FAB2(SCH_1):CLK_50M_CKMNG_BMC_2_R
 EU8F2   29 RMII<2> ICS9FGP204_MLFP-IC,E95226-001    I34 @BASEBOARD_FAB2_LIB.BASEBOARD_FAB2(SCH_1):PAGE101
  R8G1    1      A RES_0402-22.1,1.0%,1/16W,CHIP,A   I145 @BASEBOARD_FAB2_LIB.BASEBOARD_FAB2(SCH_1):PAGE101

CLK_50M_CKMNG_OCP @BASEBOARD_FAB2_LIB.BASEBOARD_FAB2(SCH_1):CLK_50M_CKMNG_OCP
 R2T42    2      B RES_0402-22.1,1.0%,1/16W,CHIP,A   I124 @BASEBOARD_FAB2_LIB.BASEBOARD_FAB2(SCH_1):PAGE101
  J9B3   29   IO29 SCONN120_A28699018_SM-SCONN,A2A   I336 @BASEBOARD_FAB2_LIB.BASEBOARD_FAB2(SCH_1):PAGE186

CLK_50M_CKMNG_OCP_R @BASEBOARD_FAB2_LIB.BASEBOARD_FAB2(SCH_1):CLK_50M_CKMNG_OCP_R
 EU8F2   33 RMII<0> ICS9FGP204_MLFP-IC,E95226-001    I34 @BASEBOARD_FAB2_LIB.BASEBOARD_FAB2(SCH_1):PAGE101
 R2T42    1      A RES_0402-22.1,1.0%,1/16W,CHIP,A   I124 @BASEBOARD_FAB2_LIB.BASEBOARD_FAB2(SCH_1):PAGE101

CLK_50M_CKMNG_PCH_10GBE @BASEBOARD_FAB2_LIB.BASEBOARD_FAB2(SCH_1):CLK_50M_CKMNG_PCH_10GBE
  U7C1  AJ1 GPP_K0_LAN_NCSI_CLK_IN LBG_CORE_QAT_EXT_D_BGA1-IC,H91A    I34 @BASEBOARD_FAB2_LIB.BASEBOARD_FAB2(SCH_1):PAGE121
 R7C20    1      A RES_0402-10.0K,1%,1/16W,CHIP,GA    I73 @BASEBOARD_FAB2_LIB.BASEBOARD_FAB2(SCH_1):PAGE121
 R8G24    2      B RES_0402-22.1,1.0%,1/16W,CHIP,A   I143 @BASEBOARD_FAB2_LIB.BASEBOARD_FAB2(SCH_1):PAGE101

CLK_50M_CKMNG_PCH_10GBE_R @BASEBOARD_FAB2_LIB.BASEBOARD_FAB2(SCH_1):CLK_50M_CKMNG_PCH_10GBE_R
 EU8F2   25 RMII<4> ICS9FGP204_MLFP-IC,E95226-001    I34 @BASEBOARD_FAB2_LIB.BASEBOARD_FAB2(SCH_1):PAGE101
 R8G24    1      A RES_0402-22.1,1.0%,1/16W,CHIP,A   I143 @BASEBOARD_FAB2_LIB.BASEBOARD_FAB2(SCH_1):PAGE101

CLK_50M_CKMNG_SPRVLLE @BASEBOARD_FAB2_LIB.BASEBOARD_FAB2(SCH_1):CLK_50M_CKMNG_SPRVLLE
 EU9E1    2 NC_SI_CLK_IN SPRINGVILLE_SM1-IC,G47144-004    I72 @BASEBOARD_FAB2_LIB.BASEBOARD_FAB2(SCH_1):PAGE139
 R1R12    1      A RES_0402-10.0K,1%,1/16W,CHIP,GA   I213 @BASEBOARD_FAB2_LIB.BASEBOARD_FAB2(SCH_1):PAGE139
 R8G25    2      B RES_0402-22.1,1.0%,1/16W,CHIP,A   I144 @BASEBOARD_FAB2_LIB.BASEBOARD_FAB2(SCH_1):PAGE101

CLK_50M_CKMNG_SPRVLLE_R @BASEBOARD_FAB2_LIB.BASEBOARD_FAB2(SCH_1):CLK_50M_CKMNG_SPRVLLE_R
 EU8F2   28 RMII<3> ICS9FGP204_MLFP-IC,E95226-001    I34 @BASEBOARD_FAB2_LIB.BASEBOARD_FAB2(SCH_1):PAGE101
 R8G25    1      A RES_0402-22.1,1.0%,1/16W,CHIP,A   I144 @BASEBOARD_FAB2_LIB.BASEBOARD_FAB2(SCH_1):PAGE101

CPU_XDP_PRESENT_N @BASEBOARD_FAB2_LIB.BASEBOARD_FAB2(SCH_1):CPU_XDP_PRESENT_N
  U5D1 AV21 DEBUG_EN_N SKX_EXT_B_BGA1-IC,TBD   I204 @BASEBOARD_FAB2_LIB.BASEBOARD_FAB2(SCH_1):PAGE22
  U2D1 AV21 DEBUG_EN_N SKX_EXT_B_BGA1-IC,TBD   I169 @BASEBOARD_FAB2_LIB.BASEBOARD_FAB2(SCH_1):PAGE56
  R9A4    1      A RES_0402-475.0,1%,1/16W,CHIP,GA    I55 @BASEBOARD_FAB2_LIB.BASEBOARD_FAB2(SCH_1):PAGE111
U25W15    4      Y TTL1G07_A_SOP-74LVC1G07,IC,C88B    I12 @BASEBOARD_FAB2_LIB.BASEBOARD_FAB2(SCH_1):PAGE268
U25W14    4      Y TTL1G07_A_SOP-74LVC1G07,IC,C88B    I13 @BASEBOARD_FAB2_LIB.BASEBOARD_FAB2(SCH_1):PAGE268

DEBUG_CARD2_PRSNT @BASEBOARD_FAB2_LIB.BASEBOARD_FAB2(SCH_1):DEBUG_CARD2_PRSNT
  J9B1    7 GND_DRAIN CONN9_H51826001_PIP2-CONN,H518A    I69 @BASEBOARD_FAB2_LIB.BASEBOARD_FAB2(SCH_1):PAGE176
  U6W4    1     OE TTL1G126_A_SOT-74HC1G126,IC,A7B   I146 @BASEBOARD_FAB2_LIB.BASEBOARD_FAB2(SCH_1):PAGE176
  U6W5    1     OE TTL1G126_A_SOT-74HC1G126,IC,A7B   I148 @BASEBOARD_FAB2_LIB.BASEBOARD_FAB2(SCH_1):PAGE176
  Q6W4    1   GATE FET_N_SOT23LF-2N7002,FET,C7925A    I43 @BASEBOARD_FAB2_LIB.BASEBOARD_FAB2(SCH_1):PAGE168
 R6W38    1      A RES_0402-20.0K,1%,1/16W,CHIP,GA   I156 @BASEBOARD_FAB2_LIB.BASEBOARD_FAB2(SCH_1):PAGE176
  U1W3    5     EN PCA9617_SSOP-IC,G81764-001-GNDA   I162 @BASEBOARD_FAB2_LIB.BASEBOARD_FAB2(SCH_1):PAGE176
 U6W12    6      S NC7SB3157_SMLF-IC,C99406-001   I182 @BASEBOARD_FAB2_LIB.BASEBOARD_FAB2(SCH_1):PAGE176

DMI_CPU0_PCH_RX_C_DN<0> @BASEBOARD_FAB2_LIB.BASEBOARD_FAB2(SCH_1):DMI_CPU0_PCH_RX_C_DN(0)
  U5D1  CK9 DMI_RX_DN<0> SKX_EXT_B_BGA1-IC,TBD    I61 @BASEBOARD_FAB2_LIB.BASEBOARD_FAB2(SCH_1):PAGE29
 C3M44    2      B CAP_0402-0.22UF,16V,10%,X7R,A3A    I80 @BASEBOARD_FAB2_LIB.BASEBOARD_FAB2(SCH_1):PAGE129

DMI_CPU0_PCH_RX_C_DN<1> @BASEBOARD_FAB2_LIB.BASEBOARD_FAB2(SCH_1):DMI_CPU0_PCH_RX_C_DN(1)
  U5D1 CM11 DMI_RX_DN<1> SKX_EXT_B_BGA1-IC,TBD    I61 @BASEBOARD_FAB2_LIB.BASEBOARD_FAB2(SCH_1):PAGE29
 C3M41    2      B CAP_0402-0.22UF,16V,10%,X7R,A3A    I81 @BASEBOARD_FAB2_LIB.BASEBOARD_FAB2(SCH_1):PAGE129

DMI_CPU0_PCH_RX_C_DN<2> @BASEBOARD_FAB2_LIB.BASEBOARD_FAB2(SCH_1):DMI_CPU0_PCH_RX_C_DN(2)
  U5D1 CR12 DMI_RX_DN<2> SKX_EXT_B_BGA1-IC,TBD    I61 @BASEBOARD_FAB2_LIB.BASEBOARD_FAB2(SCH_1):PAGE29
 C3M45    2      B CAP_0402-0.22UF,16V,10%,X7R,A3A    I82 @BASEBOARD_FAB2_LIB.BASEBOARD_FAB2(SCH_1):PAGE129

DMI_CPU0_PCH_RX_C_DN<3> @BASEBOARD_FAB2_LIB.BASEBOARD_FAB2(SCH_1):DMI_CPU0_PCH_RX_C_DN(3)
  U5D1 CT11 DMI_RX_DN<3> SKX_EXT_B_BGA1-IC,TBD    I61 @BASEBOARD_FAB2_LIB.BASEBOARD_FAB2(SCH_1):PAGE29
 C3N13    2      B CAP_0402-0.22UF,16V,10%,X7R,A3A    I83 @BASEBOARD_FAB2_LIB.BASEBOARD_FAB2(SCH_1):PAGE129

DMI_CPU0_PCH_RX_C_DP<0> @BASEBOARD_FAB2_LIB.BASEBOARD_FAB2(SCH_1):DMI_CPU0_PCH_RX_C_DP(0)
  U5D1 CL10 DMI_RX_DP<0> SKX_EXT_B_BGA1-IC,TBD    I61 @BASEBOARD_FAB2_LIB.BASEBOARD_FAB2(SCH_1):PAGE29
 C3M40    2      B CAP_0402-0.22UF,16V,10%,X7R,A3A    I72 @BASEBOARD_FAB2_LIB.BASEBOARD_FAB2(SCH_1):PAGE129

DMI_CPU0_PCH_RX_C_DP<1> @BASEBOARD_FAB2_LIB.BASEBOARD_FAB2(SCH_1):DMI_CPU0_PCH_RX_C_DP(1)
  U5D1 CN10 DMI_RX_DP<1> SKX_EXT_B_BGA1-IC,TBD    I61 @BASEBOARD_FAB2_LIB.BASEBOARD_FAB2(SCH_1):PAGE29
 C3M37    2      B CAP_0402-0.22UF,16V,10%,X7R,A3A    I73 @BASEBOARD_FAB2_LIB.BASEBOARD_FAB2(SCH_1):PAGE129

DMI_CPU0_PCH_RX_C_DP<2> @BASEBOARD_FAB2_LIB.BASEBOARD_FAB2(SCH_1):DMI_CPU0_PCH_RX_C_DP(2)
  U5D1 CP11 DMI_RX_DP<2> SKX_EXT_B_BGA1-IC,TBD    I61 @BASEBOARD_FAB2_LIB.BASEBOARD_FAB2(SCH_1):PAGE29
  C3N9    2      B CAP_0402-0.22UF,16V,10%,X7R,A3A    I74 @BASEBOARD_FAB2_LIB.BASEBOARD_FAB2(SCH_1):PAGE129

DMI_CPU0_PCH_RX_C_DP<3> @BASEBOARD_FAB2_LIB.BASEBOARD_FAB2(SCH_1):DMI_CPU0_PCH_RX_C_DP(3)
  U5D1 CV11 DMI_RX_DP<3> SKX_EXT_B_BGA1-IC,TBD    I61 @BASEBOARD_FAB2_LIB.BASEBOARD_FAB2(SCH_1):PAGE29
  C3N8    2      B CAP_0402-0.22UF,16V,10%,X7R,A3A    I75 @BASEBOARD_FAB2_LIB.BASEBOARD_FAB2(SCH_1):PAGE129

DMI_CPU0_PCH_RX_DN<0> @BASEBOARD_FAB2_LIB.BASEBOARD_FAB2(SCH_1):DMI_CPU0_PCH_RX_DN(0)
  U7C1  H46 DMI_TXN<0> LBG_CORE_QAT_EXT_D_BGA1-IC,H91A     I9 @BASEBOARD_FAB2_LIB.BASEBOARD_FAB2(SCH_1):PAGE117
 C3M44    1      A CAP_0402-0.22UF,16V,10%,X7R,A3A    I80 @BASEBOARD_FAB2_LIB.BASEBOARD_FAB2(SCH_1):PAGE129

DMI_CPU0_PCH_RX_DN<1> @BASEBOARD_FAB2_LIB.BASEBOARD_FAB2(SCH_1):DMI_CPU0_PCH_RX_DN(1)
  U7C1  J48 DMI_TXN<1> LBG_CORE_QAT_EXT_D_BGA1-IC,H91A     I9 @BASEBOARD_FAB2_LIB.BASEBOARD_FAB2(SCH_1):PAGE117
 C3M41    1      A CAP_0402-0.22UF,16V,10%,X7R,A3A    I81 @BASEBOARD_FAB2_LIB.BASEBOARD_FAB2(SCH_1):PAGE129

DMI_CPU0_PCH_RX_DN<2> @BASEBOARD_FAB2_LIB.BASEBOARD_FAB2(SCH_1):DMI_CPU0_PCH_RX_DN(2)
  U7C1  K50 DMI_TXN<2> LBG_CORE_QAT_EXT_D_BGA1-IC,H91A     I9 @BASEBOARD_FAB2_LIB.BASEBOARD_FAB2(SCH_1):PAGE117
 C3M45    1      A CAP_0402-0.22UF,16V,10%,X7R,A3A    I82 @BASEBOARD_FAB2_LIB.BASEBOARD_FAB2(SCH_1):PAGE129

DMI_CPU0_PCH_RX_DN<3> @BASEBOARD_FAB2_LIB.BASEBOARD_FAB2(SCH_1):DMI_CPU0_PCH_RX_DN(3)
  U7C1  P52 DMI_TXN<3> LBG_CORE_QAT_EXT_D_BGA1-IC,H91A     I9 @BASEBOARD_FAB2_LIB.BASEBOARD_FAB2(SCH_1):PAGE117
 C3N13    1      A CAP_0402-0.22UF,16V,10%,X7R,A3A    I83 @BASEBOARD_FAB2_LIB.BASEBOARD_FAB2(SCH_1):PAGE129

DMI_CPU0_PCH_RX_DP<0> @BASEBOARD_FAB2_LIB.BASEBOARD_FAB2(SCH_1):DMI_CPU0_PCH_RX_DP(0)
  U7C1  K46 DMI_TXP<0> LBG_CORE_QAT_EXT_D_BGA1-IC,H91A     I9 @BASEBOARD_FAB2_LIB.BASEBOARD_FAB2(SCH_1):PAGE117
 C3M40    1      A CAP_0402-0.22UF,16V,10%,X7R,A3A    I72 @BASEBOARD_FAB2_LIB.BASEBOARD_FAB2(SCH_1):PAGE129

DMI_CPU0_PCH_RX_DP<1> @BASEBOARD_FAB2_LIB.BASEBOARD_FAB2(SCH_1):DMI_CPU0_PCH_RX_DP(1)
  U7C1  H50 DMI_TXP<1> LBG_CORE_QAT_EXT_D_BGA1-IC,H91A     I9 @BASEBOARD_FAB2_LIB.BASEBOARD_FAB2(SCH_1):PAGE117
 C3M37    1      A CAP_0402-0.22UF,16V,10%,X7R,A3A    I73 @BASEBOARD_FAB2_LIB.BASEBOARD_FAB2(SCH_1):PAGE129

DMI_CPU0_PCH_RX_DP<2> @BASEBOARD_FAB2_LIB.BASEBOARD_FAB2(SCH_1):DMI_CPU0_PCH_RX_DP(2)
  U7C1  M52 DMI_TXP<2> LBG_CORE_QAT_EXT_D_BGA1-IC,H91A     I9 @BASEBOARD_FAB2_LIB.BASEBOARD_FAB2(SCH_1):PAGE117
  C3N9    1      A CAP_0402-0.22UF,16V,10%,X7R,A3A    I74 @BASEBOARD_FAB2_LIB.BASEBOARD_FAB2(SCH_1):PAGE129

DMI_CPU0_PCH_RX_DP<3> @BASEBOARD_FAB2_LIB.BASEBOARD_FAB2(SCH_1):DMI_CPU0_PCH_RX_DP(3)
  U7C1  N54 DMI_TXP<3> LBG_CORE_QAT_EXT_D_BGA1-IC,H91A     I9 @BASEBOARD_FAB2_LIB.BASEBOARD_FAB2(SCH_1):PAGE117
  C3N8    1      A CAP_0402-0.22UF,16V,10%,X7R,A3A    I75 @BASEBOARD_FAB2_LIB.BASEBOARD_FAB2(SCH_1):PAGE129

DMI_CPU0_PCH_TX_C_DN<0> @BASEBOARD_FAB2_LIB.BASEBOARD_FAB2(SCH_1):DMI_CPU0_PCH_TX_C_DN(0)
  U7C1  D42 DMI_RXN<0> LBG_CORE_QAT_EXT_D_BGA1-IC,H91A     I9 @BASEBOARD_FAB2_LIB.BASEBOARD_FAB2(SCH_1):PAGE117
  C7C3    2      B CAP_0402-0.22UF,16V,10%,X7R,A3A    I76 @BASEBOARD_FAB2_LIB.BASEBOARD_FAB2(SCH_1):PAGE129

DMI_CPU0_PCH_TX_C_DN<1> @BASEBOARD_FAB2_LIB.BASEBOARD_FAB2(SCH_1):DMI_CPU0_PCH_TX_C_DN(1)
  U7C1  C43 DMI_RXN<1> LBG_CORE_QAT_EXT_D_BGA1-IC,H91A     I9 @BASEBOARD_FAB2_LIB.BASEBOARD_FAB2(SCH_1):PAGE117
  C7C1    2      B CAP_0402-0.22UF,16V,10%,X7R,A3A    I77 @BASEBOARD_FAB2_LIB.BASEBOARD_FAB2(SCH_1):PAGE129

DMI_CPU0_PCH_TX_C_DN<2> @BASEBOARD_FAB2_LIB.BASEBOARD_FAB2(SCH_1):DMI_CPU0_PCH_TX_C_DN(2)
  U7C1  D44 DMI_RXN<2> LBG_CORE_QAT_EXT_D_BGA1-IC,H91A     I9 @BASEBOARD_FAB2_LIB.BASEBOARD_FAB2(SCH_1):PAGE117
 C7B29    2      B CAP_0402-0.22UF,16V,10%,X7R,A3A    I78 @BASEBOARD_FAB2_LIB.BASEBOARD_FAB2(SCH_1):PAGE129

DMI_CPU0_PCH_TX_C_DN<3> @BASEBOARD_FAB2_LIB.BASEBOARD_FAB2(SCH_1):DMI_CPU0_PCH_TX_C_DN(3)
  U7C1  C45 DMI_RXN<3> LBG_CORE_QAT_EXT_D_BGA1-IC,H91A     I9 @BASEBOARD_FAB2_LIB.BASEBOARD_FAB2(SCH_1):PAGE117
 C7B26    2      B CAP_0402-0.22UF,16V,10%,X7R,A3A    I79 @BASEBOARD_FAB2_LIB.BASEBOARD_FAB2(SCH_1):PAGE129

DMI_CPU0_PCH_TX_C_DP<0> @BASEBOARD_FAB2_LIB.BASEBOARD_FAB2(SCH_1):DMI_CPU0_PCH_TX_C_DP(0)
  U7C1  B42 DMI_RXP<0> LBG_CORE_QAT_EXT_D_BGA1-IC,H91A     I9 @BASEBOARD_FAB2_LIB.BASEBOARD_FAB2(SCH_1):PAGE117
  C7C2    2      B CAP_0402-0.22UF,16V,10%,X7R,A3A    I71 @BASEBOARD_FAB2_LIB.BASEBOARD_FAB2(SCH_1):PAGE129

DMI_CPU0_PCH_TX_C_DP<1> @BASEBOARD_FAB2_LIB.BASEBOARD_FAB2(SCH_1):DMI_CPU0_PCH_TX_C_DP(1)
  U7C1  A43 DMI_RXP<1> LBG_CORE_QAT_EXT_D_BGA1-IC,H91A     I9 @BASEBOARD_FAB2_LIB.BASEBOARD_FAB2(SCH_1):PAGE117
 C7B28    2      B CAP_0402-0.22UF,16V,10%,X7R,A3A    I70 @BASEBOARD_FAB2_LIB.BASEBOARD_FAB2(SCH_1):PAGE129

DMI_CPU0_PCH_TX_C_DP<2> @BASEBOARD_FAB2_LIB.BASEBOARD_FAB2(SCH_1):DMI_CPU0_PCH_TX_C_DP(2)
  U7C1  B44 DMI_RXP<2> LBG_CORE_QAT_EXT_D_BGA1-IC,H91A     I9 @BASEBOARD_FAB2_LIB.BASEBOARD_FAB2(SCH_1):PAGE117
 C7B27    2      B CAP_0402-0.22UF,16V,10%,X7R,A3A    I69 @BASEBOARD_FAB2_LIB.BASEBOARD_FAB2(SCH_1):PAGE129

DMI_CPU0_PCH_TX_C_DP<3> @BASEBOARD_FAB2_LIB.BASEBOARD_FAB2(SCH_1):DMI_CPU0_PCH_TX_C_DP(3)
  U7C1  A45 DMI_RXP<3> LBG_CORE_QAT_EXT_D_BGA1-IC,H91A     I9 @BASEBOARD_FAB2_LIB.BASEBOARD_FAB2(SCH_1):PAGE117
 C7B25    2      B CAP_0402-0.22UF,16V,10%,X7R,A3A    I35 @BASEBOARD_FAB2_LIB.BASEBOARD_FAB2(SCH_1):PAGE129

DMI_CPU0_PCH_TX_DN<0> @BASEBOARD_FAB2_LIB.BASEBOARD_FAB2(SCH_1):DMI_CPU0_PCH_TX_DN(0)
  U5D1  CG4 DMI_TX_DN<0> SKX_EXT_B_BGA1-IC,TBD    I61 @BASEBOARD_FAB2_LIB.BASEBOARD_FAB2(SCH_1):PAGE29
  C7C3    1      A CAP_0402-0.22UF,16V,10%,X7R,A3A    I76 @BASEBOARD_FAB2_LIB.BASEBOARD_FAB2(SCH_1):PAGE129

DMI_CPU0_PCH_TX_DN<1> @BASEBOARD_FAB2_LIB.BASEBOARD_FAB2(SCH_1):DMI_CPU0_PCH_TX_DN(1)
  U5D1  CJ4 DMI_TX_DN<1> SKX_EXT_B_BGA1-IC,TBD    I61 @BASEBOARD_FAB2_LIB.BASEBOARD_FAB2(SCH_1):PAGE29
  C7C1    1      A CAP_0402-0.22UF,16V,10%,X7R,A3A    I77 @BASEBOARD_FAB2_LIB.BASEBOARD_FAB2(SCH_1):PAGE129

DMI_CPU0_PCH_TX_DN<2> @BASEBOARD_FAB2_LIB.BASEBOARD_FAB2(SCH_1):DMI_CPU0_PCH_TX_DN(2)
  U5D1  CN4 DMI_TX_DN<2> SKX_EXT_B_BGA1-IC,TBD    I61 @BASEBOARD_FAB2_LIB.BASEBOARD_FAB2(SCH_1):PAGE29
 C7B29    1      A CAP_0402-0.22UF,16V,10%,X7R,A3A    I78 @BASEBOARD_FAB2_LIB.BASEBOARD_FAB2(SCH_1):PAGE129

DMI_CPU0_PCH_TX_DN<3> @BASEBOARD_FAB2_LIB.BASEBOARD_FAB2(SCH_1):DMI_CPU0_PCH_TX_DN(3)
  U5D1  CP5 DMI_TX_DN<3> SKX_EXT_B_BGA1-IC,TBD    I61 @BASEBOARD_FAB2_LIB.BASEBOARD_FAB2(SCH_1):PAGE29
 C7B26    1      A CAP_0402-0.22UF,16V,10%,X7R,A3A    I79 @BASEBOARD_FAB2_LIB.BASEBOARD_FAB2(SCH_1):PAGE129

DMI_CPU0_PCH_TX_DP<0> @BASEBOARD_FAB2_LIB.BASEBOARD_FAB2(SCH_1):DMI_CPU0_PCH_TX_DP(0)
  U5D1  CH5 DMI_TX_DP<0> SKX_EXT_B_BGA1-IC,TBD    I61 @BASEBOARD_FAB2_LIB.BASEBOARD_FAB2(SCH_1):PAGE29
  C7C2    1      A CAP_0402-0.22UF,16V,10%,X7R,A3A    I71 @BASEBOARD_FAB2_LIB.BASEBOARD_FAB2(SCH_1):PAGE129

DMI_CPU0_PCH_TX_DP<1> @BASEBOARD_FAB2_LIB.BASEBOARD_FAB2(SCH_1):DMI_CPU0_PCH_TX_DP(1)
  U5D1  CL4 DMI_TX_DP<1> SKX_EXT_B_BGA1-IC,TBD    I61 @BASEBOARD_FAB2_LIB.BASEBOARD_FAB2(SCH_1):PAGE29
 C7B28    1      A CAP_0402-0.22UF,16V,10%,X7R,A3A    I70 @BASEBOARD_FAB2_LIB.BASEBOARD_FAB2(SCH_1):PAGE129

DMI_CPU0_PCH_TX_DP<2> @BASEBOARD_FAB2_LIB.BASEBOARD_FAB2(SCH_1):DMI_CPU0_PCH_TX_DP(2)
  U5D1  CM3 DMI_TX_DP<2> SKX_EXT_B_BGA1-IC,TBD    I61 @BASEBOARD_FAB2_LIB.BASEBOARD_FAB2(SCH_1):PAGE29
 C7B27    1      A CAP_0402-0.22UF,16V,10%,X7R,A3A    I69 @BASEBOARD_FAB2_LIB.BASEBOARD_FAB2(SCH_1):PAGE129

DMI_CPU0_PCH_TX_DP<3> @BASEBOARD_FAB2_LIB.BASEBOARD_FAB2(SCH_1):DMI_CPU0_PCH_TX_DP(3)
  U5D1  CR4 DMI_TX_DP<3> SKX_EXT_B_BGA1-IC,TBD    I61 @BASEBOARD_FAB2_LIB.BASEBOARD_FAB2(SCH_1):PAGE29
 C7B25    1      A CAP_0402-0.22UF,16V,10%,X7R,A3A    I35 @BASEBOARD_FAB2_LIB.BASEBOARD_FAB2(SCH_1):PAGE129

EXT_MDIO_I2C_SEL @BASEBOARD_FAB2_LIB.BASEBOARD_FAB2(SCH_1):EXT_MDIO_I2C_SEL
  J8E4    3    IO3 SCONN64_H87568002_A_SMT-CONN,HA    I27 @BASEBOARD_FAB2_LIB.BASEBOARD_FAB2(SCH_1):PAGE188
 R1W40    2      B RES_0402-4.75K,1%,1/16W,CHIP,GA   I128 @BASEBOARD_FAB2_LIB.BASEBOARD_FAB2(SCH_1):PAGE188
 R1W41    2      B RES_0402-4.75K,1%,1/16W,CHIP,GA   I129 @BASEBOARD_FAB2_LIB.BASEBOARD_FAB2(SCH_1):PAGE188

FAN_PWM_OUT_SYS0 @BASEBOARD_FAB2_LIB.BASEBOARD_FAB2(SCH_1):FAN_PWM_OUT_SYS0
  U8G2    2      A TTL1G07_A_SOP-74LVC1G07,IC,C88B    I88 @BASEBOARD_FAB2_LIB.BASEBOARD_FAB2(SCH_1):PAGE161
 U25W4   V2 GPION0_PWM0 AST2520A1-GP-GP_ASIC2-GB1-AST2A   I106 @BASEBOARD_FAB2_LIB.BASEBOARD_FAB2(SCH_1):PAGE147

FAN_PWM_OUT_SYS0_BUF @BASEBOARD_FAB2_LIB.BASEBOARD_FAB2(SCH_1):FAN_PWM_OUT_SYS0_BUF
  U8G2    4      Y TTL1G07_A_SOP-74LVC1G07,IC,C88B    I88 @BASEBOARD_FAB2_LIB.BASEBOARD_FAB2(SCH_1):PAGE161
 R2U42    1      A RES_0402-221,1.0%,1/16W,CHIP,GA    I99 @BASEBOARD_FAB2_LIB.BASEBOARD_FAB2(SCH_1):PAGE161

FAN_PWM_OUT_SYS0_R @BASEBOARD_FAB2_LIB.BASEBOARD_FAB2(SCH_1):FAN_PWM_OUT_SYS0_R
 CR1E1    2      A DIODE_SM-SDMK0340L,EMPTY,H7179A    I50 @BASEBOARD_FAB2_LIB.BASEBOARD_FAB2(SCH_1):PAGE161
 R1E12    2      B RES_0402-4.75K,1%,1/16W,CHIP,GA    I51 @BASEBOARD_FAB2_LIB.BASEBOARD_FAB2(SCH_1):PAGE161
 R2U42    2      B RES_0402-221,1.0%,1/16W,CHIP,GA    I99 @BASEBOARD_FAB2_LIB.BASEBOARD_FAB2(SCH_1):PAGE161
  R9T1    1      A RES_0402-0.0,5%,1/16W,CHIP,G21A    I26 @BASEBOARD_FAB2_LIB.BASEBOARD_FAB2(SCH_1):PAGE181
  J1F2    4      4 LOTES-CON4-S1-GP_CONN-G7-LOTESA   I139 @BASEBOARD_FAB2_LIB.BASEBOARD_FAB2(SCH_1):PAGE161

FAN_PWM_OUT_SYS0_R1 @BASEBOARD_FAB2_LIB.BASEBOARD_FAB2(SCH_1):FAN_PWM_OUT_SYS0_R1
  R9T1    2      B RES_0402-0.0,5%,1/16W,CHIP,G21A    I26 @BASEBOARD_FAB2_LIB.BASEBOARD_FAB2(SCH_1):PAGE181
  R1F9    2      B RES_0402-0.0,5%,1/16W,EMPTY,G2A     I7 @BASEBOARD_FAB2_LIB.BASEBOARD_FAB2(SCH_1):PAGE182
  J1F1   F4 FAN_PWM0 DM-FCI-CONN76-8R-GP-U-01_CONN-A   I134 @BASEBOARD_FAB2_LIB.BASEBOARD_FAB2(SCH_1):PAGE181

FAN_PWM_OUT_SYS1 @BASEBOARD_FAB2_LIB.BASEBOARD_FAB2(SCH_1):FAN_PWM_OUT_SYS1
  U8G3    2      A TTL1G07_A_SOP-74LVC1G07,IC,C88B    I92 @BASEBOARD_FAB2_LIB.BASEBOARD_FAB2(SCH_1):PAGE161
 U25W4   W2 GPION1_PWM1 AST2520A1-GP-GP_ASIC2-GB1-AST2A   I106 @BASEBOARD_FAB2_LIB.BASEBOARD_FAB2(SCH_1):PAGE147

FAN_PWM_OUT_SYS1_BUF @BASEBOARD_FAB2_LIB.BASEBOARD_FAB2(SCH_1):FAN_PWM_OUT_SYS1_BUF
  U8G3    4      Y TTL1G07_A_SOP-74LVC1G07,IC,C88B    I92 @BASEBOARD_FAB2_LIB.BASEBOARD_FAB2(SCH_1):PAGE161
 R2U44    1      A RES_0402-221,1.0%,1/16W,CHIP,GA   I102 @BASEBOARD_FAB2_LIB.BASEBOARD_FAB2(SCH_1):PAGE161

FAN_PWM_OUT_SYS1_R @BASEBOARD_FAB2_LIB.BASEBOARD_FAB2(SCH_1):FAN_PWM_OUT_SYS1_R
 CR1B1    2      A DIODE_SM-SDMK0340L,EMPTY,H7179A    I64 @BASEBOARD_FAB2_LIB.BASEBOARD_FAB2(SCH_1):PAGE161
 R7F33    2      B RES_0402-4.75K,1%,1/16W,CHIP,GA    I65 @BASEBOARD_FAB2_LIB.BASEBOARD_FAB2(SCH_1):PAGE161
 R2U44    2      B RES_0402-221,1.0%,1/16W,CHIP,GA   I102 @BASEBOARD_FAB2_LIB.BASEBOARD_FAB2(SCH_1):PAGE161
 J10W1    4      4 LOTES-CON4-S1-GP_CONN-G7-LOTESA   I140 @BASEBOARD_FAB2_LIB.BASEBOARD_FAB2(SCH_1):PAGE161

FAN_TACH0 @BASEBOARD_FAB2_LIB.BASEBOARD_FAB2(SCH_1):FAN_TACH0
  R1F2    1      A RES_0402-100.0,1%,1/16W,CHIP,GA    I43 @BASEBOARD_FAB2_LIB.BASEBOARD_FAB2(SCH_1):PAGE161
  R1F1    2      B RES_0402-4.75K,1%,1/16W,CHIP,GA    I45 @BASEBOARD_FAB2_LIB.BASEBOARD_FAB2(SCH_1):PAGE161
  C1F9    1      A CAP_A_0402V-0.01UF,25V,10%,X7RA    I46 @BASEBOARD_FAB2_LIB.BASEBOARD_FAB2(SCH_1):PAGE161
  R1U5    1      A RES_0402-100.0K,1%,1/16W,CHIP,A    I66 @BASEBOARD_FAB2_LIB.BASEBOARD_FAB2(SCH_1):PAGE147
 U25W4   U5 GPIOO0_TACH0_VPIG8 AST2520A1-GP-GP_ASIC2-GB1-AST2A   I106 @BASEBOARD_FAB2_LIB.BASEBOARD_FAB2(SCH_1):PAGE147
  R1F8    1      A RES_0402-0.0,5%,1/16W,CHIP,G21A    I22 @BASEBOARD_FAB2_LIB.BASEBOARD_FAB2(SCH_1):PAGE181

FAN_TACH0_CPU0_D1 @BASEBOARD_FAB2_LIB.BASEBOARD_FAB2(SCH_1):FAN_TACH0_CPU0_D1
 CR1F1    1      C DIODE_SM-SDMK0340L,IC,H71799-0A    I42 @BASEBOARD_FAB2_LIB.BASEBOARD_FAB2(SCH_1):PAGE161
  J1F2    3      3 LOTES-CON4-S1-GP_CONN-G7-LOTESA   I139 @BASEBOARD_FAB2_LIB.BASEBOARD_FAB2(SCH_1):PAGE161

FAN_TACH0_CPU0_D2 @BASEBOARD_FAB2_LIB.BASEBOARD_FAB2(SCH_1):FAN_TACH0_CPU0_D2
 CR1F1    2      A DIODE_SM-SDMK0340L,IC,H71799-0A    I42 @BASEBOARD_FAB2_LIB.BASEBOARD_FAB2(SCH_1):PAGE161
  R1F2    2      B RES_0402-100.0,1%,1/16W,CHIP,GA    I43 @BASEBOARD_FAB2_LIB.BASEBOARD_FAB2(SCH_1):PAGE161

FAN_TACH0_R @BASEBOARD_FAB2_LIB.BASEBOARD_FAB2(SCH_1):FAN_TACH0_R
  R1F8    2      B RES_0402-0.0,5%,1/16W,CHIP,G21A    I22 @BASEBOARD_FAB2_LIB.BASEBOARD_FAB2(SCH_1):PAGE181
 R1C31    2      B RES_0402-0.0,5%,1/16W,EMPTY,G2A     I6 @BASEBOARD_FAB2_LIB.BASEBOARD_FAB2(SCH_1):PAGE182
  J1F1   D4 FAN_TACH0 DM-FCI-CONN76-8R-GP-U-01_CONN-A   I134 @BASEBOARD_FAB2_LIB.BASEBOARD_FAB2(SCH_1):PAGE181

FAN_TACH1 @BASEBOARD_FAB2_LIB.BASEBOARD_FAB2(SCH_1):FAN_TACH1
  R1U4    1      A RES_0402-100.0K,1%,1/16W,CHIP,A    I65 @BASEBOARD_FAB2_LIB.BASEBOARD_FAB2(SCH_1):PAGE147
 U25W4   U4 GPIOO1_TACH1_VPIG9 AST2520A1-GP-GP_ASIC2-GB1-AST2A   I106 @BASEBOARD_FAB2_LIB.BASEBOARD_FAB2(SCH_1):PAGE147
 R9R10    1      A RES_0402-0.0,5%,1/16W,CHIP,G21A    I31 @BASEBOARD_FAB2_LIB.BASEBOARD_FAB2(SCH_1):PAGE181

FAN_TACH1_R @BASEBOARD_FAB2_LIB.BASEBOARD_FAB2(SCH_1):FAN_TACH1_R
 R9R10    2      B RES_0402-0.0,5%,1/16W,CHIP,G21A    I31 @BASEBOARD_FAB2_LIB.BASEBOARD_FAB2(SCH_1):PAGE181
 R1C11    2      B RES_0402-0.0,5%,1/16W,EMPTY,G2A    I10 @BASEBOARD_FAB2_LIB.BASEBOARD_FAB2(SCH_1):PAGE182
  J1F1   C4 FAN_TACH1 DM-FCI-CONN76-8R-GP-U-01_CONN-A   I134 @BASEBOARD_FAB2_LIB.BASEBOARD_FAB2(SCH_1):PAGE181

FAN_TACH2 @BASEBOARD_FAB2_LIB.BASEBOARD_FAB2(SCH_1):FAN_TACH2
 R1B22    1      A RES_0402-100.0,1%,1/16W,CHIP,GA    I67 @BASEBOARD_FAB2_LIB.BASEBOARD_FAB2(SCH_1):PAGE161
 C1B15    1      A CAP_A_0402V-0.01UF,25V,10%,X7RA    I68 @BASEBOARD_FAB2_LIB.BASEBOARD_FAB2(SCH_1):PAGE161
 R1B21    2      B RES_0402-4.75K,1%,1/16W,CHIP,GA    I70 @BASEBOARD_FAB2_LIB.BASEBOARD_FAB2(SCH_1):PAGE161
  R1U2    1      A RES_0402-100.0K,1%,1/16W,CHIP,A    I62 @BASEBOARD_FAB2_LIB.BASEBOARD_FAB2(SCH_1):PAGE147
 U25W4   V5 GPIOO2_TACH2 AST2520A1-GP-GP_ASIC2-GB1-AST2A   I106 @BASEBOARD_FAB2_LIB.BASEBOARD_FAB2(SCH_1):PAGE147
 R9R12    1      A RES_0402-0.0,5%,1/16W,CHIP,G21A    I27 @BASEBOARD_FAB2_LIB.BASEBOARD_FAB2(SCH_1):PAGE181

FAN_TACH2_CPU1_D1 @BASEBOARD_FAB2_LIB.BASEBOARD_FAB2(SCH_1):FAN_TACH2_CPU1_D1
 CR1B2    1      C DIODE_SM-SDMK0340L,IC,H71799-0A    I62 @BASEBOARD_FAB2_LIB.BASEBOARD_FAB2(SCH_1):PAGE161
 J10W1    3      3 LOTES-CON4-S1-GP_CONN-G7-LOTESA   I140 @BASEBOARD_FAB2_LIB.BASEBOARD_FAB2(SCH_1):PAGE161

FAN_TACH2_CPU1_D2 @BASEBOARD_FAB2_LIB.BASEBOARD_FAB2(SCH_1):FAN_TACH2_CPU1_D2
 CR1B2    2      A DIODE_SM-SDMK0340L,IC,H71799-0A    I62 @BASEBOARD_FAB2_LIB.BASEBOARD_FAB2(SCH_1):PAGE161
 R1B22    2      B RES_0402-100.0,1%,1/16W,CHIP,GA    I67 @BASEBOARD_FAB2_LIB.BASEBOARD_FAB2(SCH_1):PAGE161

FAN_TACH2_R @BASEBOARD_FAB2_LIB.BASEBOARD_FAB2(SCH_1):FAN_TACH2_R
 R9R12    2      B RES_0402-0.0,5%,1/16W,CHIP,G21A    I27 @BASEBOARD_FAB2_LIB.BASEBOARD_FAB2(SCH_1):PAGE181
  R1C9    2      B RES_0402-0.0,5%,1/16W,EMPTY,G2A     I8 @BASEBOARD_FAB2_LIB.BASEBOARD_FAB2(SCH_1):PAGE182
  J1F1   B4 FAN_TACH2 DM-FCI-CONN76-8R-GP-U-01_CONN-A   I134 @BASEBOARD_FAB2_LIB.BASEBOARD_FAB2(SCH_1):PAGE181

FAN_TACH3 @BASEBOARD_FAB2_LIB.BASEBOARD_FAB2(SCH_1):FAN_TACH3
  R1U1    1      A RES_0402-100.0K,1%,1/16W,CHIP,A    I61 @BASEBOARD_FAB2_LIB.BASEBOARD_FAB2(SCH_1):PAGE147
 U25W4  AB4 GPIOO3_TACH3 AST2520A1-GP-GP_ASIC2-GB1-AST2A   I106 @BASEBOARD_FAB2_LIB.BASEBOARD_FAB2(SCH_1):PAGE147
  R9R9    1      A RES_0402-0.0,5%,1/16W,CHIP,G21A    I32 @BASEBOARD_FAB2_LIB.BASEBOARD_FAB2(SCH_1):PAGE181

FAN_TACH3_R @BASEBOARD_FAB2_LIB.BASEBOARD_FAB2(SCH_1):FAN_TACH3_R
  R9R9    2      B RES_0402-0.0,5%,1/16W,CHIP,G21A    I32 @BASEBOARD_FAB2_LIB.BASEBOARD_FAB2(SCH_1):PAGE181
 R1C10    2      B RES_0402-0.0,5%,1/16W,EMPTY,G2A     I9 @BASEBOARD_FAB2_LIB.BASEBOARD_FAB2(SCH_1):PAGE182
  J1F1   A4 FAN_TACH3 DM-FCI-CONN76-8R-GP-U-01_CONN-A   I134 @BASEBOARD_FAB2_LIB.BASEBOARD_FAB2(SCH_1):PAGE181

FM_100M_N @BASEBOARD_FAB2_LIB.BASEBOARD_FAB2(SCH_1):FM_100M_N
 EU4D2    4 100M_133M_N NB3W1200L_LCC-IC,H13585-001     I1 @BASEBOARD_FAB2_LIB.BASEBOARD_FAB2(SCH_1):PAGE102
 R4D40    2      B RES_0402-4.75K,1%,1/16W,CHIP,GA    I45 @BASEBOARD_FAB2_LIB.BASEBOARD_FAB2(SCH_1):PAGE102
 R6P23    1      A RES_0402-4.75K,1%,1/16W,EMPTY,A    I46 @BASEBOARD_FAB2_LIB.BASEBOARD_FAB2(SCH_1):PAGE102

FM_10GBE_LOM_DISABLE_N @BASEBOARD_FAB2_LIB.BASEBOARD_FAB2(SCH_1):FM_10GBE_LOM_DISABLE_N
 R8C23    2      B RES_0402-0.0,5%,1/16W,EMPTY,G2A   I125 @BASEBOARD_FAB2_LIB.BASEBOARD_FAB2(SCH_1):PAGE118
  U7C1 BY21 GPP_I9_LAN_DIS_N LBG_CORE_QAT_EXT_D_BGA1-IC,H91A   I147 @BASEBOARD_FAB2_LIB.BASEBOARD_FAB2(SCH_1):PAGE120

FM_156M_CPU0_BRD_OSC_EN @BASEBOARD_FAB2_LIB.BASEBOARD_FAB2(SCH_1):FM_156M_CPU0_BRD_OSC_EN
 R8D43    1      A RES_0402-0.0,5%,1/16W,CHIP,G21A    I93 @BASEBOARD_FAB2_LIB.BASEBOARD_FAB2(SCH_1):PAGE104
  U8D7  T10  PB18B LCMXO2_A_256BGA-IC,H63395-001   I179 @BASEBOARD_FAB2_LIB.BASEBOARD_FAB2(SCH_1):PAGE190

FM_156M_CPU1_BRD_OSC_EN @BASEBOARD_FAB2_LIB.BASEBOARD_FAB2(SCH_1):FM_156M_CPU1_BRD_OSC_EN
 R7D36    1      A RES_0402-0.0,5%,1/16W,CHIP,G21A    I96 @BASEBOARD_FAB2_LIB.BASEBOARD_FAB2(SCH_1):PAGE104
  U8D7   N8  PB12C LCMXO2_A_256BGA-IC,H63395-001   I179 @BASEBOARD_FAB2_LIB.BASEBOARD_FAB2(SCH_1):PAGE190

FM_1GB_LOM_DISABLE_N @BASEBOARD_FAB2_LIB.BASEBOARD_FAB2(SCH_1):FM_1GB_LOM_DISABLE_N
 R8C24    2      B RES_0402-0.0,5%,1/16W,CHIP,G21A   I120 @BASEBOARD_FAB2_LIB.BASEBOARD_FAB2(SCH_1):PAGE118
 EU9E1   61 SDP1_PCIE_DIS_SDP1 SPRINGVILLE_SM1-IC,G47144-004    I72 @BASEBOARD_FAB2_LIB.BASEBOARD_FAB2(SCH_1):PAGE139

FM_ADR_COMPLETE @BASEBOARD_FAB2_LIB.BASEBOARD_FAB2(SCH_1):FM_ADR_COMPLETE
  R4T2    1      A RES_0402-0.0,5%,1/16W,EMPTY,G2A     I1 @BASEBOARD_FAB2_LIB.BASEBOARD_FAB2(SCH_1):PAGE89
 R2N26    1      A RES_0402-33.2,1%,1/16W,CHIP,G2A   I219 @BASEBOARD_FAB2_LIB.BASEBOARD_FAB2(SCH_1):PAGE120
  U8D7   C8 PT17A_PCLKT0_1 LCMXO2_A_256BGA-IC,H63395-001    I59 @BASEBOARD_FAB2_LIB.BASEBOARD_FAB2(SCH_1):PAGE191

FM_ADR_COMPLETE_ABC_N @BASEBOARD_FAB2_LIB.BASEBOARD_FAB2(SCH_1):FM_ADR_COMPLETE_ABC_N
  J4G1  230 SAVE_N_NC SCONN288_H44441004_PIP-SCONN,HA     I1 @BASEBOARD_FAB2_LIB.BASEBOARD_FAB2(SCH_1):PAGE43
  J6T1  230 SAVE_N_NC SCONN288_H44441003_PIP-SCONN,HA    I13 @BASEBOARD_FAB2_LIB.BASEBOARD_FAB2(SCH_1):PAGE44
  J4G2  230 SAVE_N_NC SCONN288_H44441004_PIP-SCONN,HA   I111 @BASEBOARD_FAB2_LIB.BASEBOARD_FAB2(SCH_1):PAGE45
  J6U1  230 SAVE_N_NC SCONN288_H44441003_PIP-SCONN,HA    I14 @BASEBOARD_FAB2_LIB.BASEBOARD_FAB2(SCH_1):PAGE46
  J4G3  230 SAVE_N_NC SCONN288_H44441004_PIP-SCONN,HA   I111 @BASEBOARD_FAB2_LIB.BASEBOARD_FAB2(SCH_1):PAGE47
  J6U2  230 SAVE_N_NC SCONN288_H44441003_PIP-SCONN,HA   I111 @BASEBOARD_FAB2_LIB.BASEBOARD_FAB2(SCH_1):PAGE48
  R6F4    2      B RES_0402-49.9,1%,1/16W,CHIP,G2A     I3 @BASEBOARD_FAB2_LIB.BASEBOARD_FAB2(SCH_1):PAGE89

FM_ADR_COMPLETE_CPU0_R @BASEBOARD_FAB2_LIB.BASEBOARD_FAB2(SCH_1):FM_ADR_COMPLETE_CPU0_R
  Q1F1    1      B NPN_SM-MMBT3904,IC,C52245-001    I53 @BASEBOARD_FAB2_LIB.BASEBOARD_FAB2(SCH_1):PAGE89
 R1W32    2      B RES_0402-330,5%,1/16W,CHIP,G21A    I54 @BASEBOARD_FAB2_LIB.BASEBOARD_FAB2(SCH_1):PAGE89

FM_ADR_COMPLETE_CPU1_N @BASEBOARD_FAB2_LIB.BASEBOARD_FAB2(SCH_1):FM_ADR_COMPLETE_CPU1_N
  R6F5    1      A RES_0402-49.9,1%,1/16W,CHIP,G2A     I5 @BASEBOARD_FAB2_LIB.BASEBOARD_FAB2(SCH_1):PAGE89
  R6F2    1      A RES_0402-49.9,1%,1/16W,CHIP,G2A     I6 @BASEBOARD_FAB2_LIB.BASEBOARD_FAB2(SCH_1):PAGE89
 R6W29    2      B RES_0402-10.0K,1%,1/16W,CHIP,GA    I40 @BASEBOARD_FAB2_LIB.BASEBOARD_FAB2(SCH_1):PAGE89
WR8D30    1      A RES_0402-10.0K,1%,1/16W,CHIP,GA    I45 @BASEBOARD_FAB2_LIB.BASEBOARD_FAB2(SCH_1):PAGE89
  Q1W6    3      C NPN_SM-MMBT3904,IC,C52245-001    I55 @BASEBOARD_FAB2_LIB.BASEBOARD_FAB2(SCH_1):PAGE89

FM_ADR_COMPLETE_CPU1_R @BASEBOARD_FAB2_LIB.BASEBOARD_FAB2(SCH_1):FM_ADR_COMPLETE_CPU1_R
  Q1W6    1      B NPN_SM-MMBT3904,IC,C52245-001    I55 @BASEBOARD_FAB2_LIB.BASEBOARD_FAB2(SCH_1):PAGE89
 R1W31    2      B RES_0402-330,5%,1/16W,CHIP,G21A    I56 @BASEBOARD_FAB2_LIB.BASEBOARD_FAB2(SCH_1):PAGE89

FM_ADR_COMPLETE_DEF_N @BASEBOARD_FAB2_LIB.BASEBOARD_FAB2(SCH_1):FM_ADR_COMPLETE_DEF_N
  J4B1  230 SAVE_N_NC SCONN288_H44441004_PIP-SCONN,HA   I111 @BASEBOARD_FAB2_LIB.BASEBOARD_FAB2(SCH_1):PAGE49
  J6M1  230 SAVE_N_NC SCONN288_H44441003_PIP-SCONN,HA   I158 @BASEBOARD_FAB2_LIB.BASEBOARD_FAB2(SCH_1):PAGE50
  J4A2  230 SAVE_N_NC SCONN288_H44441004_PIP-SCONN,HA   I111 @BASEBOARD_FAB2_LIB.BASEBOARD_FAB2(SCH_1):PAGE51
  J6L2  230 SAVE_N_NC SCONN288_H44441003_PIP-SCONN,HA    I12 @BASEBOARD_FAB2_LIB.BASEBOARD_FAB2(SCH_1):PAGE52
  J4A1  230 SAVE_N_NC SCONN288_H44441004_PIP-SCONN,HA   I111 @BASEBOARD_FAB2_LIB.BASEBOARD_FAB2(SCH_1):PAGE53
  J6L1  230 SAVE_N_NC SCONN288_H44441003_PIP-SCONN,HA   I111 @BASEBOARD_FAB2_LIB.BASEBOARD_FAB2(SCH_1):PAGE54
  R6F1    2      B RES_0402-49.9,1%,1/16W,CHIP,G2A     I4 @BASEBOARD_FAB2_LIB.BASEBOARD_FAB2(SCH_1):PAGE89

FM_ADR_COMPLETE_DLY @BASEBOARD_FAB2_LIB.BASEBOARD_FAB2(SCH_1):FM_ADR_COMPLETE_DLY
  R4T1    1      A RES_0402-0.0,5%,1/16W,CHIP,G21A     I2 @BASEBOARD_FAB2_LIB.BASEBOARD_FAB2(SCH_1):PAGE89
  U8D7  B16   PR1D LCMXO2_A_256BGA-IC,H63395-001    I59 @BASEBOARD_FAB2_LIB.BASEBOARD_FAB2(SCH_1):PAGE191

FM_ADR_COMPLETE_GHJ_N @BASEBOARD_FAB2_LIB.BASEBOARD_FAB2(SCH_1):FM_ADR_COMPLETE_GHJ_N
  J1G1  230 SAVE_N_NC SCONN288_H44441004_PIP-SCONN,HA   I111 @BASEBOARD_FAB2_LIB.BASEBOARD_FAB2(SCH_1):PAGE77
  J9T1  230 SAVE_N_NC SCONN288_H44441003_PIP-SCONN,HA    I13 @BASEBOARD_FAB2_LIB.BASEBOARD_FAB2(SCH_1):PAGE78
  J1G2  230 SAVE_N_NC SCONN288_H44441004_PIP-SCONN,HA   I111 @BASEBOARD_FAB2_LIB.BASEBOARD_FAB2(SCH_1):PAGE79
  J9U1  230 SAVE_N_NC SCONN288_H44441003_PIP-SCONN,HA    I24 @BASEBOARD_FAB2_LIB.BASEBOARD_FAB2(SCH_1):PAGE80
  J1G3  230 SAVE_N_NC SCONN288_H44441004_PIP-SCONN,HA   I186 @BASEBOARD_FAB2_LIB.BASEBOARD_FAB2(SCH_1):PAGE81
  J9U2  230 SAVE_N_NC SCONN288_H44441003_PIP-SCONN,HA   I187 @BASEBOARD_FAB2_LIB.BASEBOARD_FAB2(SCH_1):PAGE82
  R6F5    2      B RES_0402-49.9,1%,1/16W,CHIP,G2A     I5 @BASEBOARD_FAB2_LIB.BASEBOARD_FAB2(SCH_1):PAGE89

FM_ADR_COMPLETE_KLM_N @BASEBOARD_FAB2_LIB.BASEBOARD_FAB2(SCH_1):FM_ADR_COMPLETE_KLM_N
  J1B1  230 SAVE_N_NC SCONN288_H44441004_PIP-SCONN,HA   I111 @BASEBOARD_FAB2_LIB.BASEBOARD_FAB2(SCH_1):PAGE83
  J9M1  230 SAVE_N_NC SCONN288_H44441003_PIP-SCONN,HA    I14 @BASEBOARD_FAB2_LIB.BASEBOARD_FAB2(SCH_1):PAGE84
  J1A2  230 SAVE_N_NC SCONN288_H44441004_PIP-SCONN,HA   I111 @BASEBOARD_FAB2_LIB.BASEBOARD_FAB2(SCH_1):PAGE85
  J9L2  230 SAVE_N_NC SCONN288_H44441003_PIP-SCONN,HA    I12 @BASEBOARD_FAB2_LIB.BASEBOARD_FAB2(SCH_1):PAGE86
  J1A1  230 SAVE_N_NC SCONN288_H44441004_PIP-SCONN,HA   I186 @BASEBOARD_FAB2_LIB.BASEBOARD_FAB2(SCH_1):PAGE87
  J9L1  230 SAVE_N_NC SCONN288_H44441003_PIP-SCONN,HA   I111 @BASEBOARD_FAB2_LIB.BASEBOARD_FAB2(SCH_1):PAGE88
  R6F2    2      B RES_0402-49.9,1%,1/16W,CHIP,G2A     I6 @BASEBOARD_FAB2_LIB.BASEBOARD_FAB2(SCH_1):PAGE89

FM_ADR_COMPLETE_R @BASEBOARD_FAB2_LIB.BASEBOARD_FAB2(SCH_1):FM_ADR_COMPLETE_R
  R4T2    2      B RES_0402-0.0,5%,1/16W,EMPTY,G2A     I1 @BASEBOARD_FAB2_LIB.BASEBOARD_FAB2(SCH_1):PAGE89
  R4T1    2      B RES_0402-0.0,5%,1/16W,CHIP,G21A     I2 @BASEBOARD_FAB2_LIB.BASEBOARD_FAB2(SCH_1):PAGE89
 R1W32    1      A RES_0402-330,5%,1/16W,CHIP,G21A    I54 @BASEBOARD_FAB2_LIB.BASEBOARD_FAB2(SCH_1):PAGE89
 R1W31    1      A RES_0402-330,5%,1/16W,CHIP,G21A    I56 @BASEBOARD_FAB2_LIB.BASEBOARD_FAB2(SCH_1):PAGE89

FM_ADR_COMPLETE_R1 @BASEBOARD_FAB2_LIB.BASEBOARD_FAB2(SCH_1):FM_ADR_COMPLETE_R1
  U7C1  BD9 GPP_G17_ADR_COMPLETE LBG_CORE_QAT_EXT_D_BGA1-IC,H91A   I147 @BASEBOARD_FAB2_LIB.BASEBOARD_FAB2(SCH_1):PAGE120
 R2N26    2      B RES_0402-33.2,1%,1/16W,CHIP,G2A   I219 @BASEBOARD_FAB2_LIB.BASEBOARD_FAB2(SCH_1):PAGE120

FM_ADR_MODE_SEL @BASEBOARD_FAB2_LIB.BASEBOARD_FAB2(SCH_1):FM_ADR_MODE_SEL
  R2M7    2      B RES_0402-33.2,1%,1/16W,CHIP,G2A   I174 @BASEBOARD_FAB2_LIB.BASEBOARD_FAB2(SCH_1):PAGE119
  U8D7   T2   PB3C LCMXO2_A_256BGA-IC,H63395-001   I179 @BASEBOARD_FAB2_LIB.BASEBOARD_FAB2(SCH_1):PAGE190

FM_ADR_MODE_SEL_R @BASEBOARD_FAB2_LIB.BASEBOARD_FAB2(SCH_1):FM_ADR_MODE_SEL_R
  U7C1 CA43 GPP_D19 LBG_CORE_QAT_EXT_D_BGA1-IC,H91A   I115 @BASEBOARD_FAB2_LIB.BASEBOARD_FAB2(SCH_1):PAGE119
  R2M7    1      A RES_0402-33.2,1%,1/16W,CHIP,G2A   I174 @BASEBOARD_FAB2_LIB.BASEBOARD_FAB2(SCH_1):PAGE119

FM_ADR_SMI_GPIO_N @BASEBOARD_FAB2_LIB.BASEBOARD_FAB2(SCH_1):FM_ADR_SMI_GPIO_N
 R2P12    2      B RES_0402-0.0,5%,1/16W,EMPTY,G2A    I23 @BASEBOARD_FAB2_LIB.BASEBOARD_FAB2(SCH_1):PAGE89
  U7C1 BJ48 GPP_E7_CPU_GP1 LBG_CORE_QAT_EXT_D_BGA1-IC,H91A   I147 @BASEBOARD_FAB2_LIB.BASEBOARD_FAB2(SCH_1):PAGE120
 R8E11    2      B RES_0402-0.0,5%,1/16W,EMPTY,G2A   I279 @BASEBOARD_FAB2_LIB.BASEBOARD_FAB2(SCH_1):PAGE156
  R2M2    2      B RES_0402-4.75K,1%,1/16W,CHIP,GA   I346 @BASEBOARD_FAB2_LIB.BASEBOARD_FAB2(SCH_1):PAGE157
  R2R4    2      B RES_0402-0.0,5%,1/16W,CHIP,G21A   I184 @BASEBOARD_FAB2_LIB.BASEBOARD_FAB2(SCH_1):PAGE191

FM_ADR_SMI_GPIO_R_N @BASEBOARD_FAB2_LIB.BASEBOARD_FAB2(SCH_1):FM_ADR_SMI_GPIO_R_N
  U8D7   C4   PT9A LCMXO2_A_256BGA-IC,H63395-001    I59 @BASEBOARD_FAB2_LIB.BASEBOARD_FAB2(SCH_1):PAGE191
  R2R4    1      A RES_0402-0.0,5%,1/16W,CHIP,G21A   I184 @BASEBOARD_FAB2_LIB.BASEBOARD_FAB2(SCH_1):PAGE191

FM_ALL_WAKE_N @BASEBOARD_FAB2_LIB.BASEBOARD_FAB2(SCH_1):FM_ALL_WAKE_N
  U8E4    2      A TTL1G126_A_SOT-74HC1G126,IC,A7B     I1 @BASEBOARD_FAB2_LIB.BASEBOARD_FAB2(SCH_1):PAGE142
 R8E29    2      B RES_0402-0.0,5%,1/16W,EMPTY,G2A    I18 @BASEBOARD_FAB2_LIB.BASEBOARD_FAB2(SCH_1):PAGE142
 R8E26    2      B RES_0402-0.0,5%,1/16W,CHIP,G21A    I30 @BASEBOARD_FAB2_LIB.BASEBOARD_FAB2(SCH_1):PAGE142
 R8E28    2      B RES_0402-0.0,5%,1/16W,CHIP,G21A    I31 @BASEBOARD_FAB2_LIB.BASEBOARD_FAB2(SCH_1):PAGE142
 R8E27    2      B RES_0402-0.0,5%,1/16W,CHIP,G21A    I32 @BASEBOARD_FAB2_LIB.BASEBOARD_FAB2(SCH_1):PAGE142
 R8E21    2      B RES_0402-0.0,5%,1/16W,CHIP,G21A    I33 @BASEBOARD_FAB2_LIB.BASEBOARD_FAB2(SCH_1):PAGE142
 R8E30    2      2 2K15R2F-1-GP_SMD-RG1-2K15R2F-1A    I35 @BASEBOARD_FAB2_LIB.BASEBOARD_FAB2(SCH_1):PAGE142

FM_BACKUP_BIOS_SEL_N @BASEBOARD_FAB2_LIB.BASEBOARD_FAB2(SCH_1):FM_BACKUP_BIOS_SEL_N
  U7C1  AW4 GPP_H1_SRCCLKREQ7_N LBG_CORE_QAT_EXT_D_BGA1-IC,H91A   I147 @BASEBOARD_FAB2_LIB.BASEBOARD_FAB2(SCH_1):PAGE120
  U2T2    1      A TTL1G32_A_SOT-74LVC1G32,IC,E60B   I100 @BASEBOARD_FAB2_LIB.BASEBOARD_FAB2(SCH_1):PAGE154
  Q8F1    1   GATE FET_N_SOT23LF-2N7002,FET,C7925A   I126 @BASEBOARD_FAB2_LIB.BASEBOARD_FAB2(SCH_1):PAGE154
  R2T6    2      B RES_0402-4.75K,1%,1/16W,CHIP,GA   I127 @BASEBOARD_FAB2_LIB.BASEBOARD_FAB2(SCH_1):PAGE154
 U25W4   W3 GPION4_PWM4_VPIG4 AST2520A1-GP-GP_ASIC2-GB1-AST2A   I106 @BASEBOARD_FAB2_LIB.BASEBOARD_FAB2(SCH_1):PAGE147

FM_BATTERY_SENSE_EN @BASEBOARD_FAB2_LIB.BASEBOARD_FAB2(SCH_1):FM_BATTERY_SENSE_EN
  Q9G1    5 GATE<0> FET_N_DUAL_SMLF-NTJD4001N,FET,A   I157 @BASEBOARD_FAB2_LIB.BASEBOARD_FAB2(SCH_1):PAGE169
  Q9G1    6 DRAIN<0> FET_N_DUAL_SMLF-NTJD4001N,FET,A   I162 @BASEBOARD_FAB2_LIB.BASEBOARD_FAB2(SCH_1):PAGE169
 R1U49    2      B RES_0402-2.7K,1%,1/16W,CHIP,G2A   I163 @BASEBOARD_FAB2_LIB.BASEBOARD_FAB2(SCH_1):PAGE169

FM_BATTERY_SENSE_EN_N @BASEBOARD_FAB2_LIB.BASEBOARD_FAB2(SCH_1):FM_BATTERY_SENSE_EN_N
  Q9G1    2 GATE<0> FET_N_DUAL_SMLF-NTJD4001N,FET,A   I162 @BASEBOARD_FAB2_LIB.BASEBOARD_FAB2(SCH_1):PAGE169
 R9G35    2      B RES_0402-2.7K,1%,1/16W,CHIP,G2A   I164 @BASEBOARD_FAB2_LIB.BASEBOARD_FAB2(SCH_1):PAGE169
 U25W4  G17 GPIOF6_TXD4_LHSIRQ# AST2520A1-GP-GP_ASIC2-GB1-AST2A   I117 @BASEBOARD_FAB2_LIB.BASEBOARD_FAB2(SCH_1):PAGE145
  R7W6    1      A RES_0402-0.0,5%,1/16W,CHIP,G21A   I176 @BASEBOARD_FAB2_LIB.BASEBOARD_FAB2(SCH_1):PAGE118

FM_BATTERY_SENSE_EN_R_N @BASEBOARD_FAB2_LIB.BASEBOARD_FAB2(SCH_1):FM_BATTERY_SENSE_EN_R_N
  U7C1   H9   GPD7 LBG_CORE_QAT_EXT_D_BGA1-IC,H91A    I73 @BASEBOARD_FAB2_LIB.BASEBOARD_FAB2(SCH_1):PAGE118
  R7W6    2      B RES_0402-0.0,5%,1/16W,CHIP,G21A   I176 @BASEBOARD_FAB2_LIB.BASEBOARD_FAB2(SCH_1):PAGE118
 R7W19    2      B RES_0402-4.75K,1%,1/16W,CHIP,GA   I180 @BASEBOARD_FAB2_LIB.BASEBOARD_FAB2(SCH_1):PAGE118

FM_BB_BMC_MP_GPIO @BASEBOARD_FAB2_LIB.BASEBOARD_FAB2(SCH_1):FM_BB_BMC_MP_GPIO
  U7C1 BW39 GPP_C19 LBG_CORE_QAT_EXT_D_BGA1-IC,H91A   I115 @BASEBOARD_FAB2_LIB.BASEBOARD_FAB2(SCH_1):PAGE119
 U25W4  C13 GPIOA6_TIMER7_MDC2 AST2520A1-GP-GP_ASIC2-GB1-AST2A   I106 @BASEBOARD_FAB2_LIB.BASEBOARD_FAB2(SCH_1):PAGE147
  J1C1   C4 FAN_TACH1 DM-FCI-CONN76-8R-GP-U-01_CONN-A    I79 @BASEBOARD_FAB2_LIB.BASEBOARD_FAB2(SCH_1):PAGE182

FM_BEEP_LED_P @BASEBOARD_FAB2_LIB.BASEBOARD_FAB2(SCH_1):FM_BEEP_LED_P
 R1L33    1      A RES_0402-221,1.0%,1/16W,CHIP,GA    I45 @BASEBOARD_FAB2_LIB.BASEBOARD_FAB2(SCH_1):PAGE175
 DS9A3    2      A LED_1NCLF-YELLOW,IC,C96565-003    I67 @BASEBOARD_FAB2_LIB.BASEBOARD_FAB2(SCH_1):PAGE175

FM_BIOS_MRC_DEBUG_MSG_DIS_N @BASEBOARD_FAB2_LIB.BASEBOARD_FAB2(SCH_1):FM_BIOS_MRC_DEBUG_MSG_DIS_N
  U7C1 BV25 GPP_I10 LBG_CORE_QAT_EXT_D_BGA1-IC,H91A   I147 @BASEBOARD_FAB2_LIB.BASEBOARD_FAB2(SCH_1):PAGE120
 U25W4  F19 GPIOD0_SD2CLK AST2520A1-GP-GP_ASIC2-GB1-AST2A   I117 @BASEBOARD_FAB2_LIB.BASEBOARD_FAB2(SCH_1):PAGE145

FM_BIOS_POST_CMPLT_N @BASEBOARD_FAB2_LIB.BASEBOARD_FAB2(SCH_1):FM_BIOS_POST_CMPLT_N
  U7C1 BJ22 GPP_B20 LBG_CORE_QAT_EXT_D_BGA1-IC,H91A   I115 @BASEBOARD_FAB2_LIB.BASEBOARD_FAB2(SCH_1):PAGE119
  U7C1 BY33 GPP_C21 LBG_CORE_QAT_EXT_D_BGA1-IC,H91A   I115 @BASEBOARD_FAB2_LIB.BASEBOARD_FAB2(SCH_1):PAGE119
  R8C6    2      B RES_0402-4.75K,1%,1/16W,CHIP,GA   I303 @BASEBOARD_FAB2_LIB.BASEBOARD_FAB2(SCH_1):PAGE133
 U25W4  P19 GPIOAA7_VPOR9_NORD7_SALT14 AST2520A1-GP-GP_ASIC2-GB1-AST2A   I104 @BASEBOARD_FAB2_LIB.BASEBOARD_FAB2(SCH_1):PAGE146

FM_BIOS_PREFRB2_GOOD @BASEBOARD_FAB2_LIB.BASEBOARD_FAB2(SCH_1):FM_BIOS_PREFRB2_GOOD
  U7C1 BK20 GPP_B19 LBG_CORE_QAT_EXT_D_BGA1-IC,H91A   I115 @BASEBOARD_FAB2_LIB.BASEBOARD_FAB2(SCH_1):PAGE119
 R2N13    1      A RES_0402-10.0K,1%,1/16W,CHIP,GA    I75 @BASEBOARD_FAB2_LIB.BASEBOARD_FAB2(SCH_1):PAGE147
 U25W4   V3 GPION2_PWM2_VPIG2 AST2520A1-GP-GP_ASIC2-GB1-AST2A   I106 @BASEBOARD_FAB2_LIB.BASEBOARD_FAB2(SCH_1):PAGE147

FM_BIOS_SMI_ACTIVE_N @BASEBOARD_FAB2_LIB.BASEBOARD_FAB2(SCH_1):FM_BIOS_SMI_ACTIVE_N
  U7C1 BE15 GPP_G19_SMI_N LBG_CORE_QAT_EXT_D_BGA1-IC,H91A   I147 @BASEBOARD_FAB2_LIB.BASEBOARD_FAB2(SCH_1):PAGE120
  U7C1  BA2 GPP_H21_SSATAXPCIE3_SSATAGP3 LBG_CORE_QAT_EXT_D_BGA1-IC,H91A   I147 @BASEBOARD_FAB2_LIB.BASEBOARD_FAB2(SCH_1):PAGE120
 R2N32    2      B RES_0402-4.75K,1%,1/16W,CHIP,GA   I341 @BASEBOARD_FAB2_LIB.BASEBOARD_FAB2(SCH_1):PAGE133
 U25W4  E14 GPIOG7_SGPS2I1_SALT4 AST2520A1-GP-GP_ASIC2-GB1-AST2A   I117 @BASEBOARD_FAB2_LIB.BASEBOARD_FAB2(SCH_1):PAGE145

FM_BIOS_SPI_BMC_CTRL @BASEBOARD_FAB2_LIB.BASEBOARD_FAB2(SCH_1):FM_BIOS_SPI_BMC_CTRL
  U8F1    1      S PI3B3257A_TSSOPLF-IC,E16801-001    I74 @BASEBOARD_FAB2_LIB.BASEBOARD_FAB2(SCH_1):PAGE154
  U2T1    1      S PI3B3257A_TSSOPLF-IC,E16801-001    I75 @BASEBOARD_FAB2_LIB.BASEBOARD_FAB2(SCH_1):PAGE154
  R1U6    1      A RES_0402-10.0K,1%,1/16W,CHIP,GA   I128 @BASEBOARD_FAB2_LIB.BASEBOARD_FAB2(SCH_1):PAGE154
 U25W4  AA3 GPION5_PWM5_VPIG5 AST2520A1-GP-GP_ASIC2-GB1-AST2A   I106 @BASEBOARD_FAB2_LIB.BASEBOARD_FAB2(SCH_1):PAGE147

FM_BIOS_TOP_SWAP @BASEBOARD_FAB2_LIB.BASEBOARD_FAB2(SCH_1):FM_BIOS_TOP_SWAP
  U7C1 AP15 GPP_F17_USB2_OC6_N LBG_CORE_QAT_EXT_D_BGA1-IC,H91A   I147 @BASEBOARD_FAB2_LIB.BASEBOARD_FAB2(SCH_1):PAGE120
  U8E3    2      A TTL1G126_A_SOT-74HC1G126,IC,A7B   I130 @BASEBOARD_FAB2_LIB.BASEBOARD_FAB2(SCH_1):PAGE136
 R8E16    1      A RES_0402-20.0K,1%,1/16W,CHIP,GA   I140 @BASEBOARD_FAB2_LIB.BASEBOARD_FAB2(SCH_1):PAGE136
  J7G3   10   IO10 CONN12_C73564003_PIP-CONN,C735A   I174 @BASEBOARD_FAB2_LIB.BASEBOARD_FAB2(SCH_1):PAGE136
 R8E19    2      B RES_0402-4.75K,1%,1/16W,EMPTY,A   I361 @BASEBOARD_FAB2_LIB.BASEBOARD_FAB2(SCH_1):PAGE157
 U25W4   U2 GPIOL3_NRI1_VPIHS AST2520A1-GP-GP_ASIC2-GB1-AST2A   I117 @BASEBOARD_FAB2_LIB.BASEBOARD_FAB2(SCH_1):PAGE145

FM_BIOS_TOP_SWAP_SPKR @BASEBOARD_FAB2_LIB.BASEBOARD_FAB2(SCH_1):FM_BIOS_TOP_SWAP_SPKR
  U7C1 BH13 GPP_B14_SPKR LBG_CORE_QAT_EXT_D_BGA1-IC,H91A   I115 @BASEBOARD_FAB2_LIB.BASEBOARD_FAB2(SCH_1):PAGE119
 R8E20    2      B RES_0402-33.2,1%,1/16W,CHIP,G2A   I126 @BASEBOARD_FAB2_LIB.BASEBOARD_FAB2(SCH_1):PAGE136
  Q9A3    1   GATE FET_N_SOT23LF-2N7002,FET,C7925A    I49 @BASEBOARD_FAB2_LIB.BASEBOARD_FAB2(SCH_1):PAGE175

FM_BIOS_TOP_SWAP_SPKR_R @BASEBOARD_FAB2_LIB.BASEBOARD_FAB2(SCH_1):FM_BIOS_TOP_SWAP_SPKR_R
 R8E20    1      A RES_0402-33.2,1%,1/16W,CHIP,G2A   I126 @BASEBOARD_FAB2_LIB.BASEBOARD_FAB2(SCH_1):PAGE136
  U8E3    4      Y TTL1G126_A_SOT-74HC1G126,IC,A7B   I130 @BASEBOARD_FAB2_LIB.BASEBOARD_FAB2(SCH_1):PAGE136

FM_BIOS_USB_RECOVERY @BASEBOARD_FAB2_LIB.BASEBOARD_FAB2(SCH_1):FM_BIOS_USB_RECOVERY
  U7C1 AH17 GPP_F5_SATA_DEVSLP3 LBG_CORE_QAT_EXT_D_BGA1-IC,H91A   I147 @BASEBOARD_FAB2_LIB.BASEBOARD_FAB2(SCH_1):PAGE120
 R3T14    1      A RES_0402-10.0K,1%,1/16W,CHIP,GA   I156 @BASEBOARD_FAB2_LIB.BASEBOARD_FAB2(SCH_1):PAGE136
  J7G3    4    IO4 CONN12_C73564003_PIP-CONN,C735A   I174 @BASEBOARD_FAB2_LIB.BASEBOARD_FAB2(SCH_1):PAGE136

FM_BMC_CPLD_GPO @BASEBOARD_FAB2_LIB.BASEBOARD_FAB2(SCH_1):FM_BMC_CPLD_GPO
  U7C1 CA45 GPP_D7 LBG_CORE_QAT_EXT_D_BGA1-IC,H91A   I115 @BASEBOARD_FAB2_LIB.BASEBOARD_FAB2(SCH_1):PAGE119
  R2M5    2      B RES_0402-4.75K,1%,1/16W,CHIP,GA   I348 @BASEBOARD_FAB2_LIB.BASEBOARD_FAB2(SCH_1):PAGE157
  U8D7   R1  PL14C LCMXO2_A_256BGA-IC,H63395-001   I179 @BASEBOARD_FAB2_LIB.BASEBOARD_FAB2(SCH_1):PAGE190
 U25W4  Y20 GPIOZ0_VPOG2_NORA0_SIOPBI# AST2520A1-GP-GP_ASIC2-GB1-AST2A   I104 @BASEBOARD_FAB2_LIB.BASEBOARD_FAB2(SCH_1):PAGE146

FM_BMC_CPLD_MP_RST_N @BASEBOARD_FAB2_LIB.BASEBOARD_FAB2(SCH_1):FM_BMC_CPLD_MP_RST_N
  U7C1  A15   GPD9 LBG_CORE_QAT_EXT_D_BGA1-IC,H91A    I73 @BASEBOARD_FAB2_LIB.BASEBOARD_FAB2(SCH_1):PAGE118
  R1L7    2      B RES_0402-4.75K,1%,1/16W,CHIP,GA   I382 @BASEBOARD_FAB2_LIB.BASEBOARD_FAB2(SCH_1):PAGE157
  U8D7   R4   PB6D LCMXO2_A_256BGA-IC,H63395-001   I179 @BASEBOARD_FAB2_LIB.BASEBOARD_FAB2(SCH_1):PAGE190
 U25W4  B13 GPIOA7_TIMER8_MDIO2 AST2520A1-GP-GP_ASIC2-GB1-AST2A   I106 @BASEBOARD_FAB2_LIB.BASEBOARD_FAB2(SCH_1):PAGE147

FM_BMC_ENABLE_N @BASEBOARD_FAB2_LIB.BASEBOARD_FAB2(SCH_1):FM_BMC_ENABLE_N
  U7C1 BM38 GPP_D5 LBG_CORE_QAT_EXT_D_BGA1-IC,H91A   I115 @BASEBOARD_FAB2_LIB.BASEBOARD_FAB2(SCH_1):PAGE119
 R9E14    2      B RES_0402-0.0,5%,1/16W,EMPTY,G2A   I393 @BASEBOARD_FAB2_LIB.BASEBOARD_FAB2(SCH_1):PAGE157
 R7W22    2      B RES_0402-4.75K,1%,1/16W,CHIP,GA   I230 @BASEBOARD_FAB2_LIB.BASEBOARD_FAB2(SCH_1):PAGE119

FM_BMC_FAULT_LED @BASEBOARD_FAB2_LIB.BASEBOARD_FAB2(SCH_1):FM_BMC_FAULT_LED
  Q9F1    5 GATE<0> FET_N_DUAL_SMLF-NTJD4001N,FET,A    I79 @BASEBOARD_FAB2_LIB.BASEBOARD_FAB2(SCH_1):PAGE177
  Q9F1    6 DRAIN<0> FET_N_DUAL_SMLF-NTJD4001N,FET,A    I80 @BASEBOARD_FAB2_LIB.BASEBOARD_FAB2(SCH_1):PAGE177
 R9F52    2      B RES_0402-4.75K,1%,1/16W,CHIP,GA    I82 @BASEBOARD_FAB2_LIB.BASEBOARD_FAB2(SCH_1):PAGE177

FM_BMC_FAULT_LED_N @BASEBOARD_FAB2_LIB.BASEBOARD_FAB2(SCH_1):FM_BMC_FAULT_LED_N
  U7C1 BR38 GPP_D8 LBG_CORE_QAT_EXT_D_BGA1-IC,H91A   I115 @BASEBOARD_FAB2_LIB.BASEBOARD_FAB2(SCH_1):PAGE119
 R9F30    2      B RES_0402-4.75K,1%,1/16W,CHIP,GA    I76 @BASEBOARD_FAB2_LIB.BASEBOARD_FAB2(SCH_1):PAGE177
  Q9F1    2 GATE<0> FET_N_DUAL_SMLF-NTJD4001N,FET,A    I80 @BASEBOARD_FAB2_LIB.BASEBOARD_FAB2(SCH_1):PAGE177
 U25W4   A4 RGMII1RXCTL_GPIOU5 AST2520A1-GP-GP_ASIC2-GB1-AST2A   I106 @BASEBOARD_FAB2_LIB.BASEBOARD_FAB2(SCH_1):PAGE147

FM_BMC_HEARTBEAT_N @BASEBOARD_FAB2_LIB.BASEBOARD_FAB2(SCH_1):FM_BMC_HEARTBEAT_N
  U7C1 CA48 GPP_D20 LBG_CORE_QAT_EXT_D_BGA1-IC,H91A   I115 @BASEBOARD_FAB2_LIB.BASEBOARD_FAB2(SCH_1):PAGE119
 U25W4  Y18 HBLED# AST2520A1-GP-GP_ASIC2-GB1-AST2A   I105 @BASEBOARD_FAB2_LIB.BASEBOARD_FAB2(SCH_1):PAGE146
 R8B25    2      B RES_0402-4.75K,1%,1/16W,CHIP,GA   I175 @BASEBOARD_FAB2_LIB.BASEBOARD_FAB2(SCH_1):PAGE151
  Q9E1    2 GATE<0> FET_N_DUAL_SMLF-NTJD4001N,FET,A   I198 @BASEBOARD_FAB2_LIB.BASEBOARD_FAB2(SCH_1):PAGE151

FM_BMC_NMI_N @BASEBOARD_FAB2_LIB.BASEBOARD_FAB2(SCH_1):FM_BMC_NMI_N
  U7C1  BF3 GPP_H20_SSATAXPCIE2_SSATAGP2 LBG_CORE_QAT_EXT_D_BGA1-IC,H91A   I147 @BASEBOARD_FAB2_LIB.BASEBOARD_FAB2(SCH_1):PAGE120
 R2N27    2      B RES_0402-4.75K,1%,1/16W,CHIP,GA    I97 @BASEBOARD_FAB2_LIB.BASEBOARD_FAB2(SCH_1):PAGE157
 R2N25    2      B RES_0402-51.1,1.0%,1/16W,CHIP,A   I302 @BASEBOARD_FAB2_LIB.BASEBOARD_FAB2(SCH_1):PAGE157
R25W83    1      A RES_0402-0.0,5%,1/16W,CHIP,G21A    I26 @BASEBOARD_FAB2_LIB.BASEBOARD_FAB2(SCH_1):PAGE146

FM_BMC_NMI_N_R @BASEBOARD_FAB2_LIB.BASEBOARD_FAB2(SCH_1):FM_BMC_NMI_N_R
R25W83    2      B RES_0402-0.0,5%,1/16W,CHIP,G21A    I26 @BASEBOARD_FAB2_LIB.BASEBOARD_FAB2(SCH_1):PAGE146
 U25W4 AB20 GPIOZ1_VPOG3_NORA1_SIOPWRGD AST2520A1-GP-GP_ASIC2-GB1-AST2A   I104 @BASEBOARD_FAB2_LIB.BASEBOARD_FAB2(SCH_1):PAGE146

FM_BMC_ONCTL_N @BASEBOARD_FAB2_LIB.BASEBOARD_FAB2(SCH_1):FM_BMC_ONCTL_N
  U8D7   C7  PT13B LCMXO2_A_256BGA-IC,H63395-001    I59 @BASEBOARD_FAB2_LIB.BASEBOARD_FAB2(SCH_1):PAGE191
 R1T15    1      A RES_0402-0.0,5%,1/16W,EMPTY,G2A   I100 @BASEBOARD_FAB2_LIB.BASEBOARD_FAB2(SCH_1):PAGE145

FM_BMC_ONCTL_R_N @BASEBOARD_FAB2_LIB.BASEBOARD_FAB2(SCH_1):FM_BMC_ONCTL_R_N
 R1T15    2      B RES_0402-0.0,5%,1/16W,EMPTY,G2A   I100 @BASEBOARD_FAB2_LIB.BASEBOARD_FAB2(SCH_1):PAGE145
 R1T23    1      A RES_0402-0.0,5%,1/16W,EMPTY,G2A   I101 @BASEBOARD_FAB2_LIB.BASEBOARD_FAB2(SCH_1):PAGE145
 U25W4  P21 GPIOY3_SIOONCTRL# AST2520A1-GP-GP_ASIC2-GB1-AST2A   I117 @BASEBOARD_FAB2_LIB.BASEBOARD_FAB2(SCH_1):PAGE145

FM_BMC_PWRBTN_OUT_N @BASEBOARD_FAB2_LIB.BASEBOARD_FAB2(SCH_1):FM_BMC_PWRBTN_OUT_N
 R2T34    2      B RES_0402-4.75K,1%,1/16W,CHIP,GA   I206 @BASEBOARD_FAB2_LIB.BASEBOARD_FAB2(SCH_1):PAGE156
 U25W4  F17 GPIOE3_NRI3 AST2520A1-GP-GP_ASIC2-GB1-AST2A   I117 @BASEBOARD_FAB2_LIB.BASEBOARD_FAB2(SCH_1):PAGE145
  U8F3    3     2A SN74LVC2G07DCKR-GP_DISCRET-G4-A   I340 @BASEBOARD_FAB2_LIB.BASEBOARD_FAB2(SCH_1):PAGE156

FM_BMC_READY_N @BASEBOARD_FAB2_LIB.BASEBOARD_FAB2(SCH_1):FM_BMC_READY_N
  R7D6    2      B RES_0402-4.75K,1%,1/16W,CHIP,GA   I306 @BASEBOARD_FAB2_LIB.BASEBOARD_FAB2(SCH_1):PAGE133
 U25W4  U19 GPIOS1_VPOB3_BMCINT AST2520A1-GP-GP_ASIC2-GB1-AST2A   I104 @BASEBOARD_FAB2_LIB.BASEBOARD_FAB2(SCH_1):PAGE146
  R1F9    1      A RES_0402-0.0,5%,1/16W,EMPTY,G2A     I7 @BASEBOARD_FAB2_LIB.BASEBOARD_FAB2(SCH_1):PAGE182
 R7W13    1      A RES_0402-0.0,5%,1/16W,CHIP,G21A   I226 @BASEBOARD_FAB2_LIB.BASEBOARD_FAB2(SCH_1):PAGE119
 R7W14    1      A RES_0402-0.0,5%,1/16W,CHIP,G21A   I274 @BASEBOARD_FAB2_LIB.BASEBOARD_FAB2(SCH_1):PAGE120

FM_BMC_READY_R1_N @BASEBOARD_FAB2_LIB.BASEBOARD_FAB2(SCH_1):FM_BMC_READY_R1_N
  U7C1 AH13 GPP_F4_SATAXPCIE7_SATAGP7 LBG_CORE_QAT_EXT_D_BGA1-IC,H91A   I147 @BASEBOARD_FAB2_LIB.BASEBOARD_FAB2(SCH_1):PAGE120
 R7W14    2      B RES_0402-0.0,5%,1/16W,CHIP,G21A   I274 @BASEBOARD_FAB2_LIB.BASEBOARD_FAB2(SCH_1):PAGE120

FM_BMC_READY_R_N @BASEBOARD_FAB2_LIB.BASEBOARD_FAB2(SCH_1):FM_BMC_READY_R_N
  U7C1   V1 GPP_A23 LBG_CORE_QAT_EXT_D_BGA1-IC,H91A   I115 @BASEBOARD_FAB2_LIB.BASEBOARD_FAB2(SCH_1):PAGE119
 R7W13    2      B RES_0402-0.0,5%,1/16W,CHIP,G21A   I226 @BASEBOARD_FAB2_LIB.BASEBOARD_FAB2(SCH_1):PAGE119

FM_BMC_SYS_THROTTLE_R_N @BASEBOARD_FAB2_LIB.BASEBOARD_FAB2(SCH_1):FM_BMC_SYS_THROTTLE_R_N
 U25W4  E13 GPIOA3_TIMER4 AST2520A1-GP-GP_ASIC2-GB1-AST2A   I117 @BASEBOARD_FAB2_LIB.BASEBOARD_FAB2(SCH_1):PAGE145
 R2T41    2      B RES_0402-22.1,1.0%,1/16W,CHIP,A   I136 @BASEBOARD_FAB2_LIB.BASEBOARD_FAB2(SCH_1):PAGE145

FM_BOARD_REV_ID0 @BASEBOARD_FAB2_LIB.BASEBOARD_FAB2(SCH_1):FM_BOARD_REV_ID0
  U7C1 CA30 GPP_C12 LBG_CORE_QAT_EXT_D_BGA1-IC,H91A   I115 @BASEBOARD_FAB2_LIB.BASEBOARD_FAB2(SCH_1):PAGE119
 U25W4  E21 GPIOD1_SD2CMD AST2520A1-GP-GP_ASIC2-GB1-AST2A   I117 @BASEBOARD_FAB2_LIB.BASEBOARD_FAB2(SCH_1):PAGE145
  R1T4    2      B RES_0402-2.7K,1%,1/16W,CHIP,G2A   I100 @BASEBOARD_FAB2_LIB.BASEBOARD_FAB2(SCH_1):PAGE164
 R1T10    1      A RES_0402-1.00K,1%,1/16W,CHIP,GA   I101 @BASEBOARD_FAB2_LIB.BASEBOARD_FAB2(SCH_1):PAGE164

FM_BOARD_REV_ID1 @BASEBOARD_FAB2_LIB.BASEBOARD_FAB2(SCH_1):FM_BOARD_REV_ID1
  U7C1 BV38 GPP_C13 LBG_CORE_QAT_EXT_D_BGA1-IC,H91A   I115 @BASEBOARD_FAB2_LIB.BASEBOARD_FAB2(SCH_1):PAGE119
 U25W4  D20 GPIOD3_SD2DAT1 AST2520A1-GP-GP_ASIC2-GB1-AST2A   I117 @BASEBOARD_FAB2_LIB.BASEBOARD_FAB2(SCH_1):PAGE145
  R1T6    2      B RES_0402-2.7K,1%,1/16W,CHIP,G2A    I51 @BASEBOARD_FAB2_LIB.BASEBOARD_FAB2(SCH_1):PAGE164
 R1T12    1      A RES_0402-1.00K,1%,1/16W,CHIP,GA    I53 @BASEBOARD_FAB2_LIB.BASEBOARD_FAB2(SCH_1):PAGE164

FM_BOARD_REV_ID2 @BASEBOARD_FAB2_LIB.BASEBOARD_FAB2(SCH_1):FM_BOARD_REV_ID2
  U7C1 BV33 GPP_C11 LBG_CORE_QAT_EXT_D_BGA1-IC,H91A   I115 @BASEBOARD_FAB2_LIB.BASEBOARD_FAB2(SCH_1):PAGE119
 R1T11    1      A RES_0402-1.00K,1%,1/16W,CHIP,GA     I7 @BASEBOARD_FAB2_LIB.BASEBOARD_FAB2(SCH_1):PAGE164
  R1T5    2      B RES_0402-2.7K,1%,1/16W,EMPTY,GA    I11 @BASEBOARD_FAB2_LIB.BASEBOARD_FAB2(SCH_1):PAGE164
 U25W4  E20 GPIOD5_SD2DAT3 AST2520A1-GP-GP_ASIC2-GB1-AST2A   I117 @BASEBOARD_FAB2_LIB.BASEBOARD_FAB2(SCH_1):PAGE145

FM_BOARD_SKU_ID0 @BASEBOARD_FAB2_LIB.BASEBOARD_FAB2(SCH_1):FM_BOARD_SKU_ID0
  U7C1 BD13 GPP_G12 LBG_CORE_QAT_EXT_D_BGA1-IC,H91A   I147 @BASEBOARD_FAB2_LIB.BASEBOARD_FAB2(SCH_1):PAGE120
 U25W4   V4 GPIOP0_TACH8_VPIR6 AST2520A1-GP-GP_ASIC2-GB1-AST2A   I106 @BASEBOARD_FAB2_LIB.BASEBOARD_FAB2(SCH_1):PAGE147
 R1U23    2      B RES_0402-2.7K,1%,1/16W,CHIP,G2A    I34 @BASEBOARD_FAB2_LIB.BASEBOARD_FAB2(SCH_1):PAGE164
 R1U18    1      A RES_0402-1.00K,1%,1/16W,CHIP,GA    I40 @BASEBOARD_FAB2_LIB.BASEBOARD_FAB2(SCH_1):PAGE164

FM_BOARD_SKU_ID1 @BASEBOARD_FAB2_LIB.BASEBOARD_FAB2(SCH_1):FM_BOARD_SKU_ID1
  U7C1 AY18 GPP_G13 LBG_CORE_QAT_EXT_D_BGA1-IC,H91A   I147 @BASEBOARD_FAB2_LIB.BASEBOARD_FAB2(SCH_1):PAGE120
 U25W4   W5 GPIOP1_TACH9_VPIR7 AST2520A1-GP-GP_ASIC2-GB1-AST2A   I106 @BASEBOARD_FAB2_LIB.BASEBOARD_FAB2(SCH_1):PAGE147
 R1U16    1      A RES_0402-1.00K,1%,1/16W,CHIP,GA    I37 @BASEBOARD_FAB2_LIB.BASEBOARD_FAB2(SCH_1):PAGE164
 R1U22    2      B RES_0402-2.7K,1%,1/16W,CHIP,G2A    I43 @BASEBOARD_FAB2_LIB.BASEBOARD_FAB2(SCH_1):PAGE164

FM_BOARD_SKU_ID2 @BASEBOARD_FAB2_LIB.BASEBOARD_FAB2(SCH_1):FM_BOARD_SKU_ID2
  U7C1  AV7 GPP_G14 LBG_CORE_QAT_EXT_D_BGA1-IC,H91A   I147 @BASEBOARD_FAB2_LIB.BASEBOARD_FAB2(SCH_1):PAGE120
 R1U17    1      A RES_0402-1.00K,1%,1/16W,CHIP,GA    I21 @BASEBOARD_FAB2_LIB.BASEBOARD_FAB2(SCH_1):PAGE164
 U25W4  AA5 GPIOP2_TACH10_VPIR8 AST2520A1-GP-GP_ASIC2-GB1-AST2A   I106 @BASEBOARD_FAB2_LIB.BASEBOARD_FAB2(SCH_1):PAGE147
 R1U24    2      B RES_0402-2.7K,1%,1/16W,CHIP,G2A    I47 @BASEBOARD_FAB2_LIB.BASEBOARD_FAB2(SCH_1):PAGE164

FM_BOARD_SKU_ID3 @BASEBOARD_FAB2_LIB.BASEBOARD_FAB2(SCH_1):FM_BOARD_SKU_ID3
  U7C1 BE18 GPP_G15 LBG_CORE_QAT_EXT_D_BGA1-IC,H91A   I147 @BASEBOARD_FAB2_LIB.BASEBOARD_FAB2(SCH_1):PAGE120
 U25W4  AB5 GPIOP3_TACH11_VPIR9 AST2520A1-GP-GP_ASIC2-GB1-AST2A   I106 @BASEBOARD_FAB2_LIB.BASEBOARD_FAB2(SCH_1):PAGE147
 R1U21    2      B RES_0402-2.7K,1%,1/16W,CHIP,G2A    I41 @BASEBOARD_FAB2_LIB.BASEBOARD_FAB2(SCH_1):PAGE164
 R1U15    1      A RES_0402-1.00K,1%,1/16W,CHIP,GA    I48 @BASEBOARD_FAB2_LIB.BASEBOARD_FAB2(SCH_1):PAGE164

FM_BOARD_SKU_ID4 @BASEBOARD_FAB2_LIB.BASEBOARD_FAB2(SCH_1):FM_BOARD_SKU_ID4
  U7C1 BD17 GPP_G16 LBG_CORE_QAT_EXT_D_BGA1-IC,H91A   I147 @BASEBOARD_FAB2_LIB.BASEBOARD_FAB2(SCH_1):PAGE120
 R2N18    1      A RES_0402-1.00K,1%,1/16W,CHIP,GA    I32 @BASEBOARD_FAB2_LIB.BASEBOARD_FAB2(SCH_1):PAGE164
 U25W4   Y6 GPIOP4_TACH12 AST2520A1-GP-GP_ASIC2-GB1-AST2A   I106 @BASEBOARD_FAB2_LIB.BASEBOARD_FAB2(SCH_1):PAGE147
 R2N17    2      B RES_0402-2.7K,1%,1/16W,CHIP,G2A    I46 @BASEBOARD_FAB2_LIB.BASEBOARD_FAB2(SCH_1):PAGE164

FM_CPLD_ADR_TRIGGER_N @BASEBOARD_FAB2_LIB.BASEBOARD_FAB2(SCH_1):FM_CPLD_ADR_TRIGGER_N
  R2M1    1      A RES_0402-33.2,1%,1/16W,CHIP,G2A   I218 @BASEBOARD_FAB2_LIB.BASEBOARD_FAB2(SCH_1):PAGE120
  U8D7  E14   PR2B LCMXO2_A_256BGA-IC,H63395-001    I59 @BASEBOARD_FAB2_LIB.BASEBOARD_FAB2(SCH_1):PAGE191

FM_CPLD_ADR_TRIGGER_R_N @BASEBOARD_FAB2_LIB.BASEBOARD_FAB2(SCH_1):FM_CPLD_ADR_TRIGGER_R_N
  U7C1 BE52 GPP_E3_CPU_GP0 LBG_CORE_QAT_EXT_D_BGA1-IC,H91A   I147 @BASEBOARD_FAB2_LIB.BASEBOARD_FAB2(SCH_1):PAGE120
  R2M1    2      B RES_0402-33.2,1%,1/16W,CHIP,G2A   I218 @BASEBOARD_FAB2_LIB.BASEBOARD_FAB2(SCH_1):PAGE120

FM_CPLD_BMC_PWRDN_N @BASEBOARD_FAB2_LIB.BASEBOARD_FAB2(SCH_1):FM_CPLD_BMC_PWRDN_N
  U7C1 BW41 GPP_D6 LBG_CORE_QAT_EXT_D_BGA1-IC,H91A   I115 @BASEBOARD_FAB2_LIB.BASEBOARD_FAB2(SCH_1):PAGE119
  R2U4    2      B RES_0402-4.75K,1%,1/16W,CHIP,GA   I367 @BASEBOARD_FAB2_LIB.BASEBOARD_FAB2(SCH_1):PAGE157
  U8D7   N9  PB16D LCMXO2_A_256BGA-IC,H63395-001   I179 @BASEBOARD_FAB2_LIB.BASEBOARD_FAB2(SCH_1):PAGE190
 U25W4  D14 GPIOA1_MAC2LINK AST2520A1-GP-GP_ASIC2-GB1-AST2A   I117 @BASEBOARD_FAB2_LIB.BASEBOARD_FAB2(SCH_1):PAGE145

FM_CPLD_DBG_PWR_EN @BASEBOARD_FAB2_LIB.BASEBOARD_FAB2(SCH_1):FM_CPLD_DBG_PWR_EN
  R1L9    2      B RES_0402-100.0K,1%,1/16W,CHIP,A   I130 @BASEBOARD_FAB2_LIB.BASEBOARD_FAB2(SCH_1):PAGE155
  Q1L2    3 DRAIN<0> FET_N_DUAL_SMLF-NTJD4001N,FET,A   I187 @BASEBOARD_FAB2_LIB.BASEBOARD_FAB2(SCH_1):PAGE155
  Q1L2    2 GATE<0> FET_N_DUAL_SMLF-NTJD4001N,FET,A   I188 @BASEBOARD_FAB2_LIB.BASEBOARD_FAB2(SCH_1):PAGE155

FM_CPLD_DBG_PWR_EN_N @BASEBOARD_FAB2_LIB.BASEBOARD_FAB2(SCH_1):FM_CPLD_DBG_PWR_EN_N
  R1L2    1      A RES_0402-10.0,1%,1/16W,CHIP,G2A   I186 @BASEBOARD_FAB2_LIB.BASEBOARD_FAB2(SCH_1):PAGE155
  U8D7   T8  PB12B LCMXO2_A_256BGA-IC,H63395-001   I179 @BASEBOARD_FAB2_LIB.BASEBOARD_FAB2(SCH_1):PAGE190

FM_CPLD_DBG_PWR_EN_R_N @BASEBOARD_FAB2_LIB.BASEBOARD_FAB2(SCH_1):FM_CPLD_DBG_PWR_EN_R_N
  R1L2    2      B RES_0402-10.0,1%,1/16W,CHIP,G2A   I186 @BASEBOARD_FAB2_LIB.BASEBOARD_FAB2(SCH_1):PAGE155
  Q1L2    5 GATE<0> FET_N_DUAL_SMLF-NTJD4001N,FET,A   I187 @BASEBOARD_FAB2_LIB.BASEBOARD_FAB2(SCH_1):PAGE155

FM_CPLD_UART_CH_LOCK_N @BASEBOARD_FAB2_LIB.BASEBOARD_FAB2(SCH_1):FM_CPLD_UART_CH_LOCK_N
 R7D30    2      B RES_0402-4.75K,1%,1/16W,CHIP,GA   I121 @BASEBOARD_FAB2_LIB.BASEBOARD_FAB2(SCH_1):PAGE135
  J8G2    9    IO9 CONN12_C73564003_PIP-CONN,C735A   I124 @BASEBOARD_FAB2_LIB.BASEBOARD_FAB2(SCH_1):PAGE135
  U8D7   M9  PB18C LCMXO2_A_256BGA-IC,H63395-001   I179 @BASEBOARD_FAB2_LIB.BASEBOARD_FAB2(SCH_1):PAGE190

FM_CPLD_USB_P0_EN_N @BASEBOARD_FAB2_LIB.BASEBOARD_FAB2(SCH_1):FM_CPLD_USB_P0_EN_N
  U8D7   R8 PB11B_PCLKC2_0 LCMXO2_A_256BGA-IC,H63395-001   I179 @BASEBOARD_FAB2_LIB.BASEBOARD_FAB2(SCH_1):PAGE190
 R1W12    1      A RES_0402-0.0,5%,1/16W,CHIP,G21A   I137 @BASEBOARD_FAB2_LIB.BASEBOARD_FAB2(SCH_1):PAGE176

FM_CPU0_AND_CPU1_MCP_PRES @BASEBOARD_FAB2_LIB.BASEBOARD_FAB2(SCH_1):FM_CPU0_AND_CPU1_MCP_PRES
  U1M6    1   OE_N 74CBTLV1G125_SMLF-IC,C88177-00A   I127 @BASEBOARD_FAB2_LIB.BASEBOARD_FAB2(SCH_1):PAGE113
  U8D7  D11  PT21D LCMXO2_A_256BGA-IC,H63395-001    I59 @BASEBOARD_FAB2_LIB.BASEBOARD_FAB2(SCH_1):PAGE191

FM_CPU0_CD_PRES @BASEBOARD_FAB2_LIB.BASEBOARD_FAB2(SCH_1):FM_CPU0_CD_PRES
  U2M1    6      S NC7SB3157_SMLF-IC,C99406-001   I255 @BASEBOARD_FAB2_LIB.BASEBOARD_FAB2(SCH_1):PAGE113
  U8D7  C11  PT21B LCMXO2_A_256BGA-IC,H63395-001    I59 @BASEBOARD_FAB2_LIB.BASEBOARD_FAB2(SCH_1):PAGE191

FM_CPU0_FIVR_FAULT_LVT3 @BASEBOARD_FAB2_LIB.BASEBOARD_FAB2(SCH_1):FM_CPU0_FIVR_FAULT_LVT3
 R7D29    2      B RES_0402-33.2,1%,1/16W,CHIP,G2A    I30 @BASEBOARD_FAB2_LIB.BASEBOARD_FAB2(SCH_1):PAGE92
  U8D7  M16  PR12B LCMXO2_A_256BGA-IC,H63395-001    I59 @BASEBOARD_FAB2_LIB.BASEBOARD_FAB2(SCH_1):PAGE191

FM_CPU0_FIVR_FAULT_LVT3_N @BASEBOARD_FAB2_LIB.BASEBOARD_FAB2(SCH_1):FM_CPU0_FIVR_FAULT_LVT3_N
  U8D7   F5   PL5C LCMXO2_A_256BGA-IC,H63395-001   I179 @BASEBOARD_FAB2_LIB.BASEBOARD_FAB2(SCH_1):PAGE190
R25W70    2      B RES_0402-33.2,1%,1/16W,CHIP,G2A   I114 @BASEBOARD_FAB2_LIB.BASEBOARD_FAB2(SCH_1):PAGE144

FM_CPU0_FIVR_FAULT_LVT3_R_N @BASEBOARD_FAB2_LIB.BASEBOARD_FAB2(SCH_1):FM_CPU0_FIVR_FAULT_LVT3_R_N
 U25W4  C18 GPIOI0_SYSCS# AST2520A1-GP-GP_ASIC2-GB1-AST2A    I95 @BASEBOARD_FAB2_LIB.BASEBOARD_FAB2(SCH_1):PAGE144
R25W70    1      A RES_0402-33.2,1%,1/16W,CHIP,G2A   I114 @BASEBOARD_FAB2_LIB.BASEBOARD_FAB2(SCH_1):PAGE144

FM_CPU0_FIVR_FAULT_R_LVT3 @BASEBOARD_FAB2_LIB.BASEBOARD_FAB2(SCH_1):FM_CPU0_FIVR_FAULT_R_LVT3
 R7D29    1      A RES_0402-33.2,1%,1/16W,CHIP,G2A    I30 @BASEBOARD_FAB2_LIB.BASEBOARD_FAB2(SCH_1):PAGE92
  U7D2   12     A1 GTL2014_SM-IC,D66151-001    I32 @BASEBOARD_FAB2_LIB.BASEBOARD_FAB2(SCH_1):PAGE92

FM_CPU0_MCP_CLK_EN_N @BASEBOARD_FAB2_LIB.BASEBOARD_FAB2(SCH_1):FM_CPU0_MCP_CLK_EN_N
 EU4D2   29 OE_3_N NB3W1200L_LCC-IC,H13585-001     I1 @BASEBOARD_FAB2_LIB.BASEBOARD_FAB2(SCH_1):PAGE102
 EU4D2   36 OE_4_N NB3W1200L_LCC-IC,H13585-001     I1 @BASEBOARD_FAB2_LIB.BASEBOARD_FAB2(SCH_1):PAGE102
 EU4D2   37 OE_5_N NB3W1200L_LCC-IC,H13585-001     I1 @BASEBOARD_FAB2_LIB.BASEBOARD_FAB2(SCH_1):PAGE102
 R4D70    2      B RES_0402-4.75K,1%,1/16W,CHIP,GA    I94 @BASEBOARD_FAB2_LIB.BASEBOARD_FAB2(SCH_1):PAGE102
  U8D7  F15   PR3B LCMXO2_A_256BGA-IC,H63395-001    I59 @BASEBOARD_FAB2_LIB.BASEBOARD_FAB2(SCH_1):PAGE191

FM_CPU0_OR_CPU1_MCP_PRES @BASEBOARD_FAB2_LIB.BASEBOARD_FAB2(SCH_1):FM_CPU0_OR_CPU1_MCP_PRES
  U9A5    1   OE_N 74CBTLV1G125_SMLF-IC,C88177-00A   I185 @BASEBOARD_FAB2_LIB.BASEBOARD_FAB2(SCH_1):PAGE113
  U1M5    1   OE_N 74CBTLV1G125_SMLF-IC,C88177-00A   I196 @BASEBOARD_FAB2_LIB.BASEBOARD_FAB2(SCH_1):PAGE113
  U8D7  A11  PT21A LCMXO2_A_256BGA-IC,H63395-001    I59 @BASEBOARD_FAB2_LIB.BASEBOARD_FAB2(SCH_1):PAGE191

FM_CPU0_PKGID0 @BASEBOARD_FAB2_LIB.BASEBOARD_FAB2(SCH_1):FM_CPU0_PKGID0
  R5N1    2      B RES_0402-10.0K,1%,1/16W,CHIP,GA   I238 @BASEBOARD_FAB2_LIB.BASEBOARD_FAB2(SCH_1):PAGE21
  U5D1 DC72 PKGID<0> SKX_EXT_B_BGA1-IC,TBD   I259 @BASEBOARD_FAB2_LIB.BASEBOARD_FAB2(SCH_1):PAGE21
  U8D7   F2 PL3B_PCLKC5_0 LCMXO2_A_256BGA-IC,H63395-001   I179 @BASEBOARD_FAB2_LIB.BASEBOARD_FAB2(SCH_1):PAGE190

FM_CPU0_PKGID1 @BASEBOARD_FAB2_LIB.BASEBOARD_FAB2(SCH_1):FM_CPU0_PKGID1
  R5N5    2      B RES_0402-10.0K,1%,1/16W,CHIP,GA   I239 @BASEBOARD_FAB2_LIB.BASEBOARD_FAB2(SCH_1):PAGE21
  U5D1 CW72 PKGID<1> SKX_EXT_B_BGA1-IC,TBD   I259 @BASEBOARD_FAB2_LIB.BASEBOARD_FAB2(SCH_1):PAGE21
  U4R1    1   OE_N 74CBTLV1G125_SMLF-IC,C88177-00A   I206 @BASEBOARD_FAB2_LIB.BASEBOARD_FAB2(SCH_1):PAGE113
  U8D7   G3   PL5B LCMXO2_A_256BGA-IC,H63395-001   I179 @BASEBOARD_FAB2_LIB.BASEBOARD_FAB2(SCH_1):PAGE190

FM_CPU0_PKGID2 @BASEBOARD_FAB2_LIB.BASEBOARD_FAB2(SCH_1):FM_CPU0_PKGID2
  R5N3    2      B RES_0402-10.0K,1%,1/16W,CHIP,GA   I240 @BASEBOARD_FAB2_LIB.BASEBOARD_FAB2(SCH_1):PAGE21
  U5D1 DA72 PKGID<2> SKX_EXT_B_BGA1-IC,TBD   I259 @BASEBOARD_FAB2_LIB.BASEBOARD_FAB2(SCH_1):PAGE21
  U8D7   G2   PL5A LCMXO2_A_256BGA-IC,H63395-001   I179 @BASEBOARD_FAB2_LIB.BASEBOARD_FAB2(SCH_1):PAGE190

FM_CPU0_PROCHOT_LVT3_BMC_N @BASEBOARD_FAB2_LIB.BASEBOARD_FAB2(SCH_1):FM_CPU0_PROCHOT_LVT3_BMC_N
 R1T36    2      B RES_0402-0.0,5%,1/16W,CHIP,G21A   I122 @BASEBOARD_FAB2_LIB.BASEBOARD_FAB2(SCH_1):PAGE93
 U25W4  A20 GPIOE6_TXD3 AST2520A1-GP-GP_ASIC2-GB1-AST2A   I117 @BASEBOARD_FAB2_LIB.BASEBOARD_FAB2(SCH_1):PAGE145

FM_CPU0_PROCHOT_LVT3_K_N @BASEBOARD_FAB2_LIB.BASEBOARD_FAB2(SCH_1):FM_CPU0_PROCHOT_LVT3_K_N
 R2T38    1      A RES_0402-33.2,1%,1/16W,CHIP,G2A    I39 @BASEBOARD_FAB2_LIB.BASEBOARD_FAB2(SCH_1):PAGE93
 R2T71    1      A RES_0402-0.0,5%,1/16W,EMPTY,G2A   I109 @BASEBOARD_FAB2_LIB.BASEBOARD_FAB2(SCH_1):PAGE93
 R2T67    2      B RES_0402-0.0,5%,1/16W,CHIP,G21A   I113 @BASEBOARD_FAB2_LIB.BASEBOARD_FAB2(SCH_1):PAGE93

FM_CPU0_PROCHOT_LVT3_N @BASEBOARD_FAB2_LIB.BASEBOARD_FAB2(SCH_1):FM_CPU0_PROCHOT_LVT3_N
 R2T38    2      B RES_0402-33.2,1%,1/16W,CHIP,G2A    I39 @BASEBOARD_FAB2_LIB.BASEBOARD_FAB2(SCH_1):PAGE93
 R1T36    1      A RES_0402-0.0,5%,1/16W,CHIP,G21A   I122 @BASEBOARD_FAB2_LIB.BASEBOARD_FAB2(SCH_1):PAGE93
 R1T35    1      A RES_0402-0.0,5%,1/16W,EMPTY,G2A   I135 @BASEBOARD_FAB2_LIB.BASEBOARD_FAB2(SCH_1):PAGE93

FM_CPU0_PROCHOT_LVT3_R_N @BASEBOARD_FAB2_LIB.BASEBOARD_FAB2(SCH_1):FM_CPU0_PROCHOT_LVT3_R_N
  U2T4   12     A1 GTL2014_SM-IC,D66151-001    I30 @BASEBOARD_FAB2_LIB.BASEBOARD_FAB2(SCH_1):PAGE93
 R2T67    1      A RES_0402-0.0,5%,1/16W,CHIP,G21A   I113 @BASEBOARD_FAB2_LIB.BASEBOARD_FAB2(SCH_1):PAGE93

FM_CPU0_PROCHOT_PCH_N @BASEBOARD_FAB2_LIB.BASEBOARD_FAB2(SCH_1):FM_CPU0_PROCHOT_PCH_N
 R1T35    2      B RES_0402-0.0,5%,1/16W,EMPTY,G2A   I135 @BASEBOARD_FAB2_LIB.BASEBOARD_FAB2(SCH_1):PAGE93
  U7C1   Y7 GPP_L16_TESTCH1_D5 LBG_CORE_QAT_EXT_D_BGA1-IC,H91A    I34 @BASEBOARD_FAB2_LIB.BASEBOARD_FAB2(SCH_1):PAGE121

FM_CPU0_PROC_ID0 @BASEBOARD_FAB2_LIB.BASEBOARD_FAB2(SCH_1):FM_CPU0_PROC_ID0
  R5N4    2      B RES_0402-1.8K,1%,1/16W,CHIP,G2A   I241 @BASEBOARD_FAB2_LIB.BASEBOARD_FAB2(SCH_1):PAGE21
  U5D1 CY71 PROC_ID<0> SKX_EXT_B_BGA1-IC,TBD   I259 @BASEBOARD_FAB2_LIB.BASEBOARD_FAB2(SCH_1):PAGE21
  U8D7   F1   PL4B LCMXO2_A_256BGA-IC,H63395-001   I179 @BASEBOARD_FAB2_LIB.BASEBOARD_FAB2(SCH_1):PAGE190

FM_CPU0_PROC_ID1 @BASEBOARD_FAB2_LIB.BASEBOARD_FAB2(SCH_1):FM_CPU0_PROC_ID1
  R5N2    2      B RES_0402-1.8K,1%,1/16W,CHIP,G2A   I227 @BASEBOARD_FAB2_LIB.BASEBOARD_FAB2(SCH_1):PAGE21
  U5D1 DB71 PROC_ID<1> SKX_EXT_B_BGA1-IC,TBD   I259 @BASEBOARD_FAB2_LIB.BASEBOARD_FAB2(SCH_1):PAGE21
  U8D7   F3   PL4A LCMXO2_A_256BGA-IC,H63395-001   I179 @BASEBOARD_FAB2_LIB.BASEBOARD_FAB2(SCH_1):PAGE190

FM_CPU0_RC_EN @BASEBOARD_FAB2_LIB.BASEBOARD_FAB2(SCH_1):FM_CPU0_RC_EN
  U7C1 BD20 GPP_G22_SSATA_DEVSLP2 LBG_CORE_QAT_EXT_D_BGA1-IC,H91A   I147 @BASEBOARD_FAB2_LIB.BASEBOARD_FAB2(SCH_1):PAGE120
 R8D44    2      B RES_0402-10.0K,1%,1/16W,CHIP,GA   I362 @BASEBOARD_FAB2_LIB.BASEBOARD_FAB2(SCH_1):PAGE133
  U8D7   R3   PB3D LCMXO2_A_256BGA-IC,H63395-001   I179 @BASEBOARD_FAB2_LIB.BASEBOARD_FAB2(SCH_1):PAGE190

FM_CPU0_RC_ERROR_N @BASEBOARD_FAB2_LIB.BASEBOARD_FAB2(SCH_1):FM_CPU0_RC_ERROR_N
  U5D1  Y23 RSVD<257> SKX_EXT_B_BGA1-IC,TBD   I204 @BASEBOARD_FAB2_LIB.BASEBOARD_FAB2(SCH_1):PAGE22
  R2M8    2      B RES_0402-1.5K,1%,1/16W,CHIP,G2A   I349 @BASEBOARD_FAB2_LIB.BASEBOARD_FAB2(SCH_1):PAGE133
 U25W4   Y1 GPIOM0_NCTS2_VPIB2 AST2520A1-GP-GP_ASIC2-GB1-AST2A   I117 @BASEBOARD_FAB2_LIB.BASEBOARD_FAB2(SCH_1):PAGE145
  R7W9    1      A RES_0402-0.0,5%,1/16W,CHIP,G21A   I177 @BASEBOARD_FAB2_LIB.BASEBOARD_FAB2(SCH_1):PAGE118
 R7W10    1      A RES_0402-0.0,5%,1/16W,CHIP,G21A   I270 @BASEBOARD_FAB2_LIB.BASEBOARD_FAB2(SCH_1):PAGE120

FM_CPU0_RC_ERROR_R1_N @BASEBOARD_FAB2_LIB.BASEBOARD_FAB2(SCH_1):FM_CPU0_RC_ERROR_R1_N
  U7C1 BH50 GPP_E0_SATAXPCIE0_SATAGP0 LBG_CORE_QAT_EXT_D_BGA1-IC,H91A   I147 @BASEBOARD_FAB2_LIB.BASEBOARD_FAB2(SCH_1):PAGE120
 R7W10    2      B RES_0402-0.0,5%,1/16W,CHIP,G21A   I270 @BASEBOARD_FAB2_LIB.BASEBOARD_FAB2(SCH_1):PAGE120

FM_CPU0_RC_ERROR_R_N @BASEBOARD_FAB2_LIB.BASEBOARD_FAB2(SCH_1):FM_CPU0_RC_ERROR_R_N
  U7C1  B14 GPD10_SLP_S5_N LBG_CORE_QAT_EXT_D_BGA1-IC,H91A    I73 @BASEBOARD_FAB2_LIB.BASEBOARD_FAB2(SCH_1):PAGE118
  R7W9    2      B RES_0402-0.0,5%,1/16W,CHIP,G21A   I177 @BASEBOARD_FAB2_LIB.BASEBOARD_FAB2(SCH_1):PAGE118

FM_CPU0_SKTOCC_LVT3_N @BASEBOARD_FAB2_LIB.BASEBOARD_FAB2(SCH_1):FM_CPU0_SKTOCC_LVT3_N
  R4R5    2      B RES_0402-4.75K,1%,1/16W,CHIP,GA   I258 @BASEBOARD_FAB2_LIB.BASEBOARD_FAB2(SCH_1):PAGE21
  U5D1 AB13 SKTOCC_N SKX_EXT_B_BGA1-IC,TBD   I259 @BASEBOARD_FAB2_LIB.BASEBOARD_FAB2(SCH_1):PAGE21
  U7C1  G11 GPD6_SLP_A_N LBG_CORE_QAT_EXT_D_BGA1-IC,H91A    I73 @BASEBOARD_FAB2_LIB.BASEBOARD_FAB2(SCH_1):PAGE118
  U8D7  T14  PB22D LCMXO2_A_256BGA-IC,H63395-001   I179 @BASEBOARD_FAB2_LIB.BASEBOARD_FAB2(SCH_1):PAGE190
 U25W4  E16 GPIOG3_SGPS1I1 AST2520A1-GP-GP_ASIC2-GB1-AST2A    I95 @BASEBOARD_FAB2_LIB.BASEBOARD_FAB2(SCH_1):PAGE144

FM_CPU0_SM_WP @BASEBOARD_FAB2_LIB.BASEBOARD_FAB2(SCH_1):FM_CPU0_SM_WP
  U5D1 CV59  SM_WP SKX_EXT_B_BGA1-IC,TBD   I259 @BASEBOARD_FAB2_LIB.BASEBOARD_FAB2(SCH_1):PAGE21
 R3P54    2      B RES_0402-3.32K,1%,1/16W,EMPTY,A   I331 @BASEBOARD_FAB2_LIB.BASEBOARD_FAB2(SCH_1):PAGE156
 R3P56    1      A RES_0402-1.00K,1%,1/16W,CHIP,GA   I333 @BASEBOARD_FAB2_LIB.BASEBOARD_FAB2(SCH_1):PAGE156

FM_CPU0_STL_BRD_OSC_EN @BASEBOARD_FAB2_LIB.BASEBOARD_FAB2(SCH_1):FM_CPU0_STL_BRD_OSC_EN
  Y6F1    1 ENABLE_DISABLE OSC_C_6P10-156.25MHZ,OSC,G6383A    I71 @BASEBOARD_FAB2_LIB.BASEBOARD_FAB2(SCH_1):PAGE104
 R8D43    2      B RES_0402-0.0,5%,1/16W,CHIP,G21A    I93 @BASEBOARD_FAB2_LIB.BASEBOARD_FAB2(SCH_1):PAGE104
 R7D40    2      B RES_0402-0.0,5%,1/16W,EMPTY,G2A    I94 @BASEBOARD_FAB2_LIB.BASEBOARD_FAB2(SCH_1):PAGE104

FM_CPU0_THERMTRIP_LATCH_LVT3_N @BASEBOARD_FAB2_LIB.BASEBOARD_FAB2(SCH_1):FM_CPU0_THERMTRIP_LATCH_LVT3_N
  U7C1 BN44 GPP_D23 LBG_CORE_QAT_EXT_D_BGA1-IC,H91A   I115 @BASEBOARD_FAB2_LIB.BASEBOARD_FAB2(SCH_1):PAGE119
  U8D7  G12   PR3D LCMXO2_A_256BGA-IC,H63395-001    I59 @BASEBOARD_FAB2_LIB.BASEBOARD_FAB2(SCH_1):PAGE191
 U25W4  AA2 GPIOM4_NDTR2_VPIB6 AST2520A1-GP-GP_ASIC2-GB1-AST2A   I117 @BASEBOARD_FAB2_LIB.BASEBOARD_FAB2(SCH_1):PAGE145

FM_CPU0_THERMTRIP_LVT3_N @BASEBOARD_FAB2_LIB.BASEBOARD_FAB2(SCH_1):FM_CPU0_THERMTRIP_LVT3_N
 R7D34    2      B RES_0402-33.2,1%,1/16W,CHIP,G2A    I24 @BASEBOARD_FAB2_LIB.BASEBOARD_FAB2(SCH_1):PAGE92
  U8D7  N15  PR13C LCMXO2_A_256BGA-IC,H63395-001    I59 @BASEBOARD_FAB2_LIB.BASEBOARD_FAB2(SCH_1):PAGE191

FM_CPU0_THERMTRIP_LVT3_R_N @BASEBOARD_FAB2_LIB.BASEBOARD_FAB2(SCH_1):FM_CPU0_THERMTRIP_LVT3_R_N
 R7D34    1      A RES_0402-33.2,1%,1/16W,CHIP,G2A    I24 @BASEBOARD_FAB2_LIB.BASEBOARD_FAB2(SCH_1):PAGE92
  U7D2    9     A3 GTL2014_SM-IC,D66151-001    I32 @BASEBOARD_FAB2_LIB.BASEBOARD_FAB2(SCH_1):PAGE92

FM_CPU0_VRM_322M_156M_OSC_EN @BASEBOARD_FAB2_LIB.BASEBOARD_FAB2(SCH_1):FM_CPU0_VRM_322M_156M_OSC_EN
  J6B1   E1   IOE1 SCONN120_H61426002_SM-CONN,H61A    I56 @BASEBOARD_FAB2_LIB.BASEBOARD_FAB2(SCH_1):PAGE194
 R7D39    2      B RES_0402-0.0,5%,1/16W,CHIP,G21A   I103 @BASEBOARD_FAB2_LIB.BASEBOARD_FAB2(SCH_1):PAGE104

FM_CPU0_VRM_OSC_EN @BASEBOARD_FAB2_LIB.BASEBOARD_FAB2(SCH_1):FM_CPU0_VRM_OSC_EN
 R7D40    1      A RES_0402-0.0,5%,1/16W,EMPTY,G2A    I94 @BASEBOARD_FAB2_LIB.BASEBOARD_FAB2(SCH_1):PAGE104
  U8D7  R13  PB22C LCMXO2_A_256BGA-IC,H63395-001   I179 @BASEBOARD_FAB2_LIB.BASEBOARD_FAB2(SCH_1):PAGE190
 R7D39    1      A RES_0402-0.0,5%,1/16W,CHIP,G21A   I103 @BASEBOARD_FAB2_LIB.BASEBOARD_FAB2(SCH_1):PAGE104

FM_CPU1_CD_PRES_N @BASEBOARD_FAB2_LIB.BASEBOARD_FAB2(SCH_1):FM_CPU1_CD_PRES_N
  U1M2    6      S NC7SB3157_SMLF-IC,C99406-001   I107 @BASEBOARD_FAB2_LIB.BASEBOARD_FAB2(SCH_1):PAGE113
  U8D7  F10  PT21C LCMXO2_A_256BGA-IC,H63395-001    I59 @BASEBOARD_FAB2_LIB.BASEBOARD_FAB2(SCH_1):PAGE191

FM_CPU1_FIVR_FAULT_LVT3 @BASEBOARD_FAB2_LIB.BASEBOARD_FAB2(SCH_1):FM_CPU1_FIVR_FAULT_LVT3
 R3P46    2      B RES_0402-33.2,1%,1/16W,CHIP,G2A    I12 @BASEBOARD_FAB2_LIB.BASEBOARD_FAB2(SCH_1):PAGE92
  U8D7  G13   PR4D LCMXO2_A_256BGA-IC,H63395-001    I59 @BASEBOARD_FAB2_LIB.BASEBOARD_FAB2(SCH_1):PAGE191

FM_CPU1_FIVR_FAULT_LVT3_N @BASEBOARD_FAB2_LIB.BASEBOARD_FAB2(SCH_1):FM_CPU1_FIVR_FAULT_LVT3_N
  U8D7   E6  PT13C LCMXO2_A_256BGA-IC,H63395-001    I59 @BASEBOARD_FAB2_LIB.BASEBOARD_FAB2(SCH_1):PAGE191
R25W75    2      B RES_0402-33.2,1%,1/16W,CHIP,G2A   I118 @BASEBOARD_FAB2_LIB.BASEBOARD_FAB2(SCH_1):PAGE144

FM_CPU1_FIVR_FAULT_LVT3_R_N @BASEBOARD_FAB2_LIB.BASEBOARD_FAB2(SCH_1):FM_CPU1_FIVR_FAULT_LVT3_R_N
 U25W4  E15 GPIOI1_SYSCK AST2520A1-GP-GP_ASIC2-GB1-AST2A    I95 @BASEBOARD_FAB2_LIB.BASEBOARD_FAB2(SCH_1):PAGE144
R25W75    1      A RES_0402-33.2,1%,1/16W,CHIP,G2A   I118 @BASEBOARD_FAB2_LIB.BASEBOARD_FAB2(SCH_1):PAGE144

FM_CPU1_FIVR_FAULT_R_LVT3 @BASEBOARD_FAB2_LIB.BASEBOARD_FAB2(SCH_1):FM_CPU1_FIVR_FAULT_R_LVT3
  U3P2   12     A1 GTL2014_SM-IC,D66151-001     I1 @BASEBOARD_FAB2_LIB.BASEBOARD_FAB2(SCH_1):PAGE92
 R3P46    1      A RES_0402-33.2,1%,1/16W,CHIP,G2A    I12 @BASEBOARD_FAB2_LIB.BASEBOARD_FAB2(SCH_1):PAGE92

FM_CPU1_MCP_CLK_EN_N @BASEBOARD_FAB2_LIB.BASEBOARD_FAB2(SCH_1):FM_CPU1_MCP_CLK_EN_N
 EU4D2   53 OE_9_N NB3W1200L_LCC-IC,H13585-001     I1 @BASEBOARD_FAB2_LIB.BASEBOARD_FAB2(SCH_1):PAGE102
 EU4D2   61 OE_10_N NB3W1200L_LCC-IC,H13585-001     I1 @BASEBOARD_FAB2_LIB.BASEBOARD_FAB2(SCH_1):PAGE102
 EU4D2   62 OE_11_N NB3W1200L_LCC-IC,H13585-001     I1 @BASEBOARD_FAB2_LIB.BASEBOARD_FAB2(SCH_1):PAGE102
 R4D69    2      B RES_0402-4.75K,1%,1/16W,CHIP,GA    I93 @BASEBOARD_FAB2_LIB.BASEBOARD_FAB2(SCH_1):PAGE102
  U8D7  F16   PR4B LCMXO2_A_256BGA-IC,H63395-001    I59 @BASEBOARD_FAB2_LIB.BASEBOARD_FAB2(SCH_1):PAGE191

FM_CPU1_PKGID0 @BASEBOARD_FAB2_LIB.BASEBOARD_FAB2(SCH_1):FM_CPU1_PKGID0
  R8N2    2      B RES_0402-10.0K,1%,1/16W,CHIP,GA   I161 @BASEBOARD_FAB2_LIB.BASEBOARD_FAB2(SCH_1):PAGE55
  U2D1 DC72 PKGID<0> SKX_EXT_B_BGA1-IC,TBD   I172 @BASEBOARD_FAB2_LIB.BASEBOARD_FAB2(SCH_1):PAGE55
  U8D7  R12 PB25A_SN LCMXO2_A_256BGA-IC,H63395-001   I179 @BASEBOARD_FAB2_LIB.BASEBOARD_FAB2(SCH_1):PAGE190

FM_CPU1_PKGID1 @BASEBOARD_FAB2_LIB.BASEBOARD_FAB2(SCH_1):FM_CPU1_PKGID1
  R8N5    2      B RES_0402-10.0K,1%,1/16W,CHIP,GA   I160 @BASEBOARD_FAB2_LIB.BASEBOARD_FAB2(SCH_1):PAGE55
  U2D1 CW72 PKGID<1> SKX_EXT_B_BGA1-IC,TBD   I172 @BASEBOARD_FAB2_LIB.BASEBOARD_FAB2(SCH_1):PAGE55
  U6M1    1   OE_N 74CBTLV1G125_SMLF-IC,C88177-00A   I190 @BASEBOARD_FAB2_LIB.BASEBOARD_FAB2(SCH_1):PAGE113
  U8D7  P12  PB24A LCMXO2_A_256BGA-IC,H63395-001   I179 @BASEBOARD_FAB2_LIB.BASEBOARD_FAB2(SCH_1):PAGE190

FM_CPU1_PKGID2 @BASEBOARD_FAB2_LIB.BASEBOARD_FAB2(SCH_1):FM_CPU1_PKGID2
  R8N3    2      B RES_0402-10.0K,1%,1/16W,CHIP,GA   I159 @BASEBOARD_FAB2_LIB.BASEBOARD_FAB2(SCH_1):PAGE55
  U2D1 DA72 PKGID<2> SKX_EXT_B_BGA1-IC,TBD   I172 @BASEBOARD_FAB2_LIB.BASEBOARD_FAB2(SCH_1):PAGE55
  U8D7  T11  PB21A LCMXO2_A_256BGA-IC,H63395-001   I179 @BASEBOARD_FAB2_LIB.BASEBOARD_FAB2(SCH_1):PAGE190

FM_CPU1_PROCHOT_LVT3_BMC_N @BASEBOARD_FAB2_LIB.BASEBOARD_FAB2(SCH_1):FM_CPU1_PROCHOT_LVT3_BMC_N
 R1T37    2      B RES_0402-0.0,5%,1/16W,CHIP,G21A   I123 @BASEBOARD_FAB2_LIB.BASEBOARD_FAB2(SCH_1):PAGE93
 U25W4  B19 GPIOE7_RXD3 AST2520A1-GP-GP_ASIC2-GB1-AST2A   I117 @BASEBOARD_FAB2_LIB.BASEBOARD_FAB2(SCH_1):PAGE145

FM_CPU1_PROCHOT_LVT3_K_N @BASEBOARD_FAB2_LIB.BASEBOARD_FAB2(SCH_1):FM_CPU1_PROCHOT_LVT3_K_N
 R7D24    1      A RES_0402-33.2,1%,1/16W,CHIP,G2A    I62 @BASEBOARD_FAB2_LIB.BASEBOARD_FAB2(SCH_1):PAGE93
 R7D43    1      A RES_0402-0.0,5%,1/16W,EMPTY,G2A   I110 @BASEBOARD_FAB2_LIB.BASEBOARD_FAB2(SCH_1):PAGE93
 R7D41    2      B RES_0402-0.0,5%,1/16W,CHIP,G21A   I114 @BASEBOARD_FAB2_LIB.BASEBOARD_FAB2(SCH_1):PAGE93

FM_CPU1_PROCHOT_LVT3_N @BASEBOARD_FAB2_LIB.BASEBOARD_FAB2(SCH_1):FM_CPU1_PROCHOT_LVT3_N
 R7D24    2      B RES_0402-33.2,1%,1/16W,CHIP,G2A    I62 @BASEBOARD_FAB2_LIB.BASEBOARD_FAB2(SCH_1):PAGE93
 R1T37    1      A RES_0402-0.0,5%,1/16W,CHIP,G21A   I123 @BASEBOARD_FAB2_LIB.BASEBOARD_FAB2(SCH_1):PAGE93
 R1T38    1      A RES_0402-0.0,5%,1/16W,EMPTY,G2A   I137 @BASEBOARD_FAB2_LIB.BASEBOARD_FAB2(SCH_1):PAGE93

FM_CPU1_PROCHOT_LVT3_R_N @BASEBOARD_FAB2_LIB.BASEBOARD_FAB2(SCH_1):FM_CPU1_PROCHOT_LVT3_R_N
  U2T4   13     A0 GTL2014_SM-IC,D66151-001    I30 @BASEBOARD_FAB2_LIB.BASEBOARD_FAB2(SCH_1):PAGE93
 R7D41    1      A RES_0402-0.0,5%,1/16W,CHIP,G21A   I114 @BASEBOARD_FAB2_LIB.BASEBOARD_FAB2(SCH_1):PAGE93

FM_CPU1_PROCHOT_PCH_N @BASEBOARD_FAB2_LIB.BASEBOARD_FAB2(SCH_1):FM_CPU1_PROCHOT_PCH_N
 R1T38    2      B RES_0402-0.0,5%,1/16W,EMPTY,G2A   I137 @BASEBOARD_FAB2_LIB.BASEBOARD_FAB2(SCH_1):PAGE93
  U7C1  AA9 GPP_L17_TESTCH1_D6 LBG_CORE_QAT_EXT_D_BGA1-IC,H91A    I34 @BASEBOARD_FAB2_LIB.BASEBOARD_FAB2(SCH_1):PAGE121

FM_CPU1_PROC_ID0 @BASEBOARD_FAB2_LIB.BASEBOARD_FAB2(SCH_1):FM_CPU1_PROC_ID0
  R8N4    2      B RES_0402-1.8K,1%,1/16W,CHIP,G2A   I158 @BASEBOARD_FAB2_LIB.BASEBOARD_FAB2(SCH_1):PAGE55
  U2D1 CY71 PROC_ID<0> SKX_EXT_B_BGA1-IC,TBD   I172 @BASEBOARD_FAB2_LIB.BASEBOARD_FAB2(SCH_1):PAGE55
  U8D7  M15  PR13B LCMXO2_A_256BGA-IC,H63395-001    I59 @BASEBOARD_FAB2_LIB.BASEBOARD_FAB2(SCH_1):PAGE191

FM_CPU1_PROC_ID1 @BASEBOARD_FAB2_LIB.BASEBOARD_FAB2(SCH_1):FM_CPU1_PROC_ID1
  R8N1    2      B RES_0402-1.8K,1%,1/16W,CHIP,G2A   I157 @BASEBOARD_FAB2_LIB.BASEBOARD_FAB2(SCH_1):PAGE55
  U2D1 DB71 PROC_ID<1> SKX_EXT_B_BGA1-IC,TBD   I172 @BASEBOARD_FAB2_LIB.BASEBOARD_FAB2(SCH_1):PAGE55
  U8D7  M14  PR13A LCMXO2_A_256BGA-IC,H63395-001    I59 @BASEBOARD_FAB2_LIB.BASEBOARD_FAB2(SCH_1):PAGE191

FM_CPU1_RC_EN @BASEBOARD_FAB2_LIB.BASEBOARD_FAB2(SCH_1):FM_CPU1_RC_EN
  U7C1 BY29 GPP_C9 LBG_CORE_QAT_EXT_D_BGA1-IC,H91A   I115 @BASEBOARD_FAB2_LIB.BASEBOARD_FAB2(SCH_1):PAGE119
 R2P22    2      B RES_0402-10.0K,1%,1/16W,CHIP,GA   I360 @BASEBOARD_FAB2_LIB.BASEBOARD_FAB2(SCH_1):PAGE133
  U8D7   P4   PB3A LCMXO2_A_256BGA-IC,H63395-001   I179 @BASEBOARD_FAB2_LIB.BASEBOARD_FAB2(SCH_1):PAGE190

FM_CPU1_RC_ERROR_N @BASEBOARD_FAB2_LIB.BASEBOARD_FAB2(SCH_1):FM_CPU1_RC_ERROR_N
  U2D1  Y23 RSVD<257> SKX_EXT_B_BGA1-IC,TBD   I169 @BASEBOARD_FAB2_LIB.BASEBOARD_FAB2(SCH_1):PAGE56
 R2N29    2      B RES_0402-1.5K,1%,1/16W,CHIP,G2A   I352 @BASEBOARD_FAB2_LIB.BASEBOARD_FAB2(SCH_1):PAGE133
 U25W4  AB2 GPIOM1_NDCD2_VPIB3 AST2520A1-GP-GP_ASIC2-GB1-AST2A   I117 @BASEBOARD_FAB2_LIB.BASEBOARD_FAB2(SCH_1):PAGE145
 R7W12    1      A RES_0402-0.0,5%,1/16W,CHIP,G21A   I271 @BASEBOARD_FAB2_LIB.BASEBOARD_FAB2(SCH_1):PAGE120
 R7W11    2      B RES_0402-0.0,5%,1/16W,CHIP,G21A   I273 @BASEBOARD_FAB2_LIB.BASEBOARD_FAB2(SCH_1):PAGE120

FM_CPU1_RC_ERROR_R1_N @BASEBOARD_FAB2_LIB.BASEBOARD_FAB2(SCH_1):FM_CPU1_RC_ERROR_R1_N
  U7C1 AY52 GPP_E1_SATAXPCIE1_SATAGP1 LBG_CORE_QAT_EXT_D_BGA1-IC,H91A   I147 @BASEBOARD_FAB2_LIB.BASEBOARD_FAB2(SCH_1):PAGE120
 R7W12    2      B RES_0402-0.0,5%,1/16W,CHIP,G21A   I271 @BASEBOARD_FAB2_LIB.BASEBOARD_FAB2(SCH_1):PAGE120

FM_CPU1_RC_ERROR_R_N @BASEBOARD_FAB2_LIB.BASEBOARD_FAB2(SCH_1):FM_CPU1_RC_ERROR_R_N
  U7C1 BV23 GPP_I6_RESET_DONE LBG_CORE_QAT_EXT_D_BGA1-IC,H91A   I147 @BASEBOARD_FAB2_LIB.BASEBOARD_FAB2(SCH_1):PAGE120
 R7W11    1      A RES_0402-0.0,5%,1/16W,CHIP,G21A   I273 @BASEBOARD_FAB2_LIB.BASEBOARD_FAB2(SCH_1):PAGE120

FM_CPU1_SKTOCC_LVT3_N @BASEBOARD_FAB2_LIB.BASEBOARD_FAB2(SCH_1):FM_CPU1_SKTOCC_LVT3_N
  U2D1 AB13 SKTOCC_N SKX_EXT_B_BGA1-IC,TBD   I172 @BASEBOARD_FAB2_LIB.BASEBOARD_FAB2(SCH_1):PAGE55
 R6P39    2      B RES_0402-4.75K,1%,1/16W,CHIP,GA   I181 @BASEBOARD_FAB2_LIB.BASEBOARD_FAB2(SCH_1):PAGE55
  U1M7    6      S NC7SB3157_SMLF-IC,C99406-001    I40 @BASEBOARD_FAB2_LIB.BASEBOARD_FAB2(SCH_1):PAGE112
  U1M4    1   OE_N 74CBTLV1G125_SMLF-IC,C88177-00A   I127 @BASEBOARD_FAB2_LIB.BASEBOARD_FAB2(SCH_1):PAGE112
  U7C1  H13 GPD1_ACPRESENT LBG_CORE_QAT_EXT_D_BGA1-IC,H91A    I73 @BASEBOARD_FAB2_LIB.BASEBOARD_FAB2(SCH_1):PAGE118
  U8D7  T12  PB22B LCMXO2_A_256BGA-IC,H63395-001   I179 @BASEBOARD_FAB2_LIB.BASEBOARD_FAB2(SCH_1):PAGE190
 U25W4  Y21 GPIOAA0_VPOR2_NORD0_SALT7 AST2520A1-GP-GP_ASIC2-GB1-AST2A   I104 @BASEBOARD_FAB2_LIB.BASEBOARD_FAB2(SCH_1):PAGE146

FM_CPU1_SM_WP @BASEBOARD_FAB2_LIB.BASEBOARD_FAB2(SCH_1):FM_CPU1_SM_WP
  U2D1 CV59  SM_WP SKX_EXT_B_BGA1-IC,TBD   I172 @BASEBOARD_FAB2_LIB.BASEBOARD_FAB2(SCH_1):PAGE55
 R1C35    2      B RES_0402-3.32K,1%,1/16W,EMPTY,A   I336 @BASEBOARD_FAB2_LIB.BASEBOARD_FAB2(SCH_1):PAGE156
 R1C36    1      A RES_0402-1.00K,1%,1/16W,CHIP,GA   I337 @BASEBOARD_FAB2_LIB.BASEBOARD_FAB2(SCH_1):PAGE156

FM_CPU1_STL_BRD_OSC_EN @BASEBOARD_FAB2_LIB.BASEBOARD_FAB2(SCH_1):FM_CPU1_STL_BRD_OSC_EN
  Y3F1    1 ENABLE_DISABLE OSC_C_6P10-156.25MHZ,OSC,G6383A    I72 @BASEBOARD_FAB2_LIB.BASEBOARD_FAB2(SCH_1):PAGE104
 R7D36    2      B RES_0402-0.0,5%,1/16W,CHIP,G21A    I96 @BASEBOARD_FAB2_LIB.BASEBOARD_FAB2(SCH_1):PAGE104
 R7D38    2      B RES_0402-0.0,5%,1/16W,EMPTY,G2A    I97 @BASEBOARD_FAB2_LIB.BASEBOARD_FAB2(SCH_1):PAGE104

FM_CPU1_THERMTRIP_LATCH_LVT3_N @BASEBOARD_FAB2_LIB.BASEBOARD_FAB2(SCH_1):FM_CPU1_THERMTRIP_LATCH_LVT3_N
  U7C1 AV18 GPP_G6_FANTACH6_FANTACH6IE LBG_CORE_QAT_EXT_D_BGA1-IC,H91A   I147 @BASEBOARD_FAB2_LIB.BASEBOARD_FAB2(SCH_1):PAGE120
  U8D7   C5  PT10B LCMXO2_A_256BGA-IC,H63395-001    I59 @BASEBOARD_FAB2_LIB.BASEBOARD_FAB2(SCH_1):PAGE191
 U25W4   P5 GPIOM5_NRTS2_VPIB7 AST2520A1-GP-GP_ASIC2-GB1-AST2A   I117 @BASEBOARD_FAB2_LIB.BASEBOARD_FAB2(SCH_1):PAGE145

FM_CPU1_THERMTRIP_LVT3_N @BASEBOARD_FAB2_LIB.BASEBOARD_FAB2(SCH_1):FM_CPU1_THERMTRIP_LVT3_N
 R3P42    2      B RES_0402-33.2,1%,1/16W,CHIP,G2A    I14 @BASEBOARD_FAB2_LIB.BASEBOARD_FAB2(SCH_1):PAGE92
  U8D7  G14   PR5B LCMXO2_A_256BGA-IC,H63395-001    I59 @BASEBOARD_FAB2_LIB.BASEBOARD_FAB2(SCH_1):PAGE191

FM_CPU1_THERMTRIP_LVT3_R_N @BASEBOARD_FAB2_LIB.BASEBOARD_FAB2(SCH_1):FM_CPU1_THERMTRIP_LVT3_R_N
  U3P2    9     A3 GTL2014_SM-IC,D66151-001     I1 @BASEBOARD_FAB2_LIB.BASEBOARD_FAB2(SCH_1):PAGE92
 R3P42    1      A RES_0402-33.2,1%,1/16W,CHIP,G2A    I14 @BASEBOARD_FAB2_LIB.BASEBOARD_FAB2(SCH_1):PAGE92

FM_CPU1_VRM_322M_156M_OSC_EN @BASEBOARD_FAB2_LIB.BASEBOARD_FAB2(SCH_1):FM_CPU1_VRM_322M_156M_OSC_EN
  J4B2   E1   IOE1 SCONN120_H61426002_SM-CONN,H61A    I46 @BASEBOARD_FAB2_LIB.BASEBOARD_FAB2(SCH_1):PAGE193
 R7D37    2      B RES_0402-0.0,5%,1/16W,CHIP,G21A   I104 @BASEBOARD_FAB2_LIB.BASEBOARD_FAB2(SCH_1):PAGE104

FM_CPU1_VRM_OSC_EN @BASEBOARD_FAB2_LIB.BASEBOARD_FAB2(SCH_1):FM_CPU1_VRM_OSC_EN
 R7D38    1      A RES_0402-0.0,5%,1/16W,EMPTY,G2A    I97 @BASEBOARD_FAB2_LIB.BASEBOARD_FAB2(SCH_1):PAGE104
  U8D7  N14  PR14B LCMXO2_A_256BGA-IC,H63395-001    I59 @BASEBOARD_FAB2_LIB.BASEBOARD_FAB2(SCH_1):PAGE191
 R7D37    1      A RES_0402-0.0,5%,1/16W,CHIP,G21A   I104 @BASEBOARD_FAB2_LIB.BASEBOARD_FAB2(SCH_1):PAGE104

FM_CPU_BMC_INIT @BASEBOARD_FAB2_LIB.BASEBOARD_FAB2(SCH_1):FM_CPU_BMC_INIT
  U7C1  AD1 GPP_A17 LBG_CORE_QAT_EXT_D_BGA1-IC,H91A   I115 @BASEBOARD_FAB2_LIB.BASEBOARD_FAB2(SCH_1):PAGE119
 R6D16    1      A RES_0402-0.0,5%,1/16W,EMPTY,G2A   I299 @BASEBOARD_FAB2_LIB.BASEBOARD_FAB2(SCH_1):PAGE156
 R3D31    1      A RES_0402-0.0,5%,1/16W,EMPTY,G2A   I300 @BASEBOARD_FAB2_LIB.BASEBOARD_FAB2(SCH_1):PAGE156
 U6W11    7     P3 PCA9554PWR-GP_DISCRET-G1-PCA95A    I97 @BASEBOARD_FAB2_LIB.BASEBOARD_FAB2(SCH_1):PAGE164

FM_CPU_CATERR_DLY_LVT3_N @BASEBOARD_FAB2_LIB.BASEBOARD_FAB2(SCH_1):FM_CPU_CATERR_DLY_LVT3_N
  R2N1    2      B RES_0402-33.2,1%,1/16W,CHIP,G2A   I173 @BASEBOARD_FAB2_LIB.BASEBOARD_FAB2(SCH_1):PAGE119
  U8D7   E2 PL2A_L_GPLLT_IN LCMXO2_A_256BGA-IC,H63395-001   I179 @BASEBOARD_FAB2_LIB.BASEBOARD_FAB2(SCH_1):PAGE190

FM_CPU_CATERR_DLY_LVT3_R_N @BASEBOARD_FAB2_LIB.BASEBOARD_FAB2(SCH_1):FM_CPU_CATERR_DLY_LVT3_R_N
  U7C1 CA37 GPP_C23 LBG_CORE_QAT_EXT_D_BGA1-IC,H91A   I115 @BASEBOARD_FAB2_LIB.BASEBOARD_FAB2(SCH_1):PAGE119
  R2N1    1      A RES_0402-33.2,1%,1/16W,CHIP,G2A   I173 @BASEBOARD_FAB2_LIB.BASEBOARD_FAB2(SCH_1):PAGE119

FM_CPU_CATERR_LVT3_N @BASEBOARD_FAB2_LIB.BASEBOARD_FAB2(SCH_1):FM_CPU_CATERR_LVT3_N
 R3P43    2      B RES_0402-33.2,1%,1/16W,CHIP,G2A    I13 @BASEBOARD_FAB2_LIB.BASEBOARD_FAB2(SCH_1):PAGE92
  U8D7  R14  PB25D LCMXO2_A_256BGA-IC,H63395-001   I179 @BASEBOARD_FAB2_LIB.BASEBOARD_FAB2(SCH_1):PAGE190
 U25W4  E19 GPIOG1_SGPS1LD AST2520A1-GP-GP_ASIC2-GB1-AST2A    I95 @BASEBOARD_FAB2_LIB.BASEBOARD_FAB2(SCH_1):PAGE144
 CR6W1    1      C DIODE_SMLF-BAT54WS,IC,C73510-0A   I157 @BASEBOARD_FAB2_LIB.BASEBOARD_FAB2(SCH_1):PAGE247

FM_CPU_CATERR_LVT3_R2_N @BASEBOARD_FAB2_LIB.BASEBOARD_FAB2(SCH_1):FM_CPU_CATERR_LVT3_R2_N
  U3P2   10     A2 GTL2014_SM-IC,D66151-001     I1 @BASEBOARD_FAB2_LIB.BASEBOARD_FAB2(SCH_1):PAGE92
 R3P43    1      A RES_0402-33.2,1%,1/16W,CHIP,G2A    I13 @BASEBOARD_FAB2_LIB.BASEBOARD_FAB2(SCH_1):PAGE92

FM_CPU_CATERR_MSMI_LVT3_N @BASEBOARD_FAB2_LIB.BASEBOARD_FAB2(SCH_1):FM_CPU_CATERR_MSMI_LVT3_N
  U6W1   18    P15 TCA9555PWR-GP_DISCRET-GC1-TCA9A   I120 @BASEBOARD_FAB2_LIB.BASEBOARD_FAB2(SCH_1):PAGE247
 CR6W1    2      A DIODE_SMLF-BAT54WS,IC,C73510-0A   I157 @BASEBOARD_FAB2_LIB.BASEBOARD_FAB2(SCH_1):PAGE247
 CR6W2    2      A DIODE_SMLF-BAT54WS,IC,C73510-0A   I158 @BASEBOARD_FAB2_LIB.BASEBOARD_FAB2(SCH_1):PAGE247
 R6W35    2      B RES_0402-100.0K,1%,1/16W,CHIP,A   I165 @BASEBOARD_FAB2_LIB.BASEBOARD_FAB2(SCH_1):PAGE247

FM_CPU_ERR0_LVT3_BMC_N @BASEBOARD_FAB2_LIB.BASEBOARD_FAB2(SCH_1):FM_CPU_ERR0_LVT3_BMC_N
 R8F38    2      B RES_0402-0.0,5%,1/16W,CHIP,G21A   I119 @BASEBOARD_FAB2_LIB.BASEBOARD_FAB2(SCH_1):PAGE93
 U25W4  G18 GPIOD6_SD2CD# AST2520A1-GP-GP_ASIC2-GB1-AST2A   I117 @BASEBOARD_FAB2_LIB.BASEBOARD_FAB2(SCH_1):PAGE145

FM_CPU_ERR0_LVT3_K_N @BASEBOARD_FAB2_LIB.BASEBOARD_FAB2(SCH_1):FM_CPU_ERR0_LVT3_K_N
 R2T30    1      A RES_0402-33.2,1%,1/16W,CHIP,G2A    I42 @BASEBOARD_FAB2_LIB.BASEBOARD_FAB2(SCH_1):PAGE93
 R2T58    2      B RES_0402-0.0,5%,1/16W,EMPTY,G2A    I94 @BASEBOARD_FAB2_LIB.BASEBOARD_FAB2(SCH_1):PAGE93
 R2T65    2      B RES_0402-0.0,5%,1/16W,CHIP,G21A   I111 @BASEBOARD_FAB2_LIB.BASEBOARD_FAB2(SCH_1):PAGE93

FM_CPU_ERR0_LVT3_N @BASEBOARD_FAB2_LIB.BASEBOARD_FAB2(SCH_1):FM_CPU_ERR0_LVT3_N
 R2T30    2      B RES_0402-33.2,1%,1/16W,CHIP,G2A    I42 @BASEBOARD_FAB2_LIB.BASEBOARD_FAB2(SCH_1):PAGE93
 R8F38    1      A RES_0402-0.0,5%,1/16W,CHIP,G21A   I119 @BASEBOARD_FAB2_LIB.BASEBOARD_FAB2(SCH_1):PAGE93
 R8F37    1      A RES_0402-0.0,5%,1/16W,EMPTY,G2A   I131 @BASEBOARD_FAB2_LIB.BASEBOARD_FAB2(SCH_1):PAGE93

FM_CPU_ERR0_LVT3_R_N @BASEBOARD_FAB2_LIB.BASEBOARD_FAB2(SCH_1):FM_CPU_ERR0_LVT3_R_N
  U2T4    9     A3 GTL2014_SM-IC,D66151-001    I30 @BASEBOARD_FAB2_LIB.BASEBOARD_FAB2(SCH_1):PAGE93
 R2T65    1      A RES_0402-0.0,5%,1/16W,CHIP,G21A   I111 @BASEBOARD_FAB2_LIB.BASEBOARD_FAB2(SCH_1):PAGE93

FM_CPU_ERR0_PCH_N @BASEBOARD_FAB2_LIB.BASEBOARD_FAB2(SCH_1):FM_CPU_ERR0_PCH_N
 R8F37    2      B RES_0402-0.0,5%,1/16W,EMPTY,G2A   I131 @BASEBOARD_FAB2_LIB.BASEBOARD_FAB2(SCH_1):PAGE93
  U7C1  AE7 GPP_L18_TESTCH1_D7 LBG_CORE_QAT_EXT_D_BGA1-IC,H91A    I34 @BASEBOARD_FAB2_LIB.BASEBOARD_FAB2(SCH_1):PAGE121

FM_CPU_ERR1_LVT3_BMC_N @BASEBOARD_FAB2_LIB.BASEBOARD_FAB2(SCH_1):FM_CPU_ERR1_LVT3_BMC_N
 R2T64    2      B RES_0402-0.0,5%,1/16W,CHIP,G21A   I121 @BASEBOARD_FAB2_LIB.BASEBOARD_FAB2(SCH_1):PAGE93
 U25W4  C21 GPIOD7_SD2WP# AST2520A1-GP-GP_ASIC2-GB1-AST2A   I117 @BASEBOARD_FAB2_LIB.BASEBOARD_FAB2(SCH_1):PAGE145

FM_CPU_ERR1_LVT3_K_N @BASEBOARD_FAB2_LIB.BASEBOARD_FAB2(SCH_1):FM_CPU_ERR1_LVT3_K_N
 R2T33    1      A RES_0402-33.2,1%,1/16W,CHIP,G2A    I40 @BASEBOARD_FAB2_LIB.BASEBOARD_FAB2(SCH_1):PAGE93
 R2T62    2      B RES_0402-0.0,5%,1/16W,EMPTY,G2A    I93 @BASEBOARD_FAB2_LIB.BASEBOARD_FAB2(SCH_1):PAGE93
 R2T66    2      B RES_0402-0.0,5%,1/16W,CHIP,G21A   I112 @BASEBOARD_FAB2_LIB.BASEBOARD_FAB2(SCH_1):PAGE93

FM_CPU_ERR1_LVT3_N @BASEBOARD_FAB2_LIB.BASEBOARD_FAB2(SCH_1):FM_CPU_ERR1_LVT3_N
 R2T33    2      B RES_0402-33.2,1%,1/16W,CHIP,G2A    I40 @BASEBOARD_FAB2_LIB.BASEBOARD_FAB2(SCH_1):PAGE93
 R2T64    1      A RES_0402-0.0,5%,1/16W,CHIP,G21A   I121 @BASEBOARD_FAB2_LIB.BASEBOARD_FAB2(SCH_1):PAGE93
 R2T63    1      A RES_0402-0.0,5%,1/16W,EMPTY,G2A   I133 @BASEBOARD_FAB2_LIB.BASEBOARD_FAB2(SCH_1):PAGE93

FM_CPU_ERR1_LVT3_R_N @BASEBOARD_FAB2_LIB.BASEBOARD_FAB2(SCH_1):FM_CPU_ERR1_LVT3_R_N
  U2T4   10     A2 GTL2014_SM-IC,D66151-001    I30 @BASEBOARD_FAB2_LIB.BASEBOARD_FAB2(SCH_1):PAGE93
 R2T66    1      A RES_0402-0.0,5%,1/16W,CHIP,G21A   I112 @BASEBOARD_FAB2_LIB.BASEBOARD_FAB2(SCH_1):PAGE93

FM_CPU_ERR1_PCH_N @BASEBOARD_FAB2_LIB.BASEBOARD_FAB2(SCH_1):FM_CPU_ERR1_PCH_N
 R2T63    2      B RES_0402-0.0,5%,1/16W,EMPTY,G2A   I133 @BASEBOARD_FAB2_LIB.BASEBOARD_FAB2(SCH_1):PAGE93
  U7C1 AG11 GPP_L19_TESTCH1_CLK LBG_CORE_QAT_EXT_D_BGA1-IC,H91A    I34 @BASEBOARD_FAB2_LIB.BASEBOARD_FAB2(SCH_1):PAGE121

FM_CPU_ERR2_LVT3_N @BASEBOARD_FAB2_LIB.BASEBOARD_FAB2(SCH_1):FM_CPU_ERR2_LVT3_N
 R7D31    2      B RES_0402-33.2,1%,1/16W,CHIP,G2A    I29 @BASEBOARD_FAB2_LIB.BASEBOARD_FAB2(SCH_1):PAGE92
  U7C1 AV52 GPP_E4_SATA_DEVSLP0 LBG_CORE_QAT_EXT_D_BGA1-IC,H91A   I147 @BASEBOARD_FAB2_LIB.BASEBOARD_FAB2(SCH_1):PAGE120
 U25W4  A19 GPIOG0_SGPS1CK AST2520A1-GP-GP_ASIC2-GB1-AST2A    I95 @BASEBOARD_FAB2_LIB.BASEBOARD_FAB2(SCH_1):PAGE144

FM_CPU_ERR2_LVT3_R_N @BASEBOARD_FAB2_LIB.BASEBOARD_FAB2(SCH_1):FM_CPU_ERR2_LVT3_R_N
 R7D31    1      A RES_0402-33.2,1%,1/16W,CHIP,G2A    I29 @BASEBOARD_FAB2_LIB.BASEBOARD_FAB2(SCH_1):PAGE92
  U7D2   10     A2 GTL2014_SM-IC,D66151-001    I32 @BASEBOARD_FAB2_LIB.BASEBOARD_FAB2(SCH_1):PAGE92

FM_CPU_MSMI_LVT3_N @BASEBOARD_FAB2_LIB.BASEBOARD_FAB2(SCH_1):FM_CPU_MSMI_LVT3_N
 R7D25    2      B RES_0402-33.2,1%,1/16W,CHIP,G2A    I70 @BASEBOARD_FAB2_LIB.BASEBOARD_FAB2(SCH_1):PAGE92
  U7C1 AT52 GPP_E5_SATA_DEVSLP1 LBG_CORE_QAT_EXT_D_BGA1-IC,H91A   I147 @BASEBOARD_FAB2_LIB.BASEBOARD_FAB2(SCH_1):PAGE120
  U8D7  T13  PB24B LCMXO2_A_256BGA-IC,H63395-001   I179 @BASEBOARD_FAB2_LIB.BASEBOARD_FAB2(SCH_1):PAGE190
 U25W4   U3 GPION3_PWM3_VPIG3 AST2520A1-GP-GP_ASIC2-GB1-AST2A   I106 @BASEBOARD_FAB2_LIB.BASEBOARD_FAB2(SCH_1):PAGE147
 CR6W2    1      C DIODE_SMLF-BAT54WS,IC,C73510-0A   I158 @BASEBOARD_FAB2_LIB.BASEBOARD_FAB2(SCH_1):PAGE247

FM_CPU_MSMI_LVT3_R_N @BASEBOARD_FAB2_LIB.BASEBOARD_FAB2(SCH_1):FM_CPU_MSMI_LVT3_R_N
  U7D2   13     A0 GTL2014_SM-IC,D66151-001    I32 @BASEBOARD_FAB2_LIB.BASEBOARD_FAB2(SCH_1):PAGE92
 R7D25    1      A RES_0402-33.2,1%,1/16W,CHIP,G2A    I70 @BASEBOARD_FAB2_LIB.BASEBOARD_FAB2(SCH_1):PAGE92

FM_CTNR_PS_ON @BASEBOARD_FAB2_LIB.BASEBOARD_FAB2(SCH_1):FM_CTNR_PS_ON
  U1E2    1   A<0> TTL1G08_SOTLF-NC7SZ08,IC,D1032B   I121 @BASEBOARD_FAB2_LIB.BASEBOARD_FAB2(SCH_1):PAGE161
  U8D7   B3   PT9C LCMXO2_A_256BGA-IC,H63395-001    I59 @BASEBOARD_FAB2_LIB.BASEBOARD_FAB2(SCH_1):PAGE191
 EU8B1    2     ON SLG55021_SM-IC,G56246-001    I13 @BASEBOARD_FAB2_LIB.BASEBOARD_FAB2(SCH_1):PAGE198
 R8E12    2      B RES_0402-4.75K,1%,1/16W,EMPTY,A    I78 @BASEBOARD_FAB2_LIB.BASEBOARD_FAB2(SCH_1):PAGE198
  R8B4    1      A RES_0402-100.0K,1%,1/16W,CHIP,A    I83 @BASEBOARD_FAB2_LIB.BASEBOARD_FAB2(SCH_1):PAGE198
  R8E5    2      B RES_0402-33.2,1%,1/16W,CHIP,G2A    I63 @BASEBOARD_FAB2_LIB.BASEBOARD_FAB2(SCH_1):PAGE181

FM_CTNR_PS_ON_R @BASEBOARD_FAB2_LIB.BASEBOARD_FAB2(SCH_1):FM_CTNR_PS_ON_R
  U8E1    8   Y<0> TTL08_QFN15-74LVC08A,IC,D90404B    I60 @BASEBOARD_FAB2_LIB.BASEBOARD_FAB2(SCH_1):PAGE181
  R8E5    1      A RES_0402-33.2,1%,1/16W,CHIP,G2A    I63 @BASEBOARD_FAB2_LIB.BASEBOARD_FAB2(SCH_1):PAGE181

FM_DB1200ZL_BCLKS_EN_N @BASEBOARD_FAB2_LIB.BASEBOARD_FAB2(SCH_1):FM_DB1200ZL_BCLKS_EN_N
 EU4D2   19 OE_0_N NB3W1200L_LCC-IC,H13585-001     I1 @BASEBOARD_FAB2_LIB.BASEBOARD_FAB2(SCH_1):PAGE102
 EU4D2   20 OE_1_N NB3W1200L_LCC-IC,H13585-001     I1 @BASEBOARD_FAB2_LIB.BASEBOARD_FAB2(SCH_1):PAGE102
 EU4D2   28 OE_2_N NB3W1200L_LCC-IC,H13585-001     I1 @BASEBOARD_FAB2_LIB.BASEBOARD_FAB2(SCH_1):PAGE102
 EU4D2   44 OE_6_N NB3W1200L_LCC-IC,H13585-001     I1 @BASEBOARD_FAB2_LIB.BASEBOARD_FAB2(SCH_1):PAGE102
 EU4D2   45 OE_7_N NB3W1200L_LCC-IC,H13585-001     I1 @BASEBOARD_FAB2_LIB.BASEBOARD_FAB2(SCH_1):PAGE102
 EU4D2   52 OE_8_N NB3W1200L_LCC-IC,H13585-001     I1 @BASEBOARD_FAB2_LIB.BASEBOARD_FAB2(SCH_1):PAGE102
  U8D7  R11  PB22A LCMXO2_A_256BGA-IC,H63395-001   I179 @BASEBOARD_FAB2_LIB.BASEBOARD_FAB2(SCH_1):PAGE190
 R6P48    2      B RES_0402-1.00K,1%,1/16W,CHIP,GA   I115 @BASEBOARD_FAB2_LIB.BASEBOARD_FAB2(SCH_1):PAGE102

FM_DB1200_PWRGD @BASEBOARD_FAB2_LIB.BASEBOARD_FAB2(SCH_1):FM_DB1200_PWRGD
  U8D7  C15   PR1C LCMXO2_A_256BGA-IC,H63395-001    I59 @BASEBOARD_FAB2_LIB.BASEBOARD_FAB2(SCH_1):PAGE191
  Q4W2    1   GATE FET_N_SOT23LF-2N7002,FET,C7925A   I112 @BASEBOARD_FAB2_LIB.BASEBOARD_FAB2(SCH_1):PAGE102
  R4W5    1      A RES_0402-0.0,5%,1/16W,EMPTY,G2A   I114 @BASEBOARD_FAB2_LIB.BASEBOARD_FAB2(SCH_1):PAGE102

FM_DB1200_PWRGD_R @BASEBOARD_FAB2_LIB.BASEBOARD_FAB2(SCH_1):FM_DB1200_PWRGD_R
 EU4D2    6 PWRGD_PWRDN_N NB3W1200L_LCC-IC,H13585-001     I1 @BASEBOARD_FAB2_LIB.BASEBOARD_FAB2(SCH_1):PAGE102
  R4W6    2      B RES_0402-4.75K,1%,1/16W,CHIP,GA   I109 @BASEBOARD_FAB2_LIB.BASEBOARD_FAB2(SCH_1):PAGE102
  Q4W2    3    DRN FET_N_SOT23LF-2N7002,FET,C7925A   I112 @BASEBOARD_FAB2_LIB.BASEBOARD_FAB2(SCH_1):PAGE102
  R4W5    2      B RES_0402-0.0,5%,1/16W,EMPTY,G2A   I114 @BASEBOARD_FAB2_LIB.BASEBOARD_FAB2(SCH_1):PAGE102

FM_DB1200_SMB_SA0 @BASEBOARD_FAB2_LIB.BASEBOARD_FAB2(SCH_1):FM_DB1200_SMB_SA0
 EU4D2   11   SA_0 NB3W1200L_LCC-IC,H13585-001     I1 @BASEBOARD_FAB2_LIB.BASEBOARD_FAB2(SCH_1):PAGE102
 R4D35    2      B RES_0402-10.0K,1%,1/16W,EMPTY,A    I38 @BASEBOARD_FAB2_LIB.BASEBOARD_FAB2(SCH_1):PAGE102
 R6P21    1      A RES_0402-1.00K,1%,1/16W,CHIP,GA    I80 @BASEBOARD_FAB2_LIB.BASEBOARD_FAB2(SCH_1):PAGE102

FM_DB1200_SMB_SA1 @BASEBOARD_FAB2_LIB.BASEBOARD_FAB2(SCH_1):FM_DB1200_SMB_SA1
 EU4D2   14   SA_1 NB3W1200L_LCC-IC,H13585-001     I1 @BASEBOARD_FAB2_LIB.BASEBOARD_FAB2(SCH_1):PAGE102
 R4D38    2      B RES_0402-10.0K,1%,1/16W,EMPTY,A    I37 @BASEBOARD_FAB2_LIB.BASEBOARD_FAB2(SCH_1):PAGE102
 R6P20    1      A RES_0402-1.00K,1%,1/16W,CHIP,GA    I81 @BASEBOARD_FAB2_LIB.BASEBOARD_FAB2(SCH_1):PAGE102

FM_DB_PRESENT @BASEBOARD_FAB2_LIB.BASEBOARD_FAB2(SCH_1):FM_DB_PRESENT
  Q1L3    3      C NPN_SM-MMBT3904,IC,C52245-001     I8 @BASEBOARD_FAB2_LIB.BASEBOARD_FAB2(SCH_1):PAGE168
 R1L36    2      B RES_0402-1.00K,1%,1/16W,CHIP,GA    I11 @BASEBOARD_FAB2_LIB.BASEBOARD_FAB2(SCH_1):PAGE168
  Q1L4    2 GATE<0> FET_N_DUAL_SMLF-2N7002DW,FET,DA    I19 @BASEBOARD_FAB2_LIB.BASEBOARD_FAB2(SCH_1):PAGE168

FM_DB_UART_SEL0_N @BASEBOARD_FAB2_LIB.BASEBOARD_FAB2(SCH_1):FM_DB_UART_SEL0_N
 CR1L1    2      A DIODE_SM-1N4148W,IC,D89194-001     I2 @BASEBOARD_FAB2_LIB.BASEBOARD_FAB2(SCH_1):PAGE168
  R1L6    2      B RES_0402-0.0,5%,1/16W,CHIP,G21A     I6 @BASEBOARD_FAB2_LIB.BASEBOARD_FAB2(SCH_1):PAGE168

FM_DB_UART_SEL1_N @BASEBOARD_FAB2_LIB.BASEBOARD_FAB2(SCH_1):FM_DB_UART_SEL1_N
 CR1L1    1      C DIODE_SM-1N4148W,IC,D89194-001     I2 @BASEBOARD_FAB2_LIB.BASEBOARD_FAB2(SCH_1):PAGE168
 CR1L2    2      A DIODE_SM-1N4148W,IC,D89194-001     I3 @BASEBOARD_FAB2_LIB.BASEBOARD_FAB2(SCH_1):PAGE168

FM_DB_UART_SEL2_N @BASEBOARD_FAB2_LIB.BASEBOARD_FAB2(SCH_1):FM_DB_UART_SEL2_N
 CR1L2    1      C DIODE_SM-1N4148W,IC,D89194-001     I3 @BASEBOARD_FAB2_LIB.BASEBOARD_FAB2(SCH_1):PAGE168
 CR1L3    2      A DIODE_SM-1N4148W,IC,D89194-001     I4 @BASEBOARD_FAB2_LIB.BASEBOARD_FAB2(SCH_1):PAGE168

FM_DB_UART_SEL3_N @BASEBOARD_FAB2_LIB.BASEBOARD_FAB2(SCH_1):FM_DB_UART_SEL3_N
 CR1L3    1      C DIODE_SM-1N4148W,IC,D89194-001     I4 @BASEBOARD_FAB2_LIB.BASEBOARD_FAB2(SCH_1):PAGE168
 CR1L4    2      A DIODE_SM-1N4148W,IC,D89194-001     I5 @BASEBOARD_FAB2_LIB.BASEBOARD_FAB2(SCH_1):PAGE168

FM_DB_UART_SEL4_N @BASEBOARD_FAB2_LIB.BASEBOARD_FAB2(SCH_1):FM_DB_UART_SEL4_N
 CR1L4    1      C DIODE_SM-1N4148W,IC,D89194-001     I5 @BASEBOARD_FAB2_LIB.BASEBOARD_FAB2(SCH_1):PAGE168
  Q1L3    1      B NPN_SM-MMBT3904,IC,C52245-001     I8 @BASEBOARD_FAB2_LIB.BASEBOARD_FAB2(SCH_1):PAGE168

FM_DEBUG_RST_BTN_N @BASEBOARD_FAB2_LIB.BASEBOARD_FAB2(SCH_1):FM_DEBUG_RST_BTN_N
 R1L29    2      B RES_0402-33.2,1%,1/16W,CHIP,G2A    I68 @BASEBOARD_FAB2_LIB.BASEBOARD_FAB2(SCH_1):PAGE111
  J9A2   11   IO11 CONN14_H54902001_PIP-CONN,H549A   I171 @BASEBOARD_FAB2_LIB.BASEBOARD_FAB2(SCH_1):PAGE155
 R1L22    1      A RES_0402-200.0,1%,1/16W,CHIP,GA    I22 @BASEBOARD_FAB2_LIB.BASEBOARD_FAB2(SCH_1):PAGE175
  S9A1    1   PIN1 SWITCH_D37771002_SM-IC,D37771-A    I78 @BASEBOARD_FAB2_LIB.BASEBOARD_FAB2(SCH_1):PAGE175
  S9A1    2   PIN2 SWITCH_D37771002_SM-IC,D37771-A    I78 @BASEBOARD_FAB2_LIB.BASEBOARD_FAB2(SCH_1):PAGE175
  U8D7   G5   PL4C LCMXO2_A_256BGA-IC,H63395-001   I179 @BASEBOARD_FAB2_LIB.BASEBOARD_FAB2(SCH_1):PAGE190
  U6W1   13    P10 TCA9555PWR-GP_DISCRET-GC1-TCA9A   I120 @BASEBOARD_FAB2_LIB.BASEBOARD_FAB2(SCH_1):PAGE247
 R1L19    2      B RES_0402-4.75K,1%,1/16W,CHIP,GA    I99 @BASEBOARD_FAB2_LIB.BASEBOARD_FAB2(SCH_1):PAGE175

FM_DEBUG_RST_BTN_R1_N @BASEBOARD_FAB2_LIB.BASEBOARD_FAB2(SCH_1):FM_DEBUG_RST_BTN_R1_N
 R1L29    1      A RES_0402-33.2,1%,1/16W,CHIP,G2A    I68 @BASEBOARD_FAB2_LIB.BASEBOARD_FAB2(SCH_1):PAGE111
  U1L4    4      Y TTL1G07_A_SOP-74LVC1G07,IC,C88B    I85 @BASEBOARD_FAB2_LIB.BASEBOARD_FAB2(SCH_1):PAGE111
 R1L28    2      B RES_0402-4.75K,1%,1/16W,EMPTY,A    I97 @BASEBOARD_FAB2_LIB.BASEBOARD_FAB2(SCH_1):PAGE111

FM_DIMM_EVENT_COD_N @BASEBOARD_FAB2_LIB.BASEBOARD_FAB2(SCH_1):FM_DIMM_EVENT_COD_N
  J4G1   78 EVENT_N SCONN288_H44441004_PIP-SCONN,HA     I1 @BASEBOARD_FAB2_LIB.BASEBOARD_FAB2(SCH_1):PAGE43
  J6T1   78 EVENT_N SCONN288_H44441003_PIP-SCONN,HA    I13 @BASEBOARD_FAB2_LIB.BASEBOARD_FAB2(SCH_1):PAGE44
  J4G2   78 EVENT_N SCONN288_H44441004_PIP-SCONN,HA   I111 @BASEBOARD_FAB2_LIB.BASEBOARD_FAB2(SCH_1):PAGE45
  J6U1   78 EVENT_N SCONN288_H44441003_PIP-SCONN,HA    I14 @BASEBOARD_FAB2_LIB.BASEBOARD_FAB2(SCH_1):PAGE46
  J4G3   78 EVENT_N SCONN288_H44441004_PIP-SCONN,HA   I111 @BASEBOARD_FAB2_LIB.BASEBOARD_FAB2(SCH_1):PAGE47
  J6U2   78 EVENT_N SCONN288_H44441003_PIP-SCONN,HA   I111 @BASEBOARD_FAB2_LIB.BASEBOARD_FAB2(SCH_1):PAGE48
  J4B1   78 EVENT_N SCONN288_H44441004_PIP-SCONN,HA   I111 @BASEBOARD_FAB2_LIB.BASEBOARD_FAB2(SCH_1):PAGE49
  J6M1   78 EVENT_N SCONN288_H44441003_PIP-SCONN,HA   I158 @BASEBOARD_FAB2_LIB.BASEBOARD_FAB2(SCH_1):PAGE50
  J4A2   78 EVENT_N SCONN288_H44441004_PIP-SCONN,HA   I111 @BASEBOARD_FAB2_LIB.BASEBOARD_FAB2(SCH_1):PAGE51
  J6L2   78 EVENT_N SCONN288_H44441003_PIP-SCONN,HA    I12 @BASEBOARD_FAB2_LIB.BASEBOARD_FAB2(SCH_1):PAGE52
  J4A1   78 EVENT_N SCONN288_H44441004_PIP-SCONN,HA   I111 @BASEBOARD_FAB2_LIB.BASEBOARD_FAB2(SCH_1):PAGE53
  J6L1   78 EVENT_N SCONN288_H44441003_PIP-SCONN,HA   I111 @BASEBOARD_FAB2_LIB.BASEBOARD_FAB2(SCH_1):PAGE54
  J1G1   78 EVENT_N SCONN288_H44441004_PIP-SCONN,HA   I111 @BASEBOARD_FAB2_LIB.BASEBOARD_FAB2(SCH_1):PAGE77
  J9T1   78 EVENT_N SCONN288_H44441003_PIP-SCONN,HA    I13 @BASEBOARD_FAB2_LIB.BASEBOARD_FAB2(SCH_1):PAGE78
  J1G2   78 EVENT_N SCONN288_H44441004_PIP-SCONN,HA   I111 @BASEBOARD_FAB2_LIB.BASEBOARD_FAB2(SCH_1):PAGE79
  J9U1   78 EVENT_N SCONN288_H44441003_PIP-SCONN,HA    I24 @BASEBOARD_FAB2_LIB.BASEBOARD_FAB2(SCH_1):PAGE80
  J1G3   78 EVENT_N SCONN288_H44441004_PIP-SCONN,HA   I186 @BASEBOARD_FAB2_LIB.BASEBOARD_FAB2(SCH_1):PAGE81
  J9U2   78 EVENT_N SCONN288_H44441003_PIP-SCONN,HA   I187 @BASEBOARD_FAB2_LIB.BASEBOARD_FAB2(SCH_1):PAGE82
  J1B1   78 EVENT_N SCONN288_H44441004_PIP-SCONN,HA   I111 @BASEBOARD_FAB2_LIB.BASEBOARD_FAB2(SCH_1):PAGE83
  J9M1   78 EVENT_N SCONN288_H44441003_PIP-SCONN,HA    I14 @BASEBOARD_FAB2_LIB.BASEBOARD_FAB2(SCH_1):PAGE84
  J1A2   78 EVENT_N SCONN288_H44441004_PIP-SCONN,HA   I111 @BASEBOARD_FAB2_LIB.BASEBOARD_FAB2(SCH_1):PAGE85
  J9L2   78 EVENT_N SCONN288_H44441003_PIP-SCONN,HA    I12 @BASEBOARD_FAB2_LIB.BASEBOARD_FAB2(SCH_1):PAGE86
  J1A1   78 EVENT_N SCONN288_H44441004_PIP-SCONN,HA   I186 @BASEBOARD_FAB2_LIB.BASEBOARD_FAB2(SCH_1):PAGE87
  J9L1   78 EVENT_N SCONN288_H44441003_PIP-SCONN,HA   I111 @BASEBOARD_FAB2_LIB.BASEBOARD_FAB2(SCH_1):PAGE88
  Q4U1    2 GATE<0> FET_N_DUAL_SMLF-NTJD4001N,FET,A    I98 @BASEBOARD_FAB2_LIB.BASEBOARD_FAB2(SCH_1):PAGE94
  R4U2    2      B RES_0402-2.21K,1%,1/16W,CHIP,GA   I100 @BASEBOARD_FAB2_LIB.BASEBOARD_FAB2(SCH_1):PAGE94

FM_DIMM_EVENT_FET @BASEBOARD_FAB2_LIB.BASEBOARD_FAB2(SCH_1):FM_DIMM_EVENT_FET
  R4U3    2      B RES_0402-4.75K,1%,1/16W,CHIP,GA    I94 @BASEBOARD_FAB2_LIB.BASEBOARD_FAB2(SCH_1):PAGE94
  Q4U1    6 DRAIN<0> FET_N_DUAL_SMLF-NTJD4001N,FET,A    I98 @BASEBOARD_FAB2_LIB.BASEBOARD_FAB2(SCH_1):PAGE94
  Q4U1    5 GATE<0> FET_N_DUAL_SMLF-NTJD4001N,FET,A   I102 @BASEBOARD_FAB2_LIB.BASEBOARD_FAB2(SCH_1):PAGE94
  R4U4    1      A RES_0402-33.0K,5%,1/16W,CHIP,GA   I104 @BASEBOARD_FAB2_LIB.BASEBOARD_FAB2(SCH_1):PAGE94

FM_DISABLE_FAN_N @BASEBOARD_FAB2_LIB.BASEBOARD_FAB2(SCH_1):FM_DISABLE_FAN_N
  U1E2    2   B<0> TTL1G08_SOTLF-NC7SZ08,IC,D1032B   I121 @BASEBOARD_FAB2_LIB.BASEBOARD_FAB2(SCH_1):PAGE161
 CR9P2    2      A DIODE_SMLF-BAT54WS,IC,C73510-0A   I213 @BASEBOARD_FAB2_LIB.BASEBOARD_FAB2(SCH_1):PAGE200
 CR9P1    2      A DIODE_SMLF-BAT54WS,IC,C73510-0A   I214 @BASEBOARD_FAB2_LIB.BASEBOARD_FAB2(SCH_1):PAGE200
  R9P5    2      B RES_0402-10.0K,1%,1/16W,CHIP,GA   I215 @BASEBOARD_FAB2_LIB.BASEBOARD_FAB2(SCH_1):PAGE200

FM_DIS_ADR_DLY @BASEBOARD_FAB2_LIB.BASEBOARD_FAB2(SCH_1):FM_DIS_ADR_DLY
 R2P19    2      B RES_0402-10.0K,1%,1/16W,CHIP,GA   I107 @BASEBOARD_FAB2_LIB.BASEBOARD_FAB2(SCH_1):PAGE135
  J8G2   10   IO10 CONN12_C73564003_PIP-CONN,C735A   I124 @BASEBOARD_FAB2_LIB.BASEBOARD_FAB2(SCH_1):PAGE135
  U8D7   T3   PB6C LCMXO2_A_256BGA-IC,H63395-001   I179 @BASEBOARD_FAB2_LIB.BASEBOARD_FAB2(SCH_1):PAGE190

FM_DUAL_BIOS_SEL_N @BASEBOARD_FAB2_LIB.BASEBOARD_FAB2(SCH_1):FM_DUAL_BIOS_SEL_N
  U2T3    1      A TTL1G32_A_SOT-74LVC1G32,IC,E60B    I99 @BASEBOARD_FAB2_LIB.BASEBOARD_FAB2(SCH_1):PAGE154
 R2T11    2      B RES_0402-4.75K,1%,1/16W,CHIP,GA   I105 @BASEBOARD_FAB2_LIB.BASEBOARD_FAB2(SCH_1):PAGE154
  Q8F1    3    DRN FET_N_SOT23LF-2N7002,FET,C7925A   I126 @BASEBOARD_FAB2_LIB.BASEBOARD_FAB2(SCH_1):PAGE154

FM_ENABLE_FAN_POWER @BASEBOARD_FAB2_LIB.BASEBOARD_FAB2(SCH_1):FM_ENABLE_FAN_POWER
 R1E11    2      B RES_0402-10.0K,1%,1/16W,EMPTY,A   I120 @BASEBOARD_FAB2_LIB.BASEBOARD_FAB2(SCH_1):PAGE161
  U1E2    4   Y<0> TTL1G08_SOTLF-NC7SZ08,IC,D1032B   I121 @BASEBOARD_FAB2_LIB.BASEBOARD_FAB2(SCH_1):PAGE161
 EU9M1    2     ON SLG55021_SM-IC,G56246-001    I69 @BASEBOARD_FAB2_LIB.BASEBOARD_FAB2(SCH_1):PAGE198
  J1F1   I3 MB_ON# DM-FCI-CONN76-8R-GP-U-01_CONN-A   I134 @BASEBOARD_FAB2_LIB.BASEBOARD_FAB2(SCH_1):PAGE181

FM_FAST_PROCHOT_AND_OUT_0_N @BASEBOARD_FAB2_LIB.BASEBOARD_FAB2(SCH_1):FM_FAST_PROCHOT_AND_OUT_0_N
  U8E1    3   Y<0> TTL08_QFN15-74LVC08A,IC,D90404B    I10 @BASEBOARD_FAB2_LIB.BASEBOARD_FAB2(SCH_1):PAGE170
  U8E1   12   A<0> TTL08_QFN15-74LVC08A,IC,D90404B    I12 @BASEBOARD_FAB2_LIB.BASEBOARD_FAB2(SCH_1):PAGE170

FM_FAST_PROCHOT_AND_OUT_1_N @BASEBOARD_FAB2_LIB.BASEBOARD_FAB2(SCH_1):FM_FAST_PROCHOT_AND_OUT_1_N
  U8E1    6   Y<0> TTL08_QFN15-74LVC08A,IC,D90404B    I11 @BASEBOARD_FAB2_LIB.BASEBOARD_FAB2(SCH_1):PAGE170
  U8E1   13   B<0> TTL08_QFN15-74LVC08A,IC,D90404B    I12 @BASEBOARD_FAB2_LIB.BASEBOARD_FAB2(SCH_1):PAGE170

FM_FAST_PROCHOT_EN @BASEBOARD_FAB2_LIB.BASEBOARD_FAB2(SCH_1):FM_FAST_PROCHOT_EN
  U1R2    1     OE TTL1G126_A_SOT-74HC1G126,IC,A7B    I20 @BASEBOARD_FAB2_LIB.BASEBOARD_FAB2(SCH_1):PAGE170
  R9F3    2      B RES_0402-4.75K,1%,1/16W,CHIP,GA    I65 @BASEBOARD_FAB2_LIB.BASEBOARD_FAB2(SCH_1):PAGE170
  Q8F2    3    DRN FET_N_SOT23LF-2N7002,FET,C7925A    I67 @BASEBOARD_FAB2_LIB.BASEBOARD_FAB2(SCH_1):PAGE170

FM_FAST_PROCHOT_EN_N @BASEBOARD_FAB2_LIB.BASEBOARD_FAB2(SCH_1):FM_FAST_PROCHOT_EN_N
  U7C1 BH17 GPP_B21 LBG_CORE_QAT_EXT_D_BGA1-IC,H91A   I115 @BASEBOARD_FAB2_LIB.BASEBOARD_FAB2(SCH_1):PAGE119
  R2T3    2      B RES_0402-4.75K,1%,1/16W,CHIP,GA    I54 @BASEBOARD_FAB2_LIB.BASEBOARD_FAB2(SCH_1):PAGE170
  Q8F2    1   GATE FET_N_SOT23LF-2N7002,FET,C7925A    I67 @BASEBOARD_FAB2_LIB.BASEBOARD_FAB2(SCH_1):PAGE170
 U25W4   C1 RGMII2RXCTL_GPIOV3 AST2520A1-GP-GP_ASIC2-GB1-AST2A   I106 @BASEBOARD_FAB2_LIB.BASEBOARD_FAB2(SCH_1):PAGE147

FM_FAST_PROCHOT_THROTTLE_DLY_BU @BASEBOARD_FAB2_LIB.BASEBOARD_FAB2(SCH_1):FM_FAST_PROCHOT_THROTTLE_DLY_BUF_N
  U1R2    4      Y TTL1G126_A_SOT-74HC1G126,IC,A7B    I20 @BASEBOARD_FAB2_LIB.BASEBOARD_FAB2(SCH_1):PAGE170
  U1R1    2      A TTL1G07_A_SOP-74LVC1G07,IC,C88B    I46 @BASEBOARD_FAB2_LIB.BASEBOARD_FAB2(SCH_1):PAGE170
  R1R5    2      B RES_0402-4.75K,1%,1/16W,CHIP,GA    I73 @BASEBOARD_FAB2_LIB.BASEBOARD_FAB2(SCH_1):PAGE170

FM_FAST_PROCHOT_THROTTLE_DLY_N @BASEBOARD_FAB2_LIB.BASEBOARD_FAB2(SCH_1):FM_FAST_PROCHOT_THROTTLE_DLY_N
  U1R2    2      A TTL1G126_A_SOT-74HC1G126,IC,A7B    I20 @BASEBOARD_FAB2_LIB.BASEBOARD_FAB2(SCH_1):PAGE170
  U8D7  J12   PR6D LCMXO2_A_256BGA-IC,H63395-001    I59 @BASEBOARD_FAB2_LIB.BASEBOARD_FAB2(SCH_1):PAGE191

FM_FAST_PROCHOT_THROTTLE_IN_N @BASEBOARD_FAB2_LIB.BASEBOARD_FAB2(SCH_1):FM_FAST_PROCHOT_THROTTLE_IN_N
  U8E1   11   Y<0> TTL08_QFN15-74LVC08A,IC,D90404B    I12 @BASEBOARD_FAB2_LIB.BASEBOARD_FAB2(SCH_1):PAGE170
  U8D7  G16   PR6A LCMXO2_A_256BGA-IC,H63395-001    I59 @BASEBOARD_FAB2_LIB.BASEBOARD_FAB2(SCH_1):PAGE191

FM_FLASH_ATTACH_CFG_STRAP @BASEBOARD_FAB2_LIB.BASEBOARD_FAB2(SCH_1):FM_FLASH_ATTACH_CFG_STRAP
  U7C1  BB1 GPP_H12_SML2ALERT_N_IE_N LBG_CORE_QAT_EXT_D_BGA1-IC,H91A   I147 @BASEBOARD_FAB2_LIB.BASEBOARD_FAB2(SCH_1):PAGE120
 R3P62    2      B RES_0402-4.75K,1%,1/16W,EMPTY,A    I22 @BASEBOARD_FAB2_LIB.BASEBOARD_FAB2(SCH_1):PAGE126
 R3P64    1      A RES_0402-1.00K,1%,1/16W,EMPTY,A    I23 @BASEBOARD_FAB2_LIB.BASEBOARD_FAB2(SCH_1):PAGE126

FM_FLASH_DESC_OVERRIDE @BASEBOARD_FAB2_LIB.BASEBOARD_FAB2(SCH_1):FM_FLASH_DESC_OVERRIDE
  U7C1  U24 HDA_SDO LBG_CORE_QAT_EXT_D_BGA1-IC,H91A    I34 @BASEBOARD_FAB2_LIB.BASEBOARD_FAB2(SCH_1):PAGE121
  R3N2    2      B RES_0402-4.75K,1%,1/16W,EMPTY,A    I72 @BASEBOARD_FAB2_LIB.BASEBOARD_FAB2(SCH_1):PAGE125
 R1T24    2      B RES_0402-0.0,5%,1/16W,EMPTY,G2A   I129 @BASEBOARD_FAB2_LIB.BASEBOARD_FAB2(SCH_1):PAGE147

FM_FORCE_ADR_N @BASEBOARD_FAB2_LIB.BASEBOARD_FAB2(SCH_1):FM_FORCE_ADR_N
  U7C1 AR13 GPP_F15_USB2_OC4_N LBG_CORE_QAT_EXT_D_BGA1-IC,H91A   I147 @BASEBOARD_FAB2_LIB.BASEBOARD_FAB2(SCH_1):PAGE120
  U8D7   D7  PT13D LCMXO2_A_256BGA-IC,H63395-001    I59 @BASEBOARD_FAB2_LIB.BASEBOARD_FAB2(SCH_1):PAGE191
  R2R7    2      B RES_0402-4.75K,1%,1/16W,CHIP,GA   I172 @BASEBOARD_FAB2_LIB.BASEBOARD_FAB2(SCH_1):PAGE191
 U25W4  B16 GPIOI2_SYSMOSI AST2520A1-GP-GP_ASIC2-GB1-AST2A    I95 @BASEBOARD_FAB2_LIB.BASEBOARD_FAB2(SCH_1):PAGE144

FM_GBE0_LVC3_MOD_ABS @BASEBOARD_FAB2_LIB.BASEBOARD_FAB2(SCH_1):FM_GBE0_LVC3_MOD_ABS
  U7C1 BV10 GPP_J16_LAN_SDP_P0_0 LBG_CORE_QAT_EXT_D_BGA1-IC,H91A   I147 @BASEBOARD_FAB2_LIB.BASEBOARD_FAB2(SCH_1):PAGE120
  J8E4   37   IO37 SCONN64_H87568002_A_SMT-CONN,HA    I27 @BASEBOARD_FAB2_LIB.BASEBOARD_FAB2(SCH_1):PAGE188
 R1W42    2      B RES_0402-4.75K,1%,1/16W,CHIP,GA   I131 @BASEBOARD_FAB2_LIB.BASEBOARD_FAB2(SCH_1):PAGE188

FM_GBE1_LVC3_MOD_ABS @BASEBOARD_FAB2_LIB.BASEBOARD_FAB2(SCH_1):FM_GBE1_LVC3_MOD_ABS
  U7C1 BY10 GPP_J18_LAN_SDP_P1_0 LBG_CORE_QAT_EXT_D_BGA1-IC,H91A   I147 @BASEBOARD_FAB2_LIB.BASEBOARD_FAB2(SCH_1):PAGE120
  J8E4   38   IO38 SCONN64_H87568002_A_SMT-CONN,HA    I27 @BASEBOARD_FAB2_LIB.BASEBOARD_FAB2(SCH_1):PAGE188
 R1W43    2      B RES_0402-4.75K,1%,1/16W,CHIP,GA   I132 @BASEBOARD_FAB2_LIB.BASEBOARD_FAB2(SCH_1):PAGE188

FM_GBE2_LVC3_MOD_ABS @BASEBOARD_FAB2_LIB.BASEBOARD_FAB2(SCH_1):FM_GBE2_LVC3_MOD_ABS
  U7C1 BW13 GPP_J20_LAN_SDP_P2_0 LBG_CORE_QAT_EXT_D_BGA1-IC,H91A   I147 @BASEBOARD_FAB2_LIB.BASEBOARD_FAB2(SCH_1):PAGE120
  J8E4   31   IO31 SCONN64_H87568002_A_SMT-CONN,HA    I27 @BASEBOARD_FAB2_LIB.BASEBOARD_FAB2(SCH_1):PAGE188
 R1W44    2      B RES_0402-4.75K,1%,1/16W,CHIP,GA   I133 @BASEBOARD_FAB2_LIB.BASEBOARD_FAB2(SCH_1):PAGE188

FM_GBE3_LVC3_MOD_ABS @BASEBOARD_FAB2_LIB.BASEBOARD_FAB2(SCH_1):FM_GBE3_LVC3_MOD_ABS
  U7C1 BY12 GPP_J22_LAN_SDP_P3_0 LBG_CORE_QAT_EXT_D_BGA1-IC,H91A   I147 @BASEBOARD_FAB2_LIB.BASEBOARD_FAB2(SCH_1):PAGE120
  J8E4   32   IO32 SCONN64_H87568002_A_SMT-CONN,HA    I27 @BASEBOARD_FAB2_LIB.BASEBOARD_FAB2(SCH_1):PAGE188
 R1W45    2      B RES_0402-4.75K,1%,1/16W,CHIP,GA   I134 @BASEBOARD_FAB2_LIB.BASEBOARD_FAB2(SCH_1):PAGE188

FM_GBE_LOM_DISABLE_N @BASEBOARD_FAB2_LIB.BASEBOARD_FAB2(SCH_1):FM_GBE_LOM_DISABLE_N
  U7C1  A13 GPD11_GBEPHY LBG_CORE_QAT_EXT_D_BGA1-IC,H91A    I73 @BASEBOARD_FAB2_LIB.BASEBOARD_FAB2(SCH_1):PAGE118
 R8C24    1      A RES_0402-0.0,5%,1/16W,CHIP,G21A   I120 @BASEBOARD_FAB2_LIB.BASEBOARD_FAB2(SCH_1):PAGE118
 R8C23    1      A RES_0402-0.0,5%,1/16W,EMPTY,G2A   I125 @BASEBOARD_FAB2_LIB.BASEBOARD_FAB2(SCH_1):PAGE118
  R2N6    2      B RES_0402-10.0K,1%,1/16W,CHIP,GA   I128 @BASEBOARD_FAB2_LIB.BASEBOARD_FAB2(SCH_1):PAGE118

FM_GLOBAL_RST_WARN_N @BASEBOARD_FAB2_LIB.BASEBOARD_FAB2(SCH_1):FM_GLOBAL_RST_WARN_N
  U7C1 BL18 GPP_B12_GLB_RST_WARN_N LBG_CORE_QAT_EXT_D_BGA1-IC,H91A   I115 @BASEBOARD_FAB2_LIB.BASEBOARD_FAB2(SCH_1):PAGE119
  U8D7   P1  PL13D LCMXO2_A_256BGA-IC,H63395-001   I179 @BASEBOARD_FAB2_LIB.BASEBOARD_FAB2(SCH_1):PAGE190
R25W143    2      B RES_0402-0.0,5%,1/16W,CHIP,G21A   I159 @BASEBOARD_FAB2_LIB.BASEBOARD_FAB2(SCH_1):PAGE147

FM_GLOBAL_RST_WARN_N_R @BASEBOARD_FAB2_LIB.BASEBOARD_FAB2(SCH_1):FM_GLOBAL_RST_WARN_N_R
 U25W4   F1 ADC11_GPIX3 AST2520A1-GP-GP_ASIC2-GB1-AST2A   I106 @BASEBOARD_FAB2_LIB.BASEBOARD_FAB2(SCH_1):PAGE147
R25W143    1      A RES_0402-0.0,5%,1/16W,CHIP,G21A   I159 @BASEBOARD_FAB2_LIB.BASEBOARD_FAB2(SCH_1):PAGE147

FM_HBW_BYPASS_LOWBW_N @BASEBOARD_FAB2_LIB.BASEBOARD_FAB2(SCH_1):FM_HBW_BYPASS_LOWBW_N
 EU4D2    5 HBW_BYPASS_LOBW_N NB3W1200L_LCC-IC,H13585-001     I1 @BASEBOARD_FAB2_LIB.BASEBOARD_FAB2(SCH_1):PAGE102
 R6P22    1      A RES_0402-4.75K,1%,1/16W,EMPTY,A    I47 @BASEBOARD_FAB2_LIB.BASEBOARD_FAB2(SCH_1):PAGE102
 R4D41    2      B RES_0402-4.75K,1%,1/16W,CHIP,GA    I53 @BASEBOARD_FAB2_LIB.BASEBOARD_FAB2(SCH_1):PAGE102

FM_HEARTBEAT_LED @BASEBOARD_FAB2_LIB.BASEBOARD_FAB2(SCH_1):FM_HEARTBEAT_LED
  Q9E1    5 GATE<0> FET_N_DUAL_SMLF-NTJD4001N,FET,A   I145 @BASEBOARD_FAB2_LIB.BASEBOARD_FAB2(SCH_1):PAGE151
 R9E21    2      B RES_0402-4.75K,1%,1/16W,CHIP,GA   I173 @BASEBOARD_FAB2_LIB.BASEBOARD_FAB2(SCH_1):PAGE151
  Q9E1    6 DRAIN<0> FET_N_DUAL_SMLF-NTJD4001N,FET,A   I198 @BASEBOARD_FAB2_LIB.BASEBOARD_FAB2(SCH_1):PAGE151

FM_HEARTBEAT_LED_A @BASEBOARD_FAB2_LIB.BASEBOARD_FAB2(SCH_1):FM_HEARTBEAT_LED_A
 R9E24    1      A RES_0402-221,1.0%,1/16W,CHIP,GA   I138 @BASEBOARD_FAB2_LIB.BASEBOARD_FAB2(SCH_1):PAGE151
 DS9E1    1      A LED_A1LF-GREEN,IC,C97278-010   I144 @BASEBOARD_FAB2_LIB.BASEBOARD_FAB2(SCH_1):PAGE151

FM_HEARTBEAT_LED_K @BASEBOARD_FAB2_LIB.BASEBOARD_FAB2(SCH_1):FM_HEARTBEAT_LED_K
 DS9E1    2      C LED_A1LF-GREEN,IC,C97278-010   I144 @BASEBOARD_FAB2_LIB.BASEBOARD_FAB2(SCH_1):PAGE151
  Q9E1    3 DRAIN<0> FET_N_DUAL_SMLF-NTJD4001N,FET,A   I145 @BASEBOARD_FAB2_LIB.BASEBOARD_FAB2(SCH_1):PAGE151

FM_HSC_TIMER_EXP_N @BASEBOARD_FAB2_LIB.BASEBOARD_FAB2(SCH_1):FM_HSC_TIMER_EXP_N
  U7C1  AK9 GPP_F1_SATAXPCIE4_SATAGP4 LBG_CORE_QAT_EXT_D_BGA1-IC,H91A   I147 @BASEBOARD_FAB2_LIB.BASEBOARD_FAB2(SCH_1):PAGE120
  U8E1    5   B<0> TTL08_QFN15-74LVC08A,IC,D90404B    I11 @BASEBOARD_FAB2_LIB.BASEBOARD_FAB2(SCH_1):PAGE170
 R9P20    2      B RES_0402-2.7K,1%,1/16W,CHIP,G2A    I86 @BASEBOARD_FAB2_LIB.BASEBOARD_FAB2(SCH_1):PAGE200
  U9P2    1   OUTB TPS3700_SM-IC,H69492-001   I200 @BASEBOARD_FAB2_LIB.BASEBOARD_FAB2(SCH_1):PAGE200
 U25W4   U1 GPIOL2_NDSR1 AST2520A1-GP-GP_ASIC2-GB1-AST2A   I117 @BASEBOARD_FAB2_LIB.BASEBOARD_FAB2(SCH_1):PAGE145

FM_IE_DISABLE_N @BASEBOARD_FAB2_LIB.BASEBOARD_FAB2(SCH_1):FM_IE_DISABLE_N
  U7C1 AU13 GPP_F16_USB2_OC5_N LBG_CORE_QAT_EXT_D_BGA1-IC,H91A   I147 @BASEBOARD_FAB2_LIB.BASEBOARD_FAB2(SCH_1):PAGE120
 R8D21    2      B RES_0402-1.00K,1%,1/16W,CHIP,GA   I120 @BASEBOARD_FAB2_LIB.BASEBOARD_FAB2(SCH_1):PAGE135
  J8G2    4    IO4 CONN12_C73564003_PIP-CONN,C735A   I124 @BASEBOARD_FAB2_LIB.BASEBOARD_FAB2(SCH_1):PAGE135
  U8D7   L9  PB12D LCMXO2_A_256BGA-IC,H63395-001   I179 @BASEBOARD_FAB2_LIB.BASEBOARD_FAB2(SCH_1):PAGE190

FM_INTRUDER_HDR_PCH_N @BASEBOARD_FAB2_LIB.BASEBOARD_FAB2(SCH_1):FM_INTRUDER_HDR_PCH_N
  U7C1 AG18 INTRUDER_N LBG_CORE_QAT_EXT_D_BGA1-IC,H91A    I34 @BASEBOARD_FAB2_LIB.BASEBOARD_FAB2(SCH_1):PAGE121
 R3N10    2      B RES_0402-10.0K,1%,1/16W,CHIP,GA    I37 @BASEBOARD_FAB2_LIB.BASEBOARD_FAB2(SCH_1):PAGE121

FM_JTAG_PLD_EN_DEBUG @BASEBOARD_FAB2_LIB.BASEBOARD_FAB2(SCH_1):FM_JTAG_PLD_EN_DEBUG
 R3R15    2      B RES_0402-1.00K,1%,1/16W,CHIP,GA    I44 @BASEBOARD_FAB2_LIB.BASEBOARD_FAB2(SCH_1):PAGE189
 R3R11    1      A RES_0402-10.0K,1%,1/16W,EMPTY,A    I45 @BASEBOARD_FAB2_LIB.BASEBOARD_FAB2(SCH_1):PAGE189
  U8D7  C10 PT20C_JTAGENB LCMXO2_A_256BGA-IC,H63395-001    I59 @BASEBOARD_FAB2_LIB.BASEBOARD_FAB2(SCH_1):PAGE191
R25W186    2      B RES_0402-0.0,5%,1/16W,CHIP,G21A    I77 @BASEBOARD_FAB2_LIB.BASEBOARD_FAB2(SCH_1):PAGE189

FM_M2_DET_LVC3 @BASEBOARD_FAB2_LIB.BASEBOARD_FAB2(SCH_1):FM_M2_DET_LVC3
  U2P1    4      Y TTL1G07_A_SOP-74LVC1G07,IC,C88B   I110 @BASEBOARD_FAB2_LIB.BASEBOARD_FAB2(SCH_1):PAGE185
 R2P16    2      B RES_0402-10.0K,1%,1/16W,CHIP,GA   I113 @BASEBOARD_FAB2_LIB.BASEBOARD_FAB2(SCH_1):PAGE185
 R2P14    1      A RES_0402-0.0,5%,1/16W,CHIP,G21A   I115 @BASEBOARD_FAB2_LIB.BASEBOARD_FAB2(SCH_1):PAGE185

FM_M2_SSD_PEDET @BASEBOARD_FAB2_LIB.BASEBOARD_FAB2(SCH_1):FM_M2_SSD_PEDET
  U2P1    2      A TTL1G07_A_SOP-74LVC1G07,IC,C88B   I110 @BASEBOARD_FAB2_LIB.BASEBOARD_FAB2(SCH_1):PAGE185
 R2P15    2      B RES_0402-10.0K,1%,1/16W,CHIP,GA   I111 @BASEBOARD_FAB2_LIB.BASEBOARD_FAB2(SCH_1):PAGE185
  J8F1   69     69 SKT-MINI67P-41-GP_SOCKET-G4-SKA   I143 @BASEBOARD_FAB2_LIB.BASEBOARD_FAB2(SCH_1):PAGE185

FM_MATED_IN_D1_N @BASEBOARD_FAB2_LIB.BASEBOARD_FAB2(SCH_1):FM_MATED_IN_D1_N
 CR1F4    1      C DIODE_SM-SDMK0340L,IC,H71799-0A     I5 @BASEBOARD_FAB2_LIB.BASEBOARD_FAB2(SCH_1):PAGE181
 CR1F3    2      A DIODE_SM-SDMK0340L,IC,H71799-0A    I37 @BASEBOARD_FAB2_LIB.BASEBOARD_FAB2(SCH_1):PAGE181

FM_MATED_IN_D2_N @BASEBOARD_FAB2_LIB.BASEBOARD_FAB2(SCH_1):FM_MATED_IN_D2_N
 CR1F3    1      C DIODE_SM-SDMK0340L,IC,H71799-0A    I37 @BASEBOARD_FAB2_LIB.BASEBOARD_FAB2(SCH_1):PAGE181
  Q9T1    1      B NPN_SM-MMBT3904,IC,C52245-001    I42 @BASEBOARD_FAB2_LIB.BASEBOARD_FAB2(SCH_1):PAGE181

FM_MATED_IN_N @BASEBOARD_FAB2_LIB.BASEBOARD_FAB2(SCH_1):FM_MATED_IN_N
  R9T9    2      B RES_0402-4.75K,1%,1/16W,CHIP,GA     I4 @BASEBOARD_FAB2_LIB.BASEBOARD_FAB2(SCH_1):PAGE181
 CR1F4    2      A DIODE_SM-SDMK0340L,IC,H71799-0A     I5 @BASEBOARD_FAB2_LIB.BASEBOARD_FAB2(SCH_1):PAGE181
  J1F3    4    IO4 CONN8_H62179001_PIP-CONN,H6217A   I106 @BASEBOARD_FAB2_LIB.BASEBOARD_FAB2(SCH_1):PAGE181
  J1F1   E4 MATED_IN# DM-FCI-CONN76-8R-GP-U-01_CONN-A   I134 @BASEBOARD_FAB2_LIB.BASEBOARD_FAB2(SCH_1):PAGE181
  R9T8    1      A RES_0402-0.0,5%,1/16W,CHIP,G21A   I137 @BASEBOARD_FAB2_LIB.BASEBOARD_FAB2(SCH_1):PAGE181

FM_MB_SLOT_ID0 @BASEBOARD_FAB2_LIB.BASEBOARD_FAB2(SCH_1):FM_MB_SLOT_ID0
  U7C1   T4 GPP_A13_SUSWARN_N_SUSPWRDNACK LBG_CORE_QAT_EXT_D_BGA1-IC,H91A   I115 @BASEBOARD_FAB2_LIB.BASEBOARD_FAB2(SCH_1):PAGE119
  R7D5    2      B RES_0402-2.26K,1.0%,1/16W,CHIPA    I82 @BASEBOARD_FAB2_LIB.BASEBOARD_FAB2(SCH_1):PAGE181
  J1F1   F5 MB_SLOT_ID0 DM-FCI-CONN76-8R-GP-U-01_CONN-A   I134 @BASEBOARD_FAB2_LIB.BASEBOARD_FAB2(SCH_1):PAGE181
 U6W11    4     P0 PCA9554PWR-GP_DISCRET-G1-PCA95A    I97 @BASEBOARD_FAB2_LIB.BASEBOARD_FAB2(SCH_1):PAGE164

FM_MB_SLOT_ID1 @BASEBOARD_FAB2_LIB.BASEBOARD_FAB2(SCH_1):FM_MB_SLOT_ID1
  U7C1  AB3 GPP_A14_ESPI_RESET_N LBG_CORE_QAT_EXT_D_BGA1-IC,H91A   I115 @BASEBOARD_FAB2_LIB.BASEBOARD_FAB2(SCH_1):PAGE119
  R7D9    2      B RES_0402-2.26K,1.0%,1/16W,CHIPA    I80 @BASEBOARD_FAB2_LIB.BASEBOARD_FAB2(SCH_1):PAGE181
  J1F1   G5 MB_SLOT_ID1 DM-FCI-CONN76-8R-GP-U-01_CONN-A   I134 @BASEBOARD_FAB2_LIB.BASEBOARD_FAB2(SCH_1):PAGE181
 U6W11    5     P1 PCA9554PWR-GP_DISCRET-G1-PCA95A    I97 @BASEBOARD_FAB2_LIB.BASEBOARD_FAB2(SCH_1):PAGE164

FM_MB_SLOT_ID2 @BASEBOARD_FAB2_LIB.BASEBOARD_FAB2(SCH_1):FM_MB_SLOT_ID2
  U7C1  AC4 GPP_A15_SUSACK_N LBG_CORE_QAT_EXT_D_BGA1-IC,H91A   I115 @BASEBOARD_FAB2_LIB.BASEBOARD_FAB2(SCH_1):PAGE119
 R3P61    2      B RES_0402-2.26K,1.0%,1/16W,CHIPA    I81 @BASEBOARD_FAB2_LIB.BASEBOARD_FAB2(SCH_1):PAGE181
  J1F1   H5 MB_SLOT_ID2 DM-FCI-CONN76-8R-GP-U-01_CONN-A   I134 @BASEBOARD_FAB2_LIB.BASEBOARD_FAB2(SCH_1):PAGE181
 U6W11    6     P2 PCA9554PWR-GP_DISCRET-G1-PCA95A    I97 @BASEBOARD_FAB2_LIB.BASEBOARD_FAB2(SCH_1):PAGE164

FM_MEM_EVENT_FUNC @BASEBOARD_FAB2_LIB.BASEBOARD_FAB2(SCH_1):FM_MEM_EVENT_FUNC
  U8D7   D2   PL2D LCMXO2_A_256BGA-IC,H63395-001   I179 @BASEBOARD_FAB2_LIB.BASEBOARD_FAB2(SCH_1):PAGE190
 R7E19    2      B RES_0402-1.00K,1%,1/16W,EMPTY,A    I57 @BASEBOARD_FAB2_LIB.BASEBOARD_FAB2(SCH_1):PAGE192
 R7E20    1      A RES_0402-1.00K,1%,1/16W,CHIP,GA    I59 @BASEBOARD_FAB2_LIB.BASEBOARD_FAB2(SCH_1):PAGE192

FM_MEM_THERM_EVENT_LVT3_N @BASEBOARD_FAB2_LIB.BASEBOARD_FAB2(SCH_1):FM_MEM_THERM_EVENT_LVT3_N
  R4U1    2      B RES_0402-4.75K,1%,1/16W,CHIP,GA    I91 @BASEBOARD_FAB2_LIB.BASEBOARD_FAB2(SCH_1):PAGE94
  Q4U1    3 DRAIN<0> FET_N_DUAL_SMLF-NTJD4001N,FET,A   I102 @BASEBOARD_FAB2_LIB.BASEBOARD_FAB2(SCH_1):PAGE94
 R8E11    1      A RES_0402-0.0,5%,1/16W,EMPTY,G2A   I279 @BASEBOARD_FAB2_LIB.BASEBOARD_FAB2(SCH_1):PAGE156
  U8D7  K13  PR11C LCMXO2_A_256BGA-IC,H63395-001    I59 @BASEBOARD_FAB2_LIB.BASEBOARD_FAB2(SCH_1):PAGE191

FM_MEM_THERM_EVENT_PCH_N @BASEBOARD_FAB2_LIB.BASEBOARD_FAB2(SCH_1):FM_MEM_THERM_EVENT_PCH_N
  U7C1 AL15 GPP_F18_USB2_OC7_N LBG_CORE_QAT_EXT_D_BGA1-IC,H91A   I147 @BASEBOARD_FAB2_LIB.BASEBOARD_FAB2(SCH_1):PAGE120
  U8D7  K12  PR11D LCMXO2_A_256BGA-IC,H63395-001    I59 @BASEBOARD_FAB2_LIB.BASEBOARD_FAB2(SCH_1):PAGE191
 U25W4   P4 GPIOL4_NDTR1_VPIVS AST2520A1-GP-GP_ASIC2-GB1-AST2A   I117 @BASEBOARD_FAB2_LIB.BASEBOARD_FAB2(SCH_1):PAGE145

FM_MEZZA_PRSNT1_N @BASEBOARD_FAB2_LIB.BASEBOARD_FAB2(SCH_1):FM_MEZZA_PRSNT1_N
  J9B3    1    IO1 SCONN120_A28699018_SM-SCONN,A2A   I336 @BASEBOARD_FAB2_LIB.BASEBOARD_FAB2(SCH_1):PAGE186
  R9W1    2      B RES_0402-10.0K,1%,1/16W,CHIP,GA   I356 @BASEBOARD_FAB2_LIB.BASEBOARD_FAB2(SCH_1):PAGE186
  R9B7    1      1 887R2F-L-GP_SMD-RG-887R2F-L-GPA   I358 @BASEBOARD_FAB2_LIB.BASEBOARD_FAB2(SCH_1):PAGE186

FM_MEZZB_PRSNT1_N @BASEBOARD_FAB2_LIB.BASEBOARD_FAB2(SCH_1):FM_MEZZB_PRSNT1_N
  J8E3    1    IO1 SCONN80_E67482007_SM-CONN,E674A   I119 @BASEBOARD_FAB2_LIB.BASEBOARD_FAB2(SCH_1):PAGE187
  R2W1    2      B RES_0402-10.0K,1%,1/16W,CHIP,GA   I174 @BASEBOARD_FAB2_LIB.BASEBOARD_FAB2(SCH_1):PAGE187
  R2R8    1      1 887R2F-L-GP_SMD-RG-887R2F-L-GPA   I175 @BASEBOARD_FAB2_LIB.BASEBOARD_FAB2(SCH_1):PAGE187

FM_ME_RECOVER_N @BASEBOARD_FAB2_LIB.BASEBOARD_FAB2(SCH_1):FM_ME_RECOVER_N
  U7C1   V3 GPP_A19 LBG_CORE_QAT_EXT_D_BGA1-IC,H91A   I115 @BASEBOARD_FAB2_LIB.BASEBOARD_FAB2(SCH_1):PAGE119
 R7G26    2      B RES_0402-10.0K,1%,1/16W,CHIP,GA   I101 @BASEBOARD_FAB2_LIB.BASEBOARD_FAB2(SCH_1):PAGE136
  J7G3    3    IO3 CONN12_C73564003_PIP-CONN,C735A   I174 @BASEBOARD_FAB2_LIB.BASEBOARD_FAB2(SCH_1):PAGE136

FM_MODPRST_HFI0_CPU0_LVT2_N @BASEBOARD_FAB2_LIB.BASEBOARD_FAB2(SCH_1):FM_MODPRST_HFI0_CPU0_LVT2_N
  U5D1 BR20 CD_HFI0_MODPRST_N SKX_EXT_B_BGA1-IC,TBD    I61 @BASEBOARD_FAB2_LIB.BASEBOARD_FAB2(SCH_1):PAGE29
  J8B1    3    IO3 SCONN24_H46321001_SM-SCONN,H46A     I1 @BASEBOARD_FAB2_LIB.BASEBOARD_FAB2(SCH_1):PAGE91
  R8B3    2      B RES_0402-4.75K,1%,1/16W,CHIP,GA    I24 @BASEBOARD_FAB2_LIB.BASEBOARD_FAB2(SCH_1):PAGE91

FM_MODPRST_HFI1_CPU0_LVT2_N @BASEBOARD_FAB2_LIB.BASEBOARD_FAB2(SCH_1):FM_MODPRST_HFI1_CPU0_LVT2_N
  U5D1 BT19 CD_HFI1_MODPRST_N SKX_EXT_B_BGA1-IC,TBD    I61 @BASEBOARD_FAB2_LIB.BASEBOARD_FAB2(SCH_1):PAGE29
  J8B1   11   IO11 SCONN24_H46321001_SM-SCONN,H46A     I1 @BASEBOARD_FAB2_LIB.BASEBOARD_FAB2(SCH_1):PAGE91
 R8B19    2      B RES_0402-4.75K,1%,1/16W,CHIP,GA    I21 @BASEBOARD_FAB2_LIB.BASEBOARD_FAB2(SCH_1):PAGE91

FM_MP_PS_FAIL_N @BASEBOARD_FAB2_LIB.BASEBOARD_FAB2(SCH_1):FM_MP_PS_FAIL_N
  U7C1 AK20 GPP_F2_SATAXPCIE5_SATAGP5 LBG_CORE_QAT_EXT_D_BGA1-IC,H91A   I147 @BASEBOARD_FAB2_LIB.BASEBOARD_FAB2(SCH_1):PAGE120
 R3N12    2      B RES_0402-4.75K,1%,1/16W,CHIP,GA   I342 @BASEBOARD_FAB2_LIB.BASEBOARD_FAB2(SCH_1):PAGE157
  U8D7   H4   PL6C LCMXO2_A_256BGA-IC,H63395-001   I179 @BASEBOARD_FAB2_LIB.BASEBOARD_FAB2(SCH_1):PAGE190
 U25W4  L18 GPIOB2 AST2520A1-GP-GP_ASIC2-GB1-AST2A    I95 @BASEBOARD_FAB2_LIB.BASEBOARD_FAB2(SCH_1):PAGE144
  J1F3    3    IO3 CONN8_H62179001_PIP-CONN,H6217A   I106 @BASEBOARD_FAB2_LIB.BASEBOARD_FAB2(SCH_1):PAGE181

FM_MP_PS_REDUNDANT_LOST_N @BASEBOARD_FAB2_LIB.BASEBOARD_FAB2(SCH_1):FM_MP_PS_REDUNDANT_LOST_N
  U7C1 AK13 GPP_F3_SATAXPCIE6_SATAGP6 LBG_CORE_QAT_EXT_D_BGA1-IC,H91A   I147 @BASEBOARD_FAB2_LIB.BASEBOARD_FAB2(SCH_1):PAGE120
 R3N11    2      B RES_0402-4.75K,1%,1/16W,CHIP,GA   I344 @BASEBOARD_FAB2_LIB.BASEBOARD_FAB2(SCH_1):PAGE157
 U25W4  T19 GPIOR1_FWSPICS2# AST2520A1-GP-GP_ASIC2-GB1-AST2A   I105 @BASEBOARD_FAB2_LIB.BASEBOARD_FAB2(SCH_1):PAGE146
  J1F3    2    IO2 CONN8_H62179001_PIP-CONN,H6217A   I106 @BASEBOARD_FAB2_LIB.BASEBOARD_FAB2(SCH_1):PAGE181

FM_NMI_EVENT_N @BASEBOARD_FAB2_LIB.BASEBOARD_FAB2(SCH_1):FM_NMI_EVENT_N
  U7C1  BE7 GPP_G18_NMI_N LBG_CORE_QAT_EXT_D_BGA1-IC,H91A   I147 @BASEBOARD_FAB2_LIB.BASEBOARD_FAB2(SCH_1):PAGE120
 R2N25    1      A RES_0402-51.1,1.0%,1/16W,CHIP,A   I302 @BASEBOARD_FAB2_LIB.BASEBOARD_FAB2(SCH_1):PAGE157

FM_OC0_USB_N @BASEBOARD_FAB2_LIB.BASEBOARD_FAB2(SCH_1):FM_OC0_USB_N
  U7C1 BL48 GPP_E9_USB2_OC0_N LBG_CORE_QAT_EXT_D_BGA1-IC,H91A   I147 @BASEBOARD_FAB2_LIB.BASEBOARD_FAB2(SCH_1):PAGE120
  U1M3    3   OC_N TPS2061_SM-IC,H66405-001   I100 @BASEBOARD_FAB2_LIB.BASEBOARD_FAB2(SCH_1):PAGE176
 R1M24    2      B RES_0402-10.0K,1%,1/16W,CHIP,GA   I105 @BASEBOARD_FAB2_LIB.BASEBOARD_FAB2(SCH_1):PAGE176
  U8D7   L7   PB8D LCMXO2_A_256BGA-IC,H63395-001   I179 @BASEBOARD_FAB2_LIB.BASEBOARD_FAB2(SCH_1):PAGE190

FM_OCP_MEZZA_PRES @BASEBOARD_FAB2_LIB.BASEBOARD_FAB2(SCH_1):FM_OCP_MEZZA_PRES
 R7D12    2      B RES_0402-10.0K,1%,1/16W,CHIP,GA   I237 @BASEBOARD_FAB2_LIB.BASEBOARD_FAB2(SCH_1):PAGE133
 U25W4  T21 GPIOAB1_VPOHS_NORWE# AST2520A1-GP-GP_ASIC2-GB1-AST2A   I105 @BASEBOARD_FAB2_LIB.BASEBOARD_FAB2(SCH_1):PAGE146
  Q1W1    3    DRN FET_N_SOT23LF-2N7002,FET,C7925A    I29 @BASEBOARD_FAB2_LIB.BASEBOARD_FAB2(SCH_1):PAGE250
 R7W15    1      A RES_0402-0.0,5%,1/16W,CHIP,G21A   I227 @BASEBOARD_FAB2_LIB.BASEBOARD_FAB2(SCH_1):PAGE119

FM_OCP_MEZZA_PRES_N @BASEBOARD_FAB2_LIB.BASEBOARD_FAB2(SCH_1):FM_OCP_MEZZA_PRES_N
  J9B3  120  IO120 SCONN120_A28699018_SM-SCONN,A2A   I336 @BASEBOARD_FAB2_LIB.BASEBOARD_FAB2(SCH_1):PAGE186
  R1W1    2      2 1MR2F-L-GP_SMD-RG1-1MR2F-L-GP,A    I18 @BASEBOARD_FAB2_LIB.BASEBOARD_FAB2(SCH_1):PAGE250
  Q1W1    1   GATE FET_N_SOT23LF-2N7002,FET,C7925A    I29 @BASEBOARD_FAB2_LIB.BASEBOARD_FAB2(SCH_1):PAGE250

FM_OCP_MEZZA_PRES_R @BASEBOARD_FAB2_LIB.BASEBOARD_FAB2(SCH_1):FM_OCP_MEZZA_PRES_R
  U7C1  AE2 GPP_A21 LBG_CORE_QAT_EXT_D_BGA1-IC,H91A   I115 @BASEBOARD_FAB2_LIB.BASEBOARD_FAB2(SCH_1):PAGE119
 R7W15    2      B RES_0402-0.0,5%,1/16W,CHIP,G21A   I227 @BASEBOARD_FAB2_LIB.BASEBOARD_FAB2(SCH_1):PAGE119

FM_OCP_MEZZB_PRES_1V05_PCH_N @BASEBOARD_FAB2_LIB.BASEBOARD_FAB2(SCH_1):FM_OCP_MEZZB_PRES_1V05_PCH_N
  U7C1  AD9 GPP_L8_TESTCH0_D6 LBG_CORE_QAT_EXT_D_BGA1-IC,H91A    I34 @BASEBOARD_FAB2_LIB.BASEBOARD_FAB2(SCH_1):PAGE121
 R7D44    2      B RES_0402-4.75K,1%,1/16W,CHIP,GA   I356 @BASEBOARD_FAB2_LIB.BASEBOARD_FAB2(SCH_1):PAGE133
  Q1W2    3 DRAIN<0> FET_N_DUAL_SMLF-2N7002DW,FET,DA    I12 @BASEBOARD_FAB2_LIB.BASEBOARD_FAB2(SCH_1):PAGE250

FM_OCP_MEZZB_PRES_LVT3_BMC @BASEBOARD_FAB2_LIB.BASEBOARD_FAB2(SCH_1):FM_OCP_MEZZB_PRES_LVT3_BMC
 U25W4  H19 GPIOF5_NRTS4_LHFRAME# AST2520A1-GP-GP_ASIC2-GB1-AST2A   I117 @BASEBOARD_FAB2_LIB.BASEBOARD_FAB2(SCH_1):PAGE145
  Q1W2    5 GATE<0> FET_N_DUAL_SMLF-2N7002DW,FET,DA    I12 @BASEBOARD_FAB2_LIB.BASEBOARD_FAB2(SCH_1):PAGE250
  R1W4    1      A RES_0402-10.0K,1%,1/16W,CHIP,GA    I22 @BASEBOARD_FAB2_LIB.BASEBOARD_FAB2(SCH_1):PAGE250
  Q1W2    6 DRAIN<0> FET_N_DUAL_SMLF-2N7002DW,FET,DA    I24 @BASEBOARD_FAB2_LIB.BASEBOARD_FAB2(SCH_1):PAGE250

FM_OCP_MEZZB_PRES_N @BASEBOARD_FAB2_LIB.BASEBOARD_FAB2(SCH_1):FM_OCP_MEZZB_PRES_N
  J8E3   80   IO80 SCONN80_E67482007_SM-CONN,E674A   I119 @BASEBOARD_FAB2_LIB.BASEBOARD_FAB2(SCH_1):PAGE187
  Q1W2    2 GATE<0> FET_N_DUAL_SMLF-2N7002DW,FET,DA    I24 @BASEBOARD_FAB2_LIB.BASEBOARD_FAB2(SCH_1):PAGE250
  R1W3    2      2 1MR2F-L-GP_SMD-RG1-1MR2F-L-GP,A    I27 @BASEBOARD_FAB2_LIB.BASEBOARD_FAB2(SCH_1):PAGE250

FM_OCP_MEZZC_PRES_1V05_PCH_N @BASEBOARD_FAB2_LIB.BASEBOARD_FAB2(SCH_1):FM_OCP_MEZZC_PRES_1V05_PCH_N
  U7C1 AD17 GPP_L9_TESTCH0_D7 LBG_CORE_QAT_EXT_D_BGA1-IC,H91A    I34 @BASEBOARD_FAB2_LIB.BASEBOARD_FAB2(SCH_1):PAGE121
  Q1W4    3 DRAIN<0> FET_N_DUAL_SMLF-2N7002DW,FET,DA     I8 @BASEBOARD_FAB2_LIB.BASEBOARD_FAB2(SCH_1):PAGE250
 R3P53    2      B RES_0402-4.75K,1%,1/16W,CHIP,GA   I365 @BASEBOARD_FAB2_LIB.BASEBOARD_FAB2(SCH_1):PAGE133

FM_OCP_MEZZC_PRES_LVT3_BMC @BASEBOARD_FAB2_LIB.BASEBOARD_FAB2(SCH_1):FM_OCP_MEZZC_PRES_LVT3_BMC
 U25W4  H18 GPIOF7_RXD4_LHRST# AST2520A1-GP-GP_ASIC2-GB1-AST2A   I117 @BASEBOARD_FAB2_LIB.BASEBOARD_FAB2(SCH_1):PAGE145
  Q1W4    6 DRAIN<0> FET_N_DUAL_SMLF-2N7002DW,FET,DA     I3 @BASEBOARD_FAB2_LIB.BASEBOARD_FAB2(SCH_1):PAGE250
  R1W7    1      A RES_0402-10.0K,1%,1/16W,CHIP,GA     I6 @BASEBOARD_FAB2_LIB.BASEBOARD_FAB2(SCH_1):PAGE250
  Q1W4    5 GATE<0> FET_N_DUAL_SMLF-2N7002DW,FET,DA     I8 @BASEBOARD_FAB2_LIB.BASEBOARD_FAB2(SCH_1):PAGE250

FM_OCP_MEZZC_PRES_N @BASEBOARD_FAB2_LIB.BASEBOARD_FAB2(SCH_1):FM_OCP_MEZZC_PRES_N
  J8E4   64   IO64 SCONN64_H87568002_A_SMT-CONN,HA    I27 @BASEBOARD_FAB2_LIB.BASEBOARD_FAB2(SCH_1):PAGE188
  R1W6    2      2 1MR2F-L-GP_SMD-RG1-1MR2F-L-GP,A     I2 @BASEBOARD_FAB2_LIB.BASEBOARD_FAB2(SCH_1):PAGE250
  Q1W4    2 GATE<0> FET_N_DUAL_SMLF-2N7002DW,FET,DA     I3 @BASEBOARD_FAB2_LIB.BASEBOARD_FAB2(SCH_1):PAGE250

FM_OC_DETECT_EN @BASEBOARD_FAB2_LIB.BASEBOARD_FAB2(SCH_1):FM_OC_DETECT_EN
  U1D1    1     OE TTL1G126_A_SOT-74HC1G126,IC,A7B   I103 @BASEBOARD_FAB2_LIB.BASEBOARD_FAB2(SCH_1):PAGE200
  Q1D2    3    DRN FET_N_SOT23LF-2N7002,FET,C7925A   I203 @BASEBOARD_FAB2_LIB.BASEBOARD_FAB2(SCH_1):PAGE200
 R1D21    2      B RES_0402-4.75K,1%,1/16W,CHIP,GA   I204 @BASEBOARD_FAB2_LIB.BASEBOARD_FAB2(SCH_1):PAGE200

FM_OC_DETECT_EN_N @BASEBOARD_FAB2_LIB.BASEBOARD_FAB2(SCH_1):FM_OC_DETECT_EN_N
  U7C1  BC4 GPP_H18_SML4ALERT_N_IE_N LBG_CORE_QAT_EXT_D_BGA1-IC,H91A   I147 @BASEBOARD_FAB2_LIB.BASEBOARD_FAB2(SCH_1):PAGE120
 R7D19    1      A RES_0402-1.00K,1%,1/16W,EMPTY,A     I6 @BASEBOARD_FAB2_LIB.BASEBOARD_FAB2(SCH_1):PAGE126
 R1D35    2      B RES_0402-4.75K,1%,1/16W,CHIP,GA    I12 @BASEBOARD_FAB2_LIB.BASEBOARD_FAB2(SCH_1):PAGE126
  Q1D2    1   GATE FET_N_SOT23LF-2N7002,FET,C7925A   I203 @BASEBOARD_FAB2_LIB.BASEBOARD_FAB2(SCH_1):PAGE200
 U25W4   Y2 GPIOM3_NRI2_VPIB5 AST2520A1-GP-GP_ASIC2-GB1-AST2A   I117 @BASEBOARD_FAB2_LIB.BASEBOARD_FAB2(SCH_1):PAGE145

FM_OC_DETECT_N @BASEBOARD_FAB2_LIB.BASEBOARD_FAB2(SCH_1):FM_OC_DETECT_N
  U8E1    2   B<0> TTL08_QFN15-74LVC08A,IC,D90404B    I10 @BASEBOARD_FAB2_LIB.BASEBOARD_FAB2(SCH_1):PAGE170
  U1D1    4      Y TTL1G126_A_SOT-74HC1G126,IC,A7B   I103 @BASEBOARD_FAB2_LIB.BASEBOARD_FAB2(SCH_1):PAGE200
 R1D22    2      B RES_0402-10.0K,1%,1/16W,CHIP,GA   I158 @BASEBOARD_FAB2_LIB.BASEBOARD_FAB2(SCH_1):PAGE200

FM_P12V_HOTSWAP0_EN @BASEBOARD_FAB2_LIB.BASEBOARD_FAB2(SCH_1):FM_P12V_HOTSWAP0_EN
 EU1D2   12 ENABLE ADM1278_SM-IC,G99251-001    I10 @BASEBOARD_FAB2_LIB.BASEBOARD_FAB2(SCH_1):PAGE199
 C1D11    1      A CAP_A_0402V-0.1UF,16V,10%,X7R,A    I53 @BASEBOARD_FAB2_LIB.BASEBOARD_FAB2(SCH_1):PAGE199
  Q9T1    3      C NPN_SM-MMBT3904,IC,C52245-001    I42 @BASEBOARD_FAB2_LIB.BASEBOARD_FAB2(SCH_1):PAGE181
  R9T3    1      A RES_0402-6.19K,1%,1/16W,CHIP,GA    I64 @BASEBOARD_FAB2_LIB.BASEBOARD_FAB2(SCH_1):PAGE181
  R9T6    2      B RES_0402-15.0K,1%,1/16W,CHIP,GA    I68 @BASEBOARD_FAB2_LIB.BASEBOARD_FAB2(SCH_1):PAGE181

FM_P12V_HSC_ADR1 @BASEBOARD_FAB2_LIB.BASEBOARD_FAB2(SCH_1):FM_P12V_HSC_ADR1
 EU1D2    7   ADR1 ADM1278_SM-IC,G99251-001    I10 @BASEBOARD_FAB2_LIB.BASEBOARD_FAB2(SCH_1):PAGE199
 R9P17    1      A RES_0402-150.0K,1%,1/16W,CHIP,A    I33 @BASEBOARD_FAB2_LIB.BASEBOARD_FAB2(SCH_1):PAGE199
 R1D29    2      B RES_0402-4.75K,1%,1/16W,CHIP,GA   I137 @BASEBOARD_FAB2_LIB.BASEBOARD_FAB2(SCH_1):PAGE199

FM_P12V_HSC_ADR2 @BASEBOARD_FAB2_LIB.BASEBOARD_FAB2(SCH_1):FM_P12V_HSC_ADR2
 EU1D2    8   ADR2 ADM1278_SM-IC,G99251-001    I10 @BASEBOARD_FAB2_LIB.BASEBOARD_FAB2(SCH_1):PAGE199
 R9P16    1      A RES_0402-0.0,5%,1/16W,CHIP,G21A    I36 @BASEBOARD_FAB2_LIB.BASEBOARD_FAB2(SCH_1):PAGE199
 R1D27    2      B RES_0402-4.75K,1%,1/16W,EMPTY,A    I38 @BASEBOARD_FAB2_LIB.BASEBOARD_FAB2(SCH_1):PAGE199

FM_P12V_MAIN_SW_EN @BASEBOARD_FAB2_LIB.BASEBOARD_FAB2(SCH_1):FM_P12V_MAIN_SW_EN
  U8D7  R16  PR14D LCMXO2_A_256BGA-IC,H63395-001    I59 @BASEBOARD_FAB2_LIB.BASEBOARD_FAB2(SCH_1):PAGE191
 EU7E1    2     ON SLG55021_SM-IC,G56246-001    I19 @BASEBOARD_FAB2_LIB.BASEBOARD_FAB2(SCH_1):PAGE198

FM_P1V8MCP_CPU0_EN @BASEBOARD_FAB2_LIB.BASEBOARD_FAB2(SCH_1):FM_P1V8MCP_CPU0_EN
  U8D7  E16   PR3A LCMXO2_A_256BGA-IC,H63395-001    I59 @BASEBOARD_FAB2_LIB.BASEBOARD_FAB2(SCH_1):PAGE191
  J6B1  A15  IOA15 SCONN120_H61426002_SM-CONN,H61A    I56 @BASEBOARD_FAB2_LIB.BASEBOARD_FAB2(SCH_1):PAGE194

FM_P1V8MCP_CPU1_EN @BASEBOARD_FAB2_LIB.BASEBOARD_FAB2(SCH_1):FM_P1V8MCP_CPU1_EN
  U8D7  F12   PR4C LCMXO2_A_256BGA-IC,H63395-001    I59 @BASEBOARD_FAB2_LIB.BASEBOARD_FAB2(SCH_1):PAGE191
  J4B2  A15  IOA15 SCONN120_H61426002_SM-CONN,H61A    I46 @BASEBOARD_FAB2_LIB.BASEBOARD_FAB2(SCH_1):PAGE193

FM_P3V3_CPLD_EN @BASEBOARD_FAB2_LIB.BASEBOARD_FAB2(SCH_1):FM_P3V3_CPLD_EN
  U8D7   A4  PT10A LCMXO2_A_256BGA-IC,H63395-001    I59 @BASEBOARD_FAB2_LIB.BASEBOARD_FAB2(SCH_1):PAGE191
 EU2T1    2     ON SLG55021_SM-IC,G56246-001     I1 @BASEBOARD_FAB2_LIB.BASEBOARD_FAB2(SCH_1):PAGE198

FM_PASSWORD_CLEAR_N @BASEBOARD_FAB2_LIB.BASEBOARD_FAB2(SCH_1):FM_PASSWORD_CLEAR_N
  U7C1 BW32 GPP_C8 LBG_CORE_QAT_EXT_D_BGA1-IC,H91A   I115 @BASEBOARD_FAB2_LIB.BASEBOARD_FAB2(SCH_1):PAGE119
 R2N28    2      B RES_0402-10.0K,1%,1/16W,CHIP,GA   I147 @BASEBOARD_FAB2_LIB.BASEBOARD_FAB2(SCH_1):PAGE136
  J7G3    9    IO9 CONN12_C73564003_PIP-CONN,C735A   I174 @BASEBOARD_FAB2_LIB.BASEBOARD_FAB2(SCH_1):PAGE136

FM_PCH_BMC_THERMTRIP_EXI_STRAP_ @BASEBOARD_FAB2_LIB.BASEBOARD_FAB2(SCH_1):FM_PCH_BMC_THERMTRIP_EXI_STRAP_N
  U7C1 BM20 GPP_B23_MEIE_SML1ALRT_N_PHOT_N LBG_CORE_QAT_EXT_D_BGA1-IC,H91A   I115 @BASEBOARD_FAB2_LIB.BASEBOARD_FAB2(SCH_1):PAGE119
  Q8D2    2    SRC FET_N_SOT23LF-2N7002,FET,C7925A    I15 @BASEBOARD_FAB2_LIB.BASEBOARD_FAB2(SCH_1):PAGE134
 R2N10    2      B RES_0402-4.75K,1%,1/16W,EMPTY,A    I27 @BASEBOARD_FAB2_LIB.BASEBOARD_FAB2(SCH_1):PAGE126

FM_PCH_BMC_THERMTRIP_N @BASEBOARD_FAB2_LIB.BASEBOARD_FAB2(SCH_1):FM_PCH_BMC_THERMTRIP_N
  U7C1  BH2 GPP_H22_SSATAXPCIE4_SSATAGP4 LBG_CORE_QAT_EXT_D_BGA1-IC,H91A   I147 @BASEBOARD_FAB2_LIB.BASEBOARD_FAB2(SCH_1):PAGE120
 R2P17    2      B RES_0402-4.75K,1%,1/16W,CHIP,GA     I3 @BASEBOARD_FAB2_LIB.BASEBOARD_FAB2(SCH_1):PAGE134
 U25W4  C19 GPIOG2_SGPS1I0 AST2520A1-GP-GP_ASIC2-GB1-AST2A    I95 @BASEBOARD_FAB2_LIB.BASEBOARD_FAB2(SCH_1):PAGE144
  Q8D2    3    DRN FET_N_SOT23LF-2N7002,FET,C7925A    I15 @BASEBOARD_FAB2_LIB.BASEBOARD_FAB2(SCH_1):PAGE134

FM_PCH_LVC1_THERMTRIP_N @BASEBOARD_FAB2_LIB.BASEBOARD_FAB2(SCH_1):FM_PCH_LVC1_THERMTRIP_N
  U7C1  V15 THRMTRIP_N LBG_CORE_QAT_EXT_D_BGA1-IC,H91A    I73 @BASEBOARD_FAB2_LIB.BASEBOARD_FAB2(SCH_1):PAGE118
 R7C21    2      B RES_0402-10.0K,1%,1/16W,CHIP,GA     I9 @BASEBOARD_FAB2_LIB.BASEBOARD_FAB2(SCH_1):PAGE134
  Q7D1    3    DRN FET_N_SOT23LF-2N7002,FET,C7925A    I14 @BASEBOARD_FAB2_LIB.BASEBOARD_FAB2(SCH_1):PAGE134

FM_PCH_PLD_DATA @BASEBOARD_FAB2_LIB.BASEBOARD_FAB2(SCH_1):FM_PCH_PLD_DATA
  R2M3    2      B RES_0402-33.2,1%,1/16W,CHIP,G2A   I172 @BASEBOARD_FAB2_LIB.BASEBOARD_FAB2(SCH_1):PAGE119
  R2R5    2      B RES_0402-1.00K,1%,1/16W,CHIP,GA   I258 @BASEBOARD_FAB2_LIB.BASEBOARD_FAB2(SCH_1):PAGE133
  U8D7   C2   PL1D LCMXO2_A_256BGA-IC,H63395-001   I179 @BASEBOARD_FAB2_LIB.BASEBOARD_FAB2(SCH_1):PAGE190

FM_PCH_PLD_DATA_R @BASEBOARD_FAB2_LIB.BASEBOARD_FAB2(SCH_1):FM_PCH_PLD_DATA_R
  U7C1 BM42 GPP_D4 LBG_CORE_QAT_EXT_D_BGA1-IC,H91A   I115 @BASEBOARD_FAB2_LIB.BASEBOARD_FAB2(SCH_1):PAGE119
  R2M3    1      A RES_0402-33.2,1%,1/16W,CHIP,G2A   I172 @BASEBOARD_FAB2_LIB.BASEBOARD_FAB2(SCH_1):PAGE119

FM_PCH_PRSNT_N @BASEBOARD_FAB2_LIB.BASEBOARD_FAB2(SCH_1):FM_PCH_PRSNT_N
  U7C1  C70 CGC_DUT_DETECT_N LBG_CORE_QAT_EXT_D_BGA1-IC,H91A    I34 @BASEBOARD_FAB2_LIB.BASEBOARD_FAB2(SCH_1):PAGE121
  R7B6    2      B RES_0402-10.0K,1%,1/16W,CHIP,GA   I295 @BASEBOARD_FAB2_LIB.BASEBOARD_FAB2(SCH_1):PAGE133
  U8D7   A3  PT11C LCMXO2_A_256BGA-IC,H63395-001    I59 @BASEBOARD_FAB2_LIB.BASEBOARD_FAB2(SCH_1):PAGE191

FM_PCH_PWRBTN_N @BASEBOARD_FAB2_LIB.BASEBOARD_FAB2(SCH_1):FM_PCH_PWRBTN_N
  U7C1  C15 GPD3_PWRBTN_N LBG_CORE_QAT_EXT_D_BGA1-IC,H91A    I73 @BASEBOARD_FAB2_LIB.BASEBOARD_FAB2(SCH_1):PAGE118
 R2T28    2      B RES_0402-33.2,1%,1/16W,CHIP,G2A   I289 @BASEBOARD_FAB2_LIB.BASEBOARD_FAB2(SCH_1):PAGE156
 R1W28    2      B RES_0402-0.0,5%,1/16W,CHIP,G21A   I197 @BASEBOARD_FAB2_LIB.BASEBOARD_FAB2(SCH_1):PAGE191

FM_PCH_PWRBTN_OUT_N @BASEBOARD_FAB2_LIB.BASEBOARD_FAB2(SCH_1):FM_PCH_PWRBTN_OUT_N
  U7C1 BG15 GPP_B17 LBG_CORE_QAT_EXT_D_BGA1-IC,H91A   I115 @BASEBOARD_FAB2_LIB.BASEBOARD_FAB2(SCH_1):PAGE119
  R8G2    2      B RES_0402-4.75K,1%,1/16W,CHIP,GA   I267 @BASEBOARD_FAB2_LIB.BASEBOARD_FAB2(SCH_1):PAGE156
  U8G1    3     2A SN74LVC2G07DCKR-GP_DISCRET-G4-A   I342 @BASEBOARD_FAB2_LIB.BASEBOARD_FAB2(SCH_1):PAGE156

FM_PCH_PWRBTN_R1_N @BASEBOARD_FAB2_LIB.BASEBOARD_FAB2(SCH_1):FM_PCH_PWRBTN_R1_N
  U8D7  B12  PT23B LCMXO2_A_256BGA-IC,H63395-001    I59 @BASEBOARD_FAB2_LIB.BASEBOARD_FAB2(SCH_1):PAGE191
 R1W28    1      A RES_0402-0.0,5%,1/16W,CHIP,G21A   I197 @BASEBOARD_FAB2_LIB.BASEBOARD_FAB2(SCH_1):PAGE191

FM_PCH_PWRBTN_R_N @BASEBOARD_FAB2_LIB.BASEBOARD_FAB2(SCH_1):FM_PCH_PWRBTN_R_N
 R8F26    2      B RES_0402-10.0K,1%,1/16W,CHIP,GA   I211 @BASEBOARD_FAB2_LIB.BASEBOARD_FAB2(SCH_1):PAGE156
 R2T28    1      A RES_0402-33.2,1%,1/16W,CHIP,G2A   I289 @BASEBOARD_FAB2_LIB.BASEBOARD_FAB2(SCH_1):PAGE156
  U8F3    4     2Y SN74LVC2G07DCKR-GP_DISCRET-G4-A   I340 @BASEBOARD_FAB2_LIB.BASEBOARD_FAB2(SCH_1):PAGE156
  U8G1    4     2Y SN74LVC2G07DCKR-GP_DISCRET-G4-A   I342 @BASEBOARD_FAB2_LIB.BASEBOARD_FAB2(SCH_1):PAGE156

FM_PCH_SATA_RAID_KEY @BASEBOARD_FAB2_LIB.BASEBOARD_FAB2(SCH_1):FM_PCH_SATA_RAID_KEY
  U7C1 BV31 GPP_C10 LBG_CORE_QAT_EXT_D_BGA1-IC,H91A   I115 @BASEBOARD_FAB2_LIB.BASEBOARD_FAB2(SCH_1):PAGE119
 R9A13    2      B RES_0402-33.2,1%,1/16W,CHIP,G2A   I118 @BASEBOARD_FAB2_LIB.BASEBOARD_FAB2(SCH_1):PAGE135

FM_PCH_SATA_RAID_KEY_R @BASEBOARD_FAB2_LIB.BASEBOARD_FAB2(SCH_1):FM_PCH_SATA_RAID_KEY_R
 R9A12    1      A RES_0402-2.21K,1%,1/16W,CHIP,GA   I117 @BASEBOARD_FAB2_LIB.BASEBOARD_FAB2(SCH_1):PAGE135
 R9A13    1      A RES_0402-33.2,1%,1/16W,CHIP,G2A   I118 @BASEBOARD_FAB2_LIB.BASEBOARD_FAB2(SCH_1):PAGE135
  J9A1    4    IO4 CONN4_D42317002_PIP-CONN,D4231A   I131 @BASEBOARD_FAB2_LIB.BASEBOARD_FAB2(SCH_1):PAGE135

FM_PE_BMC_WAKE_N @BASEBOARD_FAB2_LIB.BASEBOARD_FAB2(SCH_1):FM_PE_BMC_WAKE_N
 R8E29    1      A RES_0402-0.0,5%,1/16W,EMPTY,G2A    I18 @BASEBOARD_FAB2_LIB.BASEBOARD_FAB2(SCH_1):PAGE142
R25W63    1      A RES_0402-100.0K,1%,1/16W,CHIP,A    I65 @BASEBOARD_FAB2_LIB.BASEBOARD_FAB2(SCH_1):PAGE146
 U25W4  N20 GPIOQ7_PEWAKE# AST2520A1-GP-GP_ASIC2-GB1-AST2A   I105 @BASEBOARD_FAB2_LIB.BASEBOARD_FAB2(SCH_1):PAGE146

FM_PE_M2_WAKE_N @BASEBOARD_FAB2_LIB.BASEBOARD_FAB2(SCH_1):FM_PE_M2_WAKE_N
 R8E27    1      A RES_0402-0.0,5%,1/16W,CHIP,G21A    I32 @BASEBOARD_FAB2_LIB.BASEBOARD_FAB2(SCH_1):PAGE142
  J8F1   54     54 SKT-MINI67P-41-GP_SOCKET-G4-SKA   I143 @BASEBOARD_FAB2_LIB.BASEBOARD_FAB2(SCH_1):PAGE185

FM_PE_OCP_WAKE_N @BASEBOARD_FAB2_LIB.BASEBOARD_FAB2(SCH_1):FM_PE_OCP_WAKE_N
 R8E26    1      A RES_0402-0.0,5%,1/16W,CHIP,G21A    I30 @BASEBOARD_FAB2_LIB.BASEBOARD_FAB2(SCH_1):PAGE142
  J9B3   34   IO34 SCONN120_A28699018_SM-SCONN,A2A   I336 @BASEBOARD_FAB2_LIB.BASEBOARD_FAB2(SCH_1):PAGE186

FM_PE_SLOTX24_WAKE_N @BASEBOARD_FAB2_LIB.BASEBOARD_FAB2(SCH_1):FM_PE_SLOTX24_WAKE_N
  J8G1   28   IO28 SCONN200_H68296001_SM-CONN,H68A   I258 @BASEBOARD_FAB2_LIB.BASEBOARD_FAB2(SCH_1):PAGE108
 R8E28    1      A RES_0402-0.0,5%,1/16W,CHIP,G21A    I31 @BASEBOARD_FAB2_LIB.BASEBOARD_FAB2(SCH_1):PAGE142
 R8E36    2      2 2K15R2F-1-GP_SMD-RG1-2K15R2F-1A    I34 @BASEBOARD_FAB2_LIB.BASEBOARD_FAB2(SCH_1):PAGE142

FM_PE_SPRV_WAKE_N @BASEBOARD_FAB2_LIB.BASEBOARD_FAB2(SCH_1):FM_PE_SPRV_WAKE_N
 EU9E1   16 PE_WAKE_N SPRINGVILLE_SM1-IC,G47144-004    I72 @BASEBOARD_FAB2_LIB.BASEBOARD_FAB2(SCH_1):PAGE139
 R8E21    1      A RES_0402-0.0,5%,1/16W,CHIP,G21A    I33 @BASEBOARD_FAB2_LIB.BASEBOARD_FAB2(SCH_1):PAGE142

FM_PLD_DEBUG_MODE_N @BASEBOARD_FAB2_LIB.BASEBOARD_FAB2(SCH_1):FM_PLD_DEBUG_MODE_N
  U8D7   F7  PT16A LCMXO2_A_256BGA-IC,H63395-001    I59 @BASEBOARD_FAB2_LIB.BASEBOARD_FAB2(SCH_1):PAGE191
  R2R3    2      B RES_0402-10.0K,1%,1/16W,CHIP,GA    I41 @BASEBOARD_FAB2_LIB.BASEBOARD_FAB2(SCH_1):PAGE192

FM_PMBUS_ALERT_BUF_EN @BASEBOARD_FAB2_LIB.BASEBOARD_FAB2(SCH_1):FM_PMBUS_ALERT_BUF_EN
  U8D5    1     OE TTL1G126_A_SOT-74HC1G126,IC,A7B    I38 @BASEBOARD_FAB2_LIB.BASEBOARD_FAB2(SCH_1):PAGE170
  R2P5    2      B RES_0402-4.75K,1%,1/16W,CHIP,GA    I56 @BASEBOARD_FAB2_LIB.BASEBOARD_FAB2(SCH_1):PAGE170
  Q2P1    3    DRN FET_N_SOT23LF-2N7002,FET,C7925A    I58 @BASEBOARD_FAB2_LIB.BASEBOARD_FAB2(SCH_1):PAGE170

FM_PMBUS_ALERT_BUF_EN_N @BASEBOARD_FAB2_LIB.BASEBOARD_FAB2(SCH_1):FM_PMBUS_ALERT_BUF_EN_N
  Q2P1    1   GATE FET_N_SOT23LF-2N7002,FET,C7925A    I58 @BASEBOARD_FAB2_LIB.BASEBOARD_FAB2(SCH_1):PAGE170
 R2P13    2      B RES_0402-4.75K,1%,1/16W,CHIP,GA    I61 @BASEBOARD_FAB2_LIB.BASEBOARD_FAB2(SCH_1):PAGE170
 R2P11    1      A RES_0402-1.00K,1%,1/16W,EMPTY,A    I63 @BASEBOARD_FAB2_LIB.BASEBOARD_FAB2(SCH_1):PAGE170
  R2W3    2      B RES_0402-0.0,5%,1/16W,CHIP,G21A   I223 @BASEBOARD_FAB2_LIB.BASEBOARD_FAB2(SCH_1):PAGE119
  R2W4    1      A RES_0402-0.0,5%,1/16W,CHIP,G21A   I224 @BASEBOARD_FAB2_LIB.BASEBOARD_FAB2(SCH_1):PAGE119
  R2W5    2      B RES_0402-0.0,5%,1/16W,CHIP,G21A   I176 @BASEBOARD_FAB2_LIB.BASEBOARD_FAB2(SCH_1):PAGE145

FM_PMBUS_ALERT_BUF_EN_R2_N @BASEBOARD_FAB2_LIB.BASEBOARD_FAB2(SCH_1):FM_PMBUS_ALERT_BUF_EN_R2_N
  U7C1  BK9 GPP_B11 LBG_CORE_QAT_EXT_D_BGA1-IC,H91A   I115 @BASEBOARD_FAB2_LIB.BASEBOARD_FAB2(SCH_1):PAGE119
  R2W4    2      B RES_0402-0.0,5%,1/16W,CHIP,G21A   I224 @BASEBOARD_FAB2_LIB.BASEBOARD_FAB2(SCH_1):PAGE119

FM_PMBUS_ALERT_BUF_EN_R3_N @BASEBOARD_FAB2_LIB.BASEBOARD_FAB2(SCH_1):FM_PMBUS_ALERT_BUF_EN_R3_N
 U25W4   P3 GPIOL5_NRTS1_VPICLK AST2520A1-GP-GP_ASIC2-GB1-AST2A   I117 @BASEBOARD_FAB2_LIB.BASEBOARD_FAB2(SCH_1):PAGE145
  R2W5    1      A RES_0402-0.0,5%,1/16W,CHIP,G21A   I176 @BASEBOARD_FAB2_LIB.BASEBOARD_FAB2(SCH_1):PAGE145

FM_PMBUS_ALERT_BUF_EN_R_N @BASEBOARD_FAB2_LIB.BASEBOARD_FAB2(SCH_1):FM_PMBUS_ALERT_BUF_EN_R_N
  U7C1 BY35 GPP_C18 LBG_CORE_QAT_EXT_D_BGA1-IC,H91A   I115 @BASEBOARD_FAB2_LIB.BASEBOARD_FAB2(SCH_1):PAGE119
  R2W3    1      A RES_0402-0.0,5%,1/16W,CHIP,G21A   I223 @BASEBOARD_FAB2_LIB.BASEBOARD_FAB2(SCH_1):PAGE119

FM_POST_CARD_PRES_BMC_N @BASEBOARD_FAB2_LIB.BASEBOARD_FAB2(SCH_1):FM_POST_CARD_PRES_BMC_N
  Q1L4    6 DRAIN<0> FET_N_DUAL_SMLF-2N7002DW,FET,DA    I19 @BASEBOARD_FAB2_LIB.BASEBOARD_FAB2(SCH_1):PAGE168
 R1L38    2      B RES_0402-1.00K,1%,1/16W,CHIP,GA    I22 @BASEBOARD_FAB2_LIB.BASEBOARD_FAB2(SCH_1):PAGE168
 U25W4  B10 GPIOQ6_OSCCLK AST2520A1-GP-GP_ASIC2-GB1-AST2A   I105 @BASEBOARD_FAB2_LIB.BASEBOARD_FAB2(SCH_1):PAGE146
  Q6W4    3    DRN FET_N_SOT23LF-2N7002,FET,C7925A    I43 @BASEBOARD_FAB2_LIB.BASEBOARD_FAB2(SCH_1):PAGE168
  R7W8    1      A RES_0402-0.0,5%,1/16W,CHIP,G21A   I269 @BASEBOARD_FAB2_LIB.BASEBOARD_FAB2(SCH_1):PAGE120

FM_POST_CARD_PRES_BMC_R1_N @BASEBOARD_FAB2_LIB.BASEBOARD_FAB2(SCH_1):FM_POST_CARD_PRES_BMC_R1_N
  U7C1 BG52 GPP_E2_SATAXPCIE2_SATAGP2 LBG_CORE_QAT_EXT_D_BGA1-IC,H91A   I147 @BASEBOARD_FAB2_LIB.BASEBOARD_FAB2(SCH_1):PAGE120
  R7W8    2      B RES_0402-0.0,5%,1/16W,CHIP,G21A   I269 @BASEBOARD_FAB2_LIB.BASEBOARD_FAB2(SCH_1):PAGE120
 R7W20    2      B RES_0402-4.75K,1%,1/16W,CHIP,GA   I278 @BASEBOARD_FAB2_LIB.BASEBOARD_FAB2(SCH_1):PAGE120

FM_PRSNT_2_1_N @BASEBOARD_FAB2_LIB.BASEBOARD_FAB2(SCH_1):FM_PRSNT_2_1_N
  U7C1 AE18 GPP_L2_TESTCH0_D0 LBG_CORE_QAT_EXT_D_BGA1-IC,H91A    I34 @BASEBOARD_FAB2_LIB.BASEBOARD_FAB2(SCH_1):PAGE121
  R3P7    2      B RES_0402-1.00K,1%,1/16W,EMPTY,A   I370 @BASEBOARD_FAB2_LIB.BASEBOARD_FAB2(SCH_1):PAGE133

FM_PRSNT_2_2_N @BASEBOARD_FAB2_LIB.BASEBOARD_FAB2(SCH_1):FM_PRSNT_2_2_N
  U7C1 AE15 GPP_L3_TESTCH0_D1 LBG_CORE_QAT_EXT_D_BGA1-IC,H91A    I34 @BASEBOARD_FAB2_LIB.BASEBOARD_FAB2(SCH_1):PAGE121
  R3P5    2      B RES_0402-1.00K,1%,1/16W,EMPTY,A   I366 @BASEBOARD_FAB2_LIB.BASEBOARD_FAB2(SCH_1):PAGE133

FM_PRSNT_2_3_N @BASEBOARD_FAB2_LIB.BASEBOARD_FAB2(SCH_1):FM_PRSNT_2_3_N
  U7C1 AE11 GPP_L4_TESTCH0_D2 LBG_CORE_QAT_EXT_D_BGA1-IC,H91A    I34 @BASEBOARD_FAB2_LIB.BASEBOARD_FAB2(SCH_1):PAGE121
  R3P6    2      B RES_0402-1.00K,1%,1/16W,EMPTY,A   I367 @BASEBOARD_FAB2_LIB.BASEBOARD_FAB2(SCH_1):PAGE133

FM_PRSNT_2_4_N @BASEBOARD_FAB2_LIB.BASEBOARD_FAB2(SCH_1):FM_PRSNT_2_4_N
  U7C1  Y18 GPP_L5_TESTCH0_D3 LBG_CORE_QAT_EXT_D_BGA1-IC,H91A    I34 @BASEBOARD_FAB2_LIB.BASEBOARD_FAB2(SCH_1):PAGE121
 R3N15    2      B RES_0402-1.00K,1%,1/16W,EMPTY,A   I368 @BASEBOARD_FAB2_LIB.BASEBOARD_FAB2(SCH_1):PAGE133

FM_PRSNT_2_5_N @BASEBOARD_FAB2_LIB.BASEBOARD_FAB2(SCH_1):FM_PRSNT_2_5_N
  U7C1 AA20 GPP_L6_TESTCH0_D4 LBG_CORE_QAT_EXT_D_BGA1-IC,H91A    I34 @BASEBOARD_FAB2_LIB.BASEBOARD_FAB2(SCH_1):PAGE121
 R3N16    2      B RES_0402-1.00K,1%,1/16W,EMPTY,A   I369 @BASEBOARD_FAB2_LIB.BASEBOARD_FAB2(SCH_1):PAGE133

FM_PRSNT_2_6_N @BASEBOARD_FAB2_LIB.BASEBOARD_FAB2(SCH_1):FM_PRSNT_2_6_N
  U7C1 AA17 GPP_L7_TESTCH0_D5 LBG_CORE_QAT_EXT_D_BGA1-IC,H91A    I34 @BASEBOARD_FAB2_LIB.BASEBOARD_FAB2(SCH_1):PAGE121
  R3P8    2      B RES_0402-1.00K,1%,1/16W,CHIP,GA   I322 @BASEBOARD_FAB2_LIB.BASEBOARD_FAB2(SCH_1):PAGE133
  J8G1  199  IO199 SCONN200_H68296001_SM-CONN,H68A    I78 @BASEBOARD_FAB2_LIB.BASEBOARD_FAB2(SCH_1):PAGE109

FM_PS_EN @BASEBOARD_FAB2_LIB.BASEBOARD_FAB2(SCH_1):FM_PS_EN
  U8D7   F9  PT19C LCMXO2_A_256BGA-IC,H63395-001    I59 @BASEBOARD_FAB2_LIB.BASEBOARD_FAB2(SCH_1):PAGE191
  C2R6    1      A CAP_0402LF-470PF,50V,10%,EMPTYA    I40 @BASEBOARD_FAB2_LIB.BASEBOARD_FAB2(SCH_1):PAGE181
  U8E1    9   A<0> TTL08_QFN15-74LVC08A,IC,D90404B    I60 @BASEBOARD_FAB2_LIB.BASEBOARD_FAB2(SCH_1):PAGE181

FM_PVCCIN_CPU0_PWR_IN_ALERT_N @BASEBOARD_FAB2_LIB.BASEBOARD_FAB2(SCH_1):FM_PVCCIN_CPU0_PWR_IN_ALERT_N
  U7E2    1   A<0> TTL1G08_SOTLF-NC7SZ08,IC,D1032B   I117 @BASEBOARD_FAB2_LIB.BASEBOARD_FAB2(SCH_1):PAGE95
 EU4D4   14 PINALRT_N PXE1610B_QFN-IC,H79206-001   I155 @BASEBOARD_FAB2_LIB.BASEBOARD_FAB2(SCH_1):PAGE201
  R4E4    2      B RES_0402-1.00K,1%,1/16W,CHIP,GA   I187 @BASEBOARD_FAB2_LIB.BASEBOARD_FAB2(SCH_1):PAGE201

FM_PVCCIN_CPU1_PWR_IN_ALERT_N @BASEBOARD_FAB2_LIB.BASEBOARD_FAB2(SCH_1):FM_PVCCIN_CPU1_PWR_IN_ALERT_N
  U7E3    1   A<0> TTL1G08_SOTLF-NC7SZ08,IC,D1032B   I118 @BASEBOARD_FAB2_LIB.BASEBOARD_FAB2(SCH_1):PAGE95
 EU1C2   14 PINALRT_N PXE1610B_QFN-IC,H79206-001   I130 @BASEBOARD_FAB2_LIB.BASEBOARD_FAB2(SCH_1):PAGE206
  R1D7    2      B RES_0402-1.00K,1%,1/16W,CHIP,GA   I155 @BASEBOARD_FAB2_LIB.BASEBOARD_FAB2(SCH_1):PAGE206

FM_PVCCIN_PVCCSA_CPU0_EN_LVC1 @BASEBOARD_FAB2_LIB.BASEBOARD_FAB2(SCH_1):FM_PVCCIN_PVCCSA_CPU0_EN_LVC1
  U8D7  A10  PT19B LCMXO2_A_256BGA-IC,H63395-001    I59 @BASEBOARD_FAB2_LIB.BASEBOARD_FAB2(SCH_1):PAGE191
 R6P18    1      A RES_0402-0.0,5%,1/16W,CHIP,G21A   I131 @BASEBOARD_FAB2_LIB.BASEBOARD_FAB2(SCH_1):PAGE201

FM_PVCCIN_PVCCSA_CPU1_EN_LVC1 @BASEBOARD_FAB2_LIB.BASEBOARD_FAB2(SCH_1):FM_PVCCIN_PVCCSA_CPU1_EN_LVC1
  U8D7  N16  PR14A LCMXO2_A_256BGA-IC,H63395-001    I59 @BASEBOARD_FAB2_LIB.BASEBOARD_FAB2(SCH_1):PAGE191
 R9N16    1      A RES_0402-0.0,5%,1/16W,CHIP,G21A   I119 @BASEBOARD_FAB2_LIB.BASEBOARD_FAB2(SCH_1):PAGE206

FM_PVCCIOMCP_CPU0_EN @BASEBOARD_FAB2_LIB.BASEBOARD_FAB2(SCH_1):FM_PVCCIOMCP_CPU0_EN
  U8D7   K1   PL9B LCMXO2_A_256BGA-IC,H63395-001   I179 @BASEBOARD_FAB2_LIB.BASEBOARD_FAB2(SCH_1):PAGE190
  J6B1  A16  IOA16 SCONN120_H61426002_SM-CONN,H61A    I56 @BASEBOARD_FAB2_LIB.BASEBOARD_FAB2(SCH_1):PAGE194

FM_PVCCIOMCP_CPU1_EN @BASEBOARD_FAB2_LIB.BASEBOARD_FAB2(SCH_1):FM_PVCCIOMCP_CPU1_EN
  U8D7   P7   PB9B LCMXO2_A_256BGA-IC,H63395-001   I179 @BASEBOARD_FAB2_LIB.BASEBOARD_FAB2(SCH_1):PAGE190
  J4B2  A16  IOA16 SCONN120_H61426002_SM-CONN,H61A    I46 @BASEBOARD_FAB2_LIB.BASEBOARD_FAB2(SCH_1):PAGE193

FM_PVCCIO_CPU0_EN @BASEBOARD_FAB2_LIB.BASEBOARD_FAB2(SCH_1):FM_PVCCIO_CPU0_EN
  U8D7   M7   PB9C LCMXO2_A_256BGA-IC,H63395-001   I179 @BASEBOARD_FAB2_LIB.BASEBOARD_FAB2(SCH_1):PAGE190
 R3P26    1      A RES_0402-0.0,5%,1/16W,CHIP,G21A    I87 @BASEBOARD_FAB2_LIB.BASEBOARD_FAB2(SCH_1):PAGE211

FM_PVCCIO_CPU1_EN @BASEBOARD_FAB2_LIB.BASEBOARD_FAB2(SCH_1):FM_PVCCIO_CPU1_EN
  U8D7   T7 PB11A_PCLKT2_0 LCMXO2_A_256BGA-IC,H63395-001   I179 @BASEBOARD_FAB2_LIB.BASEBOARD_FAB2(SCH_1):PAGE190
 R6P41    1      A RES_0402-0.0,5%,1/16W,CHIP,G21A    I90 @BASEBOARD_FAB2_LIB.BASEBOARD_FAB2(SCH_1):PAGE213

FM_PVCCMCP_CPU0_EN @BASEBOARD_FAB2_LIB.BASEBOARD_FAB2(SCH_1):FM_PVCCMCP_CPU0_EN
  U8D7   H2   PL6B LCMXO2_A_256BGA-IC,H63395-001   I179 @BASEBOARD_FAB2_LIB.BASEBOARD_FAB2(SCH_1):PAGE190
  J6B1  C20  IOC20 SCONN120_H61426002_SM-CONN,H61A    I56 @BASEBOARD_FAB2_LIB.BASEBOARD_FAB2(SCH_1):PAGE194

FM_PVCCMCP_CPU1_EN @BASEBOARD_FAB2_LIB.BASEBOARD_FAB2(SCH_1):FM_PVCCMCP_CPU1_EN
  U8D7   M8  PB16C LCMXO2_A_256BGA-IC,H63395-001   I179 @BASEBOARD_FAB2_LIB.BASEBOARD_FAB2(SCH_1):PAGE190
  J4B2  C20  IOC20 SCONN120_H61426002_SM-CONN,H61A    I46 @BASEBOARD_FAB2_LIB.BASEBOARD_FAB2(SCH_1):PAGE193

FM_PVDDQ_ABC_EN @BASEBOARD_FAB2_LIB.BASEBOARD_FAB2(SCH_1):FM_PVDDQ_ABC_EN
  U8D7  K14  PR10A LCMXO2_A_256BGA-IC,H63395-001    I59 @BASEBOARD_FAB2_LIB.BASEBOARD_FAB2(SCH_1):PAGE191
 R7F21    1      A RES_0402-0.0,5%,1/16W,CHIP,G21A    I13 @BASEBOARD_FAB2_LIB.BASEBOARD_FAB2(SCH_1):PAGE215

FM_PVDDQ_DEF_EN @BASEBOARD_FAB2_LIB.BASEBOARD_FAB2(SCH_1):FM_PVDDQ_DEF_EN
  U8D7  K15  PR10B LCMXO2_A_256BGA-IC,H63395-001    I59 @BASEBOARD_FAB2_LIB.BASEBOARD_FAB2(SCH_1):PAGE191
  R3M6    1      A RES_0402-0.0,5%,1/16W,CHIP,G21A    I15 @BASEBOARD_FAB2_LIB.BASEBOARD_FAB2(SCH_1):PAGE218

FM_PVDDQ_GHJ_EN @BASEBOARD_FAB2_LIB.BASEBOARD_FAB2(SCH_1):FM_PVDDQ_GHJ_EN
  U8D7  H13   PR6C LCMXO2_A_256BGA-IC,H63395-001    I59 @BASEBOARD_FAB2_LIB.BASEBOARD_FAB2(SCH_1):PAGE191
  R9U7    1      A RES_0402-0.0,5%,1/16W,CHIP,G21A    I14 @BASEBOARD_FAB2_LIB.BASEBOARD_FAB2(SCH_1):PAGE223

FM_PVDDQ_KLM_EN @BASEBOARD_FAB2_LIB.BASEBOARD_FAB2(SCH_1):FM_PVDDQ_KLM_EN
  U8D7  H15   PR6B LCMXO2_A_256BGA-IC,H63395-001    I59 @BASEBOARD_FAB2_LIB.BASEBOARD_FAB2(SCH_1):PAGE191
  R9M9    1      A RES_0402-0.0,5%,1/16W,CHIP,G21A    I14 @BASEBOARD_FAB2_LIB.BASEBOARD_FAB2(SCH_1):PAGE226

FM_PVPP_CPU0_EN @BASEBOARD_FAB2_LIB.BASEBOARD_FAB2(SCH_1):FM_PVPP_CPU0_EN
  U8D7  P15  PR14C LCMXO2_A_256BGA-IC,H63395-001    I59 @BASEBOARD_FAB2_LIB.BASEBOARD_FAB2(SCH_1):PAGE191
 R7F14    1      A RES_0402-10.0K,1%,1/16W,CHIP,GA   I136 @BASEBOARD_FAB2_LIB.BASEBOARD_FAB2(SCH_1):PAGE231
  C7F8    1      A CAP_0402LF-1000PF,50V,10%,EMPTA   I140 @BASEBOARD_FAB2_LIB.BASEBOARD_FAB2(SCH_1):PAGE231
  R7F9    1      A RES_0402-0.0,5%,1/16W,CHIP,G21A   I220 @BASEBOARD_FAB2_LIB.BASEBOARD_FAB2(SCH_1):PAGE231
  C7B9    1      A CAP_0402LF-1000PF,50V,10%,EMPTA   I185 @BASEBOARD_FAB2_LIB.BASEBOARD_FAB2(SCH_1):PAGE232
  R7B9    1      A RES_0402-0.0,5%,1/16W,CHIP,G21A   I307 @BASEBOARD_FAB2_LIB.BASEBOARD_FAB2(SCH_1):PAGE232

FM_PVPP_CPU1_EN @BASEBOARD_FAB2_LIB.BASEBOARD_FAB2(SCH_1):FM_PVPP_CPU1_EN
  U8D7  P16  PR13D LCMXO2_A_256BGA-IC,H63395-001    I59 @BASEBOARD_FAB2_LIB.BASEBOARD_FAB2(SCH_1):PAGE191
  R4G5    1      A RES_0402-10.0K,1%,1/16W,CHIP,GA   I182 @BASEBOARD_FAB2_LIB.BASEBOARD_FAB2(SCH_1):PAGE233
  C4G7    1      A CAP_0402LF-1000PF,50V,10%,EMPTA   I183 @BASEBOARD_FAB2_LIB.BASEBOARD_FAB2(SCH_1):PAGE233
  R4G4    1      A RES_0402-0.0,5%,1/16W,CHIP,G21A   I275 @BASEBOARD_FAB2_LIB.BASEBOARD_FAB2(SCH_1):PAGE233
  C4B5    1      A CAP_0402LF-1000PF,50V,10%,EMPTA   I129 @BASEBOARD_FAB2_LIB.BASEBOARD_FAB2(SCH_1):PAGE234
  R4B1    1      A RES_0402-0.0,5%,1/16W,CHIP,G21A   I220 @BASEBOARD_FAB2_LIB.BASEBOARD_FAB2(SCH_1):PAGE234

FM_PVPP_PVDDQ_CPU0_EN_ABC @BASEBOARD_FAB2_LIB.BASEBOARD_FAB2(SCH_1):FM_PVPP_PVDDQ_CPU0_EN_ABC
 EU7F1   40     EN NCP3232L_SM-IC,H86355-001   I193 @BASEBOARD_FAB2_LIB.BASEBOARD_FAB2(SCH_1):PAGE231
  R7F9    2      B RES_0402-0.0,5%,1/16W,CHIP,G21A   I220 @BASEBOARD_FAB2_LIB.BASEBOARD_FAB2(SCH_1):PAGE231

FM_PVPP_PVDDQ_CPU0_EN_DEF @BASEBOARD_FAB2_LIB.BASEBOARD_FAB2(SCH_1):FM_PVPP_PVDDQ_CPU0_EN_DEF
 EU7B1   40     EN NCP3232L_SM-IC,H86355-001   I214 @BASEBOARD_FAB2_LIB.BASEBOARD_FAB2(SCH_1):PAGE232
  R7B9    2      B RES_0402-0.0,5%,1/16W,CHIP,G21A   I307 @BASEBOARD_FAB2_LIB.BASEBOARD_FAB2(SCH_1):PAGE232

FM_PVPP_PVDDQ_CPU1_EN_GHJ @BASEBOARD_FAB2_LIB.BASEBOARD_FAB2(SCH_1):FM_PVPP_PVDDQ_CPU1_EN_GHJ
 EU4G1   40     EN NCP3232L_SM-IC,H86355-001   I225 @BASEBOARD_FAB2_LIB.BASEBOARD_FAB2(SCH_1):PAGE233
  R4G4    2      B RES_0402-0.0,5%,1/16W,CHIP,G21A   I275 @BASEBOARD_FAB2_LIB.BASEBOARD_FAB2(SCH_1):PAGE233

FM_PVPP_PVDDQ_CPU1_EN_KLM @BASEBOARD_FAB2_LIB.BASEBOARD_FAB2(SCH_1):FM_PVPP_PVDDQ_CPU1_EN_KLM
 EU4A3   40     EN NCP3232L_SM-IC,H86355-001   I184 @BASEBOARD_FAB2_LIB.BASEBOARD_FAB2(SCH_1):PAGE234
  R4B1    2      B RES_0402-0.0,5%,1/16W,CHIP,G21A   I220 @BASEBOARD_FAB2_LIB.BASEBOARD_FAB2(SCH_1):PAGE234

FM_PVTT_ABC_EN_R @BASEBOARD_FAB2_LIB.BASEBOARD_FAB2(SCH_1):FM_PVTT_ABC_EN_R
 C4G23    1      A CAP_0402LF-1000PF,50V,10%,EMPTA     I2 @BASEBOARD_FAB2_LIB.BASEBOARD_FAB2(SCH_1):PAGE221
 R4G23    2      B RES_0402-0.0,5%,1/16W,CHIP,G21A     I4 @BASEBOARD_FAB2_LIB.BASEBOARD_FAB2(SCH_1):PAGE221
 R6U15    2      B RES_0402-1.0M,1%,1/16W,EMPTY,GA     I5 @BASEBOARD_FAB2_LIB.BASEBOARD_FAB2(SCH_1):PAGE221
 EU4G3    7     EN MIC5166_DFN-IC,H55101-001    I15 @BASEBOARD_FAB2_LIB.BASEBOARD_FAB2(SCH_1):PAGE221

FM_PVTT_DEF_EN_R @BASEBOARD_FAB2_LIB.BASEBOARD_FAB2(SCH_1):FM_PVTT_DEF_EN_R
  C4A2    1      A CAP_0402LF-1000PF,50V,10%,EMPTA     I2 @BASEBOARD_FAB2_LIB.BASEBOARD_FAB2(SCH_1):PAGE222
  R4A2    2      B RES_0402-0.0,5%,1/16W,CHIP,G21A     I4 @BASEBOARD_FAB2_LIB.BASEBOARD_FAB2(SCH_1):PAGE222
  R6L4    2      B RES_0402-1.0M,1%,1/16W,EMPTY,GA     I5 @BASEBOARD_FAB2_LIB.BASEBOARD_FAB2(SCH_1):PAGE222
 EU4A1    7     EN MIC5166_DFN-IC,H55101-001    I13 @BASEBOARD_FAB2_LIB.BASEBOARD_FAB2(SCH_1):PAGE222

FM_PVTT_GHJ_EN_R @BASEBOARD_FAB2_LIB.BASEBOARD_FAB2(SCH_1):FM_PVTT_GHJ_EN_R
 C4G12    1      A CAP_0402LF-1000PF,50V,10%,EMPTA     I2 @BASEBOARD_FAB2_LIB.BASEBOARD_FAB2(SCH_1):PAGE229
 R4G16    2      B RES_0402-0.0,5%,1/16W,CHIP,G21A     I4 @BASEBOARD_FAB2_LIB.BASEBOARD_FAB2(SCH_1):PAGE229
  R6U3    2      B RES_0402-1.0M,1%,1/16W,EMPTY,GA     I5 @BASEBOARD_FAB2_LIB.BASEBOARD_FAB2(SCH_1):PAGE229
 EU4G2    7     EN MIC5166_DFN-IC,H55101-001    I37 @BASEBOARD_FAB2_LIB.BASEBOARD_FAB2(SCH_1):PAGE229

FM_PVTT_KLM_EN_R @BASEBOARD_FAB2_LIB.BASEBOARD_FAB2(SCH_1):FM_PVTT_KLM_EN_R
  C4A6    1      A CAP_0402LF-1000PF,50V,10%,EMPTA     I2 @BASEBOARD_FAB2_LIB.BASEBOARD_FAB2(SCH_1):PAGE230
  R4A3    2      B RES_0402-0.0,5%,1/16W,CHIP,G21A     I4 @BASEBOARD_FAB2_LIB.BASEBOARD_FAB2(SCH_1):PAGE230
  R6L5    2      B RES_0402-1.0M,1%,1/16W,EMPTY,GA     I5 @BASEBOARD_FAB2_LIB.BASEBOARD_FAB2(SCH_1):PAGE230
 EU4A2    7     EN MIC5166_DFN-IC,H55101-001    I37 @BASEBOARD_FAB2_LIB.BASEBOARD_FAB2(SCH_1):PAGE230

FM_PWRBRK_N @BASEBOARD_FAB2_LIB.BASEBOARD_FAB2(SCH_1):FM_PWRBRK_N
 R7E22    1      A RES_0402-0.0,5%,1/16W,CHIP,G21A   I341 @BASEBOARD_FAB2_LIB.BASEBOARD_FAB2(SCH_1):PAGE108
 R7E21    2      B RES_0402-4.75K,1%,1/16W,CHIP,GA   I343 @BASEBOARD_FAB2_LIB.BASEBOARD_FAB2(SCH_1):PAGE108
 U25W4   T4 GPION7_PWM7_VPIG7 AST2520A1-GP-GP_ASIC2-GB1-AST2A   I106 @BASEBOARD_FAB2_LIB.BASEBOARD_FAB2(SCH_1):PAGE147
  Q7E8    3    DRN FET_N_SOT23LF-2N7002,FET,C7925A   I123 @BASEBOARD_FAB2_LIB.BASEBOARD_FAB2(SCH_1):PAGE95

FM_PWRBRK_SLOT_N @BASEBOARD_FAB2_LIB.BASEBOARD_FAB2(SCH_1):FM_PWRBRK_SLOT_N
  J8G1   20   IO20 SCONN200_H68296001_SM-CONN,H68A   I258 @BASEBOARD_FAB2_LIB.BASEBOARD_FAB2(SCH_1):PAGE108
 R7E22    2      B RES_0402-0.0,5%,1/16W,CHIP,G21A   I341 @BASEBOARD_FAB2_LIB.BASEBOARD_FAB2(SCH_1):PAGE108
 R2U50    2      B RES_0402-0.0,5%,1/16W,CHIP,G21A   I228 @BASEBOARD_FAB2_LIB.BASEBOARD_FAB2(SCH_1):PAGE119

FM_PWR_BTN_N @BASEBOARD_FAB2_LIB.BASEBOARD_FAB2(SCH_1):FM_PWR_BTN_N
  U7C1 BH20 GPP_B9_SRCCLKREQ4_N LBG_CORE_QAT_EXT_D_BGA1-IC,H91A   I115 @BASEBOARD_FAB2_LIB.BASEBOARD_FAB2(SCH_1):PAGE119
 R1L26    2      B RES_0402-33.2,1%,1/16W,CHIP,G2A    I13 @BASEBOARD_FAB2_LIB.BASEBOARD_FAB2(SCH_1):PAGE175
R25W144    2      B RES_0402-0.0,5%,1/16W,CHIP,G21A   I173 @BASEBOARD_FAB2_LIB.BASEBOARD_FAB2(SCH_1):PAGE145
 R1W27    1      A RES_0402-0.0,5%,1/16W,CHIP,G21A   I351 @BASEBOARD_FAB2_LIB.BASEBOARD_FAB2(SCH_1):PAGE190

FM_PWR_BTN_R1_N @BASEBOARD_FAB2_LIB.BASEBOARD_FAB2(SCH_1):FM_PWR_BTN_R1_N
 U25W4  F18 GPIOE2_NDSR3 AST2520A1-GP-GP_ASIC2-GB1-AST2A   I117 @BASEBOARD_FAB2_LIB.BASEBOARD_FAB2(SCH_1):PAGE145
R25W144    1      A RES_0402-0.0,5%,1/16W,CHIP,G21A   I173 @BASEBOARD_FAB2_LIB.BASEBOARD_FAB2(SCH_1):PAGE145

FM_PWR_BTN_R2_N @BASEBOARD_FAB2_LIB.BASEBOARD_FAB2(SCH_1):FM_PWR_BTN_R2_N
  U8D7   G6   PL3D LCMXO2_A_256BGA-IC,H63395-001   I179 @BASEBOARD_FAB2_LIB.BASEBOARD_FAB2(SCH_1):PAGE190
 R1W27    2      B RES_0402-0.0,5%,1/16W,CHIP,G21A   I351 @BASEBOARD_FAB2_LIB.BASEBOARD_FAB2(SCH_1):PAGE190

FM_PWR_BTN_R_N @BASEBOARD_FAB2_LIB.BASEBOARD_FAB2(SCH_1):FM_PWR_BTN_R_N
 R1L26    1      A RES_0402-33.2,1%,1/16W,CHIP,G2A    I13 @BASEBOARD_FAB2_LIB.BASEBOARD_FAB2(SCH_1):PAGE175
  U9A4    4     2Y TC7PZ14FU-GP_DISCRET-GA1-TC7PZA    I97 @BASEBOARD_FAB2_LIB.BASEBOARD_FAB2(SCH_1):PAGE175

FM_PWR_LED @BASEBOARD_FAB2_LIB.BASEBOARD_FAB2(SCH_1):FM_PWR_LED
  Q9A2    6 DRAIN<0> FET_N_DUAL_SMLF-NTJD4001N,FET,A   I175 @BASEBOARD_FAB2_LIB.BASEBOARD_FAB2(SCH_1):PAGE119
  Q9A2    5 GATE<0> FET_N_DUAL_SMLF-NTJD4001N,FET,A   I180 @BASEBOARD_FAB2_LIB.BASEBOARD_FAB2(SCH_1):PAGE119
 R9A18    2      B RES_0402-4.75K,1%,1/16W,CHIP,GA   I183 @BASEBOARD_FAB2_LIB.BASEBOARD_FAB2(SCH_1):PAGE119

FM_PWR_LED_A @BASEBOARD_FAB2_LIB.BASEBOARD_FAB2(SCH_1):FM_PWR_LED_A
 R9A20    1      A RES_0402-221,1.0%,1/16W,CHIP,GA   I178 @BASEBOARD_FAB2_LIB.BASEBOARD_FAB2(SCH_1):PAGE119
 DS9A5    1      A LED_A1LF-GREEN,IC,C97278-010   I179 @BASEBOARD_FAB2_LIB.BASEBOARD_FAB2(SCH_1):PAGE119

FM_PWR_LED_K @BASEBOARD_FAB2_LIB.BASEBOARD_FAB2(SCH_1):FM_PWR_LED_K
 DS9A5    2      C LED_A1LF-GREEN,IC,C97278-010   I179 @BASEBOARD_FAB2_LIB.BASEBOARD_FAB2(SCH_1):PAGE119
  Q9A2    3 DRAIN<0> FET_N_DUAL_SMLF-NTJD4001N,FET,A   I180 @BASEBOARD_FAB2_LIB.BASEBOARD_FAB2(SCH_1):PAGE119

FM_PWR_LED_N @BASEBOARD_FAB2_LIB.BASEBOARD_FAB2(SCH_1):FM_PWR_LED_N
  U7C1 BK46 GPP_D1 LBG_CORE_QAT_EXT_D_BGA1-IC,H91A   I115 @BASEBOARD_FAB2_LIB.BASEBOARD_FAB2(SCH_1):PAGE119
  Q9A2    2 GATE<0> FET_N_DUAL_SMLF-NTJD4001N,FET,A   I175 @BASEBOARD_FAB2_LIB.BASEBOARD_FAB2(SCH_1):PAGE119
 R9A21    2      B RES_0402-4.75K,1%,1/16W,CHIP,GA   I186 @BASEBOARD_FAB2_LIB.BASEBOARD_FAB2(SCH_1):PAGE119

FM_QAT_EN_N @BASEBOARD_FAB2_LIB.BASEBOARD_FAB2(SCH_1):FM_QAT_EN_N
  U7C1  BR9 GPP_B3_CPU_GP2 LBG_CORE_QAT_EXT_D_BGA1-IC,H91A   I115 @BASEBOARD_FAB2_LIB.BASEBOARD_FAB2(SCH_1):PAGE119
 R2N23    2      B RES_0402-10.0K,1%,1/16W,CHIP,GA   I112 @BASEBOARD_FAB2_LIB.BASEBOARD_FAB2(SCH_1):PAGE135
 R2N24    1      A RES_0402-1.00K,1%,1/16W,EMPTY,A   I113 @BASEBOARD_FAB2_LIB.BASEBOARD_FAB2(SCH_1):PAGE135

FM_RED_LED_ANODE @BASEBOARD_FAB2_LIB.BASEBOARD_FAB2(SCH_1):FM_RED_LED_ANODE
 DS9F1    1      A LED_A1-RED,IC,D14725-005    I71 @BASEBOARD_FAB2_LIB.BASEBOARD_FAB2(SCH_1):PAGE177
 R9F28    2      B RES_0402-221,1.0%,1/16W,CHIP,GA    I72 @BASEBOARD_FAB2_LIB.BASEBOARD_FAB2(SCH_1):PAGE177

FM_RED_LED_CATHODE @BASEBOARD_FAB2_LIB.BASEBOARD_FAB2(SCH_1):FM_RED_LED_CATHODE
 DS9F1    2      C LED_A1-RED,IC,D14725-005    I71 @BASEBOARD_FAB2_LIB.BASEBOARD_FAB2(SCH_1):PAGE177
  Q9F1    3 DRAIN<0> FET_N_DUAL_SMLF-NTJD4001N,FET,A    I79 @BASEBOARD_FAB2_LIB.BASEBOARD_FAB2(SCH_1):PAGE177

FM_SINT_PRSNT_N @BASEBOARD_FAB2_LIB.BASEBOARD_FAB2(SCH_1):FM_SINT_PRSNT_N
  U7C1  C18 RSVD<11> LBG_CORE_QAT_EXT_D_BGA1-IC,H91A    I34 @BASEBOARD_FAB2_LIB.BASEBOARD_FAB2(SCH_1):PAGE121
  R7C5    2      B RES_0402-10.0K,1%,1/16W,CHIP,GA   I297 @BASEBOARD_FAB2_LIB.BASEBOARD_FAB2(SCH_1):PAGE133
  U8D7  B14  PT24A LCMXO2_A_256BGA-IC,H63395-001    I59 @BASEBOARD_FAB2_LIB.BASEBOARD_FAB2(SCH_1):PAGE191

FM_SLPS3_N @BASEBOARD_FAB2_LIB.BASEBOARD_FAB2(SCH_1):FM_SLPS3_N
  U8D7   G1   PL6A LCMXO2_A_256BGA-IC,H63395-001   I179 @BASEBOARD_FAB2_LIB.BASEBOARD_FAB2(SCH_1):PAGE190
 U25W4  R22 GPIOY0_SIOS3# AST2520A1-GP-GP_ASIC2-GB1-AST2A    I28 @BASEBOARD_FAB2_LIB.BASEBOARD_FAB2(SCH_1):PAGE148
  U6W1   19    P16 TCA9555PWR-GP_DISCRET-GC1-TCA9A   I120 @BASEBOARD_FAB2_LIB.BASEBOARD_FAB2(SCH_1):PAGE247
  R7W1    1      A RES_0402-0.0,5%,1/16W,CHIP,G21A   I167 @BASEBOARD_FAB2_LIB.BASEBOARD_FAB2(SCH_1):PAGE118

FM_SLPS3_R_N @BASEBOARD_FAB2_LIB.BASEBOARD_FAB2(SCH_1):FM_SLPS3_R_N
  U7C1  D14 GPD4_SLP_S3_N LBG_CORE_QAT_EXT_D_BGA1-IC,H91A    I73 @BASEBOARD_FAB2_LIB.BASEBOARD_FAB2(SCH_1):PAGE118
  R7W1    2      B RES_0402-0.0,5%,1/16W,CHIP,G21A   I167 @BASEBOARD_FAB2_LIB.BASEBOARD_FAB2(SCH_1):PAGE118

FM_SLPS4_N @BASEBOARD_FAB2_LIB.BASEBOARD_FAB2(SCH_1):FM_SLPS4_N
  U7C1  B16 GPD5_SLP_S4_N LBG_CORE_QAT_EXT_D_BGA1-IC,H91A    I73 @BASEBOARD_FAB2_LIB.BASEBOARD_FAB2(SCH_1):PAGE118
  U8D7  C12  PT23A LCMXO2_A_256BGA-IC,H63395-001    I59 @BASEBOARD_FAB2_LIB.BASEBOARD_FAB2(SCH_1):PAGE191
 U25W4  R21 GPIOY1_SIOS5# AST2520A1-GP-GP_ASIC2-GB1-AST2A    I28 @BASEBOARD_FAB2_LIB.BASEBOARD_FAB2(SCH_1):PAGE148

FM_SLP_SUS_N @BASEBOARD_FAB2_LIB.BASEBOARD_FAB2(SCH_1):FM_SLP_SUS_N
  U7C1   P7 SLP_SUS_N LBG_CORE_QAT_EXT_D_BGA1-IC,H91A    I73 @BASEBOARD_FAB2_LIB.BASEBOARD_FAB2(SCH_1):PAGE118
  U8D7   E9  PT17D LCMXO2_A_256BGA-IC,H63395-001    I59 @BASEBOARD_FAB2_LIB.BASEBOARD_FAB2(SCH_1):PAGE191

FM_SLT_CFG0 @BASEBOARD_FAB2_LIB.BASEBOARD_FAB2(SCH_1):FM_SLT_CFG0
  J8G1   19   IO19 SCONN200_H68296001_SM-CONN,H68A   I258 @BASEBOARD_FAB2_LIB.BASEBOARD_FAB2(SCH_1):PAGE108
  U7C1 CA32 GPP_C15 LBG_CORE_QAT_EXT_D_BGA1-IC,H91A   I115 @BASEBOARD_FAB2_LIB.BASEBOARD_FAB2(SCH_1):PAGE119
  R8C7    2      B RES_0402-4.75K,1%,1/16W,CHIP,GA   I327 @BASEBOARD_FAB2_LIB.BASEBOARD_FAB2(SCH_1):PAGE133
 U25W4   D8 GPIOR6_MDC1 AST2520A1-GP-GP_ASIC2-GB1-AST2A   I106 @BASEBOARD_FAB2_LIB.BASEBOARD_FAB2(SCH_1):PAGE147

FM_SLT_CFG1 @BASEBOARD_FAB2_LIB.BASEBOARD_FAB2(SCH_1):FM_SLT_CFG1
  J8G1   18   IO18 SCONN200_H68296001_SM-CONN,H68A   I258 @BASEBOARD_FAB2_LIB.BASEBOARD_FAB2(SCH_1):PAGE108
  U7C1 BW37 GPP_C16 LBG_CORE_QAT_EXT_D_BGA1-IC,H91A   I115 @BASEBOARD_FAB2_LIB.BASEBOARD_FAB2(SCH_1):PAGE119
  R8C1    2      B RES_0402-4.75K,1%,1/16W,CHIP,GA   I326 @BASEBOARD_FAB2_LIB.BASEBOARD_FAB2(SCH_1):PAGE133
 U25W4  E10 GPIOR7_MDIO1 AST2520A1-GP-GP_ASIC2-GB1-AST2A   I106 @BASEBOARD_FAB2_LIB.BASEBOARD_FAB2(SCH_1):PAGE147

FM_SLT_CFG2_R @BASEBOARD_FAB2_LIB.BASEBOARD_FAB2(SCH_1):FM_SLT_CFG2_R
  U7C1 BY31 GPP_C17 LBG_CORE_QAT_EXT_D_BGA1-IC,H91A   I115 @BASEBOARD_FAB2_LIB.BASEBOARD_FAB2(SCH_1):PAGE119
 R2U48    2      B RES_0402-4.75K,1%,1/16W,CHIP,GA   I213 @BASEBOARD_FAB2_LIB.BASEBOARD_FAB2(SCH_1):PAGE119
 R2U50    1      A RES_0402-0.0,5%,1/16W,CHIP,G21A   I228 @BASEBOARD_FAB2_LIB.BASEBOARD_FAB2(SCH_1):PAGE119

FM_SOL_UART_CH_SEL @BASEBOARD_FAB2_LIB.BASEBOARD_FAB2(SCH_1):FM_SOL_UART_CH_SEL
  U7C1  BG7 GPP_G21_SSATA_DEVSLP1 LBG_CORE_QAT_EXT_D_BGA1-IC,H91A   I147 @BASEBOARD_FAB2_LIB.BASEBOARD_FAB2(SCH_1):PAGE120
  U8D7  L10  PB18D LCMXO2_A_256BGA-IC,H63395-001   I179 @BASEBOARD_FAB2_LIB.BASEBOARD_FAB2(SCH_1):PAGE190
 U25W4  F20 GPIOD2_SD2DAT0 AST2520A1-GP-GP_ASIC2-GB1-AST2A   I117 @BASEBOARD_FAB2_LIB.BASEBOARD_FAB2(SCH_1):PAGE145
 R6W16    2      B RES_0402-1.00K,1%,1/16W,CHIP,GA    I46 @BASEBOARD_FAB2_LIB.BASEBOARD_FAB2(SCH_1):PAGE168
  Q6W2    3      C NPN_SM-MMBT3904,IC,C52245-001    I47 @BASEBOARD_FAB2_LIB.BASEBOARD_FAB2(SCH_1):PAGE168

FM_SPEAKER_PCH_N @BASEBOARD_FAB2_LIB.BASEBOARD_FAB2(SCH_1):FM_SPEAKER_PCH_N
  Q9A3    3    DRN FET_N_SOT23LF-2N7002,FET,C7925A    I49 @BASEBOARD_FAB2_LIB.BASEBOARD_FAB2(SCH_1):PAGE175
 DS9A3    1      C LED_1NCLF-YELLOW,IC,C96565-003    I67 @BASEBOARD_FAB2_LIB.BASEBOARD_FAB2(SCH_1):PAGE175

FM_SSATA_PCIE_M2_SEL @BASEBOARD_FAB2_LIB.BASEBOARD_FAB2(SCH_1):FM_SSATA_PCIE_M2_SEL
  U7C1  BH4 GPP_H23_SSATAXPCIE5_SSATAGP5 LBG_CORE_QAT_EXT_D_BGA1-IC,H91A   I147 @BASEBOARD_FAB2_LIB.BASEBOARD_FAB2(SCH_1):PAGE120
 R2P14    2      B RES_0402-0.0,5%,1/16W,CHIP,G21A   I115 @BASEBOARD_FAB2_LIB.BASEBOARD_FAB2(SCH_1):PAGE185

FM_SYS_THROTTLE_LVC3 @BASEBOARD_FAB2_LIB.BASEBOARD_FAB2(SCH_1):FM_SYS_THROTTLE_LVC3
  Q2U1    2 GATE<0> FET_N_DUAL_SMLF-NTJD4001N,FET,A    I28 @BASEBOARD_FAB2_LIB.BASEBOARD_FAB2(SCH_1):PAGE95
  Q4B2    2 GATE<0> FET_N_DUAL_SMLF-NTJD4001N,FET,A    I32 @BASEBOARD_FAB2_LIB.BASEBOARD_FAB2(SCH_1):PAGE95
  Q4B2    5 GATE<0> FET_N_DUAL_SMLF-NTJD4001N,FET,A    I33 @BASEBOARD_FAB2_LIB.BASEBOARD_FAB2(SCH_1):PAGE95
  Q7E3    5 GATE<0> FET_N_DUAL_SMLF-NTJD4001N,FET,A    I51 @BASEBOARD_FAB2_LIB.BASEBOARD_FAB2(SCH_1):PAGE95
  Q7E3    2 GATE<0> FET_N_DUAL_SMLF-NTJD4001N,FET,A    I52 @BASEBOARD_FAB2_LIB.BASEBOARD_FAB2(SCH_1):PAGE95
  R7E7    2      B RES_0402-4.75K,1%,1/16W,CHIP,GA   I106 @BASEBOARD_FAB2_LIB.BASEBOARD_FAB2(SCH_1):PAGE95
  Q2U1    5 GATE<0> FET_N_DUAL_SMLF-NTJD4001N,FET,A   I113 @BASEBOARD_FAB2_LIB.BASEBOARD_FAB2(SCH_1):PAGE95
  Q7E4    3    DRN FET_N_SOT23LF-2N7002,FET,C7925A   I122 @BASEBOARD_FAB2_LIB.BASEBOARD_FAB2(SCH_1):PAGE95
  Q7E8    1   GATE FET_N_SOT23LF-2N7002,FET,C7925A   I123 @BASEBOARD_FAB2_LIB.BASEBOARD_FAB2(SCH_1):PAGE95

FM_THERMTRIP_DLY @BASEBOARD_FAB2_LIB.BASEBOARD_FAB2(SCH_1):FM_THERMTRIP_DLY
 R7D18    1      A RES_0402-1.00K,1%,1/16W,CHIP,GA    I11 @BASEBOARD_FAB2_LIB.BASEBOARD_FAB2(SCH_1):PAGE134
  U8D7  L15  PR12A LCMXO2_A_256BGA-IC,H63395-001    I59 @BASEBOARD_FAB2_LIB.BASEBOARD_FAB2(SCH_1):PAGE191

FM_THERMTRIP_DLY_R @BASEBOARD_FAB2_LIB.BASEBOARD_FAB2(SCH_1):FM_THERMTRIP_DLY_R
 R7D18    2      B RES_0402-1.00K,1%,1/16W,CHIP,GA    I11 @BASEBOARD_FAB2_LIB.BASEBOARD_FAB2(SCH_1):PAGE134
  Q7D1    1   GATE FET_N_SOT23LF-2N7002,FET,C7925A    I14 @BASEBOARD_FAB2_LIB.BASEBOARD_FAB2(SCH_1):PAGE134

FM_THROTTLE_N @BASEBOARD_FAB2_LIB.BASEBOARD_FAB2(SCH_1):FM_THROTTLE_N
  R7E9    1      A RES_0402-0.0,5%,1/16W,CHIP,G21A   I108 @BASEBOARD_FAB2_LIB.BASEBOARD_FAB2(SCH_1):PAGE95
 R8B31    2      B RES_0402-4.75K,1%,1/16W,CHIP,GA   I307 @BASEBOARD_FAB2_LIB.BASEBOARD_FAB2(SCH_1):PAGE133
  R1R8    2      B RES_0402-0.0,5%,1/16W,CHIP,G21A    I51 @BASEBOARD_FAB2_LIB.BASEBOARD_FAB2(SCH_1):PAGE170
 U25W4  V20 GPIOS0_VPOB2_SPI2CS1# AST2520A1-GP-GP_ASIC2-GB1-AST2A   I104 @BASEBOARD_FAB2_LIB.BASEBOARD_FAB2(SCH_1):PAGE146
 R7W17    2      B RES_0402-0.0,5%,1/16W,CHIP,G21A   I229 @BASEBOARD_FAB2_LIB.BASEBOARD_FAB2(SCH_1):PAGE119

FM_THROTTLE_R1_N @BASEBOARD_FAB2_LIB.BASEBOARD_FAB2(SCH_1):FM_THROTTLE_R1_N
  U1R1    4      Y TTL1G07_A_SOP-74LVC1G07,IC,C88B    I46 @BASEBOARD_FAB2_LIB.BASEBOARD_FAB2(SCH_1):PAGE170
  R1R8    1      A RES_0402-0.0,5%,1/16W,CHIP,G21A    I51 @BASEBOARD_FAB2_LIB.BASEBOARD_FAB2(SCH_1):PAGE170

FM_THROTTLE_R2_N @BASEBOARD_FAB2_LIB.BASEBOARD_FAB2(SCH_1):FM_THROTTLE_R2_N
  U7C1 CA39 GPP_C20 LBG_CORE_QAT_EXT_D_BGA1-IC,H91A   I115 @BASEBOARD_FAB2_LIB.BASEBOARD_FAB2(SCH_1):PAGE119
 R7W17    1      A RES_0402-0.0,5%,1/16W,CHIP,G21A   I229 @BASEBOARD_FAB2_LIB.BASEBOARD_FAB2(SCH_1):PAGE119

FM_THROTTLE_R_N @BASEBOARD_FAB2_LIB.BASEBOARD_FAB2(SCH_1):FM_THROTTLE_R_N
  R7E9    2      B RES_0402-0.0,5%,1/16W,CHIP,G21A   I108 @BASEBOARD_FAB2_LIB.BASEBOARD_FAB2(SCH_1):PAGE95
  Q7E4    1   GATE FET_N_SOT23LF-2N7002,FET,C7925A   I122 @BASEBOARD_FAB2_LIB.BASEBOARD_FAB2(SCH_1):PAGE95

FM_TPM_PRES_N @BASEBOARD_FAB2_LIB.BASEBOARD_FAB2(SCH_1):FM_TPM_PRES_N
  U7C1  AE4 GPP_A22 LBG_CORE_QAT_EXT_D_BGA1-IC,H91A   I115 @BASEBOARD_FAB2_LIB.BASEBOARD_FAB2(SCH_1):PAGE119
  Q9W4    4    OUT LMV331IDCKRG4-GP_DISCRET-G-LMVA    I15 @BASEBOARD_FAB2_LIB.BASEBOARD_FAB2(SCH_1):PAGE249
 U25W4 AA22 GPIOAA3_VPOR5_NORD3_SALT10 AST2520A1-GP-GP_ASIC2-GB1-AST2A   I104 @BASEBOARD_FAB2_LIB.BASEBOARD_FAB2(SCH_1):PAGE146
  R8E3    2      B RES_0402-4.75K,1%,1/16W,CHIP,GA   I371 @BASEBOARD_FAB2_LIB.BASEBOARD_FAB2(SCH_1):PAGE133

FM_TPM_PRES_RST @BASEBOARD_FAB2_LIB.BASEBOARD_FAB2(SCH_1):FM_TPM_PRES_RST
  Q9W2    3      C NPN_SM-MMBT3904,IC,C52245-001    I29 @BASEBOARD_FAB2_LIB.BASEBOARD_FAB2(SCH_1):PAGE249
  Q9W3    1      B NPN_SM-MMBT3904,IC,C52245-001    I49 @BASEBOARD_FAB2_LIB.BASEBOARD_FAB2(SCH_1):PAGE249
  R3W5    2      B RES_0402-10.0K,1%,1/16W,CHIP,GA    I58 @BASEBOARD_FAB2_LIB.BASEBOARD_FAB2(SCH_1):PAGE249

FM_TPM_PRES_RST_N @BASEBOARD_FAB2_LIB.BASEBOARD_FAB2(SCH_1):FM_TPM_PRES_RST_N
  U7C1 BN40 GPP_D12_SSATA_SDATAOUT1 LBG_CORE_QAT_EXT_D_BGA1-IC,H91A   I115 @BASEBOARD_FAB2_LIB.BASEBOARD_FAB2(SCH_1):PAGE119
 R8D22    2      B RES_0402-33.2,1%,1/16W,CHIP,G2A   I386 @BASEBOARD_FAB2_LIB.BASEBOARD_FAB2(SCH_1):PAGE157
  J8E1    8    IO8 SCONN11_H67026001_SM-CONN,H670A    I87 @BASEBOARD_FAB2_LIB.BASEBOARD_FAB2(SCH_1):PAGE184
  Q9W4    1    +IN LMV331IDCKRG4-GP_DISCRET-G-LMVA    I15 @BASEBOARD_FAB2_LIB.BASEBOARD_FAB2(SCH_1):PAGE249
  Q9W1    3    DRN FET_N_SOT23LF-2N7002,FET,C7925A    I30 @BASEBOARD_FAB2_LIB.BASEBOARD_FAB2(SCH_1):PAGE249
  R3W4    1      1 47KR2F-GP_RCL_GP-47KR2F-GP,64.A    I31 @BASEBOARD_FAB2_LIB.BASEBOARD_FAB2(SCH_1):PAGE249
  R8W1    2      B RES_0402-0.0,5%,1/16W,CHIP,G21A    I34 @BASEBOARD_FAB2_LIB.BASEBOARD_FAB2(SCH_1):PAGE249
  R3W3    2      B RES_0402-10.0K,1%,1/16W,EMPTY,A    I36 @BASEBOARD_FAB2_LIB.BASEBOARD_FAB2(SCH_1):PAGE249
 R9E14    1      A RES_0402-0.0,5%,1/16W,EMPTY,G2A   I393 @BASEBOARD_FAB2_LIB.BASEBOARD_FAB2(SCH_1):PAGE157

FM_TPM_PRES_RST_N_R @BASEBOARD_FAB2_LIB.BASEBOARD_FAB2(SCH_1):FM_TPM_PRES_RST_N_R
  Q9W2    1      B NPN_SM-MMBT3904,IC,C52245-001    I29 @BASEBOARD_FAB2_LIB.BASEBOARD_FAB2(SCH_1):PAGE249
  R3W4    2      2 47KR2F-GP_RCL_GP-47KR2F-GP,64.A    I31 @BASEBOARD_FAB2_LIB.BASEBOARD_FAB2(SCH_1):PAGE249

FM_UARTSW_LSB_N @BASEBOARD_FAB2_LIB.BASEBOARD_FAB2(SCH_1):FM_UARTSW_LSB_N
  U7C1  AT4 GPP_H0_SRCCLKREQ6_N LBG_CORE_QAT_EXT_D_BGA1-IC,H91A   I147 @BASEBOARD_FAB2_LIB.BASEBOARD_FAB2(SCH_1):PAGE120
  U9F2    6     S1 FSA3357_SM-IC,C63273-001    I74 @BASEBOARD_FAB2_LIB.BASEBOARD_FAB2(SCH_1):PAGE158
  U9F1    6     S1 FSA3357_SM-IC,C63273-001    I75 @BASEBOARD_FAB2_LIB.BASEBOARD_FAB2(SCH_1):PAGE158
 DS9A4    2      C LED_A1LF-GREEN,IC,D14725-022   I130 @BASEBOARD_FAB2_LIB.BASEBOARD_FAB2(SCH_1):PAGE158
  U8D7   R9  PB18A LCMXO2_A_256BGA-IC,H63395-001   I179 @BASEBOARD_FAB2_LIB.BASEBOARD_FAB2(SCH_1):PAGE190
 U25W4  N21 GPIOQ4_SCL14 AST2520A1-GP-GP_ASIC2-GB1-AST2A    I95 @BASEBOARD_FAB2_LIB.BASEBOARD_FAB2(SCH_1):PAGE144

FM_UARTSW_LSB_R_N @BASEBOARD_FAB2_LIB.BASEBOARD_FAB2(SCH_1):FM_UARTSW_LSB_R_N
 DS9A4    1      A LED_A1LF-GREEN,IC,D14725-022   I130 @BASEBOARD_FAB2_LIB.BASEBOARD_FAB2(SCH_1):PAGE158
 R1L43    1      A RES_0402-330,5%,1/16W,CHIP,G21A   I131 @BASEBOARD_FAB2_LIB.BASEBOARD_FAB2(SCH_1):PAGE158

FM_UARTSW_MSB_N @BASEBOARD_FAB2_LIB.BASEBOARD_FAB2(SCH_1):FM_UARTSW_MSB_N
  U7C1 BA13 GPP_G23_SSATAXPCIE0_SSATAGP0 LBG_CORE_QAT_EXT_D_BGA1-IC,H91A   I147 @BASEBOARD_FAB2_LIB.BASEBOARD_FAB2(SCH_1):PAGE120
  U9F2    5     S2 FSA3357_SM-IC,C63273-001    I74 @BASEBOARD_FAB2_LIB.BASEBOARD_FAB2(SCH_1):PAGE158
  U9F1    5     S2 FSA3357_SM-IC,C63273-001    I75 @BASEBOARD_FAB2_LIB.BASEBOARD_FAB2(SCH_1):PAGE158
 DS9A7    2      C LED_A1LF-GREEN,IC,D14725-022   I134 @BASEBOARD_FAB2_LIB.BASEBOARD_FAB2(SCH_1):PAGE158
  U8D7  P11  PB21B LCMXO2_A_256BGA-IC,H63395-001   I179 @BASEBOARD_FAB2_LIB.BASEBOARD_FAB2(SCH_1):PAGE190
 U25W4  N22 GPIOQ5_SDA14 AST2520A1-GP-GP_ASIC2-GB1-AST2A    I95 @BASEBOARD_FAB2_LIB.BASEBOARD_FAB2(SCH_1):PAGE144

FM_UARTSW_MSB_R_N @BASEBOARD_FAB2_LIB.BASEBOARD_FAB2(SCH_1):FM_UARTSW_MSB_R_N
 DS9A7    1      A LED_A1LF-GREEN,IC,D14725-022   I134 @BASEBOARD_FAB2_LIB.BASEBOARD_FAB2(SCH_1):PAGE158
 R1L44    1      A RES_0402-330,5%,1/16W,CHIP,G21A   I136 @BASEBOARD_FAB2_LIB.BASEBOARD_FAB2(SCH_1):PAGE158

FM_UART_ALERT_N @BASEBOARD_FAB2_LIB.BASEBOARD_FAB2(SCH_1):FM_UART_ALERT_N
  U7C1 BK13 GPP_B15 LBG_CORE_QAT_EXT_D_BGA1-IC,H91A   I115 @BASEBOARD_FAB2_LIB.BASEBOARD_FAB2(SCH_1):PAGE119
  U8D7   P2  PL14D LCMXO2_A_256BGA-IC,H63395-001   I179 @BASEBOARD_FAB2_LIB.BASEBOARD_FAB2(SCH_1):PAGE190
 R9F55    2      B RES_0402-4.75K,1%,1/16W,CHIP,GA     I3 @BASEBOARD_FAB2_LIB.BASEBOARD_FAB2(SCH_1):PAGE183

FM_UART_PRES_N @BASEBOARD_FAB2_LIB.BASEBOARD_FAB2(SCH_1):FM_UART_PRES_N
  U7C1   T2 GPP_A16_CLKOUT_LPC2 LBG_CORE_QAT_EXT_D_BGA1-IC,H91A   I115 @BASEBOARD_FAB2_LIB.BASEBOARD_FAB2(SCH_1):PAGE119
 R7C13    2      B RES_0402-10.0K,1%,1/16W,CHIP,GA    I67 @BASEBOARD_FAB2_LIB.BASEBOARD_FAB2(SCH_1):PAGE137
  J9G1    9    IO9 CONN12_C73564003_PIP-CONN,C735A   I128 @BASEBOARD_FAB2_LIB.BASEBOARD_FAB2(SCH_1):PAGE137

FM_UART_SEL_N @BASEBOARD_FAB2_LIB.BASEBOARD_FAB2(SCH_1):FM_UART_SEL_N
  Q6W2    1      B NPN_SM-MMBT3904,IC,C52245-001    I47 @BASEBOARD_FAB2_LIB.BASEBOARD_FAB2(SCH_1):PAGE168
 R6W49    2      B RES_0402-40.2K,1%,1/16W,CHIP,GA    I48 @BASEBOARD_FAB2_LIB.BASEBOARD_FAB2(SCH_1):PAGE168

FM_UART_SWITCH_N @BASEBOARD_FAB2_LIB.BASEBOARD_FAB2(SCH_1):FM_UART_SWITCH_N
  J9A2   12   IO12 CONN14_H54902001_PIP-CONN,H549A   I171 @BASEBOARD_FAB2_LIB.BASEBOARD_FAB2(SCH_1):PAGE155
  R1L6    1      A RES_0402-0.0,5%,1/16W,CHIP,G21A     I6 @BASEBOARD_FAB2_LIB.BASEBOARD_FAB2(SCH_1):PAGE168
  U6W1   20    P17 TCA9555PWR-GP_DISCRET-GC1-TCA9A   I120 @BASEBOARD_FAB2_LIB.BASEBOARD_FAB2(SCH_1):PAGE247
  R9A5    2      B RES_0402-20.0K,1%,1/16W,CHIP,GA   I198 @BASEBOARD_FAB2_LIB.BASEBOARD_FAB2(SCH_1):PAGE155
 R6W49    1      A RES_0402-40.2K,1%,1/16W,CHIP,GA    I48 @BASEBOARD_FAB2_LIB.BASEBOARD_FAB2(SCH_1):PAGE168

FM_USB_P0_EN_BOOT_BIOS_STRAP_N @BASEBOARD_FAB2_LIB.BASEBOARD_FAB2(SCH_1):FM_USB_P0_EN_BOOT_BIOS_STRAP_N
  U7C1 BR17 GPP_B22 LBG_CORE_QAT_EXT_D_BGA1-IC,H91A   I115 @BASEBOARD_FAB2_LIB.BASEBOARD_FAB2(SCH_1):PAGE119
 R2N14    2      B RES_0402-1.00K,1%,1/16W,EMPTY,A    I83 @BASEBOARD_FAB2_LIB.BASEBOARD_FAB2(SCH_1):PAGE125
 R1W13    1      A RES_0402-0.0,5%,1/16W,CHIP,G21A   I138 @BASEBOARD_FAB2_LIB.BASEBOARD_FAB2(SCH_1):PAGE176

FM_USB_P0_EN_R_N @BASEBOARD_FAB2_LIB.BASEBOARD_FAB2(SCH_1):FM_USB_P0_EN_R_N
  U1M3    4   EN_N TPS2061_SM-IC,H66405-001   I100 @BASEBOARD_FAB2_LIB.BASEBOARD_FAB2(SCH_1):PAGE176
 R1M25    1      A RES_0402-10.0K,1%,1/16W,CHIP,GA   I111 @BASEBOARD_FAB2_LIB.BASEBOARD_FAB2(SCH_1):PAGE176
 R1W12    2      B RES_0402-0.0,5%,1/16W,CHIP,G21A   I137 @BASEBOARD_FAB2_LIB.BASEBOARD_FAB2(SCH_1):PAGE176
 R1W13    2      B RES_0402-0.0,5%,1/16W,CHIP,G21A   I138 @BASEBOARD_FAB2_LIB.BASEBOARD_FAB2(SCH_1):PAGE176

FM_UV_ADR_TRIGGER_EN @BASEBOARD_FAB2_LIB.BASEBOARD_FAB2(SCH_1):FM_UV_ADR_TRIGGER_EN
  U7C1 BL15 GPP_B18 LBG_CORE_QAT_EXT_D_BGA1-IC,H91A   I115 @BASEBOARD_FAB2_LIB.BASEBOARD_FAB2(SCH_1):PAGE119
  U8D7  H12   PR5D LCMXO2_A_256BGA-IC,H63395-001    I59 @BASEBOARD_FAB2_LIB.BASEBOARD_FAB2(SCH_1):PAGE191
 U25W4  C16 GPIOI3_SYSMISO AST2520A1-GP-GP_ASIC2-GB1-AST2A    I95 @BASEBOARD_FAB2_LIB.BASEBOARD_FAB2(SCH_1):PAGE144
 R2U30    2      B RES_0402-4.75K,1%,1/16W,EMPTY,A    I88 @BASEBOARD_FAB2_LIB.BASEBOARD_FAB2(SCH_1):PAGE125

FM_UV_ADR_TRIGGER_N @BASEBOARD_FAB2_LIB.BASEBOARD_FAB2(SCH_1):FM_UV_ADR_TRIGGER_N
  U8D7  G15   PR5A LCMXO2_A_256BGA-IC,H63395-001    I59 @BASEBOARD_FAB2_LIB.BASEBOARD_FAB2(SCH_1):PAGE191
  R9P6    2      B RES_0402-10.0K,1%,1/16W,CHIP,GA   I149 @BASEBOARD_FAB2_LIB.BASEBOARD_FAB2(SCH_1):PAGE200
  U9P1    6   OUTA TPS3700_SM-IC,H69492-001   I163 @BASEBOARD_FAB2_LIB.BASEBOARD_FAB2(SCH_1):PAGE200
 CR9P2    1      C DIODE_SMLF-BAT54WS,IC,C73510-0A   I213 @BASEBOARD_FAB2_LIB.BASEBOARD_FAB2(SCH_1):PAGE200

FM_WBG_PRSNT_N @BASEBOARD_FAB2_LIB.BASEBOARD_FAB2(SCH_1):FM_WBG_PRSNT_N
  U7C1   D8 RSVD<10> LBG_CORE_QAT_EXT_D_BGA1-IC,H91A    I34 @BASEBOARD_FAB2_LIB.BASEBOARD_FAB2(SCH_1):PAGE121
  R7C8    2      B RES_0402-10.0K,1%,1/16W,CHIP,GA   I296 @BASEBOARD_FAB2_LIB.BASEBOARD_FAB2(SCH_1):PAGE133
  U8D7  G11   PR5C LCMXO2_A_256BGA-IC,H63395-001    I59 @BASEBOARD_FAB2_LIB.BASEBOARD_FAB2(SCH_1):PAGE191

FM_XRC_PRESENT_N @BASEBOARD_FAB2_LIB.BASEBOARD_FAB2(SCH_1):FM_XRC_PRESENT_N
  U7C1 BW48 GPP_D17 LBG_CORE_QAT_EXT_D_BGA1-IC,H91A   I115 @BASEBOARD_FAB2_LIB.BASEBOARD_FAB2(SCH_1):PAGE119
 R8B23    2      B RES_0402-1.00K,1%,1/16W,CHIP,GA   I280 @BASEBOARD_FAB2_LIB.BASEBOARD_FAB2(SCH_1):PAGE133
 U25W4  AA4 GPIOO6_TACH6_VPIR4 AST2520A1-GP-GP_ASIC2-GB1-AST2A   I106 @BASEBOARD_FAB2_LIB.BASEBOARD_FAB2(SCH_1):PAGE147
  J1C1   G5 MB_SLOT_ID1 DM-FCI-CONN76-8R-GP-U-01_CONN-A    I79 @BASEBOARD_FAB2_LIB.BASEBOARD_FAB2(SCH_1):PAGE182

FM_XRC_READY_N @BASEBOARD_FAB2_LIB.BASEBOARD_FAB2(SCH_1):FM_XRC_READY_N
  U7C1 CA41 GPP_D18 LBG_CORE_QAT_EXT_D_BGA1-IC,H91A   I115 @BASEBOARD_FAB2_LIB.BASEBOARD_FAB2(SCH_1):PAGE119
 R8B30    2      B RES_0402-1.00K,1%,1/16W,CHIP,GA   I282 @BASEBOARD_FAB2_LIB.BASEBOARD_FAB2(SCH_1):PAGE133
 U25W4   W4 GPIOO7_TACH7_VPIR5 AST2520A1-GP-GP_ASIC2-GB1-AST2A   I106 @BASEBOARD_FAB2_LIB.BASEBOARD_FAB2(SCH_1):PAGE147
 R1C31    1      A RES_0402-0.0,5%,1/16W,EMPTY,G2A     I6 @BASEBOARD_FAB2_LIB.BASEBOARD_FAB2(SCH_1):PAGE182
  J1C1   H5 MB_SLOT_ID2 DM-FCI-CONN76-8R-GP-U-01_CONN-A    I79 @BASEBOARD_FAB2_LIB.BASEBOARD_FAB2(SCH_1):PAGE182

FP_ID_LED_P5V_STBY_N @BASEBOARD_FAB2_LIB.BASEBOARD_FAB2(SCH_1):FP_ID_LED_P5V_STBY_N
 DS9A1    1      C LED_1NC-BLUE,IC,C96565-012    I50 @BASEBOARD_FAB2_LIB.BASEBOARD_FAB2(SCH_1):PAGE175
  U1L2    4      Y TTL1G86_SOTLF-74AHCT1G86,IC,D3B    I57 @BASEBOARD_FAB2_LIB.BASEBOARD_FAB2(SCH_1):PAGE175

FP_ID_LED_XOR_R @BASEBOARD_FAB2_LIB.BASEBOARD_FAB2(SCH_1):FP_ID_LED_XOR_R
 DS9A1    2      A LED_1NC-BLUE,IC,C96565-012    I50 @BASEBOARD_FAB2_LIB.BASEBOARD_FAB2(SCH_1):PAGE175
  R1L8    2      B RES_0402-470.0,5%,1/16W,CHIP,GA    I58 @BASEBOARD_FAB2_LIB.BASEBOARD_FAB2(SCH_1):PAGE175

FP_LED_HDD_ACTIVITY_AND_N @BASEBOARD_FAB2_LIB.BASEBOARD_FAB2(SCH_1):FP_LED_HDD_ACTIVITY_AND_N
 DS9A2    1      C LED_1NCLF-GREEN,IC,C96565-011    I42 @BASEBOARD_FAB2_LIB.BASEBOARD_FAB2(SCH_1):PAGE177
  U1M1    4   Y<0> TTL1G08_SOTLF-NC7SZ08,IC,D1032C    I70 @BASEBOARD_FAB2_LIB.BASEBOARD_FAB2(SCH_1):PAGE177

FP_LED_HDD_ACTIVITY_AND_R_N @BASEBOARD_FAB2_LIB.BASEBOARD_FAB2(SCH_1):FP_LED_HDD_ACTIVITY_AND_R_N
 DS9A2    2      A LED_1NCLF-GREEN,IC,C96565-011    I42 @BASEBOARD_FAB2_LIB.BASEBOARD_FAB2(SCH_1):PAGE177
 R1L21    2      B RES_0402-64.9,1.0%,1/16W,CHIP,A    I43 @BASEBOARD_FAB2_LIB.BASEBOARD_FAB2(SCH_1):PAGE177

FP_NMI_BTN @BASEBOARD_FAB2_LIB.BASEBOARD_FAB2(SCH_1):FP_NMI_BTN
  U2R1    1     1A TC7PZ14FU-GP_DISCRET-GA1-TC7PZA   I390 @BASEBOARD_FAB2_LIB.BASEBOARD_FAB2(SCH_1):PAGE157
  U2R1    4     2Y TC7PZ14FU-GP_DISCRET-GA1-TC7PZA   I390 @BASEBOARD_FAB2_LIB.BASEBOARD_FAB2(SCH_1):PAGE157

FP_NMI_BTN_N @BASEBOARD_FAB2_LIB.BASEBOARD_FAB2(SCH_1):FP_NMI_BTN_N
  U7C1 BN11 GPP_B8_SRCCLKREQ3_N LBG_CORE_QAT_EXT_D_BGA1-IC,H91A   I115 @BASEBOARD_FAB2_LIB.BASEBOARD_FAB2(SCH_1):PAGE119
 R8F24    2      B RES_0402-4.75K,1%,1/16W,CHIP,GA   I316 @BASEBOARD_FAB2_LIB.BASEBOARD_FAB2(SCH_1):PAGE157
 U25W4  E18 GPIOE4_NDTR3 AST2520A1-GP-GP_ASIC2-GB1-AST2A   I117 @BASEBOARD_FAB2_LIB.BASEBOARD_FAB2(SCH_1):PAGE145
 R2R10    2      B RES_0402-33.2,1%,1/16W,CHIP,G2A   I391 @BASEBOARD_FAB2_LIB.BASEBOARD_FAB2(SCH_1):PAGE157

FP_NMI_BTN_OUT_N @BASEBOARD_FAB2_LIB.BASEBOARD_FAB2(SCH_1):FP_NMI_BTN_OUT_N
  R2R9    2      B RES_0402-200.0,1%,1/16W,CHIP,GA   I352 @BASEBOARD_FAB2_LIB.BASEBOARD_FAB2(SCH_1):PAGE157
 C2R12    1      A CAP_A_0402V-1.0UF,6.3V,10%,X6SA   I353 @BASEBOARD_FAB2_LIB.BASEBOARD_FAB2(SCH_1):PAGE157
  U2R1    3     2A TC7PZ14FU-GP_DISCRET-GA1-TC7PZA   I390 @BASEBOARD_FAB2_LIB.BASEBOARD_FAB2(SCH_1):PAGE157

FP_NMI_BTN_OUT_R_N @BASEBOARD_FAB2_LIB.BASEBOARD_FAB2(SCH_1):FP_NMI_BTN_OUT_R_N
  S8E1    2      B SWITCH_D90553001_SMLF-IC,D9055A   I351 @BASEBOARD_FAB2_LIB.BASEBOARD_FAB2(SCH_1):PAGE157
  R2R9    1      A RES_0402-200.0,1%,1/16W,CHIP,GA   I352 @BASEBOARD_FAB2_LIB.BASEBOARD_FAB2(SCH_1):PAGE157
 R8E32    2      B RES_0402-4.75K,1%,1/16W,CHIP,GA   I385 @BASEBOARD_FAB2_LIB.BASEBOARD_FAB2(SCH_1):PAGE157

FP_NMI_BTN_R_N @BASEBOARD_FAB2_LIB.BASEBOARD_FAB2(SCH_1):FP_NMI_BTN_R_N
  U2R1    6     1Y TC7PZ14FU-GP_DISCRET-GA1-TC7PZA   I390 @BASEBOARD_FAB2_LIB.BASEBOARD_FAB2(SCH_1):PAGE157
 R2R10    1      A RES_0402-33.2,1%,1/16W,CHIP,G2A   I391 @BASEBOARD_FAB2_LIB.BASEBOARD_FAB2(SCH_1):PAGE157

FP_PWR_BTN_BUF1_N @BASEBOARD_FAB2_LIB.BASEBOARD_FAB2(SCH_1):FP_PWR_BTN_BUF1_N
  U9A4    6     1Y TC7PZ14FU-GP_DISCRET-GA1-TC7PZA    I97 @BASEBOARD_FAB2_LIB.BASEBOARD_FAB2(SCH_1):PAGE175
  U9A4    3     2A TC7PZ14FU-GP_DISCRET-GA1-TC7PZA    I97 @BASEBOARD_FAB2_LIB.BASEBOARD_FAB2(SCH_1):PAGE175

FP_PWR_BTN_R1_N @BASEBOARD_FAB2_LIB.BASEBOARD_FAB2(SCH_1):FP_PWR_BTN_R1_N
 R1L31    2      B RES_0402-200.0,1%,1/16W,CHIP,GA     I4 @BASEBOARD_FAB2_LIB.BASEBOARD_FAB2(SCH_1):PAGE175
 C1L18    1      A CAP_A_0402V-1.0UF,6.3V,10%,X6SA    I11 @BASEBOARD_FAB2_LIB.BASEBOARD_FAB2(SCH_1):PAGE175
  U9A4    1     1A TC7PZ14FU-GP_DISCRET-GA1-TC7PZA    I97 @BASEBOARD_FAB2_LIB.BASEBOARD_FAB2(SCH_1):PAGE175

FP_PWR_BTN_R_N @BASEBOARD_FAB2_LIB.BASEBOARD_FAB2(SCH_1):FP_PWR_BTN_R_N
 R1L31    1      A RES_0402-200.0,1%,1/16W,CHIP,GA     I4 @BASEBOARD_FAB2_LIB.BASEBOARD_FAB2(SCH_1):PAGE175
 R1L27    2      B RES_0402-4.75K,1%,1/16W,CHIP,GA     I5 @BASEBOARD_FAB2_LIB.BASEBOARD_FAB2(SCH_1):PAGE175
  S9A2    3   PIN3 SWITCH_D37771002_SM-IC,D37771-A    I92 @BASEBOARD_FAB2_LIB.BASEBOARD_FAB2(SCH_1):PAGE175
  S9A2    4   PIN4 SWITCH_D37771002_SM-IC,D37771-A    I92 @BASEBOARD_FAB2_LIB.BASEBOARD_FAB2(SCH_1):PAGE175
  U6W1   14    P11 TCA9555PWR-GP_DISCRET-GC1-TCA9A   I120 @BASEBOARD_FAB2_LIB.BASEBOARD_FAB2(SCH_1):PAGE247

FP_PWR_ID_LED_N @BASEBOARD_FAB2_LIB.BASEBOARD_FAB2(SCH_1):FP_PWR_ID_LED_N
  U7C1  BD3 GPP_H19_SSATAXPCIE1_SSATAGP1 LBG_CORE_QAT_EXT_D_BGA1-IC,H91A   I147 @BASEBOARD_FAB2_LIB.BASEBOARD_FAB2(SCH_1):PAGE120
 R8D14    2      B RES_0402-4.75K,1%,1/16W,CHIP,GA   I301 @BASEBOARD_FAB2_LIB.BASEBOARD_FAB2(SCH_1):PAGE133
  U1L2    2      B TTL1G86_SOTLF-74AHCT1G86,IC,D3B    I57 @BASEBOARD_FAB2_LIB.BASEBOARD_FAB2(SCH_1):PAGE175
 U25W4  Y22 GPIOAA2_VPOR4_NORD2_SALT9 AST2520A1-GP-GP_ASIC2-GB1-AST2A   I104 @BASEBOARD_FAB2_LIB.BASEBOARD_FAB2(SCH_1):PAGE146

FP_RST_BTN_BUF1_N @BASEBOARD_FAB2_LIB.BASEBOARD_FAB2(SCH_1):FP_RST_BTN_BUF1_N
  U9A3    6     1Y TC7PZ14FU-GP_DISCRET-GA1-TC7PZA    I93 @BASEBOARD_FAB2_LIB.BASEBOARD_FAB2(SCH_1):PAGE175
  U9A3    3     2A TC7PZ14FU-GP_DISCRET-GA1-TC7PZA    I93 @BASEBOARD_FAB2_LIB.BASEBOARD_FAB2(SCH_1):PAGE175

FP_RST_BTN_R_N @BASEBOARD_FAB2_LIB.BASEBOARD_FAB2(SCH_1):FP_RST_BTN_R_N
 C1L10    1      A CAP_A_0402V-1.0UF,6.3V,10%,X6SA    I19 @BASEBOARD_FAB2_LIB.BASEBOARD_FAB2(SCH_1):PAGE175
 R1L22    2      B RES_0402-200.0,1%,1/16W,CHIP,GA    I22 @BASEBOARD_FAB2_LIB.BASEBOARD_FAB2(SCH_1):PAGE175
  U9A3    1     1A TC7PZ14FU-GP_DISCRET-GA1-TC7PZA    I93 @BASEBOARD_FAB2_LIB.BASEBOARD_FAB2(SCH_1):PAGE175

GND @BASEBOARD_FAB2_LIB.BASEBOARD_FAB2(SCH_1):GND
  R5D1    2      B RES_0402-90.9,1%,1/16W,CHIP,G2A   I177 @BASEBOARD_FAB2_LIB.BASEBOARD_FAB2(SCH_1):PAGE21
  R5D2    2      B RES_0402-90.9,1%,1/16W,CHIP,G2A   I178 @BASEBOARD_FAB2_LIB.BASEBOARD_FAB2(SCH_1):PAGE21
  R6D1    2      B RES_0402-100.0,1%,1/16W,CHIP,GA   I179 @BASEBOARD_FAB2_LIB.BASEBOARD_FAB2(SCH_1):PAGE21
  R4P8    2      B RES_0402-90.9,1%,1/16W,CHIP,G2A   I180 @BASEBOARD_FAB2_LIB.BASEBOARD_FAB2(SCH_1):PAGE21
 R4P10    2      B RES_0402-90.9,1%,1/16W,CHIP,G2A   I181 @BASEBOARD_FAB2_LIB.BASEBOARD_FAB2(SCH_1):PAGE21
 R4P11    2      B RES_0402-100.0,1%,1/16W,CHIP,GA   I182 @BASEBOARD_FAB2_LIB.BASEBOARD_FAB2(SCH_1):PAGE21
 R6D11    2      B RES_0402-49.9,1%,1/16W,CHIP,G2A   I184 @BASEBOARD_FAB2_LIB.BASEBOARD_FAB2(SCH_1):PAGE21
  R4P3    2      B RES_0402-49.9,1%,1/16W,CHIP,G2A   I186 @BASEBOARD_FAB2_LIB.BASEBOARD_FAB2(SCH_1):PAGE21
  R4P2    2      B RES_0402-49.9,1%,1/16W,CHIP,G2A   I188 @BASEBOARD_FAB2_LIB.BASEBOARD_FAB2(SCH_1):PAGE21
  R4P4    2      B RES_0402-49.9,1%,1/16W,CHIP,G2A   I189 @BASEBOARD_FAB2_LIB.BASEBOARD_FAB2(SCH_1):PAGE21
  R6D2    2      B RES_0402-49.9,1%,1/16W,CHIP,G2A   I204 @BASEBOARD_FAB2_LIB.BASEBOARD_FAB2(SCH_1):PAGE21
  R5R1    2      B RES_0402-49.9,1%,1/16W,CHIP,G2A   I188 @BASEBOARD_FAB2_LIB.BASEBOARD_FAB2(SCH_1):PAGE22
  R5P4    2      B RES_0402-49.9,1%,1/16W,CHIP,G2A   I190 @BASEBOARD_FAB2_LIB.BASEBOARD_FAB2(SCH_1):PAGE22
  U5D1 DF23 UPI2_RX_DN<0> SKX_EXT_B_BGA1-IC,TBD     I3 @BASEBOARD_FAB2_LIB.BASEBOARD_FAB2(SCH_1):PAGE35
  U5D1 DE22 UPI2_RX_DN<1> SKX_EXT_B_BGA1-IC,TBD     I3 @BASEBOARD_FAB2_LIB.BASEBOARD_FAB2(SCH_1):PAGE35
  U5D1 DC22 UPI2_RX_DN<2> SKX_EXT_B_BGA1-IC,TBD     I3 @BASEBOARD_FAB2_LIB.BASEBOARD_FAB2(SCH_1):PAGE35
  U5D1 DB21 UPI2_RX_DN<3> SKX_EXT_B_BGA1-IC,TBD     I3 @BASEBOARD_FAB2_LIB.BASEBOARD_FAB2(SCH_1):PAGE35
  U5D1 DD19 UPI2_RX_DN<4> SKX_EXT_B_BGA1-IC,TBD     I3 @BASEBOARD_FAB2_LIB.BASEBOARD_FAB2(SCH_1):PAGE35
  U5D1 DA20 UPI2_RX_DN<5> SKX_EXT_B_BGA1-IC,TBD     I3 @BASEBOARD_FAB2_LIB.BASEBOARD_FAB2(SCH_1):PAGE35
  U5D1 CW20 UPI2_RX_DN<6> SKX_EXT_B_BGA1-IC,TBD     I3 @BASEBOARD_FAB2_LIB.BASEBOARD_FAB2(SCH_1):PAGE35
  U5D1 CV19 UPI2_RX_DN<7> SKX_EXT_B_BGA1-IC,TBD     I3 @BASEBOARD_FAB2_LIB.BASEBOARD_FAB2(SCH_1):PAGE35
  U5D1 CT21 UPI2_RX_DN<8> SKX_EXT_B_BGA1-IC,TBD     I3 @BASEBOARD_FAB2_LIB.BASEBOARD_FAB2(SCH_1):PAGE35
  U5D1 CR18 UPI2_RX_DN<9> SKX_EXT_B_BGA1-IC,TBD     I3 @BASEBOARD_FAB2_LIB.BASEBOARD_FAB2(SCH_1):PAGE35
  U5D1 CN20 UPI2_RX_DN<10> SKX_EXT_B_BGA1-IC,TBD     I3 @BASEBOARD_FAB2_LIB.BASEBOARD_FAB2(SCH_1):PAGE35
  U5D1 CP21 UPI2_RX_DN<11> SKX_EXT_B_BGA1-IC,TBD     I3 @BASEBOARD_FAB2_LIB.BASEBOARD_FAB2(SCH_1):PAGE35
  U5D1 CL16 UPI2_RX_DN<12> SKX_EXT_B_BGA1-IC,TBD     I3 @BASEBOARD_FAB2_LIB.BASEBOARD_FAB2(SCH_1):PAGE35
  U5D1 CJ18 UPI2_RX_DN<13> SKX_EXT_B_BGA1-IC,TBD     I3 @BASEBOARD_FAB2_LIB.BASEBOARD_FAB2(SCH_1):PAGE35
  U5D1 CH17 UPI2_RX_DN<14> SKX_EXT_B_BGA1-IC,TBD     I3 @BASEBOARD_FAB2_LIB.BASEBOARD_FAB2(SCH_1):PAGE35
  U5D1 CE16 UPI2_RX_DN<15> SKX_EXT_B_BGA1-IC,TBD     I3 @BASEBOARD_FAB2_LIB.BASEBOARD_FAB2(SCH_1):PAGE35
  U5D1 CD15 UPI2_RX_DN<16> SKX_EXT_B_BGA1-IC,TBD     I3 @BASEBOARD_FAB2_LIB.BASEBOARD_FAB2(SCH_1):PAGE35
  U5D1 CF17 UPI2_RX_DN<17> SKX_EXT_B_BGA1-IC,TBD     I3 @BASEBOARD_FAB2_LIB.BASEBOARD_FAB2(SCH_1):PAGE35
  U5D1 CB15 UPI2_RX_DN<18> SKX_EXT_B_BGA1-IC,TBD     I3 @BASEBOARD_FAB2_LIB.BASEBOARD_FAB2(SCH_1):PAGE35
  U5D1 BY17 UPI2_RX_DN<19> SKX_EXT_B_BGA1-IC,TBD     I3 @BASEBOARD_FAB2_LIB.BASEBOARD_FAB2(SCH_1):PAGE35
  U5D1 DG22 UPI2_RX_DP<0> SKX_EXT_B_BGA1-IC,TBD     I3 @BASEBOARD_FAB2_LIB.BASEBOARD_FAB2(SCH_1):PAGE35
  U5D1 DD21 UPI2_RX_DP<1> SKX_EXT_B_BGA1-IC,TBD     I3 @BASEBOARD_FAB2_LIB.BASEBOARD_FAB2(SCH_1):PAGE35
  U5D1 DA22 UPI2_RX_DP<2> SKX_EXT_B_BGA1-IC,TBD     I3 @BASEBOARD_FAB2_LIB.BASEBOARD_FAB2(SCH_1):PAGE35
  U5D1 DC20 UPI2_RX_DP<3> SKX_EXT_B_BGA1-IC,TBD     I3 @BASEBOARD_FAB2_LIB.BASEBOARD_FAB2(SCH_1):PAGE35
  U5D1 DB19 UPI2_RX_DP<4> SKX_EXT_B_BGA1-IC,TBD     I3 @BASEBOARD_FAB2_LIB.BASEBOARD_FAB2(SCH_1):PAGE35
  U5D1 CY19 UPI2_RX_DP<5> SKX_EXT_B_BGA1-IC,TBD     I3 @BASEBOARD_FAB2_LIB.BASEBOARD_FAB2(SCH_1):PAGE35
  U5D1 CU20 UPI2_RX_DP<6> SKX_EXT_B_BGA1-IC,TBD     I3 @BASEBOARD_FAB2_LIB.BASEBOARD_FAB2(SCH_1):PAGE35
  U5D1 CW18 UPI2_RX_DP<7> SKX_EXT_B_BGA1-IC,TBD     I3 @BASEBOARD_FAB2_LIB.BASEBOARD_FAB2(SCH_1):PAGE35
  U5D1 CR20 UPI2_RX_DP<8> SKX_EXT_B_BGA1-IC,TBD     I3 @BASEBOARD_FAB2_LIB.BASEBOARD_FAB2(SCH_1):PAGE35
  U5D1 CN18 UPI2_RX_DP<9> SKX_EXT_B_BGA1-IC,TBD     I3 @BASEBOARD_FAB2_LIB.BASEBOARD_FAB2(SCH_1):PAGE35
  U5D1 CP19 UPI2_RX_DP<10> SKX_EXT_B_BGA1-IC,TBD     I3 @BASEBOARD_FAB2_LIB.BASEBOARD_FAB2(SCH_1):PAGE35
  U5D1 CM21 UPI2_RX_DP<11> SKX_EXT_B_BGA1-IC,TBD     I3 @BASEBOARD_FAB2_LIB.BASEBOARD_FAB2(SCH_1):PAGE35
  U5D1 CJ16 UPI2_RX_DP<12> SKX_EXT_B_BGA1-IC,TBD     I3 @BASEBOARD_FAB2_LIB.BASEBOARD_FAB2(SCH_1):PAGE35
  U5D1 CK17 UPI2_RX_DP<13> SKX_EXT_B_BGA1-IC,TBD     I3 @BASEBOARD_FAB2_LIB.BASEBOARD_FAB2(SCH_1):PAGE35
  U5D1 CG16 UPI2_RX_DP<14> SKX_EXT_B_BGA1-IC,TBD     I3 @BASEBOARD_FAB2_LIB.BASEBOARD_FAB2(SCH_1):PAGE35
  U5D1 CF15 UPI2_RX_DP<15> SKX_EXT_B_BGA1-IC,TBD     I3 @BASEBOARD_FAB2_LIB.BASEBOARD_FAB2(SCH_1):PAGE35
  U5D1 CC14 UPI2_RX_DP<16> SKX_EXT_B_BGA1-IC,TBD     I3 @BASEBOARD_FAB2_LIB.BASEBOARD_FAB2(SCH_1):PAGE35
  U5D1 CD17 UPI2_RX_DP<17> SKX_EXT_B_BGA1-IC,TBD     I3 @BASEBOARD_FAB2_LIB.BASEBOARD_FAB2(SCH_1):PAGE35
  U5D1 BY15 UPI2_RX_DP<18> SKX_EXT_B_BGA1-IC,TBD     I3 @BASEBOARD_FAB2_LIB.BASEBOARD_FAB2(SCH_1):PAGE35
  U5D1 CA16 UPI2_RX_DP<19> SKX_EXT_B_BGA1-IC,TBD     I3 @BASEBOARD_FAB2_LIB.BASEBOARD_FAB2(SCH_1):PAGE35
  R5D5    2      B RES_0402-249,0.1%,1/16W,CHIP,GA   I303 @BASEBOARD_FAB2_LIB.BASEBOARD_FAB2(SCH_1):PAGE37
  C6D1    2      B CAP_0603LF-10UF,4V,20%,X6S,E15A    I19 @BASEBOARD_FAB2_LIB.BASEBOARD_FAB2(SCH_1):PAGE38
  U5D1  J74 VSS<1094> SKX_EXT_B_BGA1-IC,TBD    I20 @BASEBOARD_FAB2_LIB.BASEBOARD_FAB2(SCH_1):PAGE40
  U5D1  J72 VSS<1095> SKX_EXT_B_BGA1-IC,TBD    I20 @BASEBOARD_FAB2_LIB.BASEBOARD_FAB2(SCH_1):PAGE40
  U5D1  J40 VSS<1096> SKX_EXT_B_BGA1-IC,TBD    I20 @BASEBOARD_FAB2_LIB.BASEBOARD_FAB2(SCH_1):PAGE40
  U5D1  J38 VSS<1097> SKX_EXT_B_BGA1-IC,TBD    I20 @BASEBOARD_FAB2_LIB.BASEBOARD_FAB2(SCH_1):PAGE40
  U5D1  J34 VSS<1098> SKX_EXT_B_BGA1-IC,TBD    I20 @BASEBOARD_FAB2_LIB.BASEBOARD_FAB2(SCH_1):PAGE40
  U5D1  J32 VSS<1099> SKX_EXT_B_BGA1-IC,TBD    I20 @BASEBOARD_FAB2_LIB.BASEBOARD_FAB2(SCH_1):PAGE40
  U5D1  J28 VSS<1100> SKX_EXT_B_BGA1-IC,TBD    I20 @BASEBOARD_FAB2_LIB.BASEBOARD_FAB2(SCH_1):PAGE40
  U5D1  J26 VSS<1101> SKX_EXT_B_BGA1-IC,TBD    I20 @BASEBOARD_FAB2_LIB.BASEBOARD_FAB2(SCH_1):PAGE40
  U5D1  J22 VSS<1102> SKX_EXT_B_BGA1-IC,TBD    I20 @BASEBOARD_FAB2_LIB.BASEBOARD_FAB2(SCH_1):PAGE40
  U5D1  J14 VSS<1103> SKX_EXT_B_BGA1-IC,TBD    I20 @BASEBOARD_FAB2_LIB.BASEBOARD_FAB2(SCH_1):PAGE40
  U5D1  J12 VSS<1104> SKX_EXT_B_BGA1-IC,TBD    I20 @BASEBOARD_FAB2_LIB.BASEBOARD_FAB2(SCH_1):PAGE40
  U5D1   J4 VSS<1105> SKX_EXT_B_BGA1-IC,TBD    I20 @BASEBOARD_FAB2_LIB.BASEBOARD_FAB2(SCH_1):PAGE40
  U5D1 DN44 VSS<1106> SKX_EXT_B_BGA1-IC,TBD    I20 @BASEBOARD_FAB2_LIB.BASEBOARD_FAB2(SCH_1):PAGE40
  U5D1  H75 VSS<1107> SKX_EXT_B_BGA1-IC,TBD    I20 @BASEBOARD_FAB2_LIB.BASEBOARD_FAB2(SCH_1):PAGE40
  U5D1  H71 VSS<1108> SKX_EXT_B_BGA1-IC,TBD    I20 @BASEBOARD_FAB2_LIB.BASEBOARD_FAB2(SCH_1):PAGE40
  U5D1  H65 VSS<1109> SKX_EXT_B_BGA1-IC,TBD    I20 @BASEBOARD_FAB2_LIB.BASEBOARD_FAB2(SCH_1):PAGE40
  U5D1  H41 VSS<1110> SKX_EXT_B_BGA1-IC,TBD    I20 @BASEBOARD_FAB2_LIB.BASEBOARD_FAB2(SCH_1):PAGE40
  U5D1  H39 VSS<1111> SKX_EXT_B_BGA1-IC,TBD    I20 @BASEBOARD_FAB2_LIB.BASEBOARD_FAB2(SCH_1):PAGE40
  U5D1  H37 VSS<1112> SKX_EXT_B_BGA1-IC,TBD    I20 @BASEBOARD_FAB2_LIB.BASEBOARD_FAB2(SCH_1):PAGE40
  U5D1  H35 VSS<1113> SKX_EXT_B_BGA1-IC,TBD    I20 @BASEBOARD_FAB2_LIB.BASEBOARD_FAB2(SCH_1):PAGE40
  U5D1  H33 VSS<1114> SKX_EXT_B_BGA1-IC,TBD    I20 @BASEBOARD_FAB2_LIB.BASEBOARD_FAB2(SCH_1):PAGE40
  U5D1  H31 VSS<1115> SKX_EXT_B_BGA1-IC,TBD    I20 @BASEBOARD_FAB2_LIB.BASEBOARD_FAB2(SCH_1):PAGE40
  U5D1  H29 VSS<1116> SKX_EXT_B_BGA1-IC,TBD    I20 @BASEBOARD_FAB2_LIB.BASEBOARD_FAB2(SCH_1):PAGE40
  U5D1  H27 VSS<1117> SKX_EXT_B_BGA1-IC,TBD    I20 @BASEBOARD_FAB2_LIB.BASEBOARD_FAB2(SCH_1):PAGE40
  U5D1  H25 VSS<1118> SKX_EXT_B_BGA1-IC,TBD    I20 @BASEBOARD_FAB2_LIB.BASEBOARD_FAB2(SCH_1):PAGE40
  U5D1  H11 VSS<1119> SKX_EXT_B_BGA1-IC,TBD    I20 @BASEBOARD_FAB2_LIB.BASEBOARD_FAB2(SCH_1):PAGE40
  U5D1   H3 VSS<1120> SKX_EXT_B_BGA1-IC,TBD    I20 @BASEBOARD_FAB2_LIB.BASEBOARD_FAB2(SCH_1):PAGE40
  U5D1  G82 VSS<1121> SKX_EXT_B_BGA1-IC,TBD    I20 @BASEBOARD_FAB2_LIB.BASEBOARD_FAB2(SCH_1):PAGE40
  U5D1  G80 VSS<1122> SKX_EXT_B_BGA1-IC,TBD    I20 @BASEBOARD_FAB2_LIB.BASEBOARD_FAB2(SCH_1):PAGE40
  U5D1  G78 VSS<1123> SKX_EXT_B_BGA1-IC,TBD    I20 @BASEBOARD_FAB2_LIB.BASEBOARD_FAB2(SCH_1):PAGE40
  U5D1  G76 VSS<1124> SKX_EXT_B_BGA1-IC,TBD    I20 @BASEBOARD_FAB2_LIB.BASEBOARD_FAB2(SCH_1):PAGE40
  U5D1  G70 VSS<1125> SKX_EXT_B_BGA1-IC,TBD    I20 @BASEBOARD_FAB2_LIB.BASEBOARD_FAB2(SCH_1):PAGE40
  U5D1  G66 VSS<1126> SKX_EXT_B_BGA1-IC,TBD    I20 @BASEBOARD_FAB2_LIB.BASEBOARD_FAB2(SCH_1):PAGE40
  U5D1  G42 VSS<1127> SKX_EXT_B_BGA1-IC,TBD    I20 @BASEBOARD_FAB2_LIB.BASEBOARD_FAB2(SCH_1):PAGE40
  U5D1  G38 VSS<1128> SKX_EXT_B_BGA1-IC,TBD    I20 @BASEBOARD_FAB2_LIB.BASEBOARD_FAB2(SCH_1):PAGE40
  U5D1  G36 VSS<1129> SKX_EXT_B_BGA1-IC,TBD    I20 @BASEBOARD_FAB2_LIB.BASEBOARD_FAB2(SCH_1):PAGE40
  U5D1  G32 VSS<1130> SKX_EXT_B_BGA1-IC,TBD    I20 @BASEBOARD_FAB2_LIB.BASEBOARD_FAB2(SCH_1):PAGE40
  U5D1  G30 VSS<1131> SKX_EXT_B_BGA1-IC,TBD    I20 @BASEBOARD_FAB2_LIB.BASEBOARD_FAB2(SCH_1):PAGE40
  U5D1  G26 VSS<1132> SKX_EXT_B_BGA1-IC,TBD    I20 @BASEBOARD_FAB2_LIB.BASEBOARD_FAB2(SCH_1):PAGE40
  U5D1  G24 VSS<1133> SKX_EXT_B_BGA1-IC,TBD    I20 @BASEBOARD_FAB2_LIB.BASEBOARD_FAB2(SCH_1):PAGE40
  U5D1  G22 VSS<1134> SKX_EXT_B_BGA1-IC,TBD    I20 @BASEBOARD_FAB2_LIB.BASEBOARD_FAB2(SCH_1):PAGE40
  U5D1   G8 VSS<1135> SKX_EXT_B_BGA1-IC,TBD    I20 @BASEBOARD_FAB2_LIB.BASEBOARD_FAB2(SCH_1):PAGE40
  U5D1   G4 VSS<1136> SKX_EXT_B_BGA1-IC,TBD    I20 @BASEBOARD_FAB2_LIB.BASEBOARD_FAB2(SCH_1):PAGE40
  U5D1  F69 VSS<1137> SKX_EXT_B_BGA1-IC,TBD    I20 @BASEBOARD_FAB2_LIB.BASEBOARD_FAB2(SCH_1):PAGE40
  U5D1  F67 VSS<1138> SKX_EXT_B_BGA1-IC,TBD    I20 @BASEBOARD_FAB2_LIB.BASEBOARD_FAB2(SCH_1):PAGE40
  U5D1  F43 VSS<1139> SKX_EXT_B_BGA1-IC,TBD    I20 @BASEBOARD_FAB2_LIB.BASEBOARD_FAB2(SCH_1):PAGE40
  U5D1  F37 VSS<1140> SKX_EXT_B_BGA1-IC,TBD    I20 @BASEBOARD_FAB2_LIB.BASEBOARD_FAB2(SCH_1):PAGE40
  U5D1  F31 VSS<1141> SKX_EXT_B_BGA1-IC,TBD    I20 @BASEBOARD_FAB2_LIB.BASEBOARD_FAB2(SCH_1):PAGE40
  U5D1  F25 VSS<1142> SKX_EXT_B_BGA1-IC,TBD    I20 @BASEBOARD_FAB2_LIB.BASEBOARD_FAB2(SCH_1):PAGE40
  U5D1  F19 VSS<1143> SKX_EXT_B_BGA1-IC,TBD    I20 @BASEBOARD_FAB2_LIB.BASEBOARD_FAB2(SCH_1):PAGE40
  U5D1  F17 VSS<1144> SKX_EXT_B_BGA1-IC,TBD    I20 @BASEBOARD_FAB2_LIB.BASEBOARD_FAB2(SCH_1):PAGE40
  U5D1   F5 VSS<1145> SKX_EXT_B_BGA1-IC,TBD    I20 @BASEBOARD_FAB2_LIB.BASEBOARD_FAB2(SCH_1):PAGE40
  U5D1  E76 VSS<1146> SKX_EXT_B_BGA1-IC,TBD    I20 @BASEBOARD_FAB2_LIB.BASEBOARD_FAB2(SCH_1):PAGE40
  U5D1  E74 VSS<1147> SKX_EXT_B_BGA1-IC,TBD    I20 @BASEBOARD_FAB2_LIB.BASEBOARD_FAB2(SCH_1):PAGE40
  U5D1  E72 VSS<1148> SKX_EXT_B_BGA1-IC,TBD    I20 @BASEBOARD_FAB2_LIB.BASEBOARD_FAB2(SCH_1):PAGE40
  U5D1  E22 VSS<1149> SKX_EXT_B_BGA1-IC,TBD    I20 @BASEBOARD_FAB2_LIB.BASEBOARD_FAB2(SCH_1):PAGE40
  U5D1  E20 VSS<1150> SKX_EXT_B_BGA1-IC,TBD    I20 @BASEBOARD_FAB2_LIB.BASEBOARD_FAB2(SCH_1):PAGE40
  U5D1  E18 VSS<1151> SKX_EXT_B_BGA1-IC,TBD    I20 @BASEBOARD_FAB2_LIB.BASEBOARD_FAB2(SCH_1):PAGE40
  U5D1  E16 VSS<1152> SKX_EXT_B_BGA1-IC,TBD    I20 @BASEBOARD_FAB2_LIB.BASEBOARD_FAB2(SCH_1):PAGE40
  U5D1   E8 VSS<1153> SKX_EXT_B_BGA1-IC,TBD    I20 @BASEBOARD_FAB2_LIB.BASEBOARD_FAB2(SCH_1):PAGE40
  U5D1   E6 VSS<1154> SKX_EXT_B_BGA1-IC,TBD    I20 @BASEBOARD_FAB2_LIB.BASEBOARD_FAB2(SCH_1):PAGE40
  U5D1  D77 VSS<1155> SKX_EXT_B_BGA1-IC,TBD    I20 @BASEBOARD_FAB2_LIB.BASEBOARD_FAB2(SCH_1):PAGE40
  U5D1  D43 VSS<1156> SKX_EXT_B_BGA1-IC,TBD    I20 @BASEBOARD_FAB2_LIB.BASEBOARD_FAB2(SCH_1):PAGE40
  U5D1  D41 VSS<1157> SKX_EXT_B_BGA1-IC,TBD    I20 @BASEBOARD_FAB2_LIB.BASEBOARD_FAB2(SCH_1):PAGE40
  U5D1  D39 VSS<1158> SKX_EXT_B_BGA1-IC,TBD    I20 @BASEBOARD_FAB2_LIB.BASEBOARD_FAB2(SCH_1):PAGE40
  U5D1  D37 VSS<1159> SKX_EXT_B_BGA1-IC,TBD    I20 @BASEBOARD_FAB2_LIB.BASEBOARD_FAB2(SCH_1):PAGE40
  U5D1  D35 VSS<1160> SKX_EXT_B_BGA1-IC,TBD    I20 @BASEBOARD_FAB2_LIB.BASEBOARD_FAB2(SCH_1):PAGE40
  U5D1  D33 VSS<1161> SKX_EXT_B_BGA1-IC,TBD    I20 @BASEBOARD_FAB2_LIB.BASEBOARD_FAB2(SCH_1):PAGE40
  U5D1  D31 VSS<1162> SKX_EXT_B_BGA1-IC,TBD    I20 @BASEBOARD_FAB2_LIB.BASEBOARD_FAB2(SCH_1):PAGE40
  U5D1  D29 VSS<1163> SKX_EXT_B_BGA1-IC,TBD    I20 @BASEBOARD_FAB2_LIB.BASEBOARD_FAB2(SCH_1):PAGE40
  U5D1  D27 VSS<1164> SKX_EXT_B_BGA1-IC,TBD    I20 @BASEBOARD_FAB2_LIB.BASEBOARD_FAB2(SCH_1):PAGE40
  U5D1  D25 VSS<1165> SKX_EXT_B_BGA1-IC,TBD    I20 @BASEBOARD_FAB2_LIB.BASEBOARD_FAB2(SCH_1):PAGE40
  U5D1  D13 VSS<1166> SKX_EXT_B_BGA1-IC,TBD    I20 @BASEBOARD_FAB2_LIB.BASEBOARD_FAB2(SCH_1):PAGE40
  U5D1  D11 VSS<1167> SKX_EXT_B_BGA1-IC,TBD    I20 @BASEBOARD_FAB2_LIB.BASEBOARD_FAB2(SCH_1):PAGE40
  U5D1 CM27 VSS<1168> SKX_EXT_B_BGA1-IC,TBD    I20 @BASEBOARD_FAB2_LIB.BASEBOARD_FAB2(SCH_1):PAGE40
  U5D1  C78 VSS<1169> SKX_EXT_B_BGA1-IC,TBD    I20 @BASEBOARD_FAB2_LIB.BASEBOARD_FAB2(SCH_1):PAGE40
  U5D1  C76 VSS<1170> SKX_EXT_B_BGA1-IC,TBD    I20 @BASEBOARD_FAB2_LIB.BASEBOARD_FAB2(SCH_1):PAGE40
  U5D1  C16 VSS<1171> SKX_EXT_B_BGA1-IC,TBD    I20 @BASEBOARD_FAB2_LIB.BASEBOARD_FAB2(SCH_1):PAGE40
  U5D1  C14 VSS<1172> SKX_EXT_B_BGA1-IC,TBD    I20 @BASEBOARD_FAB2_LIB.BASEBOARD_FAB2(SCH_1):PAGE40
  U5D1  C12 VSS<1173> SKX_EXT_B_BGA1-IC,TBD    I20 @BASEBOARD_FAB2_LIB.BASEBOARD_FAB2(SCH_1):PAGE40
  U5D1  C10 VSS<1174> SKX_EXT_B_BGA1-IC,TBD    I20 @BASEBOARD_FAB2_LIB.BASEBOARD_FAB2(SCH_1):PAGE40
  U5D1   C8 VSS<1175> SKX_EXT_B_BGA1-IC,TBD    I20 @BASEBOARD_FAB2_LIB.BASEBOARD_FAB2(SCH_1):PAGE40
  U5D1  B75 VSS<1176> SKX_EXT_B_BGA1-IC,TBD    I20 @BASEBOARD_FAB2_LIB.BASEBOARD_FAB2(SCH_1):PAGE40
  U5D1  B71 VSS<1177> SKX_EXT_B_BGA1-IC,TBD    I20 @BASEBOARD_FAB2_LIB.BASEBOARD_FAB2(SCH_1):PAGE40
  U5D1  B37 VSS<1178> SKX_EXT_B_BGA1-IC,TBD    I20 @BASEBOARD_FAB2_LIB.BASEBOARD_FAB2(SCH_1):PAGE40
  U5D1  B31 VSS<1179> SKX_EXT_B_BGA1-IC,TBD    I20 @BASEBOARD_FAB2_LIB.BASEBOARD_FAB2(SCH_1):PAGE40
  U5D1  B25 VSS<1180> SKX_EXT_B_BGA1-IC,TBD    I20 @BASEBOARD_FAB2_LIB.BASEBOARD_FAB2(SCH_1):PAGE40
  U5D1  A38 VSS<1181> SKX_EXT_B_BGA1-IC,TBD    I20 @BASEBOARD_FAB2_LIB.BASEBOARD_FAB2(SCH_1):PAGE40
  U5D1  A36 VSS<1182> SKX_EXT_B_BGA1-IC,TBD    I20 @BASEBOARD_FAB2_LIB.BASEBOARD_FAB2(SCH_1):PAGE40
  U5D1  A32 VSS<1183> SKX_EXT_B_BGA1-IC,TBD    I20 @BASEBOARD_FAB2_LIB.BASEBOARD_FAB2(SCH_1):PAGE40
  U5D1  A30 VSS<1184> SKX_EXT_B_BGA1-IC,TBD    I20 @BASEBOARD_FAB2_LIB.BASEBOARD_FAB2(SCH_1):PAGE40
  U5D1  A26 VSS<1185> SKX_EXT_B_BGA1-IC,TBD    I20 @BASEBOARD_FAB2_LIB.BASEBOARD_FAB2(SCH_1):PAGE40
  U5D1 AC58 VSS<1186> SKX_EXT_B_BGA1-IC,TBD    I20 @BASEBOARD_FAB2_LIB.BASEBOARD_FAB2(SCH_1):PAGE40
  U5D1 AC60 VSS<1187> SKX_EXT_B_BGA1-IC,TBD    I20 @BASEBOARD_FAB2_LIB.BASEBOARD_FAB2(SCH_1):PAGE40
  U5D1 AC62 VSS<1188> SKX_EXT_B_BGA1-IC,TBD    I20 @BASEBOARD_FAB2_LIB.BASEBOARD_FAB2(SCH_1):PAGE40
  U5D1  AJ4 VSS<1189> SKX_EXT_B_BGA1-IC,TBD    I20 @BASEBOARD_FAB2_LIB.BASEBOARD_FAB2(SCH_1):PAGE40
  U5D1  AR6 VSS<1190> SKX_EXT_B_BGA1-IC,TBD    I20 @BASEBOARD_FAB2_LIB.BASEBOARD_FAB2(SCH_1):PAGE40
  U5D1  CG6 VSS<1191> SKX_EXT_B_BGA1-IC,TBD    I20 @BASEBOARD_FAB2_LIB.BASEBOARD_FAB2(SCH_1):PAGE40
  U5D1  CW6 VSS<1192> SKX_EXT_B_BGA1-IC,TBD    I20 @BASEBOARD_FAB2_LIB.BASEBOARD_FAB2(SCH_1):PAGE40
  U5D1 DE48 VSS<1193> SKX_EXT_B_BGA1-IC,TBD    I20 @BASEBOARD_FAB2_LIB.BASEBOARD_FAB2(SCH_1):PAGE40
  U5D1 DE50 VSS<1194> SKX_EXT_B_BGA1-IC,TBD    I20 @BASEBOARD_FAB2_LIB.BASEBOARD_FAB2(SCH_1):PAGE40
  U5D1 DE52 VSS<1195> SKX_EXT_B_BGA1-IC,TBD    I20 @BASEBOARD_FAB2_LIB.BASEBOARD_FAB2(SCH_1):PAGE40
  U5D1 DE54 VSS<1196> SKX_EXT_B_BGA1-IC,TBD    I20 @BASEBOARD_FAB2_LIB.BASEBOARD_FAB2(SCH_1):PAGE40
  U5D1 DE56 VSS<1197> SKX_EXT_B_BGA1-IC,TBD    I20 @BASEBOARD_FAB2_LIB.BASEBOARD_FAB2(SCH_1):PAGE40
  U5D1 DE58 VSS<1198> SKX_EXT_B_BGA1-IC,TBD    I20 @BASEBOARD_FAB2_LIB.BASEBOARD_FAB2(SCH_1):PAGE40
  U5D1 DE60 VSS<1199> SKX_EXT_B_BGA1-IC,TBD    I20 @BASEBOARD_FAB2_LIB.BASEBOARD_FAB2(SCH_1):PAGE40
  U5D1 DE62 VSS<1200> SKX_EXT_B_BGA1-IC,TBD    I20 @BASEBOARD_FAB2_LIB.BASEBOARD_FAB2(SCH_1):PAGE40
  U5D1  DL8 VSS<1201> SKX_EXT_B_BGA1-IC,TBD    I20 @BASEBOARD_FAB2_LIB.BASEBOARD_FAB2(SCH_1):PAGE40
  U5D1 DN18 VSS<1202> SKX_EXT_B_BGA1-IC,TBD    I20 @BASEBOARD_FAB2_LIB.BASEBOARD_FAB2(SCH_1):PAGE40
  U5D1 DP45 VSS<1203> SKX_EXT_B_BGA1-IC,TBD    I20 @BASEBOARD_FAB2_LIB.BASEBOARD_FAB2(SCH_1):PAGE40
  U5D1 DP47 VSS<1204> SKX_EXT_B_BGA1-IC,TBD    I20 @BASEBOARD_FAB2_LIB.BASEBOARD_FAB2(SCH_1):PAGE40
  U5D1 DP49 VSS<1205> SKX_EXT_B_BGA1-IC,TBD    I20 @BASEBOARD_FAB2_LIB.BASEBOARD_FAB2(SCH_1):PAGE40
  U5D1 DP51 VSS<1206> SKX_EXT_B_BGA1-IC,TBD    I20 @BASEBOARD_FAB2_LIB.BASEBOARD_FAB2(SCH_1):PAGE40
  U5D1 DP53 VSS<1207> SKX_EXT_B_BGA1-IC,TBD    I20 @BASEBOARD_FAB2_LIB.BASEBOARD_FAB2(SCH_1):PAGE40
  U5D1 DP55 VSS<1208> SKX_EXT_B_BGA1-IC,TBD    I20 @BASEBOARD_FAB2_LIB.BASEBOARD_FAB2(SCH_1):PAGE40
  U5D1 DP57 VSS<1209> SKX_EXT_B_BGA1-IC,TBD    I20 @BASEBOARD_FAB2_LIB.BASEBOARD_FAB2(SCH_1):PAGE40
  U5D1 DP59 VSS<1210> SKX_EXT_B_BGA1-IC,TBD    I20 @BASEBOARD_FAB2_LIB.BASEBOARD_FAB2(SCH_1):PAGE40
  U5D1 DP61 VSS<1211> SKX_EXT_B_BGA1-IC,TBD    I20 @BASEBOARD_FAB2_LIB.BASEBOARD_FAB2(SCH_1):PAGE40
  U5D1 DP63 VSS<1212> SKX_EXT_B_BGA1-IC,TBD    I20 @BASEBOARD_FAB2_LIB.BASEBOARD_FAB2(SCH_1):PAGE40
  U5D1  DP9 VSS<1213> SKX_EXT_B_BGA1-IC,TBD    I20 @BASEBOARD_FAB2_LIB.BASEBOARD_FAB2(SCH_1):PAGE40
  U5D1 DV19 VSS<1214> SKX_EXT_B_BGA1-IC,TBD    I20 @BASEBOARD_FAB2_LIB.BASEBOARD_FAB2(SCH_1):PAGE40
  U5D1 DY45 VSS<1215> SKX_EXT_B_BGA1-IC,TBD    I20 @BASEBOARD_FAB2_LIB.BASEBOARD_FAB2(SCH_1):PAGE40
  U5D1 DY47 VSS<1216> SKX_EXT_B_BGA1-IC,TBD    I20 @BASEBOARD_FAB2_LIB.BASEBOARD_FAB2(SCH_1):PAGE40
  U5D1 DY49 VSS<1217> SKX_EXT_B_BGA1-IC,TBD    I20 @BASEBOARD_FAB2_LIB.BASEBOARD_FAB2(SCH_1):PAGE40
  U5D1 DY51 VSS<1218> SKX_EXT_B_BGA1-IC,TBD    I20 @BASEBOARD_FAB2_LIB.BASEBOARD_FAB2(SCH_1):PAGE40
  U5D1 DY53 VSS<1219> SKX_EXT_B_BGA1-IC,TBD    I20 @BASEBOARD_FAB2_LIB.BASEBOARD_FAB2(SCH_1):PAGE40
  U5D1 DY55 VSS<1220> SKX_EXT_B_BGA1-IC,TBD    I20 @BASEBOARD_FAB2_LIB.BASEBOARD_FAB2(SCH_1):PAGE40
  U5D1 DY57 VSS<1221> SKX_EXT_B_BGA1-IC,TBD    I20 @BASEBOARD_FAB2_LIB.BASEBOARD_FAB2(SCH_1):PAGE40
  U5D1 DY59 VSS<1222> SKX_EXT_B_BGA1-IC,TBD    I20 @BASEBOARD_FAB2_LIB.BASEBOARD_FAB2(SCH_1):PAGE40
  U5D1 DY61 VSS<1223> SKX_EXT_B_BGA1-IC,TBD    I20 @BASEBOARD_FAB2_LIB.BASEBOARD_FAB2(SCH_1):PAGE40
  U5D1 DY63 VSS<1224> SKX_EXT_B_BGA1-IC,TBD    I20 @BASEBOARD_FAB2_LIB.BASEBOARD_FAB2(SCH_1):PAGE40
  U5D1 EA14 VSS<1225> SKX_EXT_B_BGA1-IC,TBD    I20 @BASEBOARD_FAB2_LIB.BASEBOARD_FAB2(SCH_1):PAGE40
  U5D1   L8 VSS<1226> SKX_EXT_B_BGA1-IC,TBD    I20 @BASEBOARD_FAB2_LIB.BASEBOARD_FAB2(SCH_1):PAGE40
  U5D1  V11 VSS<1227> SKX_EXT_B_BGA1-IC,TBD    I20 @BASEBOARD_FAB2_LIB.BASEBOARD_FAB2(SCH_1):PAGE40
  U5D1  E66 VSS<1228> SKX_EXT_B_BGA1-IC,TBD    I20 @BASEBOARD_FAB2_LIB.BASEBOARD_FAB2(SCH_1):PAGE40
  U5D1 ED69 VSS<1229> SKX_EXT_B_BGA1-IC,TBD    I20 @BASEBOARD_FAB2_LIB.BASEBOARD_FAB2(SCH_1):PAGE40
  U5D1 EE80 VSS<1230> SKX_EXT_B_BGA1-IC,TBD    I20 @BASEBOARD_FAB2_LIB.BASEBOARD_FAB2(SCH_1):PAGE40
  U5D1  EE8 VSS<1231> SKX_EXT_B_BGA1-IC,TBD    I20 @BASEBOARD_FAB2_LIB.BASEBOARD_FAB2(SCH_1):PAGE40
  U5D1 EE40 VSS<1232> SKX_EXT_B_BGA1-IC,TBD    I20 @BASEBOARD_FAB2_LIB.BASEBOARD_FAB2(SCH_1):PAGE40
  U5D1 ED81 VSS<1233> SKX_EXT_B_BGA1-IC,TBD    I20 @BASEBOARD_FAB2_LIB.BASEBOARD_FAB2(SCH_1):PAGE40
  U5D1  ED7 VSS<1234> SKX_EXT_B_BGA1-IC,TBD    I20 @BASEBOARD_FAB2_LIB.BASEBOARD_FAB2(SCH_1):PAGE40
  U5D1 ED41 VSS<1235> SKX_EXT_B_BGA1-IC,TBD    I20 @BASEBOARD_FAB2_LIB.BASEBOARD_FAB2(SCH_1):PAGE40
  U5D1 EC82 VSS<1236> SKX_EXT_B_BGA1-IC,TBD    I20 @BASEBOARD_FAB2_LIB.BASEBOARD_FAB2(SCH_1):PAGE40
  U5D1  EC6 VSS<1237> SKX_EXT_B_BGA1-IC,TBD    I20 @BASEBOARD_FAB2_LIB.BASEBOARD_FAB2(SCH_1):PAGE40
  U5D1 EC42 VSS<1238> SKX_EXT_B_BGA1-IC,TBD    I20 @BASEBOARD_FAB2_LIB.BASEBOARD_FAB2(SCH_1):PAGE40
  U5D1  DW2 VSS<1239> SKX_EXT_B_BGA1-IC,TBD    I20 @BASEBOARD_FAB2_LIB.BASEBOARD_FAB2(SCH_1):PAGE40
  U5D1 EB83 VSS<1240> SKX_EXT_B_BGA1-IC,TBD    I20 @BASEBOARD_FAB2_LIB.BASEBOARD_FAB2(SCH_1):PAGE40
  U5D1 EA84 VSS<1241> SKX_EXT_B_BGA1-IC,TBD    I20 @BASEBOARD_FAB2_LIB.BASEBOARD_FAB2(SCH_1):PAGE40
  U5D1 DY85 VSS<1242> SKX_EXT_B_BGA1-IC,TBD    I20 @BASEBOARD_FAB2_LIB.BASEBOARD_FAB2(SCH_1):PAGE40
  U5D1  J86 VSS<1243> SKX_EXT_B_BGA1-IC,TBD    I20 @BASEBOARD_FAB2_LIB.BASEBOARD_FAB2(SCH_1):PAGE40
  U5D1  E82 VSS<1244> SKX_EXT_B_BGA1-IC,TBD    I20 @BASEBOARD_FAB2_LIB.BASEBOARD_FAB2(SCH_1):PAGE40
  U5D1  D81 VSS<1245> SKX_EXT_B_BGA1-IC,TBD    I20 @BASEBOARD_FAB2_LIB.BASEBOARD_FAB2(SCH_1):PAGE40
  U5D1   D3 VSS<1246> SKX_EXT_B_BGA1-IC,TBD    I20 @BASEBOARD_FAB2_LIB.BASEBOARD_FAB2(SCH_1):PAGE40
  U5D1  C80 VSS<1247> SKX_EXT_B_BGA1-IC,TBD    I20 @BASEBOARD_FAB2_LIB.BASEBOARD_FAB2(SCH_1):PAGE40
  U5D1   C4 VSS<1248> SKX_EXT_B_BGA1-IC,TBD    I20 @BASEBOARD_FAB2_LIB.BASEBOARD_FAB2(SCH_1):PAGE40
  U5D1  B79 VSS<1249> SKX_EXT_B_BGA1-IC,TBD    I20 @BASEBOARD_FAB2_LIB.BASEBOARD_FAB2(SCH_1):PAGE40
  U5D1   B5 VSS<1250> SKX_EXT_B_BGA1-IC,TBD    I20 @BASEBOARD_FAB2_LIB.BASEBOARD_FAB2(SCH_1):PAGE40
  U5D1  B43 VSS<1251> SKX_EXT_B_BGA1-IC,TBD    I20 @BASEBOARD_FAB2_LIB.BASEBOARD_FAB2(SCH_1):PAGE40
  U5D1  A42 VSS<1252> SKX_EXT_B_BGA1-IC,TBD    I20 @BASEBOARD_FAB2_LIB.BASEBOARD_FAB2(SCH_1):PAGE40
  U5D1   B9 VSS<1253> SKX_EXT_B_BGA1-IC,TBD    I20 @BASEBOARD_FAB2_LIB.BASEBOARD_FAB2(SCH_1):PAGE40
  U5D1 AA16 VSS<934> SKX_EXT_B_BGA1-IC,TBD    I21 @BASEBOARD_FAB2_LIB.BASEBOARD_FAB2(SCH_1):PAGE40
  U5D1  AA4 VSS<935> SKX_EXT_B_BGA1-IC,TBD    I21 @BASEBOARD_FAB2_LIB.BASEBOARD_FAB2(SCH_1):PAGE40
  U5D1  Y85 VSS<936> SKX_EXT_B_BGA1-IC,TBD    I21 @BASEBOARD_FAB2_LIB.BASEBOARD_FAB2(SCH_1):PAGE40
  U5D1  Y83 VSS<937> SKX_EXT_B_BGA1-IC,TBD    I21 @BASEBOARD_FAB2_LIB.BASEBOARD_FAB2(SCH_1):PAGE40
  U5D1  Y81 VSS<938> SKX_EXT_B_BGA1-IC,TBD    I21 @BASEBOARD_FAB2_LIB.BASEBOARD_FAB2(SCH_1):PAGE40
  U5D1  Y79 VSS<939> SKX_EXT_B_BGA1-IC,TBD    I21 @BASEBOARD_FAB2_LIB.BASEBOARD_FAB2(SCH_1):PAGE40
  U5D1  Y73 VSS<940> SKX_EXT_B_BGA1-IC,TBD    I21 @BASEBOARD_FAB2_LIB.BASEBOARD_FAB2(SCH_1):PAGE40
  U5D1  Y71 VSS<941> SKX_EXT_B_BGA1-IC,TBD    I21 @BASEBOARD_FAB2_LIB.BASEBOARD_FAB2(SCH_1):PAGE40
  U5D1   Y9 VSS<942> SKX_EXT_B_BGA1-IC,TBD    I21 @BASEBOARD_FAB2_LIB.BASEBOARD_FAB2(SCH_1):PAGE40
  U5D1   Y7 VSS<943> SKX_EXT_B_BGA1-IC,TBD    I21 @BASEBOARD_FAB2_LIB.BASEBOARD_FAB2(SCH_1):PAGE40
  U5D1  Y67 VSS<944> SKX_EXT_B_BGA1-IC,TBD    I21 @BASEBOARD_FAB2_LIB.BASEBOARD_FAB2(SCH_1):PAGE40
  U5D1   Y5 VSS<945> SKX_EXT_B_BGA1-IC,TBD    I21 @BASEBOARD_FAB2_LIB.BASEBOARD_FAB2(SCH_1):PAGE40
  U5D1  Y17 VSS<946> SKX_EXT_B_BGA1-IC,TBD    I21 @BASEBOARD_FAB2_LIB.BASEBOARD_FAB2(SCH_1):PAGE40
  U5D1  Y15 VSS<947> SKX_EXT_B_BGA1-IC,TBD    I21 @BASEBOARD_FAB2_LIB.BASEBOARD_FAB2(SCH_1):PAGE40
  U5D1  W82 VSS<948> SKX_EXT_B_BGA1-IC,TBD    I21 @BASEBOARD_FAB2_LIB.BASEBOARD_FAB2(SCH_1):PAGE40
  U5D1  W78 VSS<949> SKX_EXT_B_BGA1-IC,TBD    I21 @BASEBOARD_FAB2_LIB.BASEBOARD_FAB2(SCH_1):PAGE40
  U5D1  W74 VSS<950> SKX_EXT_B_BGA1-IC,TBD    I21 @BASEBOARD_FAB2_LIB.BASEBOARD_FAB2(SCH_1):PAGE40
  U5D1  W68 VSS<951> SKX_EXT_B_BGA1-IC,TBD    I21 @BASEBOARD_FAB2_LIB.BASEBOARD_FAB2(SCH_1):PAGE40
  U5D1  W42 VSS<952> SKX_EXT_B_BGA1-IC,TBD    I21 @BASEBOARD_FAB2_LIB.BASEBOARD_FAB2(SCH_1):PAGE40
  U5D1  W40 VSS<953> SKX_EXT_B_BGA1-IC,TBD    I21 @BASEBOARD_FAB2_LIB.BASEBOARD_FAB2(SCH_1):PAGE40
  U5D1  W38 VSS<954> SKX_EXT_B_BGA1-IC,TBD    I21 @BASEBOARD_FAB2_LIB.BASEBOARD_FAB2(SCH_1):PAGE40
  U5D1  W36 VSS<955> SKX_EXT_B_BGA1-IC,TBD    I21 @BASEBOARD_FAB2_LIB.BASEBOARD_FAB2(SCH_1):PAGE40
  U5D1  W34 VSS<956> SKX_EXT_B_BGA1-IC,TBD    I21 @BASEBOARD_FAB2_LIB.BASEBOARD_FAB2(SCH_1):PAGE40
  U5D1  W32 VSS<957> SKX_EXT_B_BGA1-IC,TBD    I21 @BASEBOARD_FAB2_LIB.BASEBOARD_FAB2(SCH_1):PAGE40
  U5D1  W30 VSS<958> SKX_EXT_B_BGA1-IC,TBD    I21 @BASEBOARD_FAB2_LIB.BASEBOARD_FAB2(SCH_1):PAGE40
  U5D1  W28 VSS<959> SKX_EXT_B_BGA1-IC,TBD    I21 @BASEBOARD_FAB2_LIB.BASEBOARD_FAB2(SCH_1):PAGE40
  U5D1  W26 VSS<960> SKX_EXT_B_BGA1-IC,TBD    I21 @BASEBOARD_FAB2_LIB.BASEBOARD_FAB2(SCH_1):PAGE40
  U5D1  W24 VSS<961> SKX_EXT_B_BGA1-IC,TBD    I21 @BASEBOARD_FAB2_LIB.BASEBOARD_FAB2(SCH_1):PAGE40
  U5D1  W22 VSS<962> SKX_EXT_B_BGA1-IC,TBD    I21 @BASEBOARD_FAB2_LIB.BASEBOARD_FAB2(SCH_1):PAGE40
  U5D1  W12 VSS<963> SKX_EXT_B_BGA1-IC,TBD    I21 @BASEBOARD_FAB2_LIB.BASEBOARD_FAB2(SCH_1):PAGE40
  U5D1 AC56 VSS<964> SKX_EXT_B_BGA1-IC,TBD    I21 @BASEBOARD_FAB2_LIB.BASEBOARD_FAB2(SCH_1):PAGE40
  U5D1   W8 VSS<965> SKX_EXT_B_BGA1-IC,TBD    I21 @BASEBOARD_FAB2_LIB.BASEBOARD_FAB2(SCH_1):PAGE40
  U5D1  V83 VSS<966> SKX_EXT_B_BGA1-IC,TBD    I21 @BASEBOARD_FAB2_LIB.BASEBOARD_FAB2(SCH_1):PAGE40
  U5D1  V77 VSS<967> SKX_EXT_B_BGA1-IC,TBD    I21 @BASEBOARD_FAB2_LIB.BASEBOARD_FAB2(SCH_1):PAGE40
  U5D1  V75 VSS<968> SKX_EXT_B_BGA1-IC,TBD    I21 @BASEBOARD_FAB2_LIB.BASEBOARD_FAB2(SCH_1):PAGE40
  U5D1  V73 VSS<969> SKX_EXT_B_BGA1-IC,TBD    I21 @BASEBOARD_FAB2_LIB.BASEBOARD_FAB2(SCH_1):PAGE40
  U5D1  V43 VSS<970> SKX_EXT_B_BGA1-IC,TBD    I21 @BASEBOARD_FAB2_LIB.BASEBOARD_FAB2(SCH_1):PAGE40
  U5D1  V23 VSS<971> SKX_EXT_B_BGA1-IC,TBD    I21 @BASEBOARD_FAB2_LIB.BASEBOARD_FAB2(SCH_1):PAGE40
  U5D1  V21 VSS<972> SKX_EXT_B_BGA1-IC,TBD    I21 @BASEBOARD_FAB2_LIB.BASEBOARD_FAB2(SCH_1):PAGE40
  U5D1  V15 VSS<973> SKX_EXT_B_BGA1-IC,TBD    I21 @BASEBOARD_FAB2_LIB.BASEBOARD_FAB2(SCH_1):PAGE40
  U5D1  V13 VSS<974> SKX_EXT_B_BGA1-IC,TBD    I21 @BASEBOARD_FAB2_LIB.BASEBOARD_FAB2(SCH_1):PAGE40
  U5D1   V9 VSS<975> SKX_EXT_B_BGA1-IC,TBD    I21 @BASEBOARD_FAB2_LIB.BASEBOARD_FAB2(SCH_1):PAGE40
  U5D1   V5 VSS<976> SKX_EXT_B_BGA1-IC,TBD    I21 @BASEBOARD_FAB2_LIB.BASEBOARD_FAB2(SCH_1):PAGE40
  U5D1   V1 VSS<977> SKX_EXT_B_BGA1-IC,TBD    I21 @BASEBOARD_FAB2_LIB.BASEBOARD_FAB2(SCH_1):PAGE40
  U5D1  U86 VSS<978> SKX_EXT_B_BGA1-IC,TBD    I21 @BASEBOARD_FAB2_LIB.BASEBOARD_FAB2(SCH_1):PAGE40
  U5D1  U80 VSS<979> SKX_EXT_B_BGA1-IC,TBD    I21 @BASEBOARD_FAB2_LIB.BASEBOARD_FAB2(SCH_1):PAGE40
  U5D1  U78 VSS<980> SKX_EXT_B_BGA1-IC,TBD    I21 @BASEBOARD_FAB2_LIB.BASEBOARD_FAB2(SCH_1):PAGE40
  U5D1  U76 VSS<981> SKX_EXT_B_BGA1-IC,TBD    I21 @BASEBOARD_FAB2_LIB.BASEBOARD_FAB2(SCH_1):PAGE40
  U5D1  U74 VSS<982> SKX_EXT_B_BGA1-IC,TBD    I21 @BASEBOARD_FAB2_LIB.BASEBOARD_FAB2(SCH_1):PAGE40
  U5D1  U70 VSS<983> SKX_EXT_B_BGA1-IC,TBD    I21 @BASEBOARD_FAB2_LIB.BASEBOARD_FAB2(SCH_1):PAGE40
  U5D1  U68 VSS<984> SKX_EXT_B_BGA1-IC,TBD    I21 @BASEBOARD_FAB2_LIB.BASEBOARD_FAB2(SCH_1):PAGE40
  U5D1  U42 VSS<985> SKX_EXT_B_BGA1-IC,TBD    I21 @BASEBOARD_FAB2_LIB.BASEBOARD_FAB2(SCH_1):PAGE40
  U5D1  U36 VSS<986> SKX_EXT_B_BGA1-IC,TBD    I21 @BASEBOARD_FAB2_LIB.BASEBOARD_FAB2(SCH_1):PAGE40
  U5D1  U30 VSS<987> SKX_EXT_B_BGA1-IC,TBD    I21 @BASEBOARD_FAB2_LIB.BASEBOARD_FAB2(SCH_1):PAGE40
  U5D1  U24 VSS<988> SKX_EXT_B_BGA1-IC,TBD    I21 @BASEBOARD_FAB2_LIB.BASEBOARD_FAB2(SCH_1):PAGE40
  U5D1  U22 VSS<989> SKX_EXT_B_BGA1-IC,TBD    I21 @BASEBOARD_FAB2_LIB.BASEBOARD_FAB2(SCH_1):PAGE40
  U5D1  U20 VSS<990> SKX_EXT_B_BGA1-IC,TBD    I21 @BASEBOARD_FAB2_LIB.BASEBOARD_FAB2(SCH_1):PAGE40
  U5D1   U6 VSS<991> SKX_EXT_B_BGA1-IC,TBD    I21 @BASEBOARD_FAB2_LIB.BASEBOARD_FAB2(SCH_1):PAGE40
  U5D1   U4 VSS<992> SKX_EXT_B_BGA1-IC,TBD    I21 @BASEBOARD_FAB2_LIB.BASEBOARD_FAB2(SCH_1):PAGE40
  U5D1   U2 VSS<993> SKX_EXT_B_BGA1-IC,TBD    I21 @BASEBOARD_FAB2_LIB.BASEBOARD_FAB2(SCH_1):PAGE40
  U5D1  T85 VSS<994> SKX_EXT_B_BGA1-IC,TBD    I21 @BASEBOARD_FAB2_LIB.BASEBOARD_FAB2(SCH_1):PAGE40
  U5D1  T83 VSS<995> SKX_EXT_B_BGA1-IC,TBD    I21 @BASEBOARD_FAB2_LIB.BASEBOARD_FAB2(SCH_1):PAGE40
  U5D1  T77 VSS<996> SKX_EXT_B_BGA1-IC,TBD    I21 @BASEBOARD_FAB2_LIB.BASEBOARD_FAB2(SCH_1):PAGE40
  U5D1  T73 VSS<997> SKX_EXT_B_BGA1-IC,TBD    I21 @BASEBOARD_FAB2_LIB.BASEBOARD_FAB2(SCH_1):PAGE40
  U5D1  T65 VSS<998> SKX_EXT_B_BGA1-IC,TBD    I21 @BASEBOARD_FAB2_LIB.BASEBOARD_FAB2(SCH_1):PAGE40
  U5D1  T41 VSS<999> SKX_EXT_B_BGA1-IC,TBD    I21 @BASEBOARD_FAB2_LIB.BASEBOARD_FAB2(SCH_1):PAGE40
  U5D1  T37 VSS<1000> SKX_EXT_B_BGA1-IC,TBD    I21 @BASEBOARD_FAB2_LIB.BASEBOARD_FAB2(SCH_1):PAGE40
  U5D1  T35 VSS<1001> SKX_EXT_B_BGA1-IC,TBD    I21 @BASEBOARD_FAB2_LIB.BASEBOARD_FAB2(SCH_1):PAGE40
  U5D1  T31 VSS<1002> SKX_EXT_B_BGA1-IC,TBD    I21 @BASEBOARD_FAB2_LIB.BASEBOARD_FAB2(SCH_1):PAGE40
  U5D1  T29 VSS<1003> SKX_EXT_B_BGA1-IC,TBD    I21 @BASEBOARD_FAB2_LIB.BASEBOARD_FAB2(SCH_1):PAGE40
  U5D1  T25 VSS<1004> SKX_EXT_B_BGA1-IC,TBD    I21 @BASEBOARD_FAB2_LIB.BASEBOARD_FAB2(SCH_1):PAGE40
  U5D1  T17 VSS<1005> SKX_EXT_B_BGA1-IC,TBD    I21 @BASEBOARD_FAB2_LIB.BASEBOARD_FAB2(SCH_1):PAGE40
  U5D1  T13 VSS<1006> SKX_EXT_B_BGA1-IC,TBD    I21 @BASEBOARD_FAB2_LIB.BASEBOARD_FAB2(SCH_1):PAGE40
  U5D1  R86 VSS<1007> SKX_EXT_B_BGA1-IC,TBD    I21 @BASEBOARD_FAB2_LIB.BASEBOARD_FAB2(SCH_1):PAGE40
  U5D1  R78 VSS<1008> SKX_EXT_B_BGA1-IC,TBD    I21 @BASEBOARD_FAB2_LIB.BASEBOARD_FAB2(SCH_1):PAGE40
  U5D1  R72 VSS<1009> SKX_EXT_B_BGA1-IC,TBD    I21 @BASEBOARD_FAB2_LIB.BASEBOARD_FAB2(SCH_1):PAGE40
  U5D1  R68 VSS<1010> SKX_EXT_B_BGA1-IC,TBD    I21 @BASEBOARD_FAB2_LIB.BASEBOARD_FAB2(SCH_1):PAGE40
  U5D1  R40 VSS<1011> SKX_EXT_B_BGA1-IC,TBD    I21 @BASEBOARD_FAB2_LIB.BASEBOARD_FAB2(SCH_1):PAGE40
  U5D1  R38 VSS<1012> SKX_EXT_B_BGA1-IC,TBD    I21 @BASEBOARD_FAB2_LIB.BASEBOARD_FAB2(SCH_1):PAGE40
  U5D1  R34 VSS<1013> SKX_EXT_B_BGA1-IC,TBD    I21 @BASEBOARD_FAB2_LIB.BASEBOARD_FAB2(SCH_1):PAGE40
  U5D1  R32 VSS<1014> SKX_EXT_B_BGA1-IC,TBD    I21 @BASEBOARD_FAB2_LIB.BASEBOARD_FAB2(SCH_1):PAGE40
  U5D1  R28 VSS<1015> SKX_EXT_B_BGA1-IC,TBD    I21 @BASEBOARD_FAB2_LIB.BASEBOARD_FAB2(SCH_1):PAGE40
  U5D1  R26 VSS<1016> SKX_EXT_B_BGA1-IC,TBD    I21 @BASEBOARD_FAB2_LIB.BASEBOARD_FAB2(SCH_1):PAGE40
  U5D1  R22 VSS<1017> SKX_EXT_B_BGA1-IC,TBD    I21 @BASEBOARD_FAB2_LIB.BASEBOARD_FAB2(SCH_1):PAGE40
  U5D1   R4 VSS<1018> SKX_EXT_B_BGA1-IC,TBD    I21 @BASEBOARD_FAB2_LIB.BASEBOARD_FAB2(SCH_1):PAGE40
  U5D1   R2 VSS<1019> SKX_EXT_B_BGA1-IC,TBD    I21 @BASEBOARD_FAB2_LIB.BASEBOARD_FAB2(SCH_1):PAGE40
  U5D1  R18 VSS<1020> SKX_EXT_B_BGA1-IC,TBD    I21 @BASEBOARD_FAB2_LIB.BASEBOARD_FAB2(SCH_1):PAGE40
  U5D1  R14 VSS<1021> SKX_EXT_B_BGA1-IC,TBD    I21 @BASEBOARD_FAB2_LIB.BASEBOARD_FAB2(SCH_1):PAGE40
  U5D1  P83 VSS<1022> SKX_EXT_B_BGA1-IC,TBD    I21 @BASEBOARD_FAB2_LIB.BASEBOARD_FAB2(SCH_1):PAGE40
  U5D1  P81 VSS<1023> SKX_EXT_B_BGA1-IC,TBD    I21 @BASEBOARD_FAB2_LIB.BASEBOARD_FAB2(SCH_1):PAGE40
  U5D1  P71 VSS<1024> SKX_EXT_B_BGA1-IC,TBD    I21 @BASEBOARD_FAB2_LIB.BASEBOARD_FAB2(SCH_1):PAGE40
  U5D1  P69 VSS<1025> SKX_EXT_B_BGA1-IC,TBD    I21 @BASEBOARD_FAB2_LIB.BASEBOARD_FAB2(SCH_1):PAGE40
  U5D1  P67 VSS<1026> SKX_EXT_B_BGA1-IC,TBD    I21 @BASEBOARD_FAB2_LIB.BASEBOARD_FAB2(SCH_1):PAGE40
  U5D1  P39 VSS<1027> SKX_EXT_B_BGA1-IC,TBD    I21 @BASEBOARD_FAB2_LIB.BASEBOARD_FAB2(SCH_1):PAGE40
  U5D1  P33 VSS<1028> SKX_EXT_B_BGA1-IC,TBD    I21 @BASEBOARD_FAB2_LIB.BASEBOARD_FAB2(SCH_1):PAGE40
  U5D1  P27 VSS<1029> SKX_EXT_B_BGA1-IC,TBD    I21 @BASEBOARD_FAB2_LIB.BASEBOARD_FAB2(SCH_1):PAGE40
  U5D1  P15 VSS<1030> SKX_EXT_B_BGA1-IC,TBD    I21 @BASEBOARD_FAB2_LIB.BASEBOARD_FAB2(SCH_1):PAGE40
  U5D1  P11 VSS<1031> SKX_EXT_B_BGA1-IC,TBD    I21 @BASEBOARD_FAB2_LIB.BASEBOARD_FAB2(SCH_1):PAGE40
  U5D1   N8 VSS<1032> SKX_EXT_B_BGA1-IC,TBD    I21 @BASEBOARD_FAB2_LIB.BASEBOARD_FAB2(SCH_1):PAGE40
  U5D1   N4 VSS<1033> SKX_EXT_B_BGA1-IC,TBD    I21 @BASEBOARD_FAB2_LIB.BASEBOARD_FAB2(SCH_1):PAGE40
  U5D1  N78 VSS<1034> SKX_EXT_B_BGA1-IC,TBD    I21 @BASEBOARD_FAB2_LIB.BASEBOARD_FAB2(SCH_1):PAGE40
  U5D1  N76 VSS<1035> SKX_EXT_B_BGA1-IC,TBD    I21 @BASEBOARD_FAB2_LIB.BASEBOARD_FAB2(SCH_1):PAGE40
  U5D1  N74 VSS<1036> SKX_EXT_B_BGA1-IC,TBD    I21 @BASEBOARD_FAB2_LIB.BASEBOARD_FAB2(SCH_1):PAGE40
  U5D1  N72 VSS<1037> SKX_EXT_B_BGA1-IC,TBD    I21 @BASEBOARD_FAB2_LIB.BASEBOARD_FAB2(SCH_1):PAGE40
  U5D1  N70 VSS<1038> SKX_EXT_B_BGA1-IC,TBD    I21 @BASEBOARD_FAB2_LIB.BASEBOARD_FAB2(SCH_1):PAGE40
  U5D1  N66 VSS<1039> SKX_EXT_B_BGA1-IC,TBD    I21 @BASEBOARD_FAB2_LIB.BASEBOARD_FAB2(SCH_1):PAGE40
  U5D1   N6 VSS<1040> SKX_EXT_B_BGA1-IC,TBD    I21 @BASEBOARD_FAB2_LIB.BASEBOARD_FAB2(SCH_1):PAGE40
  U5D1  N22 VSS<1041> SKX_EXT_B_BGA1-IC,TBD    I21 @BASEBOARD_FAB2_LIB.BASEBOARD_FAB2(SCH_1):PAGE40
  U5D1  N20 VSS<1042> SKX_EXT_B_BGA1-IC,TBD    I21 @BASEBOARD_FAB2_LIB.BASEBOARD_FAB2(SCH_1):PAGE40
  U5D1 DM19 VSS<1043> SKX_EXT_B_BGA1-IC,TBD    I21 @BASEBOARD_FAB2_LIB.BASEBOARD_FAB2(SCH_1):PAGE40
  U5D1  M85 VSS<1044> SKX_EXT_B_BGA1-IC,TBD    I21 @BASEBOARD_FAB2_LIB.BASEBOARD_FAB2(SCH_1):PAGE40
  U5D1  M83 VSS<1045> SKX_EXT_B_BGA1-IC,TBD    I21 @BASEBOARD_FAB2_LIB.BASEBOARD_FAB2(SCH_1):PAGE40
  U5D1  M79 VSS<1046> SKX_EXT_B_BGA1-IC,TBD    I21 @BASEBOARD_FAB2_LIB.BASEBOARD_FAB2(SCH_1):PAGE40
  U5D1  M71 VSS<1047> SKX_EXT_B_BGA1-IC,TBD    I21 @BASEBOARD_FAB2_LIB.BASEBOARD_FAB2(SCH_1):PAGE40
  U5D1  M65 VSS<1048> SKX_EXT_B_BGA1-IC,TBD    I21 @BASEBOARD_FAB2_LIB.BASEBOARD_FAB2(SCH_1):PAGE40
  U5D1  M43 VSS<1049> SKX_EXT_B_BGA1-IC,TBD    I21 @BASEBOARD_FAB2_LIB.BASEBOARD_FAB2(SCH_1):PAGE40
  U5D1  M41 VSS<1050> SKX_EXT_B_BGA1-IC,TBD    I21 @BASEBOARD_FAB2_LIB.BASEBOARD_FAB2(SCH_1):PAGE40
  U5D1  M39 VSS<1051> SKX_EXT_B_BGA1-IC,TBD    I21 @BASEBOARD_FAB2_LIB.BASEBOARD_FAB2(SCH_1):PAGE40
  U5D1  M37 VSS<1052> SKX_EXT_B_BGA1-IC,TBD    I21 @BASEBOARD_FAB2_LIB.BASEBOARD_FAB2(SCH_1):PAGE40
  U5D1  M35 VSS<1053> SKX_EXT_B_BGA1-IC,TBD    I21 @BASEBOARD_FAB2_LIB.BASEBOARD_FAB2(SCH_1):PAGE40
  U5D1  M33 VSS<1054> SKX_EXT_B_BGA1-IC,TBD    I21 @BASEBOARD_FAB2_LIB.BASEBOARD_FAB2(SCH_1):PAGE40
  U5D1  M31 VSS<1055> SKX_EXT_B_BGA1-IC,TBD    I21 @BASEBOARD_FAB2_LIB.BASEBOARD_FAB2(SCH_1):PAGE40
  U5D1  M29 VSS<1056> SKX_EXT_B_BGA1-IC,TBD    I21 @BASEBOARD_FAB2_LIB.BASEBOARD_FAB2(SCH_1):PAGE40
  U5D1  M27 VSS<1057> SKX_EXT_B_BGA1-IC,TBD    I21 @BASEBOARD_FAB2_LIB.BASEBOARD_FAB2(SCH_1):PAGE40
  U5D1  M25 VSS<1058> SKX_EXT_B_BGA1-IC,TBD    I21 @BASEBOARD_FAB2_LIB.BASEBOARD_FAB2(SCH_1):PAGE40
  U5D1  M23 VSS<1059> SKX_EXT_B_BGA1-IC,TBD    I21 @BASEBOARD_FAB2_LIB.BASEBOARD_FAB2(SCH_1):PAGE40
  U5D1  M19 VSS<1060> SKX_EXT_B_BGA1-IC,TBD    I21 @BASEBOARD_FAB2_LIB.BASEBOARD_FAB2(SCH_1):PAGE40
  U5D1  M17 VSS<1061> SKX_EXT_B_BGA1-IC,TBD    I21 @BASEBOARD_FAB2_LIB.BASEBOARD_FAB2(SCH_1):PAGE40
  U5D1  M15 VSS<1062> SKX_EXT_B_BGA1-IC,TBD    I21 @BASEBOARD_FAB2_LIB.BASEBOARD_FAB2(SCH_1):PAGE40
  U5D1  CT7 VSS<1063> SKX_EXT_B_BGA1-IC,TBD    I21 @BASEBOARD_FAB2_LIB.BASEBOARD_FAB2(SCH_1):PAGE40
  U5D1  BT9 VSS<1064> SKX_EXT_B_BGA1-IC,TBD    I21 @BASEBOARD_FAB2_LIB.BASEBOARD_FAB2(SCH_1):PAGE40
  U5D1  L82 VSS<1065> SKX_EXT_B_BGA1-IC,TBD    I21 @BASEBOARD_FAB2_LIB.BASEBOARD_FAB2(SCH_1):PAGE40
  U5D1  L80 VSS<1066> SKX_EXT_B_BGA1-IC,TBD    I21 @BASEBOARD_FAB2_LIB.BASEBOARD_FAB2(SCH_1):PAGE40
  U5D1  L78 VSS<1067> SKX_EXT_B_BGA1-IC,TBD    I21 @BASEBOARD_FAB2_LIB.BASEBOARD_FAB2(SCH_1):PAGE40
  U5D1  L72 VSS<1068> SKX_EXT_B_BGA1-IC,TBD    I21 @BASEBOARD_FAB2_LIB.BASEBOARD_FAB2(SCH_1):PAGE40
  U5D1  L22 VSS<1069> SKX_EXT_B_BGA1-IC,TBD    I21 @BASEBOARD_FAB2_LIB.BASEBOARD_FAB2(SCH_1):PAGE40
  U5D1  L20 VSS<1070> SKX_EXT_B_BGA1-IC,TBD    I21 @BASEBOARD_FAB2_LIB.BASEBOARD_FAB2(SCH_1):PAGE40
  U5D1   L6 VSS<1071> SKX_EXT_B_BGA1-IC,TBD    I21 @BASEBOARD_FAB2_LIB.BASEBOARD_FAB2(SCH_1):PAGE40
  U5D1   L2 VSS<1072> SKX_EXT_B_BGA1-IC,TBD    I21 @BASEBOARD_FAB2_LIB.BASEBOARD_FAB2(SCH_1):PAGE40
  U5D1  L10 VSS<1073> SKX_EXT_B_BGA1-IC,TBD    I21 @BASEBOARD_FAB2_LIB.BASEBOARD_FAB2(SCH_1):PAGE40
  U5D1  K85 VSS<1074> SKX_EXT_B_BGA1-IC,TBD    I21 @BASEBOARD_FAB2_LIB.BASEBOARD_FAB2(SCH_1):PAGE40
  U5D1  K83 VSS<1075> SKX_EXT_B_BGA1-IC,TBD    I21 @BASEBOARD_FAB2_LIB.BASEBOARD_FAB2(SCH_1):PAGE40
  U5D1  K81 VSS<1076> SKX_EXT_B_BGA1-IC,TBD    I21 @BASEBOARD_FAB2_LIB.BASEBOARD_FAB2(SCH_1):PAGE40
  U5D1  K77 VSS<1077> SKX_EXT_B_BGA1-IC,TBD    I21 @BASEBOARD_FAB2_LIB.BASEBOARD_FAB2(SCH_1):PAGE40
  U5D1  K73 VSS<1078> SKX_EXT_B_BGA1-IC,TBD    I21 @BASEBOARD_FAB2_LIB.BASEBOARD_FAB2(SCH_1):PAGE40
  U5D1  K71 VSS<1079> SKX_EXT_B_BGA1-IC,TBD    I21 @BASEBOARD_FAB2_LIB.BASEBOARD_FAB2(SCH_1):PAGE40
  U5D1  K69 VSS<1080> SKX_EXT_B_BGA1-IC,TBD    I21 @BASEBOARD_FAB2_LIB.BASEBOARD_FAB2(SCH_1):PAGE40
  U5D1  K67 VSS<1081> SKX_EXT_B_BGA1-IC,TBD    I21 @BASEBOARD_FAB2_LIB.BASEBOARD_FAB2(SCH_1):PAGE40
  U5D1  K65 VSS<1082> SKX_EXT_B_BGA1-IC,TBD    I21 @BASEBOARD_FAB2_LIB.BASEBOARD_FAB2(SCH_1):PAGE40
  U5D1  K39 VSS<1083> SKX_EXT_B_BGA1-IC,TBD    I21 @BASEBOARD_FAB2_LIB.BASEBOARD_FAB2(SCH_1):PAGE40
  U5D1  K33 VSS<1084> SKX_EXT_B_BGA1-IC,TBD    I21 @BASEBOARD_FAB2_LIB.BASEBOARD_FAB2(SCH_1):PAGE40
  U5D1  K27 VSS<1085> SKX_EXT_B_BGA1-IC,TBD    I21 @BASEBOARD_FAB2_LIB.BASEBOARD_FAB2(SCH_1):PAGE40
  U5D1  DB7 VSS<1086> SKX_EXT_B_BGA1-IC,TBD    I21 @BASEBOARD_FAB2_LIB.BASEBOARD_FAB2(SCH_1):PAGE40
  U5D1  K17 VSS<1087> SKX_EXT_B_BGA1-IC,TBD    I21 @BASEBOARD_FAB2_LIB.BASEBOARD_FAB2(SCH_1):PAGE40
  U5D1  K13 VSS<1088> SKX_EXT_B_BGA1-IC,TBD    I21 @BASEBOARD_FAB2_LIB.BASEBOARD_FAB2(SCH_1):PAGE40
  U5D1  K11 VSS<1089> SKX_EXT_B_BGA1-IC,TBD    I21 @BASEBOARD_FAB2_LIB.BASEBOARD_FAB2(SCH_1):PAGE40
  U5D1   K1 VSS<1090> SKX_EXT_B_BGA1-IC,TBD    I21 @BASEBOARD_FAB2_LIB.BASEBOARD_FAB2(SCH_1):PAGE40
  U5D1  J84 VSS<1091> SKX_EXT_B_BGA1-IC,TBD    I21 @BASEBOARD_FAB2_LIB.BASEBOARD_FAB2(SCH_1):PAGE40
  U5D1  J82 VSS<1092> SKX_EXT_B_BGA1-IC,TBD    I21 @BASEBOARD_FAB2_LIB.BASEBOARD_FAB2(SCH_1):PAGE40
  U5D1  J76 VSS<1093> SKX_EXT_B_BGA1-IC,TBD    I21 @BASEBOARD_FAB2_LIB.BASEBOARD_FAB2(SCH_1):PAGE40
  U5D1 AL68 VSS<774> SKX_EXT_B_BGA1-IC,TBD    I22 @BASEBOARD_FAB2_LIB.BASEBOARD_FAB2(SCH_1):PAGE40
  U5D1 AL64 VSS<775> SKX_EXT_B_BGA1-IC,TBD    I22 @BASEBOARD_FAB2_LIB.BASEBOARD_FAB2(SCH_1):PAGE40
  U5D1 AL56 VSS<776> SKX_EXT_B_BGA1-IC,TBD    I22 @BASEBOARD_FAB2_LIB.BASEBOARD_FAB2(SCH_1):PAGE40
  U5D1 AL32 VSS<777> SKX_EXT_B_BGA1-IC,TBD    I22 @BASEBOARD_FAB2_LIB.BASEBOARD_FAB2(SCH_1):PAGE40
  U5D1 AL30 VSS<778> SKX_EXT_B_BGA1-IC,TBD    I22 @BASEBOARD_FAB2_LIB.BASEBOARD_FAB2(SCH_1):PAGE40
  U5D1 AL24 VSS<779> SKX_EXT_B_BGA1-IC,TBD    I22 @BASEBOARD_FAB2_LIB.BASEBOARD_FAB2(SCH_1):PAGE40
  U5D1 AL10 VSS<780> SKX_EXT_B_BGA1-IC,TBD    I22 @BASEBOARD_FAB2_LIB.BASEBOARD_FAB2(SCH_1):PAGE40
  U5D1  AL4 VSS<781> SKX_EXT_B_BGA1-IC,TBD    I22 @BASEBOARD_FAB2_LIB.BASEBOARD_FAB2(SCH_1):PAGE40
  U5D1 AK85 VSS<782> SKX_EXT_B_BGA1-IC,TBD    I22 @BASEBOARD_FAB2_LIB.BASEBOARD_FAB2(SCH_1):PAGE40
  U5D1 AK83 VSS<783> SKX_EXT_B_BGA1-IC,TBD    I22 @BASEBOARD_FAB2_LIB.BASEBOARD_FAB2(SCH_1):PAGE40
  U5D1 AK81 VSS<784> SKX_EXT_B_BGA1-IC,TBD    I22 @BASEBOARD_FAB2_LIB.BASEBOARD_FAB2(SCH_1):PAGE40
  U5D1 AK79 VSS<785> SKX_EXT_B_BGA1-IC,TBD    I22 @BASEBOARD_FAB2_LIB.BASEBOARD_FAB2(SCH_1):PAGE40
  U5D1 AK73 VSS<786> SKX_EXT_B_BGA1-IC,TBD    I22 @BASEBOARD_FAB2_LIB.BASEBOARD_FAB2(SCH_1):PAGE40
  U5D1 AK67 VSS<787> SKX_EXT_B_BGA1-IC,TBD    I22 @BASEBOARD_FAB2_LIB.BASEBOARD_FAB2(SCH_1):PAGE40
  U5D1 AK65 VSS<788> SKX_EXT_B_BGA1-IC,TBD    I22 @BASEBOARD_FAB2_LIB.BASEBOARD_FAB2(SCH_1):PAGE40
  U5D1 AK55 VSS<789> SKX_EXT_B_BGA1-IC,TBD    I22 @BASEBOARD_FAB2_LIB.BASEBOARD_FAB2(SCH_1):PAGE40
  U5D1 AK33 VSS<790> SKX_EXT_B_BGA1-IC,TBD    I22 @BASEBOARD_FAB2_LIB.BASEBOARD_FAB2(SCH_1):PAGE40
  U5D1 AK31 VSS<791> SKX_EXT_B_BGA1-IC,TBD    I22 @BASEBOARD_FAB2_LIB.BASEBOARD_FAB2(SCH_1):PAGE40
  U5D1 AK29 VSS<792> SKX_EXT_B_BGA1-IC,TBD    I22 @BASEBOARD_FAB2_LIB.BASEBOARD_FAB2(SCH_1):PAGE40
  U5D1 AK25 VSS<793> SKX_EXT_B_BGA1-IC,TBD    I22 @BASEBOARD_FAB2_LIB.BASEBOARD_FAB2(SCH_1):PAGE40
  U5D1 AK23 VSS<794> SKX_EXT_B_BGA1-IC,TBD    I22 @BASEBOARD_FAB2_LIB.BASEBOARD_FAB2(SCH_1):PAGE40
  U5D1 AK19 VSS<795> SKX_EXT_B_BGA1-IC,TBD    I22 @BASEBOARD_FAB2_LIB.BASEBOARD_FAB2(SCH_1):PAGE40
  U5D1 AK13 VSS<796> SKX_EXT_B_BGA1-IC,TBD    I22 @BASEBOARD_FAB2_LIB.BASEBOARD_FAB2(SCH_1):PAGE40
  U5D1  AK9 VSS<797> SKX_EXT_B_BGA1-IC,TBD    I22 @BASEBOARD_FAB2_LIB.BASEBOARD_FAB2(SCH_1):PAGE40
  U5D1 AJ86 VSS<798> SKX_EXT_B_BGA1-IC,TBD    I22 @BASEBOARD_FAB2_LIB.BASEBOARD_FAB2(SCH_1):PAGE40
  U5D1 AJ82 VSS<799> SKX_EXT_B_BGA1-IC,TBD    I22 @BASEBOARD_FAB2_LIB.BASEBOARD_FAB2(SCH_1):PAGE40
  U5D1 AJ78 VSS<800> SKX_EXT_B_BGA1-IC,TBD    I22 @BASEBOARD_FAB2_LIB.BASEBOARD_FAB2(SCH_1):PAGE40
  U5D1 AJ74 VSS<801> SKX_EXT_B_BGA1-IC,TBD    I22 @BASEBOARD_FAB2_LIB.BASEBOARD_FAB2(SCH_1):PAGE40
  U5D1 AJ68 VSS<802> SKX_EXT_B_BGA1-IC,TBD    I22 @BASEBOARD_FAB2_LIB.BASEBOARD_FAB2(SCH_1):PAGE40
  U5D1 AJ66 VSS<803> SKX_EXT_B_BGA1-IC,TBD    I22 @BASEBOARD_FAB2_LIB.BASEBOARD_FAB2(SCH_1):PAGE40
  U5D1 AJ54 VSS<804> SKX_EXT_B_BGA1-IC,TBD    I22 @BASEBOARD_FAB2_LIB.BASEBOARD_FAB2(SCH_1):PAGE40
  U5D1 AJ52 VSS<805> SKX_EXT_B_BGA1-IC,TBD    I22 @BASEBOARD_FAB2_LIB.BASEBOARD_FAB2(SCH_1):PAGE40
  U5D1 AJ50 VSS<806> SKX_EXT_B_BGA1-IC,TBD    I22 @BASEBOARD_FAB2_LIB.BASEBOARD_FAB2(SCH_1):PAGE40
  U5D1 AJ48 VSS<807> SKX_EXT_B_BGA1-IC,TBD    I22 @BASEBOARD_FAB2_LIB.BASEBOARD_FAB2(SCH_1):PAGE40
  U5D1 AJ46 VSS<808> SKX_EXT_B_BGA1-IC,TBD    I22 @BASEBOARD_FAB2_LIB.BASEBOARD_FAB2(SCH_1):PAGE40
  U5D1 AJ34 VSS<809> SKX_EXT_B_BGA1-IC,TBD    I22 @BASEBOARD_FAB2_LIB.BASEBOARD_FAB2(SCH_1):PAGE40
  U5D1 AJ32 VSS<810> SKX_EXT_B_BGA1-IC,TBD    I22 @BASEBOARD_FAB2_LIB.BASEBOARD_FAB2(SCH_1):PAGE40
  U5D1 AJ28 VSS<811> SKX_EXT_B_BGA1-IC,TBD    I22 @BASEBOARD_FAB2_LIB.BASEBOARD_FAB2(SCH_1):PAGE40
  U5D1 AJ26 VSS<812> SKX_EXT_B_BGA1-IC,TBD    I22 @BASEBOARD_FAB2_LIB.BASEBOARD_FAB2(SCH_1):PAGE40
  U5D1 AJ22 VSS<813> SKX_EXT_B_BGA1-IC,TBD    I22 @BASEBOARD_FAB2_LIB.BASEBOARD_FAB2(SCH_1):PAGE40
  U5D1  AJ8 VSS<814> SKX_EXT_B_BGA1-IC,TBD    I22 @BASEBOARD_FAB2_LIB.BASEBOARD_FAB2(SCH_1):PAGE40
  U5D1 AH83 VSS<815> SKX_EXT_B_BGA1-IC,TBD    I22 @BASEBOARD_FAB2_LIB.BASEBOARD_FAB2(SCH_1):PAGE40
  U5D1 AH77 VSS<816> SKX_EXT_B_BGA1-IC,TBD    I22 @BASEBOARD_FAB2_LIB.BASEBOARD_FAB2(SCH_1):PAGE40
  U5D1 AH75 VSS<817> SKX_EXT_B_BGA1-IC,TBD    I22 @BASEBOARD_FAB2_LIB.BASEBOARD_FAB2(SCH_1):PAGE40
  U5D1 AH69 VSS<818> SKX_EXT_B_BGA1-IC,TBD    I22 @BASEBOARD_FAB2_LIB.BASEBOARD_FAB2(SCH_1):PAGE40
  U5D1 AH65 VSS<819> SKX_EXT_B_BGA1-IC,TBD    I22 @BASEBOARD_FAB2_LIB.BASEBOARD_FAB2(SCH_1):PAGE40
  U5D1 AH61 VSS<820> SKX_EXT_B_BGA1-IC,TBD    I22 @BASEBOARD_FAB2_LIB.BASEBOARD_FAB2(SCH_1):PAGE40
  U5D1 AH59 VSS<821> SKX_EXT_B_BGA1-IC,TBD    I22 @BASEBOARD_FAB2_LIB.BASEBOARD_FAB2(SCH_1):PAGE40
  U5D1 AH53 VSS<822> SKX_EXT_B_BGA1-IC,TBD    I22 @BASEBOARD_FAB2_LIB.BASEBOARD_FAB2(SCH_1):PAGE40
  U5D1 AH51 VSS<823> SKX_EXT_B_BGA1-IC,TBD    I22 @BASEBOARD_FAB2_LIB.BASEBOARD_FAB2(SCH_1):PAGE40
  U5D1 AH49 VSS<824> SKX_EXT_B_BGA1-IC,TBD    I22 @BASEBOARD_FAB2_LIB.BASEBOARD_FAB2(SCH_1):PAGE40
  U5D1 AH47 VSS<825> SKX_EXT_B_BGA1-IC,TBD    I22 @BASEBOARD_FAB2_LIB.BASEBOARD_FAB2(SCH_1):PAGE40
  U5D1 AH45 VSS<826> SKX_EXT_B_BGA1-IC,TBD    I22 @BASEBOARD_FAB2_LIB.BASEBOARD_FAB2(SCH_1):PAGE40
  U5D1 AH35 VSS<827> SKX_EXT_B_BGA1-IC,TBD    I22 @BASEBOARD_FAB2_LIB.BASEBOARD_FAB2(SCH_1):PAGE40
  U5D1 AH33 VSS<828> SKX_EXT_B_BGA1-IC,TBD    I22 @BASEBOARD_FAB2_LIB.BASEBOARD_FAB2(SCH_1):PAGE40
  U5D1 AH27 VSS<829> SKX_EXT_B_BGA1-IC,TBD    I22 @BASEBOARD_FAB2_LIB.BASEBOARD_FAB2(SCH_1):PAGE40
  U5D1 AH21 VSS<830> SKX_EXT_B_BGA1-IC,TBD    I22 @BASEBOARD_FAB2_LIB.BASEBOARD_FAB2(SCH_1):PAGE40
  U5D1  AH5 VSS<831> SKX_EXT_B_BGA1-IC,TBD    I22 @BASEBOARD_FAB2_LIB.BASEBOARD_FAB2(SCH_1):PAGE40
  U5D1  AH1 VSS<832> SKX_EXT_B_BGA1-IC,TBD    I22 @BASEBOARD_FAB2_LIB.BASEBOARD_FAB2(SCH_1):PAGE40
  U5D1 AG80 VSS<833> SKX_EXT_B_BGA1-IC,TBD    I22 @BASEBOARD_FAB2_LIB.BASEBOARD_FAB2(SCH_1):PAGE40
  U5D1 AG78 VSS<834> SKX_EXT_B_BGA1-IC,TBD    I22 @BASEBOARD_FAB2_LIB.BASEBOARD_FAB2(SCH_1):PAGE40
  U5D1 AG76 VSS<835> SKX_EXT_B_BGA1-IC,TBD    I22 @BASEBOARD_FAB2_LIB.BASEBOARD_FAB2(SCH_1):PAGE40
  U5D1 AG74 VSS<836> SKX_EXT_B_BGA1-IC,TBD    I22 @BASEBOARD_FAB2_LIB.BASEBOARD_FAB2(SCH_1):PAGE40
  U5D1 AG70 VSS<837> SKX_EXT_B_BGA1-IC,TBD    I22 @BASEBOARD_FAB2_LIB.BASEBOARD_FAB2(SCH_1):PAGE40
  U5D1 AG64 VSS<838> SKX_EXT_B_BGA1-IC,TBD    I22 @BASEBOARD_FAB2_LIB.BASEBOARD_FAB2(SCH_1):PAGE40
  U5D1 AG36 VSS<839> SKX_EXT_B_BGA1-IC,TBD    I22 @BASEBOARD_FAB2_LIB.BASEBOARD_FAB2(SCH_1):PAGE40
  U5D1 AG18 VSS<840> SKX_EXT_B_BGA1-IC,TBD    I22 @BASEBOARD_FAB2_LIB.BASEBOARD_FAB2(SCH_1):PAGE40
  U5D1 AG14 VSS<841> SKX_EXT_B_BGA1-IC,TBD    I22 @BASEBOARD_FAB2_LIB.BASEBOARD_FAB2(SCH_1):PAGE40
  U5D1 AG12 VSS<842> SKX_EXT_B_BGA1-IC,TBD    I22 @BASEBOARD_FAB2_LIB.BASEBOARD_FAB2(SCH_1):PAGE40
  U5D1 AF85 VSS<843> SKX_EXT_B_BGA1-IC,TBD    I22 @BASEBOARD_FAB2_LIB.BASEBOARD_FAB2(SCH_1):PAGE40
  U5D1 AF83 VSS<844> SKX_EXT_B_BGA1-IC,TBD    I22 @BASEBOARD_FAB2_LIB.BASEBOARD_FAB2(SCH_1):PAGE40
  U5D1 AF77 VSS<845> SKX_EXT_B_BGA1-IC,TBD    I22 @BASEBOARD_FAB2_LIB.BASEBOARD_FAB2(SCH_1):PAGE40
  U5D1 AF73 VSS<846> SKX_EXT_B_BGA1-IC,TBD    I22 @BASEBOARD_FAB2_LIB.BASEBOARD_FAB2(SCH_1):PAGE40
  U5D1 AF41 VSS<847> SKX_EXT_B_BGA1-IC,TBD    I22 @BASEBOARD_FAB2_LIB.BASEBOARD_FAB2(SCH_1):PAGE40
  U5D1 AF39 VSS<848> SKX_EXT_B_BGA1-IC,TBD    I22 @BASEBOARD_FAB2_LIB.BASEBOARD_FAB2(SCH_1):PAGE40
  U5D1 AF37 VSS<849> SKX_EXT_B_BGA1-IC,TBD    I22 @BASEBOARD_FAB2_LIB.BASEBOARD_FAB2(SCH_1):PAGE40
  U5D1 AF33 VSS<850> SKX_EXT_B_BGA1-IC,TBD    I22 @BASEBOARD_FAB2_LIB.BASEBOARD_FAB2(SCH_1):PAGE40
  U5D1 AF31 VSS<851> SKX_EXT_B_BGA1-IC,TBD    I22 @BASEBOARD_FAB2_LIB.BASEBOARD_FAB2(SCH_1):PAGE40
  U5D1 AF29 VSS<852> SKX_EXT_B_BGA1-IC,TBD    I22 @BASEBOARD_FAB2_LIB.BASEBOARD_FAB2(SCH_1):PAGE40
  U5D1 AF27 VSS<853> SKX_EXT_B_BGA1-IC,TBD    I22 @BASEBOARD_FAB2_LIB.BASEBOARD_FAB2(SCH_1):PAGE40
  U5D1 AF25 VSS<854> SKX_EXT_B_BGA1-IC,TBD    I22 @BASEBOARD_FAB2_LIB.BASEBOARD_FAB2(SCH_1):PAGE40
  U5D1 AF23 VSS<855> SKX_EXT_B_BGA1-IC,TBD    I22 @BASEBOARD_FAB2_LIB.BASEBOARD_FAB2(SCH_1):PAGE40
  U5D1 AF21 VSS<856> SKX_EXT_B_BGA1-IC,TBD    I22 @BASEBOARD_FAB2_LIB.BASEBOARD_FAB2(SCH_1):PAGE40
  U5D1  AF9 VSS<857> SKX_EXT_B_BGA1-IC,TBD    I22 @BASEBOARD_FAB2_LIB.BASEBOARD_FAB2(SCH_1):PAGE40
  U5D1 AC52 VSS<858> SKX_EXT_B_BGA1-IC,TBD    I22 @BASEBOARD_FAB2_LIB.BASEBOARD_FAB2(SCH_1):PAGE40
  U5D1  AF1 VSS<859> SKX_EXT_B_BGA1-IC,TBD    I22 @BASEBOARD_FAB2_LIB.BASEBOARD_FAB2(SCH_1):PAGE40
  U5D1 AE78 VSS<860> SKX_EXT_B_BGA1-IC,TBD    I22 @BASEBOARD_FAB2_LIB.BASEBOARD_FAB2(SCH_1):PAGE40
  U5D1 AE70 VSS<861> SKX_EXT_B_BGA1-IC,TBD    I22 @BASEBOARD_FAB2_LIB.BASEBOARD_FAB2(SCH_1):PAGE40
  U5D1 AE68 VSS<862> SKX_EXT_B_BGA1-IC,TBD    I22 @BASEBOARD_FAB2_LIB.BASEBOARD_FAB2(SCH_1):PAGE40
  U5D1 AE66 VSS<863> SKX_EXT_B_BGA1-IC,TBD    I22 @BASEBOARD_FAB2_LIB.BASEBOARD_FAB2(SCH_1):PAGE40
  U5D1 AE64 VSS<864> SKX_EXT_B_BGA1-IC,TBD    I22 @BASEBOARD_FAB2_LIB.BASEBOARD_FAB2(SCH_1):PAGE40
  U5D1 AE42 VSS<865> SKX_EXT_B_BGA1-IC,TBD    I22 @BASEBOARD_FAB2_LIB.BASEBOARD_FAB2(SCH_1):PAGE40
  U5D1 AE40 VSS<866> SKX_EXT_B_BGA1-IC,TBD    I22 @BASEBOARD_FAB2_LIB.BASEBOARD_FAB2(SCH_1):PAGE40
  U5D1 AE38 VSS<867> SKX_EXT_B_BGA1-IC,TBD    I22 @BASEBOARD_FAB2_LIB.BASEBOARD_FAB2(SCH_1):PAGE40
  U5D1 AE16 VSS<868> SKX_EXT_B_BGA1-IC,TBD    I22 @BASEBOARD_FAB2_LIB.BASEBOARD_FAB2(SCH_1):PAGE40
  U5D1 AC54 VSS<869> SKX_EXT_B_BGA1-IC,TBD    I22 @BASEBOARD_FAB2_LIB.BASEBOARD_FAB2(SCH_1):PAGE40
  U5D1  AE8 VSS<870> SKX_EXT_B_BGA1-IC,TBD    I22 @BASEBOARD_FAB2_LIB.BASEBOARD_FAB2(SCH_1):PAGE40
  U5D1  AE4 VSS<871> SKX_EXT_B_BGA1-IC,TBD    I22 @BASEBOARD_FAB2_LIB.BASEBOARD_FAB2(SCH_1):PAGE40
  U5D1 AD85 VSS<872> SKX_EXT_B_BGA1-IC,TBD    I22 @BASEBOARD_FAB2_LIB.BASEBOARD_FAB2(SCH_1):PAGE40
  U5D1 AD83 VSS<873> SKX_EXT_B_BGA1-IC,TBD    I22 @BASEBOARD_FAB2_LIB.BASEBOARD_FAB2(SCH_1):PAGE40
  U5D1 AD81 VSS<874> SKX_EXT_B_BGA1-IC,TBD    I22 @BASEBOARD_FAB2_LIB.BASEBOARD_FAB2(SCH_1):PAGE40
  U5D1 AD75 VSS<875> SKX_EXT_B_BGA1-IC,TBD    I22 @BASEBOARD_FAB2_LIB.BASEBOARD_FAB2(SCH_1):PAGE40
  U5D1 AD73 VSS<876> SKX_EXT_B_BGA1-IC,TBD    I22 @BASEBOARD_FAB2_LIB.BASEBOARD_FAB2(SCH_1):PAGE40
  U5D1 AD71 VSS<877> SKX_EXT_B_BGA1-IC,TBD    I22 @BASEBOARD_FAB2_LIB.BASEBOARD_FAB2(SCH_1):PAGE40
  U5D1 AD43 VSS<878> SKX_EXT_B_BGA1-IC,TBD    I22 @BASEBOARD_FAB2_LIB.BASEBOARD_FAB2(SCH_1):PAGE40
  U5D1 AD39 VSS<879> SKX_EXT_B_BGA1-IC,TBD    I22 @BASEBOARD_FAB2_LIB.BASEBOARD_FAB2(SCH_1):PAGE40
  U5D1 AD33 VSS<880> SKX_EXT_B_BGA1-IC,TBD    I22 @BASEBOARD_FAB2_LIB.BASEBOARD_FAB2(SCH_1):PAGE40
  U5D1 AD27 VSS<881> SKX_EXT_B_BGA1-IC,TBD    I22 @BASEBOARD_FAB2_LIB.BASEBOARD_FAB2(SCH_1):PAGE40
  U5D1 AD21 VSS<882> SKX_EXT_B_BGA1-IC,TBD    I22 @BASEBOARD_FAB2_LIB.BASEBOARD_FAB2(SCH_1):PAGE40
  U5D1 AD19 VSS<883> SKX_EXT_B_BGA1-IC,TBD    I22 @BASEBOARD_FAB2_LIB.BASEBOARD_FAB2(SCH_1):PAGE40
  U5D1 AD15 VSS<884> SKX_EXT_B_BGA1-IC,TBD    I22 @BASEBOARD_FAB2_LIB.BASEBOARD_FAB2(SCH_1):PAGE40
  U5D1 AD13 VSS<885> SKX_EXT_B_BGA1-IC,TBD    I22 @BASEBOARD_FAB2_LIB.BASEBOARD_FAB2(SCH_1):PAGE40
  U5D1 AD11 VSS<886> SKX_EXT_B_BGA1-IC,TBD    I22 @BASEBOARD_FAB2_LIB.BASEBOARD_FAB2(SCH_1):PAGE40
  U5D1  AD9 VSS<887> SKX_EXT_B_BGA1-IC,TBD    I22 @BASEBOARD_FAB2_LIB.BASEBOARD_FAB2(SCH_1):PAGE40
  U5D1  AD7 VSS<888> SKX_EXT_B_BGA1-IC,TBD    I22 @BASEBOARD_FAB2_LIB.BASEBOARD_FAB2(SCH_1):PAGE40
  U5D1  AD3 VSS<889> SKX_EXT_B_BGA1-IC,TBD    I22 @BASEBOARD_FAB2_LIB.BASEBOARD_FAB2(SCH_1):PAGE40
  U5D1 AC86 VSS<890> SKX_EXT_B_BGA1-IC,TBD    I22 @BASEBOARD_FAB2_LIB.BASEBOARD_FAB2(SCH_1):PAGE40
  U5D1 AC84 VSS<891> SKX_EXT_B_BGA1-IC,TBD    I22 @BASEBOARD_FAB2_LIB.BASEBOARD_FAB2(SCH_1):PAGE40
  U5D1 AC78 VSS<892> SKX_EXT_B_BGA1-IC,TBD    I22 @BASEBOARD_FAB2_LIB.BASEBOARD_FAB2(SCH_1):PAGE40
  U5D1 AC72 VSS<893> SKX_EXT_B_BGA1-IC,TBD    I22 @BASEBOARD_FAB2_LIB.BASEBOARD_FAB2(SCH_1):PAGE40
  U5D1 AC70 VSS<894> SKX_EXT_B_BGA1-IC,TBD    I22 @BASEBOARD_FAB2_LIB.BASEBOARD_FAB2(SCH_1):PAGE40
  U5D1 AC64 VSS<895> SKX_EXT_B_BGA1-IC,TBD    I22 @BASEBOARD_FAB2_LIB.BASEBOARD_FAB2(SCH_1):PAGE40
  U5D1 AC40 VSS<896> SKX_EXT_B_BGA1-IC,TBD    I22 @BASEBOARD_FAB2_LIB.BASEBOARD_FAB2(SCH_1):PAGE40
  U5D1 AC38 VSS<897> SKX_EXT_B_BGA1-IC,TBD    I22 @BASEBOARD_FAB2_LIB.BASEBOARD_FAB2(SCH_1):PAGE40
  U5D1 AC34 VSS<898> SKX_EXT_B_BGA1-IC,TBD    I22 @BASEBOARD_FAB2_LIB.BASEBOARD_FAB2(SCH_1):PAGE40
  U5D1 AC32 VSS<899> SKX_EXT_B_BGA1-IC,TBD    I22 @BASEBOARD_FAB2_LIB.BASEBOARD_FAB2(SCH_1):PAGE40
  U5D1 AC28 VSS<900> SKX_EXT_B_BGA1-IC,TBD    I22 @BASEBOARD_FAB2_LIB.BASEBOARD_FAB2(SCH_1):PAGE40
  U5D1 AC26 VSS<901> SKX_EXT_B_BGA1-IC,TBD    I22 @BASEBOARD_FAB2_LIB.BASEBOARD_FAB2(SCH_1):PAGE40
  U5D1 AC22 VSS<902> SKX_EXT_B_BGA1-IC,TBD    I22 @BASEBOARD_FAB2_LIB.BASEBOARD_FAB2(SCH_1):PAGE40
  U5D1 AC18 VSS<903> SKX_EXT_B_BGA1-IC,TBD    I22 @BASEBOARD_FAB2_LIB.BASEBOARD_FAB2(SCH_1):PAGE40
  U5D1 AB85 VSS<904> SKX_EXT_B_BGA1-IC,TBD    I22 @BASEBOARD_FAB2_LIB.BASEBOARD_FAB2(SCH_1):PAGE40
  U5D1 AB83 VSS<905> SKX_EXT_B_BGA1-IC,TBD    I22 @BASEBOARD_FAB2_LIB.BASEBOARD_FAB2(SCH_1):PAGE40
  U5D1 AB79 VSS<906> SKX_EXT_B_BGA1-IC,TBD    I22 @BASEBOARD_FAB2_LIB.BASEBOARD_FAB2(SCH_1):PAGE40
  U5D1 AB73 VSS<907> SKX_EXT_B_BGA1-IC,TBD    I22 @BASEBOARD_FAB2_LIB.BASEBOARD_FAB2(SCH_1):PAGE40
  U5D1 AB69 VSS<908> SKX_EXT_B_BGA1-IC,TBD    I22 @BASEBOARD_FAB2_LIB.BASEBOARD_FAB2(SCH_1):PAGE40
  U5D1 AB65 VSS<909> SKX_EXT_B_BGA1-IC,TBD    I22 @BASEBOARD_FAB2_LIB.BASEBOARD_FAB2(SCH_1):PAGE40
  U5D1 AB41 VSS<910> SKX_EXT_B_BGA1-IC,TBD    I22 @BASEBOARD_FAB2_LIB.BASEBOARD_FAB2(SCH_1):PAGE40
  U5D1 AB37 VSS<911> SKX_EXT_B_BGA1-IC,TBD    I22 @BASEBOARD_FAB2_LIB.BASEBOARD_FAB2(SCH_1):PAGE40
  U5D1 AB35 VSS<912> SKX_EXT_B_BGA1-IC,TBD    I22 @BASEBOARD_FAB2_LIB.BASEBOARD_FAB2(SCH_1):PAGE40
  U5D1 AB31 VSS<913> SKX_EXT_B_BGA1-IC,TBD    I22 @BASEBOARD_FAB2_LIB.BASEBOARD_FAB2(SCH_1):PAGE40
  U5D1 AB29 VSS<914> SKX_EXT_B_BGA1-IC,TBD    I22 @BASEBOARD_FAB2_LIB.BASEBOARD_FAB2(SCH_1):PAGE40
  U5D1 AB25 VSS<915> SKX_EXT_B_BGA1-IC,TBD    I22 @BASEBOARD_FAB2_LIB.BASEBOARD_FAB2(SCH_1):PAGE40
  U5D1 AB23 VSS<916> SKX_EXT_B_BGA1-IC,TBD    I22 @BASEBOARD_FAB2_LIB.BASEBOARD_FAB2(SCH_1):PAGE40
  U5D1 AB21 VSS<917> SKX_EXT_B_BGA1-IC,TBD    I22 @BASEBOARD_FAB2_LIB.BASEBOARD_FAB2(SCH_1):PAGE40
  U5D1 AB11 VSS<918> SKX_EXT_B_BGA1-IC,TBD    I22 @BASEBOARD_FAB2_LIB.BASEBOARD_FAB2(SCH_1):PAGE40
  U5D1  AB5 VSS<919> SKX_EXT_B_BGA1-IC,TBD    I22 @BASEBOARD_FAB2_LIB.BASEBOARD_FAB2(SCH_1):PAGE40
  U5D1  AB1 VSS<920> SKX_EXT_B_BGA1-IC,TBD    I22 @BASEBOARD_FAB2_LIB.BASEBOARD_FAB2(SCH_1):PAGE40
  U5D1 AA82 VSS<921> SKX_EXT_B_BGA1-IC,TBD    I22 @BASEBOARD_FAB2_LIB.BASEBOARD_FAB2(SCH_1):PAGE40
  U5D1 AA80 VSS<922> SKX_EXT_B_BGA1-IC,TBD    I22 @BASEBOARD_FAB2_LIB.BASEBOARD_FAB2(SCH_1):PAGE40
  U5D1 AA78 VSS<923> SKX_EXT_B_BGA1-IC,TBD    I22 @BASEBOARD_FAB2_LIB.BASEBOARD_FAB2(SCH_1):PAGE40
  U5D1 AA76 VSS<924> SKX_EXT_B_BGA1-IC,TBD    I22 @BASEBOARD_FAB2_LIB.BASEBOARD_FAB2(SCH_1):PAGE40
  U5D1 AA68 VSS<925> SKX_EXT_B_BGA1-IC,TBD    I22 @BASEBOARD_FAB2_LIB.BASEBOARD_FAB2(SCH_1):PAGE40
  U5D1 AA66 VSS<926> SKX_EXT_B_BGA1-IC,TBD    I22 @BASEBOARD_FAB2_LIB.BASEBOARD_FAB2(SCH_1):PAGE40
  U5D1 AA64 VSS<927> SKX_EXT_B_BGA1-IC,TBD    I22 @BASEBOARD_FAB2_LIB.BASEBOARD_FAB2(SCH_1):PAGE40
  U5D1 AA42 VSS<928> SKX_EXT_B_BGA1-IC,TBD    I22 @BASEBOARD_FAB2_LIB.BASEBOARD_FAB2(SCH_1):PAGE40
  U5D1 AA36 VSS<929> SKX_EXT_B_BGA1-IC,TBD    I22 @BASEBOARD_FAB2_LIB.BASEBOARD_FAB2(SCH_1):PAGE40
  U5D1 AA30 VSS<930> SKX_EXT_B_BGA1-IC,TBD    I22 @BASEBOARD_FAB2_LIB.BASEBOARD_FAB2(SCH_1):PAGE40
  U5D1 AA24 VSS<931> SKX_EXT_B_BGA1-IC,TBD    I22 @BASEBOARD_FAB2_LIB.BASEBOARD_FAB2(SCH_1):PAGE40
  U5D1 AA22 VSS<932> SKX_EXT_B_BGA1-IC,TBD    I22 @BASEBOARD_FAB2_LIB.BASEBOARD_FAB2(SCH_1):PAGE40
  U5D1 AA18 VSS<933> SKX_EXT_B_BGA1-IC,TBD    I22 @BASEBOARD_FAB2_LIB.BASEBOARD_FAB2(SCH_1):PAGE40
  U5D1 BG72 VSS<614> SKX_EXT_B_BGA1-IC,TBD    I23 @BASEBOARD_FAB2_LIB.BASEBOARD_FAB2(SCH_1):PAGE40
  U5D1 BG24 VSS<615> SKX_EXT_B_BGA1-IC,TBD    I23 @BASEBOARD_FAB2_LIB.BASEBOARD_FAB2(SCH_1):PAGE40
  U5D1 BG22 VSS<616> SKX_EXT_B_BGA1-IC,TBD    I23 @BASEBOARD_FAB2_LIB.BASEBOARD_FAB2(SCH_1):PAGE40
  U5D1 BG10 VSS<617> SKX_EXT_B_BGA1-IC,TBD    I23 @BASEBOARD_FAB2_LIB.BASEBOARD_FAB2(SCH_1):PAGE40
  U5D1  BG8 VSS<618> SKX_EXT_B_BGA1-IC,TBD    I23 @BASEBOARD_FAB2_LIB.BASEBOARD_FAB2(SCH_1):PAGE40
  U5D1  BG6 VSS<619> SKX_EXT_B_BGA1-IC,TBD    I23 @BASEBOARD_FAB2_LIB.BASEBOARD_FAB2(SCH_1):PAGE40
  U5D1 BF71 VSS<620> SKX_EXT_B_BGA1-IC,TBD    I23 @BASEBOARD_FAB2_LIB.BASEBOARD_FAB2(SCH_1):PAGE40
  U5D1 BF69 VSS<621> SKX_EXT_B_BGA1-IC,TBD    I23 @BASEBOARD_FAB2_LIB.BASEBOARD_FAB2(SCH_1):PAGE40
  U5D1 BF67 VSS<622> SKX_EXT_B_BGA1-IC,TBD    I23 @BASEBOARD_FAB2_LIB.BASEBOARD_FAB2(SCH_1):PAGE40
  U5D1 BF65 VSS<623> SKX_EXT_B_BGA1-IC,TBD    I23 @BASEBOARD_FAB2_LIB.BASEBOARD_FAB2(SCH_1):PAGE40
  U5D1 BF63 VSS<624> SKX_EXT_B_BGA1-IC,TBD    I23 @BASEBOARD_FAB2_LIB.BASEBOARD_FAB2(SCH_1):PAGE40
  U5D1 BF25 VSS<625> SKX_EXT_B_BGA1-IC,TBD    I23 @BASEBOARD_FAB2_LIB.BASEBOARD_FAB2(SCH_1):PAGE40
  U5D1 BF19 VSS<626> SKX_EXT_B_BGA1-IC,TBD    I23 @BASEBOARD_FAB2_LIB.BASEBOARD_FAB2(SCH_1):PAGE40
  U5D1 BF17 VSS<627> SKX_EXT_B_BGA1-IC,TBD    I23 @BASEBOARD_FAB2_LIB.BASEBOARD_FAB2(SCH_1):PAGE40
  U5D1 BF15 VSS<628> SKX_EXT_B_BGA1-IC,TBD    I23 @BASEBOARD_FAB2_LIB.BASEBOARD_FAB2(SCH_1):PAGE40
  U5D1  BF9 VSS<629> SKX_EXT_B_BGA1-IC,TBD    I23 @BASEBOARD_FAB2_LIB.BASEBOARD_FAB2(SCH_1):PAGE40
  U5D1 BE70 VSS<630> SKX_EXT_B_BGA1-IC,TBD    I23 @BASEBOARD_FAB2_LIB.BASEBOARD_FAB2(SCH_1):PAGE40
  U5D1 BE68 VSS<631> SKX_EXT_B_BGA1-IC,TBD    I23 @BASEBOARD_FAB2_LIB.BASEBOARD_FAB2(SCH_1):PAGE40
  U5D1 BE66 VSS<632> SKX_EXT_B_BGA1-IC,TBD    I23 @BASEBOARD_FAB2_LIB.BASEBOARD_FAB2(SCH_1):PAGE40
  U5D1 BE64 VSS<633> SKX_EXT_B_BGA1-IC,TBD    I23 @BASEBOARD_FAB2_LIB.BASEBOARD_FAB2(SCH_1):PAGE40
  U5D1 BE26 VSS<634> SKX_EXT_B_BGA1-IC,TBD    I23 @BASEBOARD_FAB2_LIB.BASEBOARD_FAB2(SCH_1):PAGE40
  U5D1 BE10 VSS<635> SKX_EXT_B_BGA1-IC,TBD    I23 @BASEBOARD_FAB2_LIB.BASEBOARD_FAB2(SCH_1):PAGE40
  U5D1  BE8 VSS<636> SKX_EXT_B_BGA1-IC,TBD    I23 @BASEBOARD_FAB2_LIB.BASEBOARD_FAB2(SCH_1):PAGE40
  U5D1  BE6 VSS<637> SKX_EXT_B_BGA1-IC,TBD    I23 @BASEBOARD_FAB2_LIB.BASEBOARD_FAB2(SCH_1):PAGE40
  U5D1  BE4 VSS<638> SKX_EXT_B_BGA1-IC,TBD    I23 @BASEBOARD_FAB2_LIB.BASEBOARD_FAB2(SCH_1):PAGE40
  U5D1 BD71 VSS<639> SKX_EXT_B_BGA1-IC,TBD    I23 @BASEBOARD_FAB2_LIB.BASEBOARD_FAB2(SCH_1):PAGE40
  U5D1 BD63 VSS<640> SKX_EXT_B_BGA1-IC,TBD    I23 @BASEBOARD_FAB2_LIB.BASEBOARD_FAB2(SCH_1):PAGE40
  U5D1 BD27 VSS<641> SKX_EXT_B_BGA1-IC,TBD    I23 @BASEBOARD_FAB2_LIB.BASEBOARD_FAB2(SCH_1):PAGE40
  U5D1 BD21 VSS<642> SKX_EXT_B_BGA1-IC,TBD    I23 @BASEBOARD_FAB2_LIB.BASEBOARD_FAB2(SCH_1):PAGE40
  U5D1 BD15 VSS<643> SKX_EXT_B_BGA1-IC,TBD    I23 @BASEBOARD_FAB2_LIB.BASEBOARD_FAB2(SCH_1):PAGE40
  U5D1 BD11 VSS<644> SKX_EXT_B_BGA1-IC,TBD    I23 @BASEBOARD_FAB2_LIB.BASEBOARD_FAB2(SCH_1):PAGE40
  U5D1  BD5 VSS<645> SKX_EXT_B_BGA1-IC,TBD    I23 @BASEBOARD_FAB2_LIB.BASEBOARD_FAB2(SCH_1):PAGE40
  U5D1 BC82 VSS<646> SKX_EXT_B_BGA1-IC,TBD    I23 @BASEBOARD_FAB2_LIB.BASEBOARD_FAB2(SCH_1):PAGE40
  U5D1 BC80 VSS<647> SKX_EXT_B_BGA1-IC,TBD    I23 @BASEBOARD_FAB2_LIB.BASEBOARD_FAB2(SCH_1):PAGE40
  U5D1 BC78 VSS<648> SKX_EXT_B_BGA1-IC,TBD    I23 @BASEBOARD_FAB2_LIB.BASEBOARD_FAB2(SCH_1):PAGE40
  U5D1 BC76 VSS<649> SKX_EXT_B_BGA1-IC,TBD    I23 @BASEBOARD_FAB2_LIB.BASEBOARD_FAB2(SCH_1):PAGE40
  U5D1 BC74 VSS<650> SKX_EXT_B_BGA1-IC,TBD    I23 @BASEBOARD_FAB2_LIB.BASEBOARD_FAB2(SCH_1):PAGE40
  U5D1 BC72 VSS<651> SKX_EXT_B_BGA1-IC,TBD    I23 @BASEBOARD_FAB2_LIB.BASEBOARD_FAB2(SCH_1):PAGE40
  U5D1 BC70 VSS<652> SKX_EXT_B_BGA1-IC,TBD    I23 @BASEBOARD_FAB2_LIB.BASEBOARD_FAB2(SCH_1):PAGE40
  U5D1 BC16 VSS<653> SKX_EXT_B_BGA1-IC,TBD    I23 @BASEBOARD_FAB2_LIB.BASEBOARD_FAB2(SCH_1):PAGE40
  U5D1 BC12 VSS<654> SKX_EXT_B_BGA1-IC,TBD    I23 @BASEBOARD_FAB2_LIB.BASEBOARD_FAB2(SCH_1):PAGE40
  U5D1  BC8 VSS<655> SKX_EXT_B_BGA1-IC,TBD    I23 @BASEBOARD_FAB2_LIB.BASEBOARD_FAB2(SCH_1):PAGE40
  U5D1  BC4 VSS<656> SKX_EXT_B_BGA1-IC,TBD    I23 @BASEBOARD_FAB2_LIB.BASEBOARD_FAB2(SCH_1):PAGE40
  U5D1 BB83 VSS<657> SKX_EXT_B_BGA1-IC,TBD    I23 @BASEBOARD_FAB2_LIB.BASEBOARD_FAB2(SCH_1):PAGE40
  U5D1 BB81 VSS<658> SKX_EXT_B_BGA1-IC,TBD    I23 @BASEBOARD_FAB2_LIB.BASEBOARD_FAB2(SCH_1):PAGE40
  U5D1 BB79 VSS<659> SKX_EXT_B_BGA1-IC,TBD    I23 @BASEBOARD_FAB2_LIB.BASEBOARD_FAB2(SCH_1):PAGE40
  U5D1 BB77 VSS<660> SKX_EXT_B_BGA1-IC,TBD    I23 @BASEBOARD_FAB2_LIB.BASEBOARD_FAB2(SCH_1):PAGE40
  U5D1 BB75 VSS<661> SKX_EXT_B_BGA1-IC,TBD    I23 @BASEBOARD_FAB2_LIB.BASEBOARD_FAB2(SCH_1):PAGE40
  U5D1 BB73 VSS<662> SKX_EXT_B_BGA1-IC,TBD    I23 @BASEBOARD_FAB2_LIB.BASEBOARD_FAB2(SCH_1):PAGE40
  U5D1 BB69 VSS<663> SKX_EXT_B_BGA1-IC,TBD    I23 @BASEBOARD_FAB2_LIB.BASEBOARD_FAB2(SCH_1):PAGE40
  U5D1 BB63 VSS<664> SKX_EXT_B_BGA1-IC,TBD    I23 @BASEBOARD_FAB2_LIB.BASEBOARD_FAB2(SCH_1):PAGE40
  U5D1 BB23 VSS<665> SKX_EXT_B_BGA1-IC,TBD    I23 @BASEBOARD_FAB2_LIB.BASEBOARD_FAB2(SCH_1):PAGE40
  U5D1 BB19 VSS<666> SKX_EXT_B_BGA1-IC,TBD    I23 @BASEBOARD_FAB2_LIB.BASEBOARD_FAB2(SCH_1):PAGE40
  U5D1 BA84 VSS<667> SKX_EXT_B_BGA1-IC,TBD    I23 @BASEBOARD_FAB2_LIB.BASEBOARD_FAB2(SCH_1):PAGE40
  U5D1 BA80 VSS<668> SKX_EXT_B_BGA1-IC,TBD    I23 @BASEBOARD_FAB2_LIB.BASEBOARD_FAB2(SCH_1):PAGE40
  U5D1 BA74 VSS<669> SKX_EXT_B_BGA1-IC,TBD    I23 @BASEBOARD_FAB2_LIB.BASEBOARD_FAB2(SCH_1):PAGE40
  U5D1 BA68 VSS<670> SKX_EXT_B_BGA1-IC,TBD    I23 @BASEBOARD_FAB2_LIB.BASEBOARD_FAB2(SCH_1):PAGE40
  U5D1 BA62 VSS<671> SKX_EXT_B_BGA1-IC,TBD    I23 @BASEBOARD_FAB2_LIB.BASEBOARD_FAB2(SCH_1):PAGE40
  U5D1 BA12 VSS<672> SKX_EXT_B_BGA1-IC,TBD    I23 @BASEBOARD_FAB2_LIB.BASEBOARD_FAB2(SCH_1):PAGE40
  U5D1  BA6 VSS<673> SKX_EXT_B_BGA1-IC,TBD    I23 @BASEBOARD_FAB2_LIB.BASEBOARD_FAB2(SCH_1):PAGE40
  U5D1  BA2 VSS<674> SKX_EXT_B_BGA1-IC,TBD    I23 @BASEBOARD_FAB2_LIB.BASEBOARD_FAB2(SCH_1):PAGE40
  U5D1 AY81 VSS<675> SKX_EXT_B_BGA1-IC,TBD    I23 @BASEBOARD_FAB2_LIB.BASEBOARD_FAB2(SCH_1):PAGE40
  U5D1 AY79 VSS<676> SKX_EXT_B_BGA1-IC,TBD    I23 @BASEBOARD_FAB2_LIB.BASEBOARD_FAB2(SCH_1):PAGE40
  U5D1 AY63 VSS<677> SKX_EXT_B_BGA1-IC,TBD    I23 @BASEBOARD_FAB2_LIB.BASEBOARD_FAB2(SCH_1):PAGE40
  U5D1 AY25 VSS<678> SKX_EXT_B_BGA1-IC,TBD    I23 @BASEBOARD_FAB2_LIB.BASEBOARD_FAB2(SCH_1):PAGE40
  U5D1 AY23 VSS<679> SKX_EXT_B_BGA1-IC,TBD    I23 @BASEBOARD_FAB2_LIB.BASEBOARD_FAB2(SCH_1):PAGE40
  U5D1 AY21 VSS<680> SKX_EXT_B_BGA1-IC,TBD    I23 @BASEBOARD_FAB2_LIB.BASEBOARD_FAB2(SCH_1):PAGE40
  U5D1 AY17 VSS<681> SKX_EXT_B_BGA1-IC,TBD    I23 @BASEBOARD_FAB2_LIB.BASEBOARD_FAB2(SCH_1):PAGE40
  U5D1 AY15 VSS<682> SKX_EXT_B_BGA1-IC,TBD    I23 @BASEBOARD_FAB2_LIB.BASEBOARD_FAB2(SCH_1):PAGE40
  U5D1  AY5 VSS<683> SKX_EXT_B_BGA1-IC,TBD    I23 @BASEBOARD_FAB2_LIB.BASEBOARD_FAB2(SCH_1):PAGE40
  U5D1 AW84 VSS<684> SKX_EXT_B_BGA1-IC,TBD    I23 @BASEBOARD_FAB2_LIB.BASEBOARD_FAB2(SCH_1):PAGE40
  U5D1 AW82 VSS<685> SKX_EXT_B_BGA1-IC,TBD    I23 @BASEBOARD_FAB2_LIB.BASEBOARD_FAB2(SCH_1):PAGE40
  U5D1 AW78 VSS<686> SKX_EXT_B_BGA1-IC,TBD    I23 @BASEBOARD_FAB2_LIB.BASEBOARD_FAB2(SCH_1):PAGE40
  U5D1 AW74 VSS<687> SKX_EXT_B_BGA1-IC,TBD    I23 @BASEBOARD_FAB2_LIB.BASEBOARD_FAB2(SCH_1):PAGE40
  U5D1 AW72 VSS<688> SKX_EXT_B_BGA1-IC,TBD    I23 @BASEBOARD_FAB2_LIB.BASEBOARD_FAB2(SCH_1):PAGE40
  U5D1 AW70 VSS<689> SKX_EXT_B_BGA1-IC,TBD    I23 @BASEBOARD_FAB2_LIB.BASEBOARD_FAB2(SCH_1):PAGE40
  U5D1 AW68 VSS<690> SKX_EXT_B_BGA1-IC,TBD    I23 @BASEBOARD_FAB2_LIB.BASEBOARD_FAB2(SCH_1):PAGE40
  U5D1 AW66 VSS<691> SKX_EXT_B_BGA1-IC,TBD    I23 @BASEBOARD_FAB2_LIB.BASEBOARD_FAB2(SCH_1):PAGE40
  U5D1 AW62 VSS<692> SKX_EXT_B_BGA1-IC,TBD    I23 @BASEBOARD_FAB2_LIB.BASEBOARD_FAB2(SCH_1):PAGE40
  U5D1 AW10 VSS<693> SKX_EXT_B_BGA1-IC,TBD    I23 @BASEBOARD_FAB2_LIB.BASEBOARD_FAB2(SCH_1):PAGE40
  U5D1  AW2 VSS<694> SKX_EXT_B_BGA1-IC,TBD    I23 @BASEBOARD_FAB2_LIB.BASEBOARD_FAB2(SCH_1):PAGE40
  U5D1 AV83 VSS<695> SKX_EXT_B_BGA1-IC,TBD    I23 @BASEBOARD_FAB2_LIB.BASEBOARD_FAB2(SCH_1):PAGE40
  U5D1 AV75 VSS<696> SKX_EXT_B_BGA1-IC,TBD    I23 @BASEBOARD_FAB2_LIB.BASEBOARD_FAB2(SCH_1):PAGE40
  U5D1 AV67 VSS<697> SKX_EXT_B_BGA1-IC,TBD    I23 @BASEBOARD_FAB2_LIB.BASEBOARD_FAB2(SCH_1):PAGE40
  U5D1 AV65 VSS<698> SKX_EXT_B_BGA1-IC,TBD    I23 @BASEBOARD_FAB2_LIB.BASEBOARD_FAB2(SCH_1):PAGE40
  U5D1 AV63 VSS<699> SKX_EXT_B_BGA1-IC,TBD    I23 @BASEBOARD_FAB2_LIB.BASEBOARD_FAB2(SCH_1):PAGE40
  U5D1 AV25 VSS<700> SKX_EXT_B_BGA1-IC,TBD    I23 @BASEBOARD_FAB2_LIB.BASEBOARD_FAB2(SCH_1):PAGE40
  U5D1 AV23 VSS<701> SKX_EXT_B_BGA1-IC,TBD    I23 @BASEBOARD_FAB2_LIB.BASEBOARD_FAB2(SCH_1):PAGE40
  U5D1 AV19 VSS<702> SKX_EXT_B_BGA1-IC,TBD    I23 @BASEBOARD_FAB2_LIB.BASEBOARD_FAB2(SCH_1):PAGE40
  U5D1 AV13 VSS<703> SKX_EXT_B_BGA1-IC,TBD    I23 @BASEBOARD_FAB2_LIB.BASEBOARD_FAB2(SCH_1):PAGE40
  U5D1 AV11 VSS<704> SKX_EXT_B_BGA1-IC,TBD    I23 @BASEBOARD_FAB2_LIB.BASEBOARD_FAB2(SCH_1):PAGE40
  U5D1  AV7 VSS<705> SKX_EXT_B_BGA1-IC,TBD    I23 @BASEBOARD_FAB2_LIB.BASEBOARD_FAB2(SCH_1):PAGE40
  U5D1  AV3 VSS<706> SKX_EXT_B_BGA1-IC,TBD    I23 @BASEBOARD_FAB2_LIB.BASEBOARD_FAB2(SCH_1):PAGE40
  U5D1  AV1 VSS<707> SKX_EXT_B_BGA1-IC,TBD    I23 @BASEBOARD_FAB2_LIB.BASEBOARD_FAB2(SCH_1):PAGE40
  U5D1 AU86 VSS<708> SKX_EXT_B_BGA1-IC,TBD    I23 @BASEBOARD_FAB2_LIB.BASEBOARD_FAB2(SCH_1):PAGE40
  U5D1 AU84 VSS<709> SKX_EXT_B_BGA1-IC,TBD    I23 @BASEBOARD_FAB2_LIB.BASEBOARD_FAB2(SCH_1):PAGE40
  U5D1 AU80 VSS<710> SKX_EXT_B_BGA1-IC,TBD    I23 @BASEBOARD_FAB2_LIB.BASEBOARD_FAB2(SCH_1):PAGE40
  U5D1 AU78 VSS<711> SKX_EXT_B_BGA1-IC,TBD    I23 @BASEBOARD_FAB2_LIB.BASEBOARD_FAB2(SCH_1):PAGE40
  U5D1 AU76 VSS<712> SKX_EXT_B_BGA1-IC,TBD    I23 @BASEBOARD_FAB2_LIB.BASEBOARD_FAB2(SCH_1):PAGE40
  U5D1 AU74 VSS<713> SKX_EXT_B_BGA1-IC,TBD    I23 @BASEBOARD_FAB2_LIB.BASEBOARD_FAB2(SCH_1):PAGE40
  U5D1 AU68 VSS<714> SKX_EXT_B_BGA1-IC,TBD    I23 @BASEBOARD_FAB2_LIB.BASEBOARD_FAB2(SCH_1):PAGE40
  U5D1 AU64 VSS<715> SKX_EXT_B_BGA1-IC,TBD    I23 @BASEBOARD_FAB2_LIB.BASEBOARD_FAB2(SCH_1):PAGE40
  U5D1 AU62 VSS<716> SKX_EXT_B_BGA1-IC,TBD    I23 @BASEBOARD_FAB2_LIB.BASEBOARD_FAB2(SCH_1):PAGE40
  U5D1 AU28 VSS<717> SKX_EXT_B_BGA1-IC,TBD    I23 @BASEBOARD_FAB2_LIB.BASEBOARD_FAB2(SCH_1):PAGE40
  U5D1 AU26 VSS<718> SKX_EXT_B_BGA1-IC,TBD    I23 @BASEBOARD_FAB2_LIB.BASEBOARD_FAB2(SCH_1):PAGE40
  U5D1  AU6 VSS<719> SKX_EXT_B_BGA1-IC,TBD    I23 @BASEBOARD_FAB2_LIB.BASEBOARD_FAB2(SCH_1):PAGE40
  U5D1  AU2 VSS<720> SKX_EXT_B_BGA1-IC,TBD    I23 @BASEBOARD_FAB2_LIB.BASEBOARD_FAB2(SCH_1):PAGE40
  U5D1 AT85 VSS<721> SKX_EXT_B_BGA1-IC,TBD    I23 @BASEBOARD_FAB2_LIB.BASEBOARD_FAB2(SCH_1):PAGE40
  U5D1 AT83 VSS<722> SKX_EXT_B_BGA1-IC,TBD    I23 @BASEBOARD_FAB2_LIB.BASEBOARD_FAB2(SCH_1):PAGE40
  U5D1 AT77 VSS<723> SKX_EXT_B_BGA1-IC,TBD    I23 @BASEBOARD_FAB2_LIB.BASEBOARD_FAB2(SCH_1):PAGE40
  U5D1 AT73 VSS<724> SKX_EXT_B_BGA1-IC,TBD    I23 @BASEBOARD_FAB2_LIB.BASEBOARD_FAB2(SCH_1):PAGE40
  U5D1 AT69 VSS<725> SKX_EXT_B_BGA1-IC,TBD    I23 @BASEBOARD_FAB2_LIB.BASEBOARD_FAB2(SCH_1):PAGE40
  U5D1 AT63 VSS<726> SKX_EXT_B_BGA1-IC,TBD    I23 @BASEBOARD_FAB2_LIB.BASEBOARD_FAB2(SCH_1):PAGE40
  U5D1 AT61 VSS<727> SKX_EXT_B_BGA1-IC,TBD    I23 @BASEBOARD_FAB2_LIB.BASEBOARD_FAB2(SCH_1):PAGE40
  U5D1 AT27 VSS<728> SKX_EXT_B_BGA1-IC,TBD    I23 @BASEBOARD_FAB2_LIB.BASEBOARD_FAB2(SCH_1):PAGE40
  U5D1 AT21 VSS<729> SKX_EXT_B_BGA1-IC,TBD    I23 @BASEBOARD_FAB2_LIB.BASEBOARD_FAB2(SCH_1):PAGE40
  U5D1 AT17 VSS<730> SKX_EXT_B_BGA1-IC,TBD    I23 @BASEBOARD_FAB2_LIB.BASEBOARD_FAB2(SCH_1):PAGE40
  U5D1 AT15 VSS<731> SKX_EXT_B_BGA1-IC,TBD    I23 @BASEBOARD_FAB2_LIB.BASEBOARD_FAB2(SCH_1):PAGE40
  U5D1  P63 VSS<732> SKX_EXT_B_BGA1-IC,TBD    I23 @BASEBOARD_FAB2_LIB.BASEBOARD_FAB2(SCH_1):PAGE40
  U5D1 AC48 VSS<733> SKX_EXT_B_BGA1-IC,TBD    I23 @BASEBOARD_FAB2_LIB.BASEBOARD_FAB2(SCH_1):PAGE40
  U5D1 AR78 VSS<734> SKX_EXT_B_BGA1-IC,TBD    I23 @BASEBOARD_FAB2_LIB.BASEBOARD_FAB2(SCH_1):PAGE40
  U5D1 AR72 VSS<735> SKX_EXT_B_BGA1-IC,TBD    I23 @BASEBOARD_FAB2_LIB.BASEBOARD_FAB2(SCH_1):PAGE40
  U5D1 AR60 VSS<736> SKX_EXT_B_BGA1-IC,TBD    I23 @BASEBOARD_FAB2_LIB.BASEBOARD_FAB2(SCH_1):PAGE40
  U5D1 AR30 VSS<737> SKX_EXT_B_BGA1-IC,TBD    I23 @BASEBOARD_FAB2_LIB.BASEBOARD_FAB2(SCH_1):PAGE40
  U5D1 AR24 VSS<738> SKX_EXT_B_BGA1-IC,TBD    I23 @BASEBOARD_FAB2_LIB.BASEBOARD_FAB2(SCH_1):PAGE40
  U5D1 AR10 VSS<739> SKX_EXT_B_BGA1-IC,TBD    I23 @BASEBOARD_FAB2_LIB.BASEBOARD_FAB2(SCH_1):PAGE40
  U5D1 AP85 VSS<740> SKX_EXT_B_BGA1-IC,TBD    I23 @BASEBOARD_FAB2_LIB.BASEBOARD_FAB2(SCH_1):PAGE40
  U5D1 AP83 VSS<741> SKX_EXT_B_BGA1-IC,TBD    I23 @BASEBOARD_FAB2_LIB.BASEBOARD_FAB2(SCH_1):PAGE40
  U5D1 AP81 VSS<742> SKX_EXT_B_BGA1-IC,TBD    I23 @BASEBOARD_FAB2_LIB.BASEBOARD_FAB2(SCH_1):PAGE40
  U5D1 AP75 VSS<743> SKX_EXT_B_BGA1-IC,TBD    I23 @BASEBOARD_FAB2_LIB.BASEBOARD_FAB2(SCH_1):PAGE40
  U5D1 AP73 VSS<744> SKX_EXT_B_BGA1-IC,TBD    I23 @BASEBOARD_FAB2_LIB.BASEBOARD_FAB2(SCH_1):PAGE40
  U5D1 AP69 VSS<745> SKX_EXT_B_BGA1-IC,TBD    I23 @BASEBOARD_FAB2_LIB.BASEBOARD_FAB2(SCH_1):PAGE40
  U5D1 AP67 VSS<746> SKX_EXT_B_BGA1-IC,TBD    I23 @BASEBOARD_FAB2_LIB.BASEBOARD_FAB2(SCH_1):PAGE40
  U5D1 AP65 VSS<747> SKX_EXT_B_BGA1-IC,TBD    I23 @BASEBOARD_FAB2_LIB.BASEBOARD_FAB2(SCH_1):PAGE40
  U5D1 AP63 VSS<748> SKX_EXT_B_BGA1-IC,TBD    I23 @BASEBOARD_FAB2_LIB.BASEBOARD_FAB2(SCH_1):PAGE40
  U5D1 AP59 VSS<749> SKX_EXT_B_BGA1-IC,TBD    I23 @BASEBOARD_FAB2_LIB.BASEBOARD_FAB2(SCH_1):PAGE40
  U5D1 AP31 VSS<750> SKX_EXT_B_BGA1-IC,TBD    I23 @BASEBOARD_FAB2_LIB.BASEBOARD_FAB2(SCH_1):PAGE40
  U5D1 AP19 VSS<751> SKX_EXT_B_BGA1-IC,TBD    I23 @BASEBOARD_FAB2_LIB.BASEBOARD_FAB2(SCH_1):PAGE40
  U5D1 AP13 VSS<752> SKX_EXT_B_BGA1-IC,TBD    I23 @BASEBOARD_FAB2_LIB.BASEBOARD_FAB2(SCH_1):PAGE40
  U5D1  AP9 VSS<753> SKX_EXT_B_BGA1-IC,TBD    I23 @BASEBOARD_FAB2_LIB.BASEBOARD_FAB2(SCH_1):PAGE40
  U5D1  AP5 VSS<754> SKX_EXT_B_BGA1-IC,TBD    I23 @BASEBOARD_FAB2_LIB.BASEBOARD_FAB2(SCH_1):PAGE40
  U5D1 AN78 VSS<755> SKX_EXT_B_BGA1-IC,TBD    I23 @BASEBOARD_FAB2_LIB.BASEBOARD_FAB2(SCH_1):PAGE40
  U5D1 AN58 VSS<756> SKX_EXT_B_BGA1-IC,TBD    I23 @BASEBOARD_FAB2_LIB.BASEBOARD_FAB2(SCH_1):PAGE40
  U5D1 AN28 VSS<757> SKX_EXT_B_BGA1-IC,TBD    I23 @BASEBOARD_FAB2_LIB.BASEBOARD_FAB2(SCH_1):PAGE40
  U5D1  AN6 VSS<758> SKX_EXT_B_BGA1-IC,TBD    I23 @BASEBOARD_FAB2_LIB.BASEBOARD_FAB2(SCH_1):PAGE40
  U5D1  AN2 VSS<759> SKX_EXT_B_BGA1-IC,TBD    I23 @BASEBOARD_FAB2_LIB.BASEBOARD_FAB2(SCH_1):PAGE40
  U5D1 AM83 VSS<760> SKX_EXT_B_BGA1-IC,TBD    I23 @BASEBOARD_FAB2_LIB.BASEBOARD_FAB2(SCH_1):PAGE40
  U5D1 AM79 VSS<761> SKX_EXT_B_BGA1-IC,TBD    I23 @BASEBOARD_FAB2_LIB.BASEBOARD_FAB2(SCH_1):PAGE40
  U5D1 AM73 VSS<762> SKX_EXT_B_BGA1-IC,TBD    I23 @BASEBOARD_FAB2_LIB.BASEBOARD_FAB2(SCH_1):PAGE40
  U5D1 AM69 VSS<763> SKX_EXT_B_BGA1-IC,TBD    I23 @BASEBOARD_FAB2_LIB.BASEBOARD_FAB2(SCH_1):PAGE40
  U5D1 AM63 VSS<764> SKX_EXT_B_BGA1-IC,TBD    I23 @BASEBOARD_FAB2_LIB.BASEBOARD_FAB2(SCH_1):PAGE40
  U5D1 AM57 VSS<765> SKX_EXT_B_BGA1-IC,TBD    I23 @BASEBOARD_FAB2_LIB.BASEBOARD_FAB2(SCH_1):PAGE40
  U5D1 AM31 VSS<766> SKX_EXT_B_BGA1-IC,TBD    I23 @BASEBOARD_FAB2_LIB.BASEBOARD_FAB2(SCH_1):PAGE40
  U5D1 AC50 VSS<767> SKX_EXT_B_BGA1-IC,TBD    I23 @BASEBOARD_FAB2_LIB.BASEBOARD_FAB2(SCH_1):PAGE40
  U5D1  AM1 VSS<768> SKX_EXT_B_BGA1-IC,TBD    I23 @BASEBOARD_FAB2_LIB.BASEBOARD_FAB2(SCH_1):PAGE40
  U5D1 AL86 VSS<769> SKX_EXT_B_BGA1-IC,TBD    I23 @BASEBOARD_FAB2_LIB.BASEBOARD_FAB2(SCH_1):PAGE40
  U5D1 AL82 VSS<770> SKX_EXT_B_BGA1-IC,TBD    I23 @BASEBOARD_FAB2_LIB.BASEBOARD_FAB2(SCH_1):PAGE40
  U5D1 AL80 VSS<771> SKX_EXT_B_BGA1-IC,TBD    I23 @BASEBOARD_FAB2_LIB.BASEBOARD_FAB2(SCH_1):PAGE40
  U5D1 AL78 VSS<772> SKX_EXT_B_BGA1-IC,TBD    I23 @BASEBOARD_FAB2_LIB.BASEBOARD_FAB2(SCH_1):PAGE40
  U5D1 AL76 VSS<773> SKX_EXT_B_BGA1-IC,TBD    I23 @BASEBOARD_FAB2_LIB.BASEBOARD_FAB2(SCH_1):PAGE40
  U5D1  P49 VSS<454> SKX_EXT_B_BGA1-IC,TBD   I283 @BASEBOARD_FAB2_LIB.BASEBOARD_FAB2(SCH_1):PAGE41
  U5D1 CJ12 VSS<455> SKX_EXT_B_BGA1-IC,TBD   I283 @BASEBOARD_FAB2_LIB.BASEBOARD_FAB2(SCH_1):PAGE41
  U5D1 CJ10 VSS<456> SKX_EXT_B_BGA1-IC,TBD   I283 @BASEBOARD_FAB2_LIB.BASEBOARD_FAB2(SCH_1):PAGE41
  U5D1  CJ8 VSS<457> SKX_EXT_B_BGA1-IC,TBD   I283 @BASEBOARD_FAB2_LIB.BASEBOARD_FAB2(SCH_1):PAGE41
  U5D1  CJ6 VSS<458> SKX_EXT_B_BGA1-IC,TBD   I283 @BASEBOARD_FAB2_LIB.BASEBOARD_FAB2(SCH_1):PAGE41
  U5D1  CJ2 VSS<459> SKX_EXT_B_BGA1-IC,TBD   I283 @BASEBOARD_FAB2_LIB.BASEBOARD_FAB2(SCH_1):PAGE41
  U5D1 CH83 VSS<460> SKX_EXT_B_BGA1-IC,TBD   I283 @BASEBOARD_FAB2_LIB.BASEBOARD_FAB2(SCH_1):PAGE41
  U5D1 CH81 VSS<461> SKX_EXT_B_BGA1-IC,TBD   I283 @BASEBOARD_FAB2_LIB.BASEBOARD_FAB2(SCH_1):PAGE41
  U5D1 CH79 VSS<462> SKX_EXT_B_BGA1-IC,TBD   I283 @BASEBOARD_FAB2_LIB.BASEBOARD_FAB2(SCH_1):PAGE41
  U5D1 CH73 VSS<463> SKX_EXT_B_BGA1-IC,TBD   I283 @BASEBOARD_FAB2_LIB.BASEBOARD_FAB2(SCH_1):PAGE41
  U5D1 CH67 VSS<464> SKX_EXT_B_BGA1-IC,TBD   I283 @BASEBOARD_FAB2_LIB.BASEBOARD_FAB2(SCH_1):PAGE41
  U5D1 CH63 VSS<465> SKX_EXT_B_BGA1-IC,TBD   I283 @BASEBOARD_FAB2_LIB.BASEBOARD_FAB2(SCH_1):PAGE41
  U5D1 CH19 VSS<466> SKX_EXT_B_BGA1-IC,TBD   I283 @BASEBOARD_FAB2_LIB.BASEBOARD_FAB2(SCH_1):PAGE41
  U5D1 CH15 VSS<467> SKX_EXT_B_BGA1-IC,TBD   I283 @BASEBOARD_FAB2_LIB.BASEBOARD_FAB2(SCH_1):PAGE41
  U5D1  CH3 VSS<468> SKX_EXT_B_BGA1-IC,TBD   I283 @BASEBOARD_FAB2_LIB.BASEBOARD_FAB2(SCH_1):PAGE41
  U5D1  CH1 VSS<469> SKX_EXT_B_BGA1-IC,TBD   I283 @BASEBOARD_FAB2_LIB.BASEBOARD_FAB2(SCH_1):PAGE41
  U5D1 CG80 VSS<470> SKX_EXT_B_BGA1-IC,TBD   I283 @BASEBOARD_FAB2_LIB.BASEBOARD_FAB2(SCH_1):PAGE41
  U5D1 CG72 VSS<471> SKX_EXT_B_BGA1-IC,TBD   I283 @BASEBOARD_FAB2_LIB.BASEBOARD_FAB2(SCH_1):PAGE41
  U5D1 CG68 VSS<472> SKX_EXT_B_BGA1-IC,TBD   I283 @BASEBOARD_FAB2_LIB.BASEBOARD_FAB2(SCH_1):PAGE41
  U5D1 CG62 VSS<473> SKX_EXT_B_BGA1-IC,TBD   I283 @BASEBOARD_FAB2_LIB.BASEBOARD_FAB2(SCH_1):PAGE41
  U5D1 CG22 VSS<474> SKX_EXT_B_BGA1-IC,TBD   I283 @BASEBOARD_FAB2_LIB.BASEBOARD_FAB2(SCH_1):PAGE41
  U5D1 CG18 VSS<475> SKX_EXT_B_BGA1-IC,TBD   I283 @BASEBOARD_FAB2_LIB.BASEBOARD_FAB2(SCH_1):PAGE41
  U5D1  P51 VSS<476> SKX_EXT_B_BGA1-IC,TBD   I283 @BASEBOARD_FAB2_LIB.BASEBOARD_FAB2(SCH_1):PAGE41
  U5D1 CF83 VSS<477> SKX_EXT_B_BGA1-IC,TBD   I283 @BASEBOARD_FAB2_LIB.BASEBOARD_FAB2(SCH_1):PAGE41
  U5D1 CF77 VSS<478> SKX_EXT_B_BGA1-IC,TBD   I283 @BASEBOARD_FAB2_LIB.BASEBOARD_FAB2(SCH_1):PAGE41
  U5D1 CF71 VSS<479> SKX_EXT_B_BGA1-IC,TBD   I283 @BASEBOARD_FAB2_LIB.BASEBOARD_FAB2(SCH_1):PAGE41
  U5D1 CF69 VSS<480> SKX_EXT_B_BGA1-IC,TBD   I283 @BASEBOARD_FAB2_LIB.BASEBOARD_FAB2(SCH_1):PAGE41
  U5D1 CF63 VSS<481> SKX_EXT_B_BGA1-IC,TBD   I283 @BASEBOARD_FAB2_LIB.BASEBOARD_FAB2(SCH_1):PAGE41
  U5D1  CF9 VSS<482> SKX_EXT_B_BGA1-IC,TBD   I283 @BASEBOARD_FAB2_LIB.BASEBOARD_FAB2(SCH_1):PAGE41
  U5D1  P53 VSS<483> SKX_EXT_B_BGA1-IC,TBD   I283 @BASEBOARD_FAB2_LIB.BASEBOARD_FAB2(SCH_1):PAGE41
  U5D1 CE82 VSS<484> SKX_EXT_B_BGA1-IC,TBD   I283 @BASEBOARD_FAB2_LIB.BASEBOARD_FAB2(SCH_1):PAGE41
  U5D1 CE70 VSS<485> SKX_EXT_B_BGA1-IC,TBD   I283 @BASEBOARD_FAB2_LIB.BASEBOARD_FAB2(SCH_1):PAGE41
  U5D1 CE62 VSS<486> SKX_EXT_B_BGA1-IC,TBD   I283 @BASEBOARD_FAB2_LIB.BASEBOARD_FAB2(SCH_1):PAGE41
  U5D1 CE26 VSS<487> SKX_EXT_B_BGA1-IC,TBD   I283 @BASEBOARD_FAB2_LIB.BASEBOARD_FAB2(SCH_1):PAGE41
  U5D1 CE20 VSS<488> SKX_EXT_B_BGA1-IC,TBD   I283 @BASEBOARD_FAB2_LIB.BASEBOARD_FAB2(SCH_1):PAGE41
  U5D1 CE14 VSS<489> SKX_EXT_B_BGA1-IC,TBD   I283 @BASEBOARD_FAB2_LIB.BASEBOARD_FAB2(SCH_1):PAGE41
  U5D1 CE10 VSS<490> SKX_EXT_B_BGA1-IC,TBD   I283 @BASEBOARD_FAB2_LIB.BASEBOARD_FAB2(SCH_1):PAGE41
  U5D1 CD81 VSS<491> SKX_EXT_B_BGA1-IC,TBD   I283 @BASEBOARD_FAB2_LIB.BASEBOARD_FAB2(SCH_1):PAGE41
  U5D1 CD79 VSS<492> SKX_EXT_B_BGA1-IC,TBD   I283 @BASEBOARD_FAB2_LIB.BASEBOARD_FAB2(SCH_1):PAGE41
  U5D1 CD77 VSS<493> SKX_EXT_B_BGA1-IC,TBD   I283 @BASEBOARD_FAB2_LIB.BASEBOARD_FAB2(SCH_1):PAGE41
  U5D1 CD75 VSS<494> SKX_EXT_B_BGA1-IC,TBD   I283 @BASEBOARD_FAB2_LIB.BASEBOARD_FAB2(SCH_1):PAGE41
  U5D1 CD73 VSS<495> SKX_EXT_B_BGA1-IC,TBD   I283 @BASEBOARD_FAB2_LIB.BASEBOARD_FAB2(SCH_1):PAGE41
  U5D1 CD63 VSS<496> SKX_EXT_B_BGA1-IC,TBD   I283 @BASEBOARD_FAB2_LIB.BASEBOARD_FAB2(SCH_1):PAGE41
  U5D1 CD13 VSS<497> SKX_EXT_B_BGA1-IC,TBD   I283 @BASEBOARD_FAB2_LIB.BASEBOARD_FAB2(SCH_1):PAGE41
  U5D1  CD5 VSS<498> SKX_EXT_B_BGA1-IC,TBD   I283 @BASEBOARD_FAB2_LIB.BASEBOARD_FAB2(SCH_1):PAGE41
  U5D1 CC82 VSS<499> SKX_EXT_B_BGA1-IC,TBD   I283 @BASEBOARD_FAB2_LIB.BASEBOARD_FAB2(SCH_1):PAGE41
  U5D1 CC80 VSS<500> SKX_EXT_B_BGA1-IC,TBD   I283 @BASEBOARD_FAB2_LIB.BASEBOARD_FAB2(SCH_1):PAGE41
  U5D1 CC78 VSS<501> SKX_EXT_B_BGA1-IC,TBD   I283 @BASEBOARD_FAB2_LIB.BASEBOARD_FAB2(SCH_1):PAGE41
  U5D1 CC76 VSS<502> SKX_EXT_B_BGA1-IC,TBD   I283 @BASEBOARD_FAB2_LIB.BASEBOARD_FAB2(SCH_1):PAGE41
  U5D1 CC74 VSS<503> SKX_EXT_B_BGA1-IC,TBD   I283 @BASEBOARD_FAB2_LIB.BASEBOARD_FAB2(SCH_1):PAGE41
  U5D1 CC72 VSS<504> SKX_EXT_B_BGA1-IC,TBD   I283 @BASEBOARD_FAB2_LIB.BASEBOARD_FAB2(SCH_1):PAGE41
  U5D1 CC64 VSS<505> SKX_EXT_B_BGA1-IC,TBD   I283 @BASEBOARD_FAB2_LIB.BASEBOARD_FAB2(SCH_1):PAGE41
  U5D1 CC24 VSS<506> SKX_EXT_B_BGA1-IC,TBD   I283 @BASEBOARD_FAB2_LIB.BASEBOARD_FAB2(SCH_1):PAGE41
  U5D1 CC18 VSS<507> SKX_EXT_B_BGA1-IC,TBD   I283 @BASEBOARD_FAB2_LIB.BASEBOARD_FAB2(SCH_1):PAGE41
  U5D1 CC16 VSS<508> SKX_EXT_B_BGA1-IC,TBD   I283 @BASEBOARD_FAB2_LIB.BASEBOARD_FAB2(SCH_1):PAGE41
  U5D1  CC4 VSS<509> SKX_EXT_B_BGA1-IC,TBD   I283 @BASEBOARD_FAB2_LIB.BASEBOARD_FAB2(SCH_1):PAGE41
  U5D1 CB71 VSS<510> SKX_EXT_B_BGA1-IC,TBD   I283 @BASEBOARD_FAB2_LIB.BASEBOARD_FAB2(SCH_1):PAGE41
  U5D1 CB63 VSS<511> SKX_EXT_B_BGA1-IC,TBD   I283 @BASEBOARD_FAB2_LIB.BASEBOARD_FAB2(SCH_1):PAGE41
  U5D1 CB27 VSS<512> SKX_EXT_B_BGA1-IC,TBD   I283 @BASEBOARD_FAB2_LIB.BASEBOARD_FAB2(SCH_1):PAGE41
  U5D1  CB9 VSS<513> SKX_EXT_B_BGA1-IC,TBD   I283 @BASEBOARD_FAB2_LIB.BASEBOARD_FAB2(SCH_1):PAGE41
  U5D1  CB7 VSS<514> SKX_EXT_B_BGA1-IC,TBD   I283 @BASEBOARD_FAB2_LIB.BASEBOARD_FAB2(SCH_1):PAGE41
  U5D1 CA70 VSS<515> SKX_EXT_B_BGA1-IC,TBD   I283 @BASEBOARD_FAB2_LIB.BASEBOARD_FAB2(SCH_1):PAGE41
  U5D1 CA68 VSS<516> SKX_EXT_B_BGA1-IC,TBD   I283 @BASEBOARD_FAB2_LIB.BASEBOARD_FAB2(SCH_1):PAGE41
  U5D1 CA66 VSS<517> SKX_EXT_B_BGA1-IC,TBD   I283 @BASEBOARD_FAB2_LIB.BASEBOARD_FAB2(SCH_1):PAGE41
  U5D1 CA64 VSS<518> SKX_EXT_B_BGA1-IC,TBD   I283 @BASEBOARD_FAB2_LIB.BASEBOARD_FAB2(SCH_1):PAGE41
  U5D1 CA26 VSS<519> SKX_EXT_B_BGA1-IC,TBD   I283 @BASEBOARD_FAB2_LIB.BASEBOARD_FAB2(SCH_1):PAGE41
  U5D1 CA18 VSS<520> SKX_EXT_B_BGA1-IC,TBD   I283 @BASEBOARD_FAB2_LIB.BASEBOARD_FAB2(SCH_1):PAGE41
  U5D1 CA14 VSS<521> SKX_EXT_B_BGA1-IC,TBD   I283 @BASEBOARD_FAB2_LIB.BASEBOARD_FAB2(SCH_1):PAGE41
  U5D1 CA10 VSS<522> SKX_EXT_B_BGA1-IC,TBD   I283 @BASEBOARD_FAB2_LIB.BASEBOARD_FAB2(SCH_1):PAGE41
  U5D1  CA8 VSS<523> SKX_EXT_B_BGA1-IC,TBD   I283 @BASEBOARD_FAB2_LIB.BASEBOARD_FAB2(SCH_1):PAGE41
  U5D1  CA6 VSS<524> SKX_EXT_B_BGA1-IC,TBD   I283 @BASEBOARD_FAB2_LIB.BASEBOARD_FAB2(SCH_1):PAGE41
  U5D1  CA2 VSS<525> SKX_EXT_B_BGA1-IC,TBD   I283 @BASEBOARD_FAB2_LIB.BASEBOARD_FAB2(SCH_1):PAGE41
  U5D1 BY71 VSS<526> SKX_EXT_B_BGA1-IC,TBD   I283 @BASEBOARD_FAB2_LIB.BASEBOARD_FAB2(SCH_1):PAGE41
  U5D1 BY69 VSS<527> SKX_EXT_B_BGA1-IC,TBD   I283 @BASEBOARD_FAB2_LIB.BASEBOARD_FAB2(SCH_1):PAGE41
  U5D1 BY67 VSS<528> SKX_EXT_B_BGA1-IC,TBD   I283 @BASEBOARD_FAB2_LIB.BASEBOARD_FAB2(SCH_1):PAGE41
  U5D1 BY65 VSS<529> SKX_EXT_B_BGA1-IC,TBD   I283 @BASEBOARD_FAB2_LIB.BASEBOARD_FAB2(SCH_1):PAGE41
  U5D1 BY63 VSS<530> SKX_EXT_B_BGA1-IC,TBD   I283 @BASEBOARD_FAB2_LIB.BASEBOARD_FAB2(SCH_1):PAGE41
  U5D1 BY23 VSS<531> SKX_EXT_B_BGA1-IC,TBD   I283 @BASEBOARD_FAB2_LIB.BASEBOARD_FAB2(SCH_1):PAGE41
  U5D1 BY13 VSS<532> SKX_EXT_B_BGA1-IC,TBD   I283 @BASEBOARD_FAB2_LIB.BASEBOARD_FAB2(SCH_1):PAGE41
  U5D1 BY11 VSS<533> SKX_EXT_B_BGA1-IC,TBD   I283 @BASEBOARD_FAB2_LIB.BASEBOARD_FAB2(SCH_1):PAGE41
  U5D1 BW82 VSS<534> SKX_EXT_B_BGA1-IC,TBD   I283 @BASEBOARD_FAB2_LIB.BASEBOARD_FAB2(SCH_1):PAGE41
  U5D1 BW80 VSS<535> SKX_EXT_B_BGA1-IC,TBD   I283 @BASEBOARD_FAB2_LIB.BASEBOARD_FAB2(SCH_1):PAGE41
  U5D1 BW78 VSS<536> SKX_EXT_B_BGA1-IC,TBD   I283 @BASEBOARD_FAB2_LIB.BASEBOARD_FAB2(SCH_1):PAGE41
  U5D1 BW76 VSS<537> SKX_EXT_B_BGA1-IC,TBD   I283 @BASEBOARD_FAB2_LIB.BASEBOARD_FAB2(SCH_1):PAGE41
  U5D1 BW74 VSS<538> SKX_EXT_B_BGA1-IC,TBD   I283 @BASEBOARD_FAB2_LIB.BASEBOARD_FAB2(SCH_1):PAGE41
  U5D1 BW72 VSS<539> SKX_EXT_B_BGA1-IC,TBD   I283 @BASEBOARD_FAB2_LIB.BASEBOARD_FAB2(SCH_1):PAGE41
  U5D1 BW26 VSS<540> SKX_EXT_B_BGA1-IC,TBD   I283 @BASEBOARD_FAB2_LIB.BASEBOARD_FAB2(SCH_1):PAGE41
  U5D1 BW18 VSS<541> SKX_EXT_B_BGA1-IC,TBD   I283 @BASEBOARD_FAB2_LIB.BASEBOARD_FAB2(SCH_1):PAGE41
  U5D1 BW16 VSS<542> SKX_EXT_B_BGA1-IC,TBD   I283 @BASEBOARD_FAB2_LIB.BASEBOARD_FAB2(SCH_1):PAGE41
  U5D1 BW14 VSS<543> SKX_EXT_B_BGA1-IC,TBD   I283 @BASEBOARD_FAB2_LIB.BASEBOARD_FAB2(SCH_1):PAGE41
  U5D1 BW12 VSS<544> SKX_EXT_B_BGA1-IC,TBD   I283 @BASEBOARD_FAB2_LIB.BASEBOARD_FAB2(SCH_1):PAGE41
  U5D1  P55 VSS<545> SKX_EXT_B_BGA1-IC,TBD   I283 @BASEBOARD_FAB2_LIB.BASEBOARD_FAB2(SCH_1):PAGE41
  U5D1  BW6 VSS<546> SKX_EXT_B_BGA1-IC,TBD   I283 @BASEBOARD_FAB2_LIB.BASEBOARD_FAB2(SCH_1):PAGE41
  U5D1 BV25 VSS<547> SKX_EXT_B_BGA1-IC,TBD   I283 @BASEBOARD_FAB2_LIB.BASEBOARD_FAB2(SCH_1):PAGE41
  U5D1 BV17 VSS<548> SKX_EXT_B_BGA1-IC,TBD   I283 @BASEBOARD_FAB2_LIB.BASEBOARD_FAB2(SCH_1):PAGE41
  U5D1 BU10 VSS<549> SKX_EXT_B_BGA1-IC,TBD   I283 @BASEBOARD_FAB2_LIB.BASEBOARD_FAB2(SCH_1):PAGE41
  U5D1  BV5 VSS<550> SKX_EXT_B_BGA1-IC,TBD   I283 @BASEBOARD_FAB2_LIB.BASEBOARD_FAB2(SCH_1):PAGE41
  U5D1  BU8 VSS<551> SKX_EXT_B_BGA1-IC,TBD   I283 @BASEBOARD_FAB2_LIB.BASEBOARD_FAB2(SCH_1):PAGE41
  U5D1 BT25 VSS<552> SKX_EXT_B_BGA1-IC,TBD   I283 @BASEBOARD_FAB2_LIB.BASEBOARD_FAB2(SCH_1):PAGE41
  U5D1 BT23 VSS<553> SKX_EXT_B_BGA1-IC,TBD   I283 @BASEBOARD_FAB2_LIB.BASEBOARD_FAB2(SCH_1):PAGE41
  U5D1 BT21 VSS<554> SKX_EXT_B_BGA1-IC,TBD   I283 @BASEBOARD_FAB2_LIB.BASEBOARD_FAB2(SCH_1):PAGE41
  U5D1  BT5 VSS<555> SKX_EXT_B_BGA1-IC,TBD   I283 @BASEBOARD_FAB2_LIB.BASEBOARD_FAB2(SCH_1):PAGE41
  U5D1  BT3 VSS<556> SKX_EXT_B_BGA1-IC,TBD   I283 @BASEBOARD_FAB2_LIB.BASEBOARD_FAB2(SCH_1):PAGE41
  U5D1 BR82 VSS<557> SKX_EXT_B_BGA1-IC,TBD   I283 @BASEBOARD_FAB2_LIB.BASEBOARD_FAB2(SCH_1):PAGE41
  U5D1 BR80 VSS<558> SKX_EXT_B_BGA1-IC,TBD   I283 @BASEBOARD_FAB2_LIB.BASEBOARD_FAB2(SCH_1):PAGE41
  U5D1 BR78 VSS<559> SKX_EXT_B_BGA1-IC,TBD   I283 @BASEBOARD_FAB2_LIB.BASEBOARD_FAB2(SCH_1):PAGE41
  U5D1 BR76 VSS<560> SKX_EXT_B_BGA1-IC,TBD   I283 @BASEBOARD_FAB2_LIB.BASEBOARD_FAB2(SCH_1):PAGE41
  U5D1 BR74 VSS<561> SKX_EXT_B_BGA1-IC,TBD   I283 @BASEBOARD_FAB2_LIB.BASEBOARD_FAB2(SCH_1):PAGE41
  U5D1 BR72 VSS<562> SKX_EXT_B_BGA1-IC,TBD   I283 @BASEBOARD_FAB2_LIB.BASEBOARD_FAB2(SCH_1):PAGE41
  U5D1 BR70 VSS<563> SKX_EXT_B_BGA1-IC,TBD   I283 @BASEBOARD_FAB2_LIB.BASEBOARD_FAB2(SCH_1):PAGE41
  U5D1 BR68 VSS<564> SKX_EXT_B_BGA1-IC,TBD   I283 @BASEBOARD_FAB2_LIB.BASEBOARD_FAB2(SCH_1):PAGE41
  U5D1 BR66 VSS<565> SKX_EXT_B_BGA1-IC,TBD   I283 @BASEBOARD_FAB2_LIB.BASEBOARD_FAB2(SCH_1):PAGE41
  U5D1 BR64 VSS<566> SKX_EXT_B_BGA1-IC,TBD   I283 @BASEBOARD_FAB2_LIB.BASEBOARD_FAB2(SCH_1):PAGE41
  U5D1  P57 VSS<567> SKX_EXT_B_BGA1-IC,TBD   I283 @BASEBOARD_FAB2_LIB.BASEBOARD_FAB2(SCH_1):PAGE41
  U5D1 BR16 VSS<568> SKX_EXT_B_BGA1-IC,TBD   I283 @BASEBOARD_FAB2_LIB.BASEBOARD_FAB2(SCH_1):PAGE41
  U5D1 BR10 VSS<569> SKX_EXT_B_BGA1-IC,TBD   I283 @BASEBOARD_FAB2_LIB.BASEBOARD_FAB2(SCH_1):PAGE41
  U5D1  BR6 VSS<570> SKX_EXT_B_BGA1-IC,TBD   I283 @BASEBOARD_FAB2_LIB.BASEBOARD_FAB2(SCH_1):PAGE41
  U5D1 BP27 VSS<571> SKX_EXT_B_BGA1-IC,TBD   I283 @BASEBOARD_FAB2_LIB.BASEBOARD_FAB2(SCH_1):PAGE41
  U5D1  BP3 VSS<572> SKX_EXT_B_BGA1-IC,TBD   I283 @BASEBOARD_FAB2_LIB.BASEBOARD_FAB2(SCH_1):PAGE41
  U5D1 BN26 VSS<573> SKX_EXT_B_BGA1-IC,TBD   I283 @BASEBOARD_FAB2_LIB.BASEBOARD_FAB2(SCH_1):PAGE41
  U5D1 BN20 VSS<574> SKX_EXT_B_BGA1-IC,TBD   I283 @BASEBOARD_FAB2_LIB.BASEBOARD_FAB2(SCH_1):PAGE41
  U5D1 BN10 VSS<575> SKX_EXT_B_BGA1-IC,TBD   I283 @BASEBOARD_FAB2_LIB.BASEBOARD_FAB2(SCH_1):PAGE41
  U5D1  BN6 VSS<576> SKX_EXT_B_BGA1-IC,TBD   I283 @BASEBOARD_FAB2_LIB.BASEBOARD_FAB2(SCH_1):PAGE41
  U5D1 BM25 VSS<577> SKX_EXT_B_BGA1-IC,TBD   I283 @BASEBOARD_FAB2_LIB.BASEBOARD_FAB2(SCH_1):PAGE41
  U5D1  P59 VSS<578> SKX_EXT_B_BGA1-IC,TBD   I283 @BASEBOARD_FAB2_LIB.BASEBOARD_FAB2(SCH_1):PAGE41
  U5D1 BM15 VSS<579> SKX_EXT_B_BGA1-IC,TBD   I283 @BASEBOARD_FAB2_LIB.BASEBOARD_FAB2(SCH_1):PAGE41
  U5D1 BM13 VSS<580> SKX_EXT_B_BGA1-IC,TBD   I283 @BASEBOARD_FAB2_LIB.BASEBOARD_FAB2(SCH_1):PAGE41
  U5D1  BM9 VSS<581> SKX_EXT_B_BGA1-IC,TBD   I283 @BASEBOARD_FAB2_LIB.BASEBOARD_FAB2(SCH_1):PAGE41
  U5D1 BL82 VSS<582> SKX_EXT_B_BGA1-IC,TBD   I283 @BASEBOARD_FAB2_LIB.BASEBOARD_FAB2(SCH_1):PAGE41
  U5D1 BL80 VSS<583> SKX_EXT_B_BGA1-IC,TBD   I283 @BASEBOARD_FAB2_LIB.BASEBOARD_FAB2(SCH_1):PAGE41
  U5D1 BL78 VSS<584> SKX_EXT_B_BGA1-IC,TBD   I283 @BASEBOARD_FAB2_LIB.BASEBOARD_FAB2(SCH_1):PAGE41
  U5D1 BL76 VSS<585> SKX_EXT_B_BGA1-IC,TBD   I283 @BASEBOARD_FAB2_LIB.BASEBOARD_FAB2(SCH_1):PAGE41
  U5D1 BL74 VSS<586> SKX_EXT_B_BGA1-IC,TBD   I283 @BASEBOARD_FAB2_LIB.BASEBOARD_FAB2(SCH_1):PAGE41
  U5D1 BL72 VSS<587> SKX_EXT_B_BGA1-IC,TBD   I283 @BASEBOARD_FAB2_LIB.BASEBOARD_FAB2(SCH_1):PAGE41
  U5D1 BL70 VSS<588> SKX_EXT_B_BGA1-IC,TBD   I283 @BASEBOARD_FAB2_LIB.BASEBOARD_FAB2(SCH_1):PAGE41
  U5D1 BL68 VSS<589> SKX_EXT_B_BGA1-IC,TBD   I283 @BASEBOARD_FAB2_LIB.BASEBOARD_FAB2(SCH_1):PAGE41
  U5D1 BL66 VSS<590> SKX_EXT_B_BGA1-IC,TBD   I283 @BASEBOARD_FAB2_LIB.BASEBOARD_FAB2(SCH_1):PAGE41
  U5D1 BL64 VSS<591> SKX_EXT_B_BGA1-IC,TBD   I283 @BASEBOARD_FAB2_LIB.BASEBOARD_FAB2(SCH_1):PAGE41
  U5D1 BL24 VSS<592> SKX_EXT_B_BGA1-IC,TBD   I283 @BASEBOARD_FAB2_LIB.BASEBOARD_FAB2(SCH_1):PAGE41
  U5D1 BL22 VSS<593> SKX_EXT_B_BGA1-IC,TBD   I283 @BASEBOARD_FAB2_LIB.BASEBOARD_FAB2(SCH_1):PAGE41
  U5D1  P61 VSS<594> SKX_EXT_B_BGA1-IC,TBD   I283 @BASEBOARD_FAB2_LIB.BASEBOARD_FAB2(SCH_1):PAGE41
  U5D1 BL12 VSS<595> SKX_EXT_B_BGA1-IC,TBD   I283 @BASEBOARD_FAB2_LIB.BASEBOARD_FAB2(SCH_1):PAGE41
  U5D1 BL10 VSS<596> SKX_EXT_B_BGA1-IC,TBD   I283 @BASEBOARD_FAB2_LIB.BASEBOARD_FAB2(SCH_1):PAGE41
  U5D1  BL6 VSS<597> SKX_EXT_B_BGA1-IC,TBD   I283 @BASEBOARD_FAB2_LIB.BASEBOARD_FAB2(SCH_1):PAGE41
  U5D1 BK19 VSS<598> SKX_EXT_B_BGA1-IC,TBD   I283 @BASEBOARD_FAB2_LIB.BASEBOARD_FAB2(SCH_1):PAGE41
  U5D1 BK11 VSS<599> SKX_EXT_B_BGA1-IC,TBD   I283 @BASEBOARD_FAB2_LIB.BASEBOARD_FAB2(SCH_1):PAGE41
  U5D1  BK7 VSS<600> SKX_EXT_B_BGA1-IC,TBD   I283 @BASEBOARD_FAB2_LIB.BASEBOARD_FAB2(SCH_1):PAGE41
  U5D1  BK3 VSS<601> SKX_EXT_B_BGA1-IC,TBD   I283 @BASEBOARD_FAB2_LIB.BASEBOARD_FAB2(SCH_1):PAGE41
  U5D1  BJ6 VSS<602> SKX_EXT_B_BGA1-IC,TBD   I283 @BASEBOARD_FAB2_LIB.BASEBOARD_FAB2(SCH_1):PAGE41
  U5D1  BJ4 VSS<603> SKX_EXT_B_BGA1-IC,TBD   I283 @BASEBOARD_FAB2_LIB.BASEBOARD_FAB2(SCH_1):PAGE41
  U5D1 BH21 VSS<604> SKX_EXT_B_BGA1-IC,TBD   I283 @BASEBOARD_FAB2_LIB.BASEBOARD_FAB2(SCH_1):PAGE41
  U5D1 BH15 VSS<605> SKX_EXT_B_BGA1-IC,TBD   I283 @BASEBOARD_FAB2_LIB.BASEBOARD_FAB2(SCH_1):PAGE41
  U5D1 BH11 VSS<606> SKX_EXT_B_BGA1-IC,TBD   I283 @BASEBOARD_FAB2_LIB.BASEBOARD_FAB2(SCH_1):PAGE41
  U5D1  BH9 VSS<607> SKX_EXT_B_BGA1-IC,TBD   I283 @BASEBOARD_FAB2_LIB.BASEBOARD_FAB2(SCH_1):PAGE41
  U5D1  BH7 VSS<608> SKX_EXT_B_BGA1-IC,TBD   I283 @BASEBOARD_FAB2_LIB.BASEBOARD_FAB2(SCH_1):PAGE41
  U5D1 BG82 VSS<609> SKX_EXT_B_BGA1-IC,TBD   I283 @BASEBOARD_FAB2_LIB.BASEBOARD_FAB2(SCH_1):PAGE41
  U5D1 BG80 VSS<610> SKX_EXT_B_BGA1-IC,TBD   I283 @BASEBOARD_FAB2_LIB.BASEBOARD_FAB2(SCH_1):PAGE41
  U5D1 BG78 VSS<611> SKX_EXT_B_BGA1-IC,TBD   I283 @BASEBOARD_FAB2_LIB.BASEBOARD_FAB2(SCH_1):PAGE41
  U5D1 BG76 VSS<612> SKX_EXT_B_BGA1-IC,TBD   I283 @BASEBOARD_FAB2_LIB.BASEBOARD_FAB2(SCH_1):PAGE41
  U5D1 BG74 VSS<613> SKX_EXT_B_BGA1-IC,TBD   I283 @BASEBOARD_FAB2_LIB.BASEBOARD_FAB2(SCH_1):PAGE41
  U5D1 DA46 VSS<294> SKX_EXT_B_BGA1-IC,TBD   I284 @BASEBOARD_FAB2_LIB.BASEBOARD_FAB2(SCH_1):PAGE41
  U5D1 DA44 VSS<295> SKX_EXT_B_BGA1-IC,TBD   I284 @BASEBOARD_FAB2_LIB.BASEBOARD_FAB2(SCH_1):PAGE41
  U5D1 DA38 VSS<296> SKX_EXT_B_BGA1-IC,TBD   I284 @BASEBOARD_FAB2_LIB.BASEBOARD_FAB2(SCH_1):PAGE41
  U5D1 DA36 VSS<297> SKX_EXT_B_BGA1-IC,TBD   I284 @BASEBOARD_FAB2_LIB.BASEBOARD_FAB2(SCH_1):PAGE41
  U5D1 DA34 VSS<298> SKX_EXT_B_BGA1-IC,TBD   I284 @BASEBOARD_FAB2_LIB.BASEBOARD_FAB2(SCH_1):PAGE41
  U5D1 DA32 VSS<299> SKX_EXT_B_BGA1-IC,TBD   I284 @BASEBOARD_FAB2_LIB.BASEBOARD_FAB2(SCH_1):PAGE41
  U5D1 DA30 VSS<300> SKX_EXT_B_BGA1-IC,TBD   I284 @BASEBOARD_FAB2_LIB.BASEBOARD_FAB2(SCH_1):PAGE41
  U5D1 DA28 VSS<301> SKX_EXT_B_BGA1-IC,TBD   I284 @BASEBOARD_FAB2_LIB.BASEBOARD_FAB2(SCH_1):PAGE41
  U5D1 DA26 VSS<302> SKX_EXT_B_BGA1-IC,TBD   I284 @BASEBOARD_FAB2_LIB.BASEBOARD_FAB2(SCH_1):PAGE41
  U5D1 DA18 VSS<303> SKX_EXT_B_BGA1-IC,TBD   I284 @BASEBOARD_FAB2_LIB.BASEBOARD_FAB2(SCH_1):PAGE41
  U5D1  H53 VSS<304> SKX_EXT_B_BGA1-IC,TBD   I284 @BASEBOARD_FAB2_LIB.BASEBOARD_FAB2(SCH_1):PAGE41
  U5D1  DA6 VSS<305> SKX_EXT_B_BGA1-IC,TBD   I284 @BASEBOARD_FAB2_LIB.BASEBOARD_FAB2(SCH_1):PAGE41
  U5D1 CY85 VSS<306> SKX_EXT_B_BGA1-IC,TBD   I284 @BASEBOARD_FAB2_LIB.BASEBOARD_FAB2(SCH_1):PAGE41
  U5D1 CY83 VSS<307> SKX_EXT_B_BGA1-IC,TBD   I284 @BASEBOARD_FAB2_LIB.BASEBOARD_FAB2(SCH_1):PAGE41
  U5D1 CY77 VSS<308> SKX_EXT_B_BGA1-IC,TBD   I284 @BASEBOARD_FAB2_LIB.BASEBOARD_FAB2(SCH_1):PAGE41
  U5D1 CY75 VSS<309> SKX_EXT_B_BGA1-IC,TBD   I284 @BASEBOARD_FAB2_LIB.BASEBOARD_FAB2(SCH_1):PAGE41
  U5D1 CY69 VSS<310> SKX_EXT_B_BGA1-IC,TBD   I284 @BASEBOARD_FAB2_LIB.BASEBOARD_FAB2(SCH_1):PAGE41
  U5D1 CY65 VSS<311> SKX_EXT_B_BGA1-IC,TBD   I284 @BASEBOARD_FAB2_LIB.BASEBOARD_FAB2(SCH_1):PAGE41
  U5D1 CY61 VSS<312> SKX_EXT_B_BGA1-IC,TBD   I284 @BASEBOARD_FAB2_LIB.BASEBOARD_FAB2(SCH_1):PAGE41
  U5D1 CY59 VSS<313> SKX_EXT_B_BGA1-IC,TBD   I284 @BASEBOARD_FAB2_LIB.BASEBOARD_FAB2(SCH_1):PAGE41
  U5D1 CY51 VSS<314> SKX_EXT_B_BGA1-IC,TBD   I284 @BASEBOARD_FAB2_LIB.BASEBOARD_FAB2(SCH_1):PAGE41
  U5D1 CY45 VSS<315> SKX_EXT_B_BGA1-IC,TBD   I284 @BASEBOARD_FAB2_LIB.BASEBOARD_FAB2(SCH_1):PAGE41
  U5D1 CY41 VSS<316> SKX_EXT_B_BGA1-IC,TBD   I284 @BASEBOARD_FAB2_LIB.BASEBOARD_FAB2(SCH_1):PAGE41
  U5D1 CY21 VSS<317> SKX_EXT_B_BGA1-IC,TBD   I284 @BASEBOARD_FAB2_LIB.BASEBOARD_FAB2(SCH_1):PAGE41
  U5D1 CY15 VSS<318> SKX_EXT_B_BGA1-IC,TBD   I284 @BASEBOARD_FAB2_LIB.BASEBOARD_FAB2(SCH_1):PAGE41
  U5D1 CY13 VSS<319> SKX_EXT_B_BGA1-IC,TBD   I284 @BASEBOARD_FAB2_LIB.BASEBOARD_FAB2(SCH_1):PAGE41
  U5D1  CY9 VSS<320> SKX_EXT_B_BGA1-IC,TBD   I284 @BASEBOARD_FAB2_LIB.BASEBOARD_FAB2(SCH_1):PAGE41
  U5D1  CY1 VSS<321> SKX_EXT_B_BGA1-IC,TBD   I284 @BASEBOARD_FAB2_LIB.BASEBOARD_FAB2(SCH_1):PAGE41
  U5D1 CW82 VSS<322> SKX_EXT_B_BGA1-IC,TBD   I284 @BASEBOARD_FAB2_LIB.BASEBOARD_FAB2(SCH_1):PAGE41
  U5D1 CW78 VSS<323> SKX_EXT_B_BGA1-IC,TBD   I284 @BASEBOARD_FAB2_LIB.BASEBOARD_FAB2(SCH_1):PAGE41
  U5D1 CW74 VSS<324> SKX_EXT_B_BGA1-IC,TBD   I284 @BASEBOARD_FAB2_LIB.BASEBOARD_FAB2(SCH_1):PAGE41
  U5D1 CW68 VSS<325> SKX_EXT_B_BGA1-IC,TBD   I284 @BASEBOARD_FAB2_LIB.BASEBOARD_FAB2(SCH_1):PAGE41
  U5D1 CW66 VSS<326> SKX_EXT_B_BGA1-IC,TBD   I284 @BASEBOARD_FAB2_LIB.BASEBOARD_FAB2(SCH_1):PAGE41
  U5D1 CW64 VSS<327> SKX_EXT_B_BGA1-IC,TBD   I284 @BASEBOARD_FAB2_LIB.BASEBOARD_FAB2(SCH_1):PAGE41
  U5D1 CW54 VSS<328> SKX_EXT_B_BGA1-IC,TBD   I284 @BASEBOARD_FAB2_LIB.BASEBOARD_FAB2(SCH_1):PAGE41
  U5D1 CW52 VSS<329> SKX_EXT_B_BGA1-IC,TBD   I284 @BASEBOARD_FAB2_LIB.BASEBOARD_FAB2(SCH_1):PAGE41
  U5D1 CW42 VSS<330> SKX_EXT_B_BGA1-IC,TBD   I284 @BASEBOARD_FAB2_LIB.BASEBOARD_FAB2(SCH_1):PAGE41
  U5D1 CW40 VSS<331> SKX_EXT_B_BGA1-IC,TBD   I284 @BASEBOARD_FAB2_LIB.BASEBOARD_FAB2(SCH_1):PAGE41
  U5D1 CW38 VSS<332> SKX_EXT_B_BGA1-IC,TBD   I284 @BASEBOARD_FAB2_LIB.BASEBOARD_FAB2(SCH_1):PAGE41
  U5D1 CW32 VSS<333> SKX_EXT_B_BGA1-IC,TBD   I284 @BASEBOARD_FAB2_LIB.BASEBOARD_FAB2(SCH_1):PAGE41
  U5D1 CW26 VSS<334> SKX_EXT_B_BGA1-IC,TBD   I284 @BASEBOARD_FAB2_LIB.BASEBOARD_FAB2(SCH_1):PAGE41
  U5D1 CW12 VSS<335> SKX_EXT_B_BGA1-IC,TBD   I284 @BASEBOARD_FAB2_LIB.BASEBOARD_FAB2(SCH_1):PAGE41
  U5D1 CV83 VSS<336> SKX_EXT_B_BGA1-IC,TBD   I284 @BASEBOARD_FAB2_LIB.BASEBOARD_FAB2(SCH_1):PAGE41
  U5D1 CV81 VSS<337> SKX_EXT_B_BGA1-IC,TBD   I284 @BASEBOARD_FAB2_LIB.BASEBOARD_FAB2(SCH_1):PAGE41
  U5D1 CV79 VSS<338> SKX_EXT_B_BGA1-IC,TBD   I284 @BASEBOARD_FAB2_LIB.BASEBOARD_FAB2(SCH_1):PAGE41
  U5D1 CV73 VSS<339> SKX_EXT_B_BGA1-IC,TBD   I284 @BASEBOARD_FAB2_LIB.BASEBOARD_FAB2(SCH_1):PAGE41
  U5D1 CV67 VSS<340> SKX_EXT_B_BGA1-IC,TBD   I284 @BASEBOARD_FAB2_LIB.BASEBOARD_FAB2(SCH_1):PAGE41
  U5D1 CV63 VSS<341> SKX_EXT_B_BGA1-IC,TBD   I284 @BASEBOARD_FAB2_LIB.BASEBOARD_FAB2(SCH_1):PAGE41
  U5D1 CV55 VSS<342> SKX_EXT_B_BGA1-IC,TBD   I284 @BASEBOARD_FAB2_LIB.BASEBOARD_FAB2(SCH_1):PAGE41
  U5D1 CV53 VSS<343> SKX_EXT_B_BGA1-IC,TBD   I284 @BASEBOARD_FAB2_LIB.BASEBOARD_FAB2(SCH_1):PAGE41
  U5D1 CV41 VSS<344> SKX_EXT_B_BGA1-IC,TBD   I284 @BASEBOARD_FAB2_LIB.BASEBOARD_FAB2(SCH_1):PAGE41
  U5D1 CV39 VSS<345> SKX_EXT_B_BGA1-IC,TBD   I284 @BASEBOARD_FAB2_LIB.BASEBOARD_FAB2(SCH_1):PAGE41
  U5D1 CV37 VSS<346> SKX_EXT_B_BGA1-IC,TBD   I284 @BASEBOARD_FAB2_LIB.BASEBOARD_FAB2(SCH_1):PAGE41
  U5D1 CV33 VSS<347> SKX_EXT_B_BGA1-IC,TBD   I284 @BASEBOARD_FAB2_LIB.BASEBOARD_FAB2(SCH_1):PAGE41
  U5D1 CV31 VSS<348> SKX_EXT_B_BGA1-IC,TBD   I284 @BASEBOARD_FAB2_LIB.BASEBOARD_FAB2(SCH_1):PAGE41
  U5D1 CV27 VSS<349> SKX_EXT_B_BGA1-IC,TBD   I284 @BASEBOARD_FAB2_LIB.BASEBOARD_FAB2(SCH_1):PAGE41
  U5D1 CV25 VSS<350> SKX_EXT_B_BGA1-IC,TBD   I284 @BASEBOARD_FAB2_LIB.BASEBOARD_FAB2(SCH_1):PAGE41
  U5D1 CV17 VSS<351> SKX_EXT_B_BGA1-IC,TBD   I284 @BASEBOARD_FAB2_LIB.BASEBOARD_FAB2(SCH_1):PAGE41
  U5D1  H55 VSS<352> SKX_EXT_B_BGA1-IC,TBD   I284 @BASEBOARD_FAB2_LIB.BASEBOARD_FAB2(SCH_1):PAGE41
  U5D1  CV1 VSS<353> SKX_EXT_B_BGA1-IC,TBD   I284 @BASEBOARD_FAB2_LIB.BASEBOARD_FAB2(SCH_1):PAGE41
  U5D1 CU86 VSS<354> SKX_EXT_B_BGA1-IC,TBD   I284 @BASEBOARD_FAB2_LIB.BASEBOARD_FAB2(SCH_1):PAGE41
  U5D1 CU82 VSS<355> SKX_EXT_B_BGA1-IC,TBD   I284 @BASEBOARD_FAB2_LIB.BASEBOARD_FAB2(SCH_1):PAGE41
  U5D1 CU80 VSS<356> SKX_EXT_B_BGA1-IC,TBD   I284 @BASEBOARD_FAB2_LIB.BASEBOARD_FAB2(SCH_1):PAGE41
  U5D1 CU78 VSS<357> SKX_EXT_B_BGA1-IC,TBD   I284 @BASEBOARD_FAB2_LIB.BASEBOARD_FAB2(SCH_1):PAGE41
  U5D1 CU76 VSS<358> SKX_EXT_B_BGA1-IC,TBD   I284 @BASEBOARD_FAB2_LIB.BASEBOARD_FAB2(SCH_1):PAGE41
  U5D1 CU68 VSS<359> SKX_EXT_B_BGA1-IC,TBD   I284 @BASEBOARD_FAB2_LIB.BASEBOARD_FAB2(SCH_1):PAGE41
  U5D1 CU62 VSS<360> SKX_EXT_B_BGA1-IC,TBD   I284 @BASEBOARD_FAB2_LIB.BASEBOARD_FAB2(SCH_1):PAGE41
  U5D1 CU56 VSS<361> SKX_EXT_B_BGA1-IC,TBD   I284 @BASEBOARD_FAB2_LIB.BASEBOARD_FAB2(SCH_1):PAGE41
  U5D1 CU36 VSS<362> SKX_EXT_B_BGA1-IC,TBD   I284 @BASEBOARD_FAB2_LIB.BASEBOARD_FAB2(SCH_1):PAGE41
  U5D1 CU34 VSS<363> SKX_EXT_B_BGA1-IC,TBD   I284 @BASEBOARD_FAB2_LIB.BASEBOARD_FAB2(SCH_1):PAGE41
  U5D1 CU30 VSS<364> SKX_EXT_B_BGA1-IC,TBD   I284 @BASEBOARD_FAB2_LIB.BASEBOARD_FAB2(SCH_1):PAGE41
  U5D1 CU28 VSS<365> SKX_EXT_B_BGA1-IC,TBD   I284 @BASEBOARD_FAB2_LIB.BASEBOARD_FAB2(SCH_1):PAGE41
  U5D1 CU22 VSS<366> SKX_EXT_B_BGA1-IC,TBD   I284 @BASEBOARD_FAB2_LIB.BASEBOARD_FAB2(SCH_1):PAGE41
  U5D1  CU4 VSS<367> SKX_EXT_B_BGA1-IC,TBD   I284 @BASEBOARD_FAB2_LIB.BASEBOARD_FAB2(SCH_1):PAGE41
  U5D1 CT85 VSS<368> SKX_EXT_B_BGA1-IC,TBD   I284 @BASEBOARD_FAB2_LIB.BASEBOARD_FAB2(SCH_1):PAGE41
  U5D1 CT83 VSS<369> SKX_EXT_B_BGA1-IC,TBD   I284 @BASEBOARD_FAB2_LIB.BASEBOARD_FAB2(SCH_1):PAGE41
  U5D1 CT79 VSS<370> SKX_EXT_B_BGA1-IC,TBD   I284 @BASEBOARD_FAB2_LIB.BASEBOARD_FAB2(SCH_1):PAGE41
  U5D1 CT73 VSS<371> SKX_EXT_B_BGA1-IC,TBD   I284 @BASEBOARD_FAB2_LIB.BASEBOARD_FAB2(SCH_1):PAGE41
  U5D1 CT57 VSS<372> SKX_EXT_B_BGA1-IC,TBD   I284 @BASEBOARD_FAB2_LIB.BASEBOARD_FAB2(SCH_1):PAGE41
  U5D1 CT35 VSS<373> SKX_EXT_B_BGA1-IC,TBD   I284 @BASEBOARD_FAB2_LIB.BASEBOARD_FAB2(SCH_1):PAGE41
  U5D1 CT33 VSS<374> SKX_EXT_B_BGA1-IC,TBD   I284 @BASEBOARD_FAB2_LIB.BASEBOARD_FAB2(SCH_1):PAGE41
  U5D1 CT29 VSS<375> SKX_EXT_B_BGA1-IC,TBD   I284 @BASEBOARD_FAB2_LIB.BASEBOARD_FAB2(SCH_1):PAGE41
  U5D1 CT27 VSS<376> SKX_EXT_B_BGA1-IC,TBD   I284 @BASEBOARD_FAB2_LIB.BASEBOARD_FAB2(SCH_1):PAGE41
  U5D1 CT19 VSS<377> SKX_EXT_B_BGA1-IC,TBD   I284 @BASEBOARD_FAB2_LIB.BASEBOARD_FAB2(SCH_1):PAGE41
  U5D1 CT13 VSS<378> SKX_EXT_B_BGA1-IC,TBD   I284 @BASEBOARD_FAB2_LIB.BASEBOARD_FAB2(SCH_1):PAGE41
  U5D1  H57 VSS<379> SKX_EXT_B_BGA1-IC,TBD   I284 @BASEBOARD_FAB2_LIB.BASEBOARD_FAB2(SCH_1):PAGE41
  U5D1 CR86 VSS<380> SKX_EXT_B_BGA1-IC,TBD   I284 @BASEBOARD_FAB2_LIB.BASEBOARD_FAB2(SCH_1):PAGE41
  U5D1 CR78 VSS<381> SKX_EXT_B_BGA1-IC,TBD   I284 @BASEBOARD_FAB2_LIB.BASEBOARD_FAB2(SCH_1):PAGE41
  U5D1 CR68 VSS<382> SKX_EXT_B_BGA1-IC,TBD   I284 @BASEBOARD_FAB2_LIB.BASEBOARD_FAB2(SCH_1):PAGE41
  U5D1 CR66 VSS<383> SKX_EXT_B_BGA1-IC,TBD   I284 @BASEBOARD_FAB2_LIB.BASEBOARD_FAB2(SCH_1):PAGE41
  U5D1 CR64 VSS<384> SKX_EXT_B_BGA1-IC,TBD   I284 @BASEBOARD_FAB2_LIB.BASEBOARD_FAB2(SCH_1):PAGE41
  U5D1 CR62 VSS<385> SKX_EXT_B_BGA1-IC,TBD   I284 @BASEBOARD_FAB2_LIB.BASEBOARD_FAB2(SCH_1):PAGE41
  U5D1 CR58 VSS<386> SKX_EXT_B_BGA1-IC,TBD   I284 @BASEBOARD_FAB2_LIB.BASEBOARD_FAB2(SCH_1):PAGE41
  U5D1 CR32 VSS<387> SKX_EXT_B_BGA1-IC,TBD   I284 @BASEBOARD_FAB2_LIB.BASEBOARD_FAB2(SCH_1):PAGE41
  U5D1 CR24 VSS<388> SKX_EXT_B_BGA1-IC,TBD   I284 @BASEBOARD_FAB2_LIB.BASEBOARD_FAB2(SCH_1):PAGE41
  U5D1 CR22 VSS<389> SKX_EXT_B_BGA1-IC,TBD   I284 @BASEBOARD_FAB2_LIB.BASEBOARD_FAB2(SCH_1):PAGE41
  U5D1 CR10 VSS<390> SKX_EXT_B_BGA1-IC,TBD   I284 @BASEBOARD_FAB2_LIB.BASEBOARD_FAB2(SCH_1):PAGE41
  U5D1  CR6 VSS<391> SKX_EXT_B_BGA1-IC,TBD   I284 @BASEBOARD_FAB2_LIB.BASEBOARD_FAB2(SCH_1):PAGE41
  U5D1 CP83 VSS<392> SKX_EXT_B_BGA1-IC,TBD   I284 @BASEBOARD_FAB2_LIB.BASEBOARD_FAB2(SCH_1):PAGE41
  U5D1 CP81 VSS<393> SKX_EXT_B_BGA1-IC,TBD   I284 @BASEBOARD_FAB2_LIB.BASEBOARD_FAB2(SCH_1):PAGE41
  U5D1 CP75 VSS<394> SKX_EXT_B_BGA1-IC,TBD   I284 @BASEBOARD_FAB2_LIB.BASEBOARD_FAB2(SCH_1):PAGE41
  U5D1 CP73 VSS<395> SKX_EXT_B_BGA1-IC,TBD   I284 @BASEBOARD_FAB2_LIB.BASEBOARD_FAB2(SCH_1):PAGE41
  U5D1 CP69 VSS<396> SKX_EXT_B_BGA1-IC,TBD   I284 @BASEBOARD_FAB2_LIB.BASEBOARD_FAB2(SCH_1):PAGE41
  U5D1 CP59 VSS<397> SKX_EXT_B_BGA1-IC,TBD   I284 @BASEBOARD_FAB2_LIB.BASEBOARD_FAB2(SCH_1):PAGE41
  U5D1 CP25 VSS<398> SKX_EXT_B_BGA1-IC,TBD   I284 @BASEBOARD_FAB2_LIB.BASEBOARD_FAB2(SCH_1):PAGE41
  U5D1  H59 VSS<399> SKX_EXT_B_BGA1-IC,TBD   I284 @BASEBOARD_FAB2_LIB.BASEBOARD_FAB2(SCH_1):PAGE41
  U5D1  CP1 VSS<400> SKX_EXT_B_BGA1-IC,TBD   I284 @BASEBOARD_FAB2_LIB.BASEBOARD_FAB2(SCH_1):PAGE41
  U5D1 CN78 VSS<401> SKX_EXT_B_BGA1-IC,TBD   I284 @BASEBOARD_FAB2_LIB.BASEBOARD_FAB2(SCH_1):PAGE41
  U5D1 CN68 VSS<402> SKX_EXT_B_BGA1-IC,TBD   I284 @BASEBOARD_FAB2_LIB.BASEBOARD_FAB2(SCH_1):PAGE41
  U5D1 CN62 VSS<403> SKX_EXT_B_BGA1-IC,TBD   I284 @BASEBOARD_FAB2_LIB.BASEBOARD_FAB2(SCH_1):PAGE41
  U5D1 CN60 VSS<404> SKX_EXT_B_BGA1-IC,TBD   I284 @BASEBOARD_FAB2_LIB.BASEBOARD_FAB2(SCH_1):PAGE41
  U5D1 CN32 VSS<405> SKX_EXT_B_BGA1-IC,TBD   I284 @BASEBOARD_FAB2_LIB.BASEBOARD_FAB2(SCH_1):PAGE41
  U5D1 CN26 VSS<406> SKX_EXT_B_BGA1-IC,TBD   I284 @BASEBOARD_FAB2_LIB.BASEBOARD_FAB2(SCH_1):PAGE41
  U5D1  H61 VSS<407> SKX_EXT_B_BGA1-IC,TBD   I284 @BASEBOARD_FAB2_LIB.BASEBOARD_FAB2(SCH_1):PAGE41
  U5D1 CN12 VSS<408> SKX_EXT_B_BGA1-IC,TBD   I284 @BASEBOARD_FAB2_LIB.BASEBOARD_FAB2(SCH_1):PAGE41
  U5D1  CN2 VSS<409> SKX_EXT_B_BGA1-IC,TBD   I284 @BASEBOARD_FAB2_LIB.BASEBOARD_FAB2(SCH_1):PAGE41
  U5D1 CM85 VSS<410> SKX_EXT_B_BGA1-IC,TBD   I284 @BASEBOARD_FAB2_LIB.BASEBOARD_FAB2(SCH_1):PAGE41
  U5D1 CM83 VSS<411> SKX_EXT_B_BGA1-IC,TBD   I284 @BASEBOARD_FAB2_LIB.BASEBOARD_FAB2(SCH_1):PAGE41
  U5D1 CM77 VSS<412> SKX_EXT_B_BGA1-IC,TBD   I284 @BASEBOARD_FAB2_LIB.BASEBOARD_FAB2(SCH_1):PAGE41
  U5D1 CM73 VSS<413> SKX_EXT_B_BGA1-IC,TBD   I284 @BASEBOARD_FAB2_LIB.BASEBOARD_FAB2(SCH_1):PAGE41
  U5D1 CM67 VSS<414> SKX_EXT_B_BGA1-IC,TBD   I284 @BASEBOARD_FAB2_LIB.BASEBOARD_FAB2(SCH_1):PAGE41
  U5D1 CM63 VSS<415> SKX_EXT_B_BGA1-IC,TBD   I284 @BASEBOARD_FAB2_LIB.BASEBOARD_FAB2(SCH_1):PAGE41
  U5D1 CM61 VSS<416> SKX_EXT_B_BGA1-IC,TBD   I284 @BASEBOARD_FAB2_LIB.BASEBOARD_FAB2(SCH_1):PAGE41
  U5D1 CM31 VSS<417> SKX_EXT_B_BGA1-IC,TBD   I284 @BASEBOARD_FAB2_LIB.BASEBOARD_FAB2(SCH_1):PAGE41
  U5D1  CM5 VSS<418> SKX_EXT_B_BGA1-IC,TBD   I284 @BASEBOARD_FAB2_LIB.BASEBOARD_FAB2(SCH_1):PAGE41
  U5D1 CM29 VSS<419> SKX_EXT_B_BGA1-IC,TBD   I284 @BASEBOARD_FAB2_LIB.BASEBOARD_FAB2(SCH_1):PAGE41
  U5D1 CM19 VSS<420> SKX_EXT_B_BGA1-IC,TBD   I284 @BASEBOARD_FAB2_LIB.BASEBOARD_FAB2(SCH_1):PAGE41
  U5D1 CL80 VSS<421> SKX_EXT_B_BGA1-IC,TBD   I284 @BASEBOARD_FAB2_LIB.BASEBOARD_FAB2(SCH_1):PAGE41
  U5D1 CL78 VSS<422> SKX_EXT_B_BGA1-IC,TBD   I284 @BASEBOARD_FAB2_LIB.BASEBOARD_FAB2(SCH_1):PAGE41
  U5D1 CL76 VSS<423> SKX_EXT_B_BGA1-IC,TBD   I284 @BASEBOARD_FAB2_LIB.BASEBOARD_FAB2(SCH_1):PAGE41
  U5D1 CL74 VSS<424> SKX_EXT_B_BGA1-IC,TBD   I284 @BASEBOARD_FAB2_LIB.BASEBOARD_FAB2(SCH_1):PAGE41
  U5D1 CL66 VSS<425> SKX_EXT_B_BGA1-IC,TBD   I284 @BASEBOARD_FAB2_LIB.BASEBOARD_FAB2(SCH_1):PAGE41
  U5D1 CL64 VSS<426> SKX_EXT_B_BGA1-IC,TBD   I284 @BASEBOARD_FAB2_LIB.BASEBOARD_FAB2(SCH_1):PAGE41
  U5D1 CL62 VSS<427> SKX_EXT_B_BGA1-IC,TBD   I284 @BASEBOARD_FAB2_LIB.BASEBOARD_FAB2(SCH_1):PAGE41
  U5D1  H63 VSS<428> SKX_EXT_B_BGA1-IC,TBD   I284 @BASEBOARD_FAB2_LIB.BASEBOARD_FAB2(SCH_1):PAGE41
  U5D1  P45 VSS<429> SKX_EXT_B_BGA1-IC,TBD   I284 @BASEBOARD_FAB2_LIB.BASEBOARD_FAB2(SCH_1):PAGE41
  U5D1 CL18 VSS<430> SKX_EXT_B_BGA1-IC,TBD   I284 @BASEBOARD_FAB2_LIB.BASEBOARD_FAB2(SCH_1):PAGE41
  U5D1 CL14 VSS<431> SKX_EXT_B_BGA1-IC,TBD   I284 @BASEBOARD_FAB2_LIB.BASEBOARD_FAB2(SCH_1):PAGE41
  U5D1  CL8 VSS<432> SKX_EXT_B_BGA1-IC,TBD   I284 @BASEBOARD_FAB2_LIB.BASEBOARD_FAB2(SCH_1):PAGE41
  U5D1 CK85 VSS<433> SKX_EXT_B_BGA1-IC,TBD   I284 @BASEBOARD_FAB2_LIB.BASEBOARD_FAB2(SCH_1):PAGE41
  U5D1 CK83 VSS<434> SKX_EXT_B_BGA1-IC,TBD   I284 @BASEBOARD_FAB2_LIB.BASEBOARD_FAB2(SCH_1):PAGE41
  U5D1 CK75 VSS<435> SKX_EXT_B_BGA1-IC,TBD   I284 @BASEBOARD_FAB2_LIB.BASEBOARD_FAB2(SCH_1):PAGE41
  U5D1 CK73 VSS<436> SKX_EXT_B_BGA1-IC,TBD   I284 @BASEBOARD_FAB2_LIB.BASEBOARD_FAB2(SCH_1):PAGE41
  U5D1 CK71 VSS<437> SKX_EXT_B_BGA1-IC,TBD   I284 @BASEBOARD_FAB2_LIB.BASEBOARD_FAB2(SCH_1):PAGE41
  U5D1 CK69 VSS<438> SKX_EXT_B_BGA1-IC,TBD   I284 @BASEBOARD_FAB2_LIB.BASEBOARD_FAB2(SCH_1):PAGE41
  U5D1 CK67 VSS<439> SKX_EXT_B_BGA1-IC,TBD   I284 @BASEBOARD_FAB2_LIB.BASEBOARD_FAB2(SCH_1):PAGE41
  U5D1 CK65 VSS<440> SKX_EXT_B_BGA1-IC,TBD   I284 @BASEBOARD_FAB2_LIB.BASEBOARD_FAB2(SCH_1):PAGE41
  U5D1 CK63 VSS<441> SKX_EXT_B_BGA1-IC,TBD   I284 @BASEBOARD_FAB2_LIB.BASEBOARD_FAB2(SCH_1):PAGE41
  U5D1 CK27 VSS<442> SKX_EXT_B_BGA1-IC,TBD   I284 @BASEBOARD_FAB2_LIB.BASEBOARD_FAB2(SCH_1):PAGE41
  U5D1 CK21 VSS<443> SKX_EXT_B_BGA1-IC,TBD   I284 @BASEBOARD_FAB2_LIB.BASEBOARD_FAB2(SCH_1):PAGE41
  U5D1 CK15 VSS<444> SKX_EXT_B_BGA1-IC,TBD   I284 @BASEBOARD_FAB2_LIB.BASEBOARD_FAB2(SCH_1):PAGE41
  U5D1 CK11 VSS<445> SKX_EXT_B_BGA1-IC,TBD   I284 @BASEBOARD_FAB2_LIB.BASEBOARD_FAB2(SCH_1):PAGE41
  U5D1 CJ86 VSS<446> SKX_EXT_B_BGA1-IC,TBD   I284 @BASEBOARD_FAB2_LIB.BASEBOARD_FAB2(SCH_1):PAGE41
  U5D1 CJ84 VSS<447> SKX_EXT_B_BGA1-IC,TBD   I284 @BASEBOARD_FAB2_LIB.BASEBOARD_FAB2(SCH_1):PAGE41
  U5D1 CJ82 VSS<448> SKX_EXT_B_BGA1-IC,TBD   I284 @BASEBOARD_FAB2_LIB.BASEBOARD_FAB2(SCH_1):PAGE41
  U5D1 CJ78 VSS<449> SKX_EXT_B_BGA1-IC,TBD   I284 @BASEBOARD_FAB2_LIB.BASEBOARD_FAB2(SCH_1):PAGE41
  U5D1 CJ76 VSS<450> SKX_EXT_B_BGA1-IC,TBD   I284 @BASEBOARD_FAB2_LIB.BASEBOARD_FAB2(SCH_1):PAGE41
  U5D1 CJ74 VSS<451> SKX_EXT_B_BGA1-IC,TBD   I284 @BASEBOARD_FAB2_LIB.BASEBOARD_FAB2(SCH_1):PAGE41
  U5D1 CJ62 VSS<452> SKX_EXT_B_BGA1-IC,TBD   I284 @BASEBOARD_FAB2_LIB.BASEBOARD_FAB2(SCH_1):PAGE41
  U5D1  P47 VSS<453> SKX_EXT_B_BGA1-IC,TBD   I284 @BASEBOARD_FAB2_LIB.BASEBOARD_FAB2(SCH_1):PAGE41
  U5D1 DN72 VSS<134> SKX_EXT_B_BGA1-IC,TBD   I285 @BASEBOARD_FAB2_LIB.BASEBOARD_FAB2(SCH_1):PAGE41
  U5D1 DN68 VSS<135> SKX_EXT_B_BGA1-IC,TBD   I285 @BASEBOARD_FAB2_LIB.BASEBOARD_FAB2(SCH_1):PAGE41
  U5D1 DN38 VSS<136> SKX_EXT_B_BGA1-IC,TBD   I285 @BASEBOARD_FAB2_LIB.BASEBOARD_FAB2(SCH_1):PAGE41
  U5D1 DN32 VSS<137> SKX_EXT_B_BGA1-IC,TBD   I285 @BASEBOARD_FAB2_LIB.BASEBOARD_FAB2(SCH_1):PAGE41
  U5D1 DN26 VSS<138> SKX_EXT_B_BGA1-IC,TBD   I285 @BASEBOARD_FAB2_LIB.BASEBOARD_FAB2(SCH_1):PAGE41
  U5D1 DN22 VSS<139> SKX_EXT_B_BGA1-IC,TBD   I285 @BASEBOARD_FAB2_LIB.BASEBOARD_FAB2(SCH_1):PAGE41
  U5D1 DN12 VSS<140> SKX_EXT_B_BGA1-IC,TBD   I285 @BASEBOARD_FAB2_LIB.BASEBOARD_FAB2(SCH_1):PAGE41
  U5D1 BH17 VSS<141> SKX_EXT_B_BGA1-IC,TBD   I285 @BASEBOARD_FAB2_LIB.BASEBOARD_FAB2(SCH_1):PAGE41
  U5D1  DN2 VSS<142> SKX_EXT_B_BGA1-IC,TBD   I285 @BASEBOARD_FAB2_LIB.BASEBOARD_FAB2(SCH_1):PAGE41
  U5D1 DM83 VSS<143> SKX_EXT_B_BGA1-IC,TBD   I285 @BASEBOARD_FAB2_LIB.BASEBOARD_FAB2(SCH_1):PAGE41
  U5D1 DM77 VSS<144> SKX_EXT_B_BGA1-IC,TBD   I285 @BASEBOARD_FAB2_LIB.BASEBOARD_FAB2(SCH_1):PAGE41
  U5D1 DM73 VSS<145> SKX_EXT_B_BGA1-IC,TBD   I285 @BASEBOARD_FAB2_LIB.BASEBOARD_FAB2(SCH_1):PAGE41
  U5D1 DM65 VSS<146> SKX_EXT_B_BGA1-IC,TBD   I285 @BASEBOARD_FAB2_LIB.BASEBOARD_FAB2(SCH_1):PAGE41
  U5D1 DM39 VSS<147> SKX_EXT_B_BGA1-IC,TBD   I285 @BASEBOARD_FAB2_LIB.BASEBOARD_FAB2(SCH_1):PAGE41
  U5D1 DM37 VSS<148> SKX_EXT_B_BGA1-IC,TBD   I285 @BASEBOARD_FAB2_LIB.BASEBOARD_FAB2(SCH_1):PAGE41
  U5D1 DM33 VSS<149> SKX_EXT_B_BGA1-IC,TBD   I285 @BASEBOARD_FAB2_LIB.BASEBOARD_FAB2(SCH_1):PAGE41
  U5D1 DM31 VSS<150> SKX_EXT_B_BGA1-IC,TBD   I285 @BASEBOARD_FAB2_LIB.BASEBOARD_FAB2(SCH_1):PAGE41
  U5D1 DM27 VSS<151> SKX_EXT_B_BGA1-IC,TBD   I285 @BASEBOARD_FAB2_LIB.BASEBOARD_FAB2(SCH_1):PAGE41
  U5D1 DM25 VSS<152> SKX_EXT_B_BGA1-IC,TBD   I285 @BASEBOARD_FAB2_LIB.BASEBOARD_FAB2(SCH_1):PAGE41
  U5D1  H45 VSS<153> SKX_EXT_B_BGA1-IC,TBD   I285 @BASEBOARD_FAB2_LIB.BASEBOARD_FAB2(SCH_1):PAGE41
  U5D1 DM15 VSS<154> SKX_EXT_B_BGA1-IC,TBD   I285 @BASEBOARD_FAB2_LIB.BASEBOARD_FAB2(SCH_1):PAGE41
  U5D1 DL80 VSS<155> SKX_EXT_B_BGA1-IC,TBD   I285 @BASEBOARD_FAB2_LIB.BASEBOARD_FAB2(SCH_1):PAGE41
  U5D1 DL78 VSS<156> SKX_EXT_B_BGA1-IC,TBD   I285 @BASEBOARD_FAB2_LIB.BASEBOARD_FAB2(SCH_1):PAGE41
  U5D1 DL76 VSS<157> SKX_EXT_B_BGA1-IC,TBD   I285 @BASEBOARD_FAB2_LIB.BASEBOARD_FAB2(SCH_1):PAGE41
  U5D1 DL74 VSS<158> SKX_EXT_B_BGA1-IC,TBD   I285 @BASEBOARD_FAB2_LIB.BASEBOARD_FAB2(SCH_1):PAGE41
  U5D1 DL70 VSS<159> SKX_EXT_B_BGA1-IC,TBD   I285 @BASEBOARD_FAB2_LIB.BASEBOARD_FAB2(SCH_1):PAGE41
  U5D1 DL68 VSS<160> SKX_EXT_B_BGA1-IC,TBD   I285 @BASEBOARD_FAB2_LIB.BASEBOARD_FAB2(SCH_1):PAGE41
  U5D1 DL40 VSS<161> SKX_EXT_B_BGA1-IC,TBD   I285 @BASEBOARD_FAB2_LIB.BASEBOARD_FAB2(SCH_1):PAGE41
  U5D1 DL36 VSS<162> SKX_EXT_B_BGA1-IC,TBD   I285 @BASEBOARD_FAB2_LIB.BASEBOARD_FAB2(SCH_1):PAGE41
  U5D1 DL34 VSS<163> SKX_EXT_B_BGA1-IC,TBD   I285 @BASEBOARD_FAB2_LIB.BASEBOARD_FAB2(SCH_1):PAGE41
  U5D1 DL30 VSS<164> SKX_EXT_B_BGA1-IC,TBD   I285 @BASEBOARD_FAB2_LIB.BASEBOARD_FAB2(SCH_1):PAGE41
  U5D1 DL28 VSS<165> SKX_EXT_B_BGA1-IC,TBD   I285 @BASEBOARD_FAB2_LIB.BASEBOARD_FAB2(SCH_1):PAGE41
  U5D1 DL24 VSS<166> SKX_EXT_B_BGA1-IC,TBD   I285 @BASEBOARD_FAB2_LIB.BASEBOARD_FAB2(SCH_1):PAGE41
  U5D1 DL22 VSS<167> SKX_EXT_B_BGA1-IC,TBD   I285 @BASEBOARD_FAB2_LIB.BASEBOARD_FAB2(SCH_1):PAGE41
  U5D1  DL4 VSS<168> SKX_EXT_B_BGA1-IC,TBD   I285 @BASEBOARD_FAB2_LIB.BASEBOARD_FAB2(SCH_1):PAGE41
  U5D1 DL18 VSS<169> SKX_EXT_B_BGA1-IC,TBD   I285 @BASEBOARD_FAB2_LIB.BASEBOARD_FAB2(SCH_1):PAGE41
  U5D1 DL16 VSS<170> SKX_EXT_B_BGA1-IC,TBD   I285 @BASEBOARD_FAB2_LIB.BASEBOARD_FAB2(SCH_1):PAGE41
  U5D1 DK85 VSS<171> SKX_EXT_B_BGA1-IC,TBD   I285 @BASEBOARD_FAB2_LIB.BASEBOARD_FAB2(SCH_1):PAGE41
  U5D1 DK83 VSS<172> SKX_EXT_B_BGA1-IC,TBD   I285 @BASEBOARD_FAB2_LIB.BASEBOARD_FAB2(SCH_1):PAGE41
  U5D1 DK77 VSS<173> SKX_EXT_B_BGA1-IC,TBD   I285 @BASEBOARD_FAB2_LIB.BASEBOARD_FAB2(SCH_1):PAGE41
  U5D1 DK75 VSS<174> SKX_EXT_B_BGA1-IC,TBD   I285 @BASEBOARD_FAB2_LIB.BASEBOARD_FAB2(SCH_1):PAGE41
  U5D1 DK73 VSS<175> SKX_EXT_B_BGA1-IC,TBD   I285 @BASEBOARD_FAB2_LIB.BASEBOARD_FAB2(SCH_1):PAGE41
  U5D1 DK41 VSS<176> SKX_EXT_B_BGA1-IC,TBD   I285 @BASEBOARD_FAB2_LIB.BASEBOARD_FAB2(SCH_1):PAGE41
  U5D1 DK39 VSS<177> SKX_EXT_B_BGA1-IC,TBD   I285 @BASEBOARD_FAB2_LIB.BASEBOARD_FAB2(SCH_1):PAGE41
  U5D1 DK35 VSS<178> SKX_EXT_B_BGA1-IC,TBD   I285 @BASEBOARD_FAB2_LIB.BASEBOARD_FAB2(SCH_1):PAGE41
  U5D1 DK29 VSS<179> SKX_EXT_B_BGA1-IC,TBD   I285 @BASEBOARD_FAB2_LIB.BASEBOARD_FAB2(SCH_1):PAGE41
  U5D1 DK23 VSS<180> SKX_EXT_B_BGA1-IC,TBD   I285 @BASEBOARD_FAB2_LIB.BASEBOARD_FAB2(SCH_1):PAGE41
  U5D1  DK7 VSS<181> SKX_EXT_B_BGA1-IC,TBD   I285 @BASEBOARD_FAB2_LIB.BASEBOARD_FAB2(SCH_1):PAGE41
  U5D1 DJ84 VSS<182> SKX_EXT_B_BGA1-IC,TBD   I285 @BASEBOARD_FAB2_LIB.BASEBOARD_FAB2(SCH_1):PAGE41
  U5D1 DJ82 VSS<183> SKX_EXT_B_BGA1-IC,TBD   I285 @BASEBOARD_FAB2_LIB.BASEBOARD_FAB2(SCH_1):PAGE41
  U5D1 DJ78 VSS<184> SKX_EXT_B_BGA1-IC,TBD   I285 @BASEBOARD_FAB2_LIB.BASEBOARD_FAB2(SCH_1):PAGE41
  U5D1 DJ74 VSS<185> SKX_EXT_B_BGA1-IC,TBD   I285 @BASEBOARD_FAB2_LIB.BASEBOARD_FAB2(SCH_1):PAGE41
  U5D1 DJ68 VSS<186> SKX_EXT_B_BGA1-IC,TBD   I285 @BASEBOARD_FAB2_LIB.BASEBOARD_FAB2(SCH_1):PAGE41
  U5D1 DJ42 VSS<187> SKX_EXT_B_BGA1-IC,TBD   I285 @BASEBOARD_FAB2_LIB.BASEBOARD_FAB2(SCH_1):PAGE41
  U5D1 DJ38 VSS<188> SKX_EXT_B_BGA1-IC,TBD   I285 @BASEBOARD_FAB2_LIB.BASEBOARD_FAB2(SCH_1):PAGE41
  U5D1 DJ22 VSS<189> SKX_EXT_B_BGA1-IC,TBD   I285 @BASEBOARD_FAB2_LIB.BASEBOARD_FAB2(SCH_1):PAGE41
  U5D1  H47 VSS<190> SKX_EXT_B_BGA1-IC,TBD   I285 @BASEBOARD_FAB2_LIB.BASEBOARD_FAB2(SCH_1):PAGE41
  U5D1 DJ10 VSS<191> SKX_EXT_B_BGA1-IC,TBD   I285 @BASEBOARD_FAB2_LIB.BASEBOARD_FAB2(SCH_1):PAGE41
  U5D1  DJ2 VSS<192> SKX_EXT_B_BGA1-IC,TBD   I285 @BASEBOARD_FAB2_LIB.BASEBOARD_FAB2(SCH_1):PAGE41
  U5D1 DH83 VSS<193> SKX_EXT_B_BGA1-IC,TBD   I285 @BASEBOARD_FAB2_LIB.BASEBOARD_FAB2(SCH_1):PAGE41
  U5D1 DH81 VSS<194> SKX_EXT_B_BGA1-IC,TBD   I285 @BASEBOARD_FAB2_LIB.BASEBOARD_FAB2(SCH_1):PAGE41
  U5D1 DH79 VSS<195> SKX_EXT_B_BGA1-IC,TBD   I285 @BASEBOARD_FAB2_LIB.BASEBOARD_FAB2(SCH_1):PAGE41
  U5D1 DH73 VSS<196> SKX_EXT_B_BGA1-IC,TBD   I285 @BASEBOARD_FAB2_LIB.BASEBOARD_FAB2(SCH_1):PAGE41
  U5D1 DH71 VSS<197> SKX_EXT_B_BGA1-IC,TBD   I285 @BASEBOARD_FAB2_LIB.BASEBOARD_FAB2(SCH_1):PAGE41
  U5D1 DH67 VSS<198> SKX_EXT_B_BGA1-IC,TBD   I285 @BASEBOARD_FAB2_LIB.BASEBOARD_FAB2(SCH_1):PAGE41
  U5D1 DH41 VSS<199> SKX_EXT_B_BGA1-IC,TBD   I285 @BASEBOARD_FAB2_LIB.BASEBOARD_FAB2(SCH_1):PAGE41
  U5D1 DH37 VSS<200> SKX_EXT_B_BGA1-IC,TBD   I285 @BASEBOARD_FAB2_LIB.BASEBOARD_FAB2(SCH_1):PAGE41
  U5D1 DH35 VSS<201> SKX_EXT_B_BGA1-IC,TBD   I285 @BASEBOARD_FAB2_LIB.BASEBOARD_FAB2(SCH_1):PAGE41
  U5D1 DH33 VSS<202> SKX_EXT_B_BGA1-IC,TBD   I285 @BASEBOARD_FAB2_LIB.BASEBOARD_FAB2(SCH_1):PAGE41
  U5D1 DH31 VSS<203> SKX_EXT_B_BGA1-IC,TBD   I285 @BASEBOARD_FAB2_LIB.BASEBOARD_FAB2(SCH_1):PAGE41
  U5D1 DH29 VSS<204> SKX_EXT_B_BGA1-IC,TBD   I285 @BASEBOARD_FAB2_LIB.BASEBOARD_FAB2(SCH_1):PAGE41
  U5D1 DH27 VSS<205> SKX_EXT_B_BGA1-IC,TBD   I285 @BASEBOARD_FAB2_LIB.BASEBOARD_FAB2(SCH_1):PAGE41
  U5D1 DH25 VSS<206> SKX_EXT_B_BGA1-IC,TBD   I285 @BASEBOARD_FAB2_LIB.BASEBOARD_FAB2(SCH_1):PAGE41
  U5D1 DH23 VSS<207> SKX_EXT_B_BGA1-IC,TBD   I285 @BASEBOARD_FAB2_LIB.BASEBOARD_FAB2(SCH_1):PAGE41
  U5D1 DH15 VSS<208> SKX_EXT_B_BGA1-IC,TBD   I285 @BASEBOARD_FAB2_LIB.BASEBOARD_FAB2(SCH_1):PAGE41
  U5D1 DH13 VSS<209> SKX_EXT_B_BGA1-IC,TBD   I285 @BASEBOARD_FAB2_LIB.BASEBOARD_FAB2(SCH_1):PAGE41
  U5D1 DG82 VSS<210> SKX_EXT_B_BGA1-IC,TBD   I285 @BASEBOARD_FAB2_LIB.BASEBOARD_FAB2(SCH_1):PAGE41
  U5D1 DG80 VSS<211> SKX_EXT_B_BGA1-IC,TBD   I285 @BASEBOARD_FAB2_LIB.BASEBOARD_FAB2(SCH_1):PAGE41
  U5D1 DG78 VSS<212> SKX_EXT_B_BGA1-IC,TBD   I285 @BASEBOARD_FAB2_LIB.BASEBOARD_FAB2(SCH_1):PAGE41
  U5D1 DG76 VSS<213> SKX_EXT_B_BGA1-IC,TBD   I285 @BASEBOARD_FAB2_LIB.BASEBOARD_FAB2(SCH_1):PAGE41
  U5D1 DG68 VSS<214> SKX_EXT_B_BGA1-IC,TBD   I285 @BASEBOARD_FAB2_LIB.BASEBOARD_FAB2(SCH_1):PAGE41
  U5D1 DG66 VSS<215> SKX_EXT_B_BGA1-IC,TBD   I285 @BASEBOARD_FAB2_LIB.BASEBOARD_FAB2(SCH_1):PAGE41
  U5D1 DG24 VSS<216> SKX_EXT_B_BGA1-IC,TBD   I285 @BASEBOARD_FAB2_LIB.BASEBOARD_FAB2(SCH_1):PAGE41
  U5D1 DG16 VSS<217> SKX_EXT_B_BGA1-IC,TBD   I285 @BASEBOARD_FAB2_LIB.BASEBOARD_FAB2(SCH_1):PAGE41
  U5D1 DG14 VSS<218> SKX_EXT_B_BGA1-IC,TBD   I285 @BASEBOARD_FAB2_LIB.BASEBOARD_FAB2(SCH_1):PAGE41
  U5D1  H49 VSS<219> SKX_EXT_B_BGA1-IC,TBD   I285 @BASEBOARD_FAB2_LIB.BASEBOARD_FAB2(SCH_1):PAGE41
  U5D1  DG2 VSS<220> SKX_EXT_B_BGA1-IC,TBD   I285 @BASEBOARD_FAB2_LIB.BASEBOARD_FAB2(SCH_1):PAGE41
  U5D1 DF85 VSS<221> SKX_EXT_B_BGA1-IC,TBD   I285 @BASEBOARD_FAB2_LIB.BASEBOARD_FAB2(SCH_1):PAGE41
  U5D1 DF83 VSS<222> SKX_EXT_B_BGA1-IC,TBD   I285 @BASEBOARD_FAB2_LIB.BASEBOARD_FAB2(SCH_1):PAGE41
  U5D1 DF79 VSS<223> SKX_EXT_B_BGA1-IC,TBD   I285 @BASEBOARD_FAB2_LIB.BASEBOARD_FAB2(SCH_1):PAGE41
  U5D1 DF73 VSS<224> SKX_EXT_B_BGA1-IC,TBD   I285 @BASEBOARD_FAB2_LIB.BASEBOARD_FAB2(SCH_1):PAGE41
  U5D1 DF69 VSS<225> SKX_EXT_B_BGA1-IC,TBD   I285 @BASEBOARD_FAB2_LIB.BASEBOARD_FAB2(SCH_1):PAGE41
  U5D1 DF65 VSS<226> SKX_EXT_B_BGA1-IC,TBD   I285 @BASEBOARD_FAB2_LIB.BASEBOARD_FAB2(SCH_1):PAGE41
  U5D1 DF41 VSS<227> SKX_EXT_B_BGA1-IC,TBD   I285 @BASEBOARD_FAB2_LIB.BASEBOARD_FAB2(SCH_1):PAGE41
  U5D1 DF39 VSS<228> SKX_EXT_B_BGA1-IC,TBD   I285 @BASEBOARD_FAB2_LIB.BASEBOARD_FAB2(SCH_1):PAGE41
  U5D1 DF37 VSS<229> SKX_EXT_B_BGA1-IC,TBD   I285 @BASEBOARD_FAB2_LIB.BASEBOARD_FAB2(SCH_1):PAGE41
  U5D1 DF35 VSS<230> SKX_EXT_B_BGA1-IC,TBD   I285 @BASEBOARD_FAB2_LIB.BASEBOARD_FAB2(SCH_1):PAGE41
  U5D1 DF29 VSS<231> SKX_EXT_B_BGA1-IC,TBD   I285 @BASEBOARD_FAB2_LIB.BASEBOARD_FAB2(SCH_1):PAGE41
  U5D1 DF19 VSS<232> SKX_EXT_B_BGA1-IC,TBD   I285 @BASEBOARD_FAB2_LIB.BASEBOARD_FAB2(SCH_1):PAGE41
  U5D1  H51 VSS<233> SKX_EXT_B_BGA1-IC,TBD   I285 @BASEBOARD_FAB2_LIB.BASEBOARD_FAB2(SCH_1):PAGE41
  U5D1  DF7 VSS<234> SKX_EXT_B_BGA1-IC,TBD   I285 @BASEBOARD_FAB2_LIB.BASEBOARD_FAB2(SCH_1):PAGE41
  U5D1  DF5 VSS<235> SKX_EXT_B_BGA1-IC,TBD   I285 @BASEBOARD_FAB2_LIB.BASEBOARD_FAB2(SCH_1):PAGE41
  U5D1 DE78 VSS<236> SKX_EXT_B_BGA1-IC,TBD   I285 @BASEBOARD_FAB2_LIB.BASEBOARD_FAB2(SCH_1):PAGE41
  U5D1 DE72 VSS<237> SKX_EXT_B_BGA1-IC,TBD   I285 @BASEBOARD_FAB2_LIB.BASEBOARD_FAB2(SCH_1):PAGE41
  U5D1 DE70 VSS<238> SKX_EXT_B_BGA1-IC,TBD   I285 @BASEBOARD_FAB2_LIB.BASEBOARD_FAB2(SCH_1):PAGE41
  U5D1 DE64 VSS<239> SKX_EXT_B_BGA1-IC,TBD   I285 @BASEBOARD_FAB2_LIB.BASEBOARD_FAB2(SCH_1):PAGE41
  U5D1 DE36 VSS<240> SKX_EXT_B_BGA1-IC,TBD   I285 @BASEBOARD_FAB2_LIB.BASEBOARD_FAB2(SCH_1):PAGE41
  U5D1 DE34 VSS<241> SKX_EXT_B_BGA1-IC,TBD   I285 @BASEBOARD_FAB2_LIB.BASEBOARD_FAB2(SCH_1):PAGE41
  U5D1 DE30 VSS<242> SKX_EXT_B_BGA1-IC,TBD   I285 @BASEBOARD_FAB2_LIB.BASEBOARD_FAB2(SCH_1):PAGE41
  U5D1 DE28 VSS<243> SKX_EXT_B_BGA1-IC,TBD   I285 @BASEBOARD_FAB2_LIB.BASEBOARD_FAB2(SCH_1):PAGE41
  U5D1 DE24 VSS<244> SKX_EXT_B_BGA1-IC,TBD   I285 @BASEBOARD_FAB2_LIB.BASEBOARD_FAB2(SCH_1):PAGE41
  U5D1 DE20 VSS<245> SKX_EXT_B_BGA1-IC,TBD   I285 @BASEBOARD_FAB2_LIB.BASEBOARD_FAB2(SCH_1):PAGE41
  U5D1 DE18 VSS<246> SKX_EXT_B_BGA1-IC,TBD   I285 @BASEBOARD_FAB2_LIB.BASEBOARD_FAB2(SCH_1):PAGE41
  U5D1  DE8 VSS<247> SKX_EXT_B_BGA1-IC,TBD   I285 @BASEBOARD_FAB2_LIB.BASEBOARD_FAB2(SCH_1):PAGE41
  U5D1  DE6 VSS<248> SKX_EXT_B_BGA1-IC,TBD   I285 @BASEBOARD_FAB2_LIB.BASEBOARD_FAB2(SCH_1):PAGE41
  U5D1 DD83 VSS<249> SKX_EXT_B_BGA1-IC,TBD   I285 @BASEBOARD_FAB2_LIB.BASEBOARD_FAB2(SCH_1):PAGE41
  U5D1 DD81 VSS<250> SKX_EXT_B_BGA1-IC,TBD   I285 @BASEBOARD_FAB2_LIB.BASEBOARD_FAB2(SCH_1):PAGE41
  U5D1 DD75 VSS<251> SKX_EXT_B_BGA1-IC,TBD   I285 @BASEBOARD_FAB2_LIB.BASEBOARD_FAB2(SCH_1):PAGE41
  U5D1 DD73 VSS<252> SKX_EXT_B_BGA1-IC,TBD   I285 @BASEBOARD_FAB2_LIB.BASEBOARD_FAB2(SCH_1):PAGE41
  U5D1 DD71 VSS<253> SKX_EXT_B_BGA1-IC,TBD   I285 @BASEBOARD_FAB2_LIB.BASEBOARD_FAB2(SCH_1):PAGE41
  U5D1 DD37 VSS<254> SKX_EXT_B_BGA1-IC,TBD   I285 @BASEBOARD_FAB2_LIB.BASEBOARD_FAB2(SCH_1):PAGE41
  U5D1 DD33 VSS<255> SKX_EXT_B_BGA1-IC,TBD   I285 @BASEBOARD_FAB2_LIB.BASEBOARD_FAB2(SCH_1):PAGE41
  U5D1 DD31 VSS<256> SKX_EXT_B_BGA1-IC,TBD   I285 @BASEBOARD_FAB2_LIB.BASEBOARD_FAB2(SCH_1):PAGE41
  U5D1 DD27 VSS<257> SKX_EXT_B_BGA1-IC,TBD   I285 @BASEBOARD_FAB2_LIB.BASEBOARD_FAB2(SCH_1):PAGE41
  U5D1 DD23 VSS<258> SKX_EXT_B_BGA1-IC,TBD   I285 @BASEBOARD_FAB2_LIB.BASEBOARD_FAB2(SCH_1):PAGE41
  U5D1 DD11 VSS<259> SKX_EXT_B_BGA1-IC,TBD   I285 @BASEBOARD_FAB2_LIB.BASEBOARD_FAB2(SCH_1):PAGE41
  U5D1 DC86 VSS<260> SKX_EXT_B_BGA1-IC,TBD   I285 @BASEBOARD_FAB2_LIB.BASEBOARD_FAB2(SCH_1):PAGE41
  U5D1 DC84 VSS<261> SKX_EXT_B_BGA1-IC,TBD   I285 @BASEBOARD_FAB2_LIB.BASEBOARD_FAB2(SCH_1):PAGE41
  U5D1 DC78 VSS<262> SKX_EXT_B_BGA1-IC,TBD   I285 @BASEBOARD_FAB2_LIB.BASEBOARD_FAB2(SCH_1):PAGE41
  U5D1 DC70 VSS<263> SKX_EXT_B_BGA1-IC,TBD   I285 @BASEBOARD_FAB2_LIB.BASEBOARD_FAB2(SCH_1):PAGE41
  U5D1 DC68 VSS<264> SKX_EXT_B_BGA1-IC,TBD   I285 @BASEBOARD_FAB2_LIB.BASEBOARD_FAB2(SCH_1):PAGE41
  U5D1 DC66 VSS<265> SKX_EXT_B_BGA1-IC,TBD   I285 @BASEBOARD_FAB2_LIB.BASEBOARD_FAB2(SCH_1):PAGE41
  U5D1 DC64 VSS<266> SKX_EXT_B_BGA1-IC,TBD   I285 @BASEBOARD_FAB2_LIB.BASEBOARD_FAB2(SCH_1):PAGE41
  U5D1 DC42 VSS<267> SKX_EXT_B_BGA1-IC,TBD   I285 @BASEBOARD_FAB2_LIB.BASEBOARD_FAB2(SCH_1):PAGE41
  U5D1 DC38 VSS<268> SKX_EXT_B_BGA1-IC,TBD   I285 @BASEBOARD_FAB2_LIB.BASEBOARD_FAB2(SCH_1):PAGE41
  U5D1 DC32 VSS<269> SKX_EXT_B_BGA1-IC,TBD   I285 @BASEBOARD_FAB2_LIB.BASEBOARD_FAB2(SCH_1):PAGE41
  U5D1 DC26 VSS<270> SKX_EXT_B_BGA1-IC,TBD   I285 @BASEBOARD_FAB2_LIB.BASEBOARD_FAB2(SCH_1):PAGE41
  U5D1 DC24 VSS<271> SKX_EXT_B_BGA1-IC,TBD   I285 @BASEBOARD_FAB2_LIB.BASEBOARD_FAB2(SCH_1):PAGE41
  U5D1 DC14 VSS<272> SKX_EXT_B_BGA1-IC,TBD   I285 @BASEBOARD_FAB2_LIB.BASEBOARD_FAB2(SCH_1):PAGE41
  U5D1 DB85 VSS<273> SKX_EXT_B_BGA1-IC,TBD   I285 @BASEBOARD_FAB2_LIB.BASEBOARD_FAB2(SCH_1):PAGE41
  U5D1 DB83 VSS<274> SKX_EXT_B_BGA1-IC,TBD   I285 @BASEBOARD_FAB2_LIB.BASEBOARD_FAB2(SCH_1):PAGE41
  U5D1 DB77 VSS<275> SKX_EXT_B_BGA1-IC,TBD   I285 @BASEBOARD_FAB2_LIB.BASEBOARD_FAB2(SCH_1):PAGE41
  U5D1 DB73 VSS<276> SKX_EXT_B_BGA1-IC,TBD   I285 @BASEBOARD_FAB2_LIB.BASEBOARD_FAB2(SCH_1):PAGE41
  U5D1 DB49 VSS<277> SKX_EXT_B_BGA1-IC,TBD   I285 @BASEBOARD_FAB2_LIB.BASEBOARD_FAB2(SCH_1):PAGE41
  U5D1 DB47 VSS<278> SKX_EXT_B_BGA1-IC,TBD   I285 @BASEBOARD_FAB2_LIB.BASEBOARD_FAB2(SCH_1):PAGE41
  U5D1 DB41 VSS<279> SKX_EXT_B_BGA1-IC,TBD   I285 @BASEBOARD_FAB2_LIB.BASEBOARD_FAB2(SCH_1):PAGE41
  U5D1 DB39 VSS<280> SKX_EXT_B_BGA1-IC,TBD   I285 @BASEBOARD_FAB2_LIB.BASEBOARD_FAB2(SCH_1):PAGE41
  U5D1 DB25 VSS<281> SKX_EXT_B_BGA1-IC,TBD   I285 @BASEBOARD_FAB2_LIB.BASEBOARD_FAB2(SCH_1):PAGE41
  U5D1 DB23 VSS<282> SKX_EXT_B_BGA1-IC,TBD   I285 @BASEBOARD_FAB2_LIB.BASEBOARD_FAB2(SCH_1):PAGE41
  U5D1 DB17 VSS<283> SKX_EXT_B_BGA1-IC,TBD   I285 @BASEBOARD_FAB2_LIB.BASEBOARD_FAB2(SCH_1):PAGE41
  U5D1 DB13 VSS<284> SKX_EXT_B_BGA1-IC,TBD   I285 @BASEBOARD_FAB2_LIB.BASEBOARD_FAB2(SCH_1):PAGE41
  U5D1  DB3 VSS<285> SKX_EXT_B_BGA1-IC,TBD   I285 @BASEBOARD_FAB2_LIB.BASEBOARD_FAB2(SCH_1):PAGE41
  U5D1 DA80 VSS<286> SKX_EXT_B_BGA1-IC,TBD   I285 @BASEBOARD_FAB2_LIB.BASEBOARD_FAB2(SCH_1):PAGE41
  U5D1 DA78 VSS<287> SKX_EXT_B_BGA1-IC,TBD   I285 @BASEBOARD_FAB2_LIB.BASEBOARD_FAB2(SCH_1):PAGE41
  U5D1 DA76 VSS<288> SKX_EXT_B_BGA1-IC,TBD   I285 @BASEBOARD_FAB2_LIB.BASEBOARD_FAB2(SCH_1):PAGE41
  U5D1 DA74 VSS<289> SKX_EXT_B_BGA1-IC,TBD   I285 @BASEBOARD_FAB2_LIB.BASEBOARD_FAB2(SCH_1):PAGE41
  U5D1 DA70 VSS<290> SKX_EXT_B_BGA1-IC,TBD   I285 @BASEBOARD_FAB2_LIB.BASEBOARD_FAB2(SCH_1):PAGE41
  U5D1 DA64 VSS<291> SKX_EXT_B_BGA1-IC,TBD   I285 @BASEBOARD_FAB2_LIB.BASEBOARD_FAB2(SCH_1):PAGE41
  U5D1 DA50 VSS<292> SKX_EXT_B_BGA1-IC,TBD   I285 @BASEBOARD_FAB2_LIB.BASEBOARD_FAB2(SCH_1):PAGE41
  U5D1 DA48 VSS<293> SKX_EXT_B_BGA1-IC,TBD   I285 @BASEBOARD_FAB2_LIB.BASEBOARD_FAB2(SCH_1):PAGE41
  U5D1 EF79 VSS<0> SKX_EXT_B_BGA1-IC,TBD   I286 @BASEBOARD_FAB2_LIB.BASEBOARD_FAB2(SCH_1):PAGE41
  U5D1 EF75 VSS<1> SKX_EXT_B_BGA1-IC,TBD   I286 @BASEBOARD_FAB2_LIB.BASEBOARD_FAB2(SCH_1):PAGE41
  U5D1 EF71 VSS<2> SKX_EXT_B_BGA1-IC,TBD   I286 @BASEBOARD_FAB2_LIB.BASEBOARD_FAB2(SCH_1):PAGE41
  U5D1 EE78 VSS<3> SKX_EXT_B_BGA1-IC,TBD   I286 @BASEBOARD_FAB2_LIB.BASEBOARD_FAB2(SCH_1):PAGE41
  U5D1 EE76 VSS<4> SKX_EXT_B_BGA1-IC,TBD   I286 @BASEBOARD_FAB2_LIB.BASEBOARD_FAB2(SCH_1):PAGE41
  U5D1 EE70 VSS<5> SKX_EXT_B_BGA1-IC,TBD   I286 @BASEBOARD_FAB2_LIB.BASEBOARD_FAB2(SCH_1):PAGE41
  U5D1 EE36 VSS<6> SKX_EXT_B_BGA1-IC,TBD   I286 @BASEBOARD_FAB2_LIB.BASEBOARD_FAB2(SCH_1):PAGE41
  U5D1 EE34 VSS<7> SKX_EXT_B_BGA1-IC,TBD   I286 @BASEBOARD_FAB2_LIB.BASEBOARD_FAB2(SCH_1):PAGE41
  U5D1 EE30 VSS<8> SKX_EXT_B_BGA1-IC,TBD   I286 @BASEBOARD_FAB2_LIB.BASEBOARD_FAB2(SCH_1):PAGE41
  U5D1 EE28 VSS<9> SKX_EXT_B_BGA1-IC,TBD   I286 @BASEBOARD_FAB2_LIB.BASEBOARD_FAB2(SCH_1):PAGE41
  U5D1 EE24 VSS<10> SKX_EXT_B_BGA1-IC,TBD   I286 @BASEBOARD_FAB2_LIB.BASEBOARD_FAB2(SCH_1):PAGE41
  U5D1 ED77 VSS<11> SKX_EXT_B_BGA1-IC,TBD   I286 @BASEBOARD_FAB2_LIB.BASEBOARD_FAB2(SCH_1):PAGE41
  U5D1 ED35 VSS<12> SKX_EXT_B_BGA1-IC,TBD   I286 @BASEBOARD_FAB2_LIB.BASEBOARD_FAB2(SCH_1):PAGE41
  U5D1 ED29 VSS<13> SKX_EXT_B_BGA1-IC,TBD   I286 @BASEBOARD_FAB2_LIB.BASEBOARD_FAB2(SCH_1):PAGE41
  U5D1 ED23 VSS<14> SKX_EXT_B_BGA1-IC,TBD   I286 @BASEBOARD_FAB2_LIB.BASEBOARD_FAB2(SCH_1):PAGE41
  U5D1 ED15 VSS<15> SKX_EXT_B_BGA1-IC,TBD   I286 @BASEBOARD_FAB2_LIB.BASEBOARD_FAB2(SCH_1):PAGE41
  U5D1 ED11 VSS<16> SKX_EXT_B_BGA1-IC,TBD   I286 @BASEBOARD_FAB2_LIB.BASEBOARD_FAB2(SCH_1):PAGE41
  U5D1 EC76 VSS<17> SKX_EXT_B_BGA1-IC,TBD   I286 @BASEBOARD_FAB2_LIB.BASEBOARD_FAB2(SCH_1):PAGE41
  U5D1 EC74 VSS<18> SKX_EXT_B_BGA1-IC,TBD   I286 @BASEBOARD_FAB2_LIB.BASEBOARD_FAB2(SCH_1):PAGE41
  U5D1 EC72 VSS<19> SKX_EXT_B_BGA1-IC,TBD   I286 @BASEBOARD_FAB2_LIB.BASEBOARD_FAB2(SCH_1):PAGE41
  U5D1 EC70 VSS<20> SKX_EXT_B_BGA1-IC,TBD   I286 @BASEBOARD_FAB2_LIB.BASEBOARD_FAB2(SCH_1):PAGE41
  U5D1 EC10 VSS<21> SKX_EXT_B_BGA1-IC,TBD   I286 @BASEBOARD_FAB2_LIB.BASEBOARD_FAB2(SCH_1):PAGE41
  U5D1 EB69 VSS<22> SKX_EXT_B_BGA1-IC,TBD   I286 @BASEBOARD_FAB2_LIB.BASEBOARD_FAB2(SCH_1):PAGE41
  U5D1 EB65 VSS<23> SKX_EXT_B_BGA1-IC,TBD   I286 @BASEBOARD_FAB2_LIB.BASEBOARD_FAB2(SCH_1):PAGE41
  U5D1 EB41 VSS<24> SKX_EXT_B_BGA1-IC,TBD   I286 @BASEBOARD_FAB2_LIB.BASEBOARD_FAB2(SCH_1):PAGE41
  U5D1 EB39 VSS<25> SKX_EXT_B_BGA1-IC,TBD   I286 @BASEBOARD_FAB2_LIB.BASEBOARD_FAB2(SCH_1):PAGE41
  U5D1 EB37 VSS<26> SKX_EXT_B_BGA1-IC,TBD   I286 @BASEBOARD_FAB2_LIB.BASEBOARD_FAB2(SCH_1):PAGE41
  U5D1 EB35 VSS<27> SKX_EXT_B_BGA1-IC,TBD   I286 @BASEBOARD_FAB2_LIB.BASEBOARD_FAB2(SCH_1):PAGE41
  U5D1 EB33 VSS<28> SKX_EXT_B_BGA1-IC,TBD   I286 @BASEBOARD_FAB2_LIB.BASEBOARD_FAB2(SCH_1):PAGE41
  U5D1 EB31 VSS<29> SKX_EXT_B_BGA1-IC,TBD   I286 @BASEBOARD_FAB2_LIB.BASEBOARD_FAB2(SCH_1):PAGE41
  U5D1 EB29 VSS<30> SKX_EXT_B_BGA1-IC,TBD   I286 @BASEBOARD_FAB2_LIB.BASEBOARD_FAB2(SCH_1):PAGE41
  U5D1 EB27 VSS<31> SKX_EXT_B_BGA1-IC,TBD   I286 @BASEBOARD_FAB2_LIB.BASEBOARD_FAB2(SCH_1):PAGE41
  U5D1 EB25 VSS<32> SKX_EXT_B_BGA1-IC,TBD   I286 @BASEBOARD_FAB2_LIB.BASEBOARD_FAB2(SCH_1):PAGE41
  U5D1 EB23 VSS<33> SKX_EXT_B_BGA1-IC,TBD   I286 @BASEBOARD_FAB2_LIB.BASEBOARD_FAB2(SCH_1):PAGE41
  U5D1 BR18 VSS<34> SKX_EXT_B_BGA1-IC,TBD   I286 @BASEBOARD_FAB2_LIB.BASEBOARD_FAB2(SCH_1):PAGE41
  U5D1 EB13 VSS<35> SKX_EXT_B_BGA1-IC,TBD   I286 @BASEBOARD_FAB2_LIB.BASEBOARD_FAB2(SCH_1):PAGE41
  U5D1 EA82 VSS<36> SKX_EXT_B_BGA1-IC,TBD   I286 @BASEBOARD_FAB2_LIB.BASEBOARD_FAB2(SCH_1):PAGE41
  U5D1 EA80 VSS<37> SKX_EXT_B_BGA1-IC,TBD   I286 @BASEBOARD_FAB2_LIB.BASEBOARD_FAB2(SCH_1):PAGE41
  U5D1 EA78 VSS<38> SKX_EXT_B_BGA1-IC,TBD   I286 @BASEBOARD_FAB2_LIB.BASEBOARD_FAB2(SCH_1):PAGE41
  U5D1 EA76 VSS<39> SKX_EXT_B_BGA1-IC,TBD   I286 @BASEBOARD_FAB2_LIB.BASEBOARD_FAB2(SCH_1):PAGE41
  U5D1 EA70 VSS<40> SKX_EXT_B_BGA1-IC,TBD   I286 @BASEBOARD_FAB2_LIB.BASEBOARD_FAB2(SCH_1):PAGE41
  U5D1 EA64 VSS<41> SKX_EXT_B_BGA1-IC,TBD   I286 @BASEBOARD_FAB2_LIB.BASEBOARD_FAB2(SCH_1):PAGE41
  U5D1 EA42 VSS<42> SKX_EXT_B_BGA1-IC,TBD   I286 @BASEBOARD_FAB2_LIB.BASEBOARD_FAB2(SCH_1):PAGE41
  U5D1 EA22 VSS<43> SKX_EXT_B_BGA1-IC,TBD   I286 @BASEBOARD_FAB2_LIB.BASEBOARD_FAB2(SCH_1):PAGE41
  U5D1 EA20 VSS<44> SKX_EXT_B_BGA1-IC,TBD   I286 @BASEBOARD_FAB2_LIB.BASEBOARD_FAB2(SCH_1):PAGE41
  U5D1 EA16 VSS<45> SKX_EXT_B_BGA1-IC,TBD   I286 @BASEBOARD_FAB2_LIB.BASEBOARD_FAB2(SCH_1):PAGE41
  U5D1  J16 VSS<46> SKX_EXT_B_BGA1-IC,TBD   I286 @BASEBOARD_FAB2_LIB.BASEBOARD_FAB2(SCH_1):PAGE41
  U5D1  EA6 VSS<47> SKX_EXT_B_BGA1-IC,TBD   I286 @BASEBOARD_FAB2_LIB.BASEBOARD_FAB2(SCH_1):PAGE41
  U5D1 DY75 VSS<48> SKX_EXT_B_BGA1-IC,TBD   I286 @BASEBOARD_FAB2_LIB.BASEBOARD_FAB2(SCH_1):PAGE41
  U5D1 DY71 VSS<49> SKX_EXT_B_BGA1-IC,TBD   I286 @BASEBOARD_FAB2_LIB.BASEBOARD_FAB2(SCH_1):PAGE41
  U5D1 DY41 VSS<50> SKX_EXT_B_BGA1-IC,TBD   I286 @BASEBOARD_FAB2_LIB.BASEBOARD_FAB2(SCH_1):PAGE41
  U5D1 DY35 VSS<51> SKX_EXT_B_BGA1-IC,TBD   I286 @BASEBOARD_FAB2_LIB.BASEBOARD_FAB2(SCH_1):PAGE41
  U5D1 DY29 VSS<52> SKX_EXT_B_BGA1-IC,TBD   I286 @BASEBOARD_FAB2_LIB.BASEBOARD_FAB2(SCH_1):PAGE41
  U5D1 DY23 VSS<53> SKX_EXT_B_BGA1-IC,TBD   I286 @BASEBOARD_FAB2_LIB.BASEBOARD_FAB2(SCH_1):PAGE41
  U5D1 DY19 VSS<54> SKX_EXT_B_BGA1-IC,TBD   I286 @BASEBOARD_FAB2_LIB.BASEBOARD_FAB2(SCH_1):PAGE41
  U5D1  DY5 VSS<55> SKX_EXT_B_BGA1-IC,TBD   I286 @BASEBOARD_FAB2_LIB.BASEBOARD_FAB2(SCH_1):PAGE41
  U5D1 DW84 VSS<56> SKX_EXT_B_BGA1-IC,TBD   I286 @BASEBOARD_FAB2_LIB.BASEBOARD_FAB2(SCH_1):PAGE41
  U5D1 DW82 VSS<57> SKX_EXT_B_BGA1-IC,TBD   I286 @BASEBOARD_FAB2_LIB.BASEBOARD_FAB2(SCH_1):PAGE41
  U5D1  DW8 VSS<58> SKX_EXT_B_BGA1-IC,TBD   I286 @BASEBOARD_FAB2_LIB.BASEBOARD_FAB2(SCH_1):PAGE41
  U5D1 DW76 VSS<59> SKX_EXT_B_BGA1-IC,TBD   I286 @BASEBOARD_FAB2_LIB.BASEBOARD_FAB2(SCH_1):PAGE41
  U5D1 DW74 VSS<60> SKX_EXT_B_BGA1-IC,TBD   I286 @BASEBOARD_FAB2_LIB.BASEBOARD_FAB2(SCH_1):PAGE41
  U5D1 DW72 VSS<61> SKX_EXT_B_BGA1-IC,TBD   I286 @BASEBOARD_FAB2_LIB.BASEBOARD_FAB2(SCH_1):PAGE41
  U5D1 DW70 VSS<62> SKX_EXT_B_BGA1-IC,TBD   I286 @BASEBOARD_FAB2_LIB.BASEBOARD_FAB2(SCH_1):PAGE41
  U5D1 DW68 VSS<63> SKX_EXT_B_BGA1-IC,TBD   I286 @BASEBOARD_FAB2_LIB.BASEBOARD_FAB2(SCH_1):PAGE41
  U5D1 DW66 VSS<64> SKX_EXT_B_BGA1-IC,TBD   I286 @BASEBOARD_FAB2_LIB.BASEBOARD_FAB2(SCH_1):PAGE41
  U5D1 DW64 VSS<65> SKX_EXT_B_BGA1-IC,TBD   I286 @BASEBOARD_FAB2_LIB.BASEBOARD_FAB2(SCH_1):PAGE41
  U5D1 DW40 VSS<66> SKX_EXT_B_BGA1-IC,TBD   I286 @BASEBOARD_FAB2_LIB.BASEBOARD_FAB2(SCH_1):PAGE41
  U5D1 DW36 VSS<67> SKX_EXT_B_BGA1-IC,TBD   I286 @BASEBOARD_FAB2_LIB.BASEBOARD_FAB2(SCH_1):PAGE41
  U5D1 DW34 VSS<68> SKX_EXT_B_BGA1-IC,TBD   I286 @BASEBOARD_FAB2_LIB.BASEBOARD_FAB2(SCH_1):PAGE41
  U5D1 DW30 VSS<69> SKX_EXT_B_BGA1-IC,TBD   I286 @BASEBOARD_FAB2_LIB.BASEBOARD_FAB2(SCH_1):PAGE41
  U5D1 DW28 VSS<70> SKX_EXT_B_BGA1-IC,TBD   I286 @BASEBOARD_FAB2_LIB.BASEBOARD_FAB2(SCH_1):PAGE41
  U5D1 DW24 VSS<71> SKX_EXT_B_BGA1-IC,TBD   I286 @BASEBOARD_FAB2_LIB.BASEBOARD_FAB2(SCH_1):PAGE41
  U5D1 DW20 VSS<72> SKX_EXT_B_BGA1-IC,TBD   I286 @BASEBOARD_FAB2_LIB.BASEBOARD_FAB2(SCH_1):PAGE41
  U5D1 DW12 VSS<73> SKX_EXT_B_BGA1-IC,TBD   I286 @BASEBOARD_FAB2_LIB.BASEBOARD_FAB2(SCH_1):PAGE41
  U5D1 DV81 VSS<74> SKX_EXT_B_BGA1-IC,TBD   I286 @BASEBOARD_FAB2_LIB.BASEBOARD_FAB2(SCH_1):PAGE41
  U5D1 DV77 VSS<75> SKX_EXT_B_BGA1-IC,TBD   I286 @BASEBOARD_FAB2_LIB.BASEBOARD_FAB2(SCH_1):PAGE41
  U5D1 DV73 VSS<76> SKX_EXT_B_BGA1-IC,TBD   I286 @BASEBOARD_FAB2_LIB.BASEBOARD_FAB2(SCH_1):PAGE41
  U5D1 DV39 VSS<77> SKX_EXT_B_BGA1-IC,TBD   I286 @BASEBOARD_FAB2_LIB.BASEBOARD_FAB2(SCH_1):PAGE41
  U5D1 DV37 VSS<78> SKX_EXT_B_BGA1-IC,TBD   I286 @BASEBOARD_FAB2_LIB.BASEBOARD_FAB2(SCH_1):PAGE41
  U5D1 DV33 VSS<79> SKX_EXT_B_BGA1-IC,TBD   I286 @BASEBOARD_FAB2_LIB.BASEBOARD_FAB2(SCH_1):PAGE41
  U5D1 DV31 VSS<80> SKX_EXT_B_BGA1-IC,TBD   I286 @BASEBOARD_FAB2_LIB.BASEBOARD_FAB2(SCH_1):PAGE41
  U5D1 DV27 VSS<81> SKX_EXT_B_BGA1-IC,TBD   I286 @BASEBOARD_FAB2_LIB.BASEBOARD_FAB2(SCH_1):PAGE41
  U5D1 DV25 VSS<82> SKX_EXT_B_BGA1-IC,TBD   I286 @BASEBOARD_FAB2_LIB.BASEBOARD_FAB2(SCH_1):PAGE41
  U5D1 DV21 VSS<83> SKX_EXT_B_BGA1-IC,TBD   I286 @BASEBOARD_FAB2_LIB.BASEBOARD_FAB2(SCH_1):PAGE41
  U5D1 DU84 VSS<84> SKX_EXT_B_BGA1-IC,TBD   I286 @BASEBOARD_FAB2_LIB.BASEBOARD_FAB2(SCH_1):PAGE41
  U5D1 DU82 VSS<85> SKX_EXT_B_BGA1-IC,TBD   I286 @BASEBOARD_FAB2_LIB.BASEBOARD_FAB2(SCH_1):PAGE41
  U5D1 DU80 VSS<86> SKX_EXT_B_BGA1-IC,TBD   I286 @BASEBOARD_FAB2_LIB.BASEBOARD_FAB2(SCH_1):PAGE41
  U5D1 DU78 VSS<87> SKX_EXT_B_BGA1-IC,TBD   I286 @BASEBOARD_FAB2_LIB.BASEBOARD_FAB2(SCH_1):PAGE41
  U5D1 DU72 VSS<88> SKX_EXT_B_BGA1-IC,TBD   I286 @BASEBOARD_FAB2_LIB.BASEBOARD_FAB2(SCH_1):PAGE41
  U5D1 DU70 VSS<89> SKX_EXT_B_BGA1-IC,TBD   I286 @BASEBOARD_FAB2_LIB.BASEBOARD_FAB2(SCH_1):PAGE41
  U5D1 DU38 VSS<90> SKX_EXT_B_BGA1-IC,TBD   I286 @BASEBOARD_FAB2_LIB.BASEBOARD_FAB2(SCH_1):PAGE41
  U5D1 DU32 VSS<91> SKX_EXT_B_BGA1-IC,TBD   I286 @BASEBOARD_FAB2_LIB.BASEBOARD_FAB2(SCH_1):PAGE41
  U5D1 DU26 VSS<92> SKX_EXT_B_BGA1-IC,TBD   I286 @BASEBOARD_FAB2_LIB.BASEBOARD_FAB2(SCH_1):PAGE41
  U5D1 DU22 VSS<93> SKX_EXT_B_BGA1-IC,TBD   I286 @BASEBOARD_FAB2_LIB.BASEBOARD_FAB2(SCH_1):PAGE41
  U5D1 CN14 VSS<94> SKX_EXT_B_BGA1-IC,TBD   I286 @BASEBOARD_FAB2_LIB.BASEBOARD_FAB2(SCH_1):PAGE41
  U5D1 DU14 VSS<95> SKX_EXT_B_BGA1-IC,TBD   I286 @BASEBOARD_FAB2_LIB.BASEBOARD_FAB2(SCH_1):PAGE41
  U5D1 DU10 VSS<96> SKX_EXT_B_BGA1-IC,TBD   I286 @BASEBOARD_FAB2_LIB.BASEBOARD_FAB2(SCH_1):PAGE41
  U5D1 DT85 VSS<97> SKX_EXT_B_BGA1-IC,TBD   I286 @BASEBOARD_FAB2_LIB.BASEBOARD_FAB2(SCH_1):PAGE41
  U5D1 DT83 VSS<98> SKX_EXT_B_BGA1-IC,TBD   I286 @BASEBOARD_FAB2_LIB.BASEBOARD_FAB2(SCH_1):PAGE41
  U5D1 DT79 VSS<99> SKX_EXT_B_BGA1-IC,TBD   I286 @BASEBOARD_FAB2_LIB.BASEBOARD_FAB2(SCH_1):PAGE41
  U5D1 DT69 VSS<100> SKX_EXT_B_BGA1-IC,TBD   I286 @BASEBOARD_FAB2_LIB.BASEBOARD_FAB2(SCH_1):PAGE41
  U5D1 DT65 VSS<101> SKX_EXT_B_BGA1-IC,TBD   I286 @BASEBOARD_FAB2_LIB.BASEBOARD_FAB2(SCH_1):PAGE41
  U5D1 DH21 VSS<102> SKX_EXT_B_BGA1-IC,TBD   I286 @BASEBOARD_FAB2_LIB.BASEBOARD_FAB2(SCH_1):PAGE41
  U5D1 DT17 VSS<103> SKX_EXT_B_BGA1-IC,TBD   I286 @BASEBOARD_FAB2_LIB.BASEBOARD_FAB2(SCH_1):PAGE41
  U5D1  DT3 VSS<104> SKX_EXT_B_BGA1-IC,TBD   I286 @BASEBOARD_FAB2_LIB.BASEBOARD_FAB2(SCH_1):PAGE41
  U5D1 DR78 VSS<105> SKX_EXT_B_BGA1-IC,TBD   I286 @BASEBOARD_FAB2_LIB.BASEBOARD_FAB2(SCH_1):PAGE41
  U5D1 DR76 VSS<106> SKX_EXT_B_BGA1-IC,TBD   I286 @BASEBOARD_FAB2_LIB.BASEBOARD_FAB2(SCH_1):PAGE41
  U5D1 DR74 VSS<107> SKX_EXT_B_BGA1-IC,TBD   I286 @BASEBOARD_FAB2_LIB.BASEBOARD_FAB2(SCH_1):PAGE41
  U5D1 DR72 VSS<108> SKX_EXT_B_BGA1-IC,TBD   I286 @BASEBOARD_FAB2_LIB.BASEBOARD_FAB2(SCH_1):PAGE41
  U5D1 DR70 VSS<109> SKX_EXT_B_BGA1-IC,TBD   I286 @BASEBOARD_FAB2_LIB.BASEBOARD_FAB2(SCH_1):PAGE41
  U5D1 DR68 VSS<110> SKX_EXT_B_BGA1-IC,TBD   I286 @BASEBOARD_FAB2_LIB.BASEBOARD_FAB2(SCH_1):PAGE41
  U5D1 DR66 VSS<111> SKX_EXT_B_BGA1-IC,TBD   I286 @BASEBOARD_FAB2_LIB.BASEBOARD_FAB2(SCH_1):PAGE41
  U5D1 DR42 VSS<112> SKX_EXT_B_BGA1-IC,TBD   I286 @BASEBOARD_FAB2_LIB.BASEBOARD_FAB2(SCH_1):PAGE41
  U5D1 DR40 VSS<113> SKX_EXT_B_BGA1-IC,TBD   I286 @BASEBOARD_FAB2_LIB.BASEBOARD_FAB2(SCH_1):PAGE41
  U5D1 DR38 VSS<114> SKX_EXT_B_BGA1-IC,TBD   I286 @BASEBOARD_FAB2_LIB.BASEBOARD_FAB2(SCH_1):PAGE41
  U5D1 DR36 VSS<115> SKX_EXT_B_BGA1-IC,TBD   I286 @BASEBOARD_FAB2_LIB.BASEBOARD_FAB2(SCH_1):PAGE41
  U5D1 DR34 VSS<116> SKX_EXT_B_BGA1-IC,TBD   I286 @BASEBOARD_FAB2_LIB.BASEBOARD_FAB2(SCH_1):PAGE41
  U5D1 DR32 VSS<117> SKX_EXT_B_BGA1-IC,TBD   I286 @BASEBOARD_FAB2_LIB.BASEBOARD_FAB2(SCH_1):PAGE41
  U5D1 DR30 VSS<118> SKX_EXT_B_BGA1-IC,TBD   I286 @BASEBOARD_FAB2_LIB.BASEBOARD_FAB2(SCH_1):PAGE41
  U5D1 DR28 VSS<119> SKX_EXT_B_BGA1-IC,TBD   I286 @BASEBOARD_FAB2_LIB.BASEBOARD_FAB2(SCH_1):PAGE41
  U5D1 DR26 VSS<120> SKX_EXT_B_BGA1-IC,TBD   I286 @BASEBOARD_FAB2_LIB.BASEBOARD_FAB2(SCH_1):PAGE41
  U5D1 DR24 VSS<121> SKX_EXT_B_BGA1-IC,TBD   I286 @BASEBOARD_FAB2_LIB.BASEBOARD_FAB2(SCH_1):PAGE41
  U5D1 DR22 VSS<122> SKX_EXT_B_BGA1-IC,TBD   I286 @BASEBOARD_FAB2_LIB.BASEBOARD_FAB2(SCH_1):PAGE41
  U5D1 DR20 VSS<123> SKX_EXT_B_BGA1-IC,TBD   I286 @BASEBOARD_FAB2_LIB.BASEBOARD_FAB2(SCH_1):PAGE41
  U5D1 CL22 VSS<124> SKX_EXT_B_BGA1-IC,TBD   I286 @BASEBOARD_FAB2_LIB.BASEBOARD_FAB2(SCH_1):PAGE41
  U5D1 CA20 VSS<125> SKX_EXT_B_BGA1-IC,TBD   I286 @BASEBOARD_FAB2_LIB.BASEBOARD_FAB2(SCH_1):PAGE41
  U5D1  DR6 VSS<126> SKX_EXT_B_BGA1-IC,TBD   I286 @BASEBOARD_FAB2_LIB.BASEBOARD_FAB2(SCH_1):PAGE41
  U5D1 BR26 VSS<127> SKX_EXT_B_BGA1-IC,TBD   I286 @BASEBOARD_FAB2_LIB.BASEBOARD_FAB2(SCH_1):PAGE41
  U5D1 DP83 VSS<128> SKX_EXT_B_BGA1-IC,TBD   I286 @BASEBOARD_FAB2_LIB.BASEBOARD_FAB2(SCH_1):PAGE41
  U5D1 DP81 VSS<129> SKX_EXT_B_BGA1-IC,TBD   I286 @BASEBOARD_FAB2_LIB.BASEBOARD_FAB2(SCH_1):PAGE41
  U5D1 DP71 VSS<130> SKX_EXT_B_BGA1-IC,TBD   I286 @BASEBOARD_FAB2_LIB.BASEBOARD_FAB2(SCH_1):PAGE41
  U5D1 DP69 VSS<131> SKX_EXT_B_BGA1-IC,TBD   I286 @BASEBOARD_FAB2_LIB.BASEBOARD_FAB2(SCH_1):PAGE41
  U5D1 DP67 VSS<132> SKX_EXT_B_BGA1-IC,TBD   I286 @BASEBOARD_FAB2_LIB.BASEBOARD_FAB2(SCH_1):PAGE41
  U5D1 DN78 VSS<133> SKX_EXT_B_BGA1-IC,TBD   I286 @BASEBOARD_FAB2_LIB.BASEBOARD_FAB2(SCH_1):PAGE41
  C4P1    2      B CAP_0805-47UF,4V,20%,X6S,C9533A    I10 @BASEBOARD_FAB2_LIB.BASEBOARD_FAB2(SCH_1):PAGE42
  C4P9    2      B CAP_0805-47UF,4V,20%,X6S,C9533A    I12 @BASEBOARD_FAB2_LIB.BASEBOARD_FAB2(SCH_1):PAGE42
 C4P10    2      B CAP_0805-47UF,4V,20%,X6S,C9533A    I17 @BASEBOARD_FAB2_LIB.BASEBOARD_FAB2(SCH_1):PAGE42
  C5P7    2      B CAP_0805LF-22UF,4V,20%,X6S,C95A    I25 @BASEBOARD_FAB2_LIB.BASEBOARD_FAB2(SCH_1):PAGE42
 C5P23    2      B CAP_0805-47UF,4V,20%,X6S,C9533A    I28 @BASEBOARD_FAB2_LIB.BASEBOARD_FAB2(SCH_1):PAGE42
 C5P24    2      B CAP_0805-47UF,4V,20%,X6S,C9533A    I33 @BASEBOARD_FAB2_LIB.BASEBOARD_FAB2(SCH_1):PAGE42
 C5P25    2      B CAP_0805-47UF,4V,20%,X6S,C9533A    I37 @BASEBOARD_FAB2_LIB.BASEBOARD_FAB2(SCH_1):PAGE42
 C5P14    2      B CAP_0805-47UF,4V,20%,X6S,C9533A    I41 @BASEBOARD_FAB2_LIB.BASEBOARD_FAB2(SCH_1):PAGE42
 C5P27    2      B CAP_0805-47UF,4V,20%,X6S,C9533A    I44 @BASEBOARD_FAB2_LIB.BASEBOARD_FAB2(SCH_1):PAGE42
 C5P33    2      B CAP_0805-47UF,4V,20%,X6S,C9533A    I50 @BASEBOARD_FAB2_LIB.BASEBOARD_FAB2(SCH_1):PAGE42
 C5P35    2      B CAP_0805-47UF,4V,20%,X6S,C9533A    I51 @BASEBOARD_FAB2_LIB.BASEBOARD_FAB2(SCH_1):PAGE42
 C5P32    2      B CAP_0805-47UF,4V,20%,X6S,C9533A    I53 @BASEBOARD_FAB2_LIB.BASEBOARD_FAB2(SCH_1):PAGE42
 C5P34    2      B CAP_0805-47UF,4V,20%,X6S,C9533A    I54 @BASEBOARD_FAB2_LIB.BASEBOARD_FAB2(SCH_1):PAGE42
 C5P22    2      B CAP_0805-47UF,4V,20%,X6S,C9533A    I55 @BASEBOARD_FAB2_LIB.BASEBOARD_FAB2(SCH_1):PAGE42
 C5P26    2      B CAP_0805-47UF,4V,20%,X6S,C9533A    I56 @BASEBOARD_FAB2_LIB.BASEBOARD_FAB2(SCH_1):PAGE42
 C5P40    2      B CAP_0805-47UF,4V,20%,X6S,C9533A    I57 @BASEBOARD_FAB2_LIB.BASEBOARD_FAB2(SCH_1):PAGE42
 C5P37    2      B CAP_0805-47UF,4V,20%,X6S,C9533A    I63 @BASEBOARD_FAB2_LIB.BASEBOARD_FAB2(SCH_1):PAGE42
 C5P36    2      B CAP_0805-47UF,4V,20%,X6S,C9533A    I65 @BASEBOARD_FAB2_LIB.BASEBOARD_FAB2(SCH_1):PAGE42
  C6D8    2      B CAP_A_0603V-22.0UF,4V,20%,X6S,A    I68 @BASEBOARD_FAB2_LIB.BASEBOARD_FAB2(SCH_1):PAGE42
 C5D38    2      B CAP_A_0603V-22.0UF,4V,20%,X6S,A    I69 @BASEBOARD_FAB2_LIB.BASEBOARD_FAB2(SCH_1):PAGE42
 C5D37    2      B CAP_A_0603V-22.0UF,4V,20%,X6S,A    I70 @BASEBOARD_FAB2_LIB.BASEBOARD_FAB2(SCH_1):PAGE42
  C6D7    2      B CAP_A_0603V-22.0UF,4V,20%,X6S,A    I72 @BASEBOARD_FAB2_LIB.BASEBOARD_FAB2(SCH_1):PAGE42
  C6D4    2      B CAP_A_0603V-22.0UF,4V,20%,X6S,A    I74 @BASEBOARD_FAB2_LIB.BASEBOARD_FAB2(SCH_1):PAGE42
  C6D5    2      B CAP_A_0603V-22.0UF,4V,20%,X6S,A    I75 @BASEBOARD_FAB2_LIB.BASEBOARD_FAB2(SCH_1):PAGE42
  C6D2    2      B CAP_A_0603V-22.0UF,4V,20%,X6S,A    I77 @BASEBOARD_FAB2_LIB.BASEBOARD_FAB2(SCH_1):PAGE42
  C6D3    2      B CAP_A_0603V-22.0UF,4V,20%,X6S,A    I80 @BASEBOARD_FAB2_LIB.BASEBOARD_FAB2(SCH_1):PAGE42
  C6D6    2      B CAP_A_0603V-22.0UF,4V,20%,X6S,A    I81 @BASEBOARD_FAB2_LIB.BASEBOARD_FAB2(SCH_1):PAGE42
 C5D51    2      B CAP_A_0603V-22.0UF,4V,20%,X6S,A    I83 @BASEBOARD_FAB2_LIB.BASEBOARD_FAB2(SCH_1):PAGE42
 C5D21    2      B CAP_A_0603V-22.0UF,4V,20%,X6S,A    I88 @BASEBOARD_FAB2_LIB.BASEBOARD_FAB2(SCH_1):PAGE42
 C5D50    2      B CAP_A_0603V-22.0UF,4V,20%,X6S,A    I89 @BASEBOARD_FAB2_LIB.BASEBOARD_FAB2(SCH_1):PAGE42
 C5D48    2      B CAP_A_0603V-22.0UF,4V,20%,X6S,A    I90 @BASEBOARD_FAB2_LIB.BASEBOARD_FAB2(SCH_1):PAGE42
 C5D13    2      B CAP_0603LF-10UF,4V,20%,X6S,E15A    I91 @BASEBOARD_FAB2_LIB.BASEBOARD_FAB2(SCH_1):PAGE42
 C5D11    2      B CAP_0603LF-10UF,4V,20%,X6S,E15A    I93 @BASEBOARD_FAB2_LIB.BASEBOARD_FAB2(SCH_1):PAGE42
 C5D12    2      B CAP_0603LF-10UF,4V,20%,X6S,E15A    I94 @BASEBOARD_FAB2_LIB.BASEBOARD_FAB2(SCH_1):PAGE42
 C5D23    2      B CAP_A_0603V-22.0UF,4V,20%,X6S,A    I98 @BASEBOARD_FAB2_LIB.BASEBOARD_FAB2(SCH_1):PAGE42
 C5D28    2      B CAP_A_0603V-22.0UF,4V,20%,X6S,A   I100 @BASEBOARD_FAB2_LIB.BASEBOARD_FAB2(SCH_1):PAGE42
 C5D29    2      B CAP_A_0603V-22.0UF,4V,20%,X6S,A   I102 @BASEBOARD_FAB2_LIB.BASEBOARD_FAB2(SCH_1):PAGE42
 C5D32    2      B CAP_A_0603V-22.0UF,4V,20%,X6S,A   I103 @BASEBOARD_FAB2_LIB.BASEBOARD_FAB2(SCH_1):PAGE42
 C5D47    2      B CAP_A_0603V-22.0UF,4V,20%,X6S,A   I104 @BASEBOARD_FAB2_LIB.BASEBOARD_FAB2(SCH_1):PAGE42
 C5D31    2      B CAP_A_0603V-22.0UF,4V,20%,X6S,A   I106 @BASEBOARD_FAB2_LIB.BASEBOARD_FAB2(SCH_1):PAGE42
 C5D46    2      B CAP_A_0603V-22.0UF,4V,20%,X6S,A   I107 @BASEBOARD_FAB2_LIB.BASEBOARD_FAB2(SCH_1):PAGE42
 C5D10    2      B CAP_0603LF-10UF,4V,20%,X6S,E15A   I108 @BASEBOARD_FAB2_LIB.BASEBOARD_FAB2(SCH_1):PAGE42
 C5D27    2      B CAP_A_0603V-22.0UF,4V,20%,X6S,A   I109 @BASEBOARD_FAB2_LIB.BASEBOARD_FAB2(SCH_1):PAGE42
 C5D30    2      B CAP_A_0603V-22.0UF,4V,20%,X6S,A   I111 @BASEBOARD_FAB2_LIB.BASEBOARD_FAB2(SCH_1):PAGE42
 C5D41    2      B CAP_A_0603V-22.0UF,4V,20%,X6S,A   I114 @BASEBOARD_FAB2_LIB.BASEBOARD_FAB2(SCH_1):PAGE42
 C5D40    2      B CAP_A_0603V-22.0UF,4V,20%,X6S,A   I115 @BASEBOARD_FAB2_LIB.BASEBOARD_FAB2(SCH_1):PAGE42
 C5D14    2      B CAP_A_0603V-22.0UF,4V,20%,X6S,A   I117 @BASEBOARD_FAB2_LIB.BASEBOARD_FAB2(SCH_1):PAGE42
 C5D17    2      B CAP_A_0603V-22.0UF,4V,20%,X6S,A   I118 @BASEBOARD_FAB2_LIB.BASEBOARD_FAB2(SCH_1):PAGE42
 C5D16    2      B CAP_A_0603V-22.0UF,4V,20%,X6S,A   I123 @BASEBOARD_FAB2_LIB.BASEBOARD_FAB2(SCH_1):PAGE42
  C5D5    2      B CAP_A_0603V-22.0UF,4V,20%,X6S,A   I125 @BASEBOARD_FAB2_LIB.BASEBOARD_FAB2(SCH_1):PAGE42
 C5D19    2      B CAP_A_0603V-22.0UF,4V,20%,X6S,A   I128 @BASEBOARD_FAB2_LIB.BASEBOARD_FAB2(SCH_1):PAGE42
 C5D43    2      B CAP_A_0603V-22.0UF,4V,20%,X6S,A   I131 @BASEBOARD_FAB2_LIB.BASEBOARD_FAB2(SCH_1):PAGE42
 C5D15    2      B CAP_A_0603V-22.0UF,4V,20%,X6S,A   I132 @BASEBOARD_FAB2_LIB.BASEBOARD_FAB2(SCH_1):PAGE42
 C5D18    2      B CAP_A_0603V-22.0UF,4V,20%,X6S,A   I134 @BASEBOARD_FAB2_LIB.BASEBOARD_FAB2(SCH_1):PAGE42
 C5D42    2      B CAP_A_0603V-22.0UF,4V,20%,X6S,A   I135 @BASEBOARD_FAB2_LIB.BASEBOARD_FAB2(SCH_1):PAGE42
 C5D24    2      B CAP_A_0603V-22.0UF,4V,20%,X6S,A   I138 @BASEBOARD_FAB2_LIB.BASEBOARD_FAB2(SCH_1):PAGE42
 C5D39    2      B CAP_A_0603V-22.0UF,4V,20%,X6S,A   I140 @BASEBOARD_FAB2_LIB.BASEBOARD_FAB2(SCH_1):PAGE42
 C5D44    2      B CAP_A_0603V-22.0UF,4V,20%,X6S,A   I142 @BASEBOARD_FAB2_LIB.BASEBOARD_FAB2(SCH_1):PAGE42
  C6D9    2      B CAP_A_0603V-22.0UF,4V,20%,X6S,A   I145 @BASEBOARD_FAB2_LIB.BASEBOARD_FAB2(SCH_1):PAGE42
 C6D10    2      B CAP_A_0603V-22.0UF,4V,20%,X6S,A   I147 @BASEBOARD_FAB2_LIB.BASEBOARD_FAB2(SCH_1):PAGE42
 C5D36    2      B CAP_A_0603V-22.0UF,4V,20%,X6S,A   I151 @BASEBOARD_FAB2_LIB.BASEBOARD_FAB2(SCH_1):PAGE42
 C5D49    2      B CAP_A_0603V-22.0UF,4V,20%,X6S,A   I152 @BASEBOARD_FAB2_LIB.BASEBOARD_FAB2(SCH_1):PAGE42
 C5D22    2      B CAP_A_0603V-22.0UF,4V,20%,X6S,A   I153 @BASEBOARD_FAB2_LIB.BASEBOARD_FAB2(SCH_1):PAGE42
 C5D26    2      B CAP_A_0603V-22.0UF,4V,20%,X6S,A   I154 @BASEBOARD_FAB2_LIB.BASEBOARD_FAB2(SCH_1):PAGE42
 C5D25    2      B CAP_A_0603V-22.0UF,4V,20%,X6S,A   I155 @BASEBOARD_FAB2_LIB.BASEBOARD_FAB2(SCH_1):PAGE42
 C5D45    2      B CAP_A_0603V-22.0UF,4V,20%,X6S,A   I156 @BASEBOARD_FAB2_LIB.BASEBOARD_FAB2(SCH_1):PAGE42
  C4P6    2      B CAP_A_0603V-22.0UF,4V,20%,X6S,A   I164 @BASEBOARD_FAB2_LIB.BASEBOARD_FAB2(SCH_1):PAGE42
 C5D20    2      B CAP_A_0603V-22.0UF,4V,20%,X6S,A   I173 @BASEBOARD_FAB2_LIB.BASEBOARD_FAB2(SCH_1):PAGE42
 C5D33    2      B CAP_A_0603V-22.0UF,4V,20%,X6S,A   I174 @BASEBOARD_FAB2_LIB.BASEBOARD_FAB2(SCH_1):PAGE42
 C5D34    2      B CAP_A_0603V-22.0UF,4V,20%,X6S,A   I175 @BASEBOARD_FAB2_LIB.BASEBOARD_FAB2(SCH_1):PAGE42
 C5D35    2      B CAP_A_0603V-22.0UF,4V,20%,X6S,A   I176 @BASEBOARD_FAB2_LIB.BASEBOARD_FAB2(SCH_1):PAGE42
  C4P8    2      B CAP_A_0603V-22.0UF,4V,20%,X6S,A   I178 @BASEBOARD_FAB2_LIB.BASEBOARD_FAB2(SCH_1):PAGE42
 C5D53    2      B CAP_A_0603V-22.0UF,4V,20%,X6S,A   I179 @BASEBOARD_FAB2_LIB.BASEBOARD_FAB2(SCH_1):PAGE42
 C5D52    2      B CAP_A_0603V-22.0UF,4V,20%,X6S,A   I180 @BASEBOARD_FAB2_LIB.BASEBOARD_FAB2(SCH_1):PAGE42
 C5P15    2      B CAP_0805-47UF,4V,20%,X6S,C9533A   I187 @BASEBOARD_FAB2_LIB.BASEBOARD_FAB2(SCH_1):PAGE42
 C5P16    2      B CAP_0805-47UF,4V,20%,X6S,C9533A   I188 @BASEBOARD_FAB2_LIB.BASEBOARD_FAB2(SCH_1):PAGE42
 C5P17    2      B CAP_0805-47UF,4V,20%,X6S,C9533A   I190 @BASEBOARD_FAB2_LIB.BASEBOARD_FAB2(SCH_1):PAGE42
  J4G1  139  SA<0> SCONN288_H44441004_PIP-SCONN,HA     I1 @BASEBOARD_FAB2_LIB.BASEBOARD_FAB2(SCH_1):PAGE43
  J4G1  140  SA<1> SCONN288_H44441004_PIP-SCONN,HA     I1 @BASEBOARD_FAB2_LIB.BASEBOARD_FAB2(SCH_1):PAGE43
  J4G1  238  SA<2> SCONN288_H44441004_PIP-SCONN,HA     I1 @BASEBOARD_FAB2_LIB.BASEBOARD_FAB2(SCH_1):PAGE43
  J4G1  283 VSS<0> SCONN288_H44441004_PIP-SCONN,HA   I259 @BASEBOARD_FAB2_LIB.BASEBOARD_FAB2(SCH_1):PAGE43
  J4G1  281 VSS<1> SCONN288_H44441004_PIP-SCONN,HA   I259 @BASEBOARD_FAB2_LIB.BASEBOARD_FAB2(SCH_1):PAGE43
  J4G1  279 VSS<2> SCONN288_H44441004_PIP-SCONN,HA   I259 @BASEBOARD_FAB2_LIB.BASEBOARD_FAB2(SCH_1):PAGE43
  J4G1  276 VSS<3> SCONN288_H44441004_PIP-SCONN,HA   I259 @BASEBOARD_FAB2_LIB.BASEBOARD_FAB2(SCH_1):PAGE43
  J4G1  274 VSS<4> SCONN288_H44441004_PIP-SCONN,HA   I259 @BASEBOARD_FAB2_LIB.BASEBOARD_FAB2(SCH_1):PAGE43
  J4G1  272 VSS<5> SCONN288_H44441004_PIP-SCONN,HA   I259 @BASEBOARD_FAB2_LIB.BASEBOARD_FAB2(SCH_1):PAGE43
  J4G1  270 VSS<6> SCONN288_H44441004_PIP-SCONN,HA   I259 @BASEBOARD_FAB2_LIB.BASEBOARD_FAB2(SCH_1):PAGE43
  J4G1  268 VSS<7> SCONN288_H44441004_PIP-SCONN,HA   I259 @BASEBOARD_FAB2_LIB.BASEBOARD_FAB2(SCH_1):PAGE43
  J4G1  265 VSS<8> SCONN288_H44441004_PIP-SCONN,HA   I259 @BASEBOARD_FAB2_LIB.BASEBOARD_FAB2(SCH_1):PAGE43
  J4G1  263 VSS<9> SCONN288_H44441004_PIP-SCONN,HA   I259 @BASEBOARD_FAB2_LIB.BASEBOARD_FAB2(SCH_1):PAGE43
  J4G1  261 VSS<10> SCONN288_H44441004_PIP-SCONN,HA   I259 @BASEBOARD_FAB2_LIB.BASEBOARD_FAB2(SCH_1):PAGE43
  J4G1  259 VSS<11> SCONN288_H44441004_PIP-SCONN,HA   I259 @BASEBOARD_FAB2_LIB.BASEBOARD_FAB2(SCH_1):PAGE43
  J4G1  257 VSS<12> SCONN288_H44441004_PIP-SCONN,HA   I259 @BASEBOARD_FAB2_LIB.BASEBOARD_FAB2(SCH_1):PAGE43
  J4G1  254 VSS<13> SCONN288_H44441004_PIP-SCONN,HA   I259 @BASEBOARD_FAB2_LIB.BASEBOARD_FAB2(SCH_1):PAGE43
  J4G1  252 VSS<14> SCONN288_H44441004_PIP-SCONN,HA   I259 @BASEBOARD_FAB2_LIB.BASEBOARD_FAB2(SCH_1):PAGE43
  J4G1  250 VSS<15> SCONN288_H44441004_PIP-SCONN,HA   I259 @BASEBOARD_FAB2_LIB.BASEBOARD_FAB2(SCH_1):PAGE43
  J4G1  248 VSS<16> SCONN288_H44441004_PIP-SCONN,HA   I259 @BASEBOARD_FAB2_LIB.BASEBOARD_FAB2(SCH_1):PAGE43
  J4G1  246 VSS<17> SCONN288_H44441004_PIP-SCONN,HA   I259 @BASEBOARD_FAB2_LIB.BASEBOARD_FAB2(SCH_1):PAGE43
  J4G1  243 VSS<18> SCONN288_H44441004_PIP-SCONN,HA   I259 @BASEBOARD_FAB2_LIB.BASEBOARD_FAB2(SCH_1):PAGE43
  J4G1  241 VSS<19> SCONN288_H44441004_PIP-SCONN,HA   I259 @BASEBOARD_FAB2_LIB.BASEBOARD_FAB2(SCH_1):PAGE43
  J4G1  239 VSS<20> SCONN288_H44441004_PIP-SCONN,HA   I259 @BASEBOARD_FAB2_LIB.BASEBOARD_FAB2(SCH_1):PAGE43
  J4G1  202 VSS<21> SCONN288_H44441004_PIP-SCONN,HA   I259 @BASEBOARD_FAB2_LIB.BASEBOARD_FAB2(SCH_1):PAGE43
  J4G1  200 VSS<22> SCONN288_H44441004_PIP-SCONN,HA   I259 @BASEBOARD_FAB2_LIB.BASEBOARD_FAB2(SCH_1):PAGE43
  J4G1  198 VSS<23> SCONN288_H44441004_PIP-SCONN,HA   I259 @BASEBOARD_FAB2_LIB.BASEBOARD_FAB2(SCH_1):PAGE43
  J4G1  195 VSS<24> SCONN288_H44441004_PIP-SCONN,HA   I259 @BASEBOARD_FAB2_LIB.BASEBOARD_FAB2(SCH_1):PAGE43
  J4G1  193 VSS<25> SCONN288_H44441004_PIP-SCONN,HA   I259 @BASEBOARD_FAB2_LIB.BASEBOARD_FAB2(SCH_1):PAGE43
  J4G1  191 VSS<26> SCONN288_H44441004_PIP-SCONN,HA   I259 @BASEBOARD_FAB2_LIB.BASEBOARD_FAB2(SCH_1):PAGE43
  J4G1  189 VSS<27> SCONN288_H44441004_PIP-SCONN,HA   I259 @BASEBOARD_FAB2_LIB.BASEBOARD_FAB2(SCH_1):PAGE43
  J4G1  187 VSS<28> SCONN288_H44441004_PIP-SCONN,HA   I259 @BASEBOARD_FAB2_LIB.BASEBOARD_FAB2(SCH_1):PAGE43
  J4G1  184 VSS<29> SCONN288_H44441004_PIP-SCONN,HA   I259 @BASEBOARD_FAB2_LIB.BASEBOARD_FAB2(SCH_1):PAGE43
  J4G1  182 VSS<30> SCONN288_H44441004_PIP-SCONN,HA   I259 @BASEBOARD_FAB2_LIB.BASEBOARD_FAB2(SCH_1):PAGE43
  J4G1  180 VSS<31> SCONN288_H44441004_PIP-SCONN,HA   I259 @BASEBOARD_FAB2_LIB.BASEBOARD_FAB2(SCH_1):PAGE43
  J4G1  178 VSS<32> SCONN288_H44441004_PIP-SCONN,HA   I259 @BASEBOARD_FAB2_LIB.BASEBOARD_FAB2(SCH_1):PAGE43
  J4G1  176 VSS<33> SCONN288_H44441004_PIP-SCONN,HA   I259 @BASEBOARD_FAB2_LIB.BASEBOARD_FAB2(SCH_1):PAGE43
  J4G1  173 VSS<34> SCONN288_H44441004_PIP-SCONN,HA   I259 @BASEBOARD_FAB2_LIB.BASEBOARD_FAB2(SCH_1):PAGE43
  J4G1  171 VSS<35> SCONN288_H44441004_PIP-SCONN,HA   I259 @BASEBOARD_FAB2_LIB.BASEBOARD_FAB2(SCH_1):PAGE43
  J4G1  169 VSS<36> SCONN288_H44441004_PIP-SCONN,HA   I259 @BASEBOARD_FAB2_LIB.BASEBOARD_FAB2(SCH_1):PAGE43
  J4G1  167 VSS<37> SCONN288_H44441004_PIP-SCONN,HA   I259 @BASEBOARD_FAB2_LIB.BASEBOARD_FAB2(SCH_1):PAGE43
  J4G1  165 VSS<38> SCONN288_H44441004_PIP-SCONN,HA   I259 @BASEBOARD_FAB2_LIB.BASEBOARD_FAB2(SCH_1):PAGE43
  J4G1  162 VSS<39> SCONN288_H44441004_PIP-SCONN,HA   I259 @BASEBOARD_FAB2_LIB.BASEBOARD_FAB2(SCH_1):PAGE43
  J4G1  160 VSS<40> SCONN288_H44441004_PIP-SCONN,HA   I259 @BASEBOARD_FAB2_LIB.BASEBOARD_FAB2(SCH_1):PAGE43
  J4G1  158 VSS<41> SCONN288_H44441004_PIP-SCONN,HA   I259 @BASEBOARD_FAB2_LIB.BASEBOARD_FAB2(SCH_1):PAGE43
  J4G1  156 VSS<42> SCONN288_H44441004_PIP-SCONN,HA   I259 @BASEBOARD_FAB2_LIB.BASEBOARD_FAB2(SCH_1):PAGE43
  J4G1  154 VSS<43> SCONN288_H44441004_PIP-SCONN,HA   I259 @BASEBOARD_FAB2_LIB.BASEBOARD_FAB2(SCH_1):PAGE43
  J4G1  151 VSS<44> SCONN288_H44441004_PIP-SCONN,HA   I259 @BASEBOARD_FAB2_LIB.BASEBOARD_FAB2(SCH_1):PAGE43
  J4G1  149 VSS<45> SCONN288_H44441004_PIP-SCONN,HA   I259 @BASEBOARD_FAB2_LIB.BASEBOARD_FAB2(SCH_1):PAGE43
  J4G1  147 VSS<46> SCONN288_H44441004_PIP-SCONN,HA   I259 @BASEBOARD_FAB2_LIB.BASEBOARD_FAB2(SCH_1):PAGE43
  J4G1  138 VSS<47> SCONN288_H44441004_PIP-SCONN,HA   I259 @BASEBOARD_FAB2_LIB.BASEBOARD_FAB2(SCH_1):PAGE43
  J4G1  136 VSS<48> SCONN288_H44441004_PIP-SCONN,HA   I259 @BASEBOARD_FAB2_LIB.BASEBOARD_FAB2(SCH_1):PAGE43
  J4G1  134 VSS<49> SCONN288_H44441004_PIP-SCONN,HA   I259 @BASEBOARD_FAB2_LIB.BASEBOARD_FAB2(SCH_1):PAGE43
  J4G1  131 VSS<50> SCONN288_H44441004_PIP-SCONN,HA   I259 @BASEBOARD_FAB2_LIB.BASEBOARD_FAB2(SCH_1):PAGE43
  J4G1  129 VSS<51> SCONN288_H44441004_PIP-SCONN,HA   I259 @BASEBOARD_FAB2_LIB.BASEBOARD_FAB2(SCH_1):PAGE43
  J4G1  127 VSS<52> SCONN288_H44441004_PIP-SCONN,HA   I259 @BASEBOARD_FAB2_LIB.BASEBOARD_FAB2(SCH_1):PAGE43
  J4G1  125 VSS<53> SCONN288_H44441004_PIP-SCONN,HA   I259 @BASEBOARD_FAB2_LIB.BASEBOARD_FAB2(SCH_1):PAGE43
  J4G1  123 VSS<54> SCONN288_H44441004_PIP-SCONN,HA   I259 @BASEBOARD_FAB2_LIB.BASEBOARD_FAB2(SCH_1):PAGE43
  J4G1  120 VSS<55> SCONN288_H44441004_PIP-SCONN,HA   I259 @BASEBOARD_FAB2_LIB.BASEBOARD_FAB2(SCH_1):PAGE43
  J4G1  118 VSS<56> SCONN288_H44441004_PIP-SCONN,HA   I259 @BASEBOARD_FAB2_LIB.BASEBOARD_FAB2(SCH_1):PAGE43
  J4G1  116 VSS<57> SCONN288_H44441004_PIP-SCONN,HA   I259 @BASEBOARD_FAB2_LIB.BASEBOARD_FAB2(SCH_1):PAGE43
  J4G1  114 VSS<58> SCONN288_H44441004_PIP-SCONN,HA   I259 @BASEBOARD_FAB2_LIB.BASEBOARD_FAB2(SCH_1):PAGE43
  J4G1  112 VSS<59> SCONN288_H44441004_PIP-SCONN,HA   I259 @BASEBOARD_FAB2_LIB.BASEBOARD_FAB2(SCH_1):PAGE43
  J4G1  109 VSS<60> SCONN288_H44441004_PIP-SCONN,HA   I259 @BASEBOARD_FAB2_LIB.BASEBOARD_FAB2(SCH_1):PAGE43
  J4G1  107 VSS<61> SCONN288_H44441004_PIP-SCONN,HA   I259 @BASEBOARD_FAB2_LIB.BASEBOARD_FAB2(SCH_1):PAGE43
  J4G1  105 VSS<62> SCONN288_H44441004_PIP-SCONN,HA   I259 @BASEBOARD_FAB2_LIB.BASEBOARD_FAB2(SCH_1):PAGE43
  J4G1  103 VSS<63> SCONN288_H44441004_PIP-SCONN,HA   I259 @BASEBOARD_FAB2_LIB.BASEBOARD_FAB2(SCH_1):PAGE43
  J4G1  101 VSS<64> SCONN288_H44441004_PIP-SCONN,HA   I259 @BASEBOARD_FAB2_LIB.BASEBOARD_FAB2(SCH_1):PAGE43
  J4G1   98 VSS<65> SCONN288_H44441004_PIP-SCONN,HA   I259 @BASEBOARD_FAB2_LIB.BASEBOARD_FAB2(SCH_1):PAGE43
  J4G1   96 VSS<66> SCONN288_H44441004_PIP-SCONN,HA   I259 @BASEBOARD_FAB2_LIB.BASEBOARD_FAB2(SCH_1):PAGE43
  J4G1   94 VSS<67> SCONN288_H44441004_PIP-SCONN,HA   I259 @BASEBOARD_FAB2_LIB.BASEBOARD_FAB2(SCH_1):PAGE43
  J4G1   57 VSS<68> SCONN288_H44441004_PIP-SCONN,HA   I259 @BASEBOARD_FAB2_LIB.BASEBOARD_FAB2(SCH_1):PAGE43
  J4G1   55 VSS<69> SCONN288_H44441004_PIP-SCONN,HA   I259 @BASEBOARD_FAB2_LIB.BASEBOARD_FAB2(SCH_1):PAGE43
  J4G1   53 VSS<70> SCONN288_H44441004_PIP-SCONN,HA   I259 @BASEBOARD_FAB2_LIB.BASEBOARD_FAB2(SCH_1):PAGE43
  J4G1   50 VSS<71> SCONN288_H44441004_PIP-SCONN,HA   I259 @BASEBOARD_FAB2_LIB.BASEBOARD_FAB2(SCH_1):PAGE43
  J4G1   48 VSS<72> SCONN288_H44441004_PIP-SCONN,HA   I259 @BASEBOARD_FAB2_LIB.BASEBOARD_FAB2(SCH_1):PAGE43
  J4G1   46 VSS<73> SCONN288_H44441004_PIP-SCONN,HA   I259 @BASEBOARD_FAB2_LIB.BASEBOARD_FAB2(SCH_1):PAGE43
  J4G1   44 VSS<74> SCONN288_H44441004_PIP-SCONN,HA   I259 @BASEBOARD_FAB2_LIB.BASEBOARD_FAB2(SCH_1):PAGE43
  J4G1   42 VSS<75> SCONN288_H44441004_PIP-SCONN,HA   I259 @BASEBOARD_FAB2_LIB.BASEBOARD_FAB2(SCH_1):PAGE43
  J4G1   39 VSS<76> SCONN288_H44441004_PIP-SCONN,HA   I259 @BASEBOARD_FAB2_LIB.BASEBOARD_FAB2(SCH_1):PAGE43
  J4G1   37 VSS<77> SCONN288_H44441004_PIP-SCONN,HA   I259 @BASEBOARD_FAB2_LIB.BASEBOARD_FAB2(SCH_1):PAGE43
  J4G1   35 VSS<78> SCONN288_H44441004_PIP-SCONN,HA   I259 @BASEBOARD_FAB2_LIB.BASEBOARD_FAB2(SCH_1):PAGE43
  J4G1   33 VSS<79> SCONN288_H44441004_PIP-SCONN,HA   I259 @BASEBOARD_FAB2_LIB.BASEBOARD_FAB2(SCH_1):PAGE43
  J4G1   31 VSS<80> SCONN288_H44441004_PIP-SCONN,HA   I259 @BASEBOARD_FAB2_LIB.BASEBOARD_FAB2(SCH_1):PAGE43
  J4G1   28 VSS<81> SCONN288_H44441004_PIP-SCONN,HA   I259 @BASEBOARD_FAB2_LIB.BASEBOARD_FAB2(SCH_1):PAGE43
  J4G1   26 VSS<82> SCONN288_H44441004_PIP-SCONN,HA   I259 @BASEBOARD_FAB2_LIB.BASEBOARD_FAB2(SCH_1):PAGE43
  J4G1   24 VSS<83> SCONN288_H44441004_PIP-SCONN,HA   I259 @BASEBOARD_FAB2_LIB.BASEBOARD_FAB2(SCH_1):PAGE43
  J4G1   22 VSS<84> SCONN288_H44441004_PIP-SCONN,HA   I259 @BASEBOARD_FAB2_LIB.BASEBOARD_FAB2(SCH_1):PAGE43
  J4G1   20 VSS<85> SCONN288_H44441004_PIP-SCONN,HA   I259 @BASEBOARD_FAB2_LIB.BASEBOARD_FAB2(SCH_1):PAGE43
  J4G1   17 VSS<86> SCONN288_H44441004_PIP-SCONN,HA   I259 @BASEBOARD_FAB2_LIB.BASEBOARD_FAB2(SCH_1):PAGE43
  J4G1   15 VSS<87> SCONN288_H44441004_PIP-SCONN,HA   I259 @BASEBOARD_FAB2_LIB.BASEBOARD_FAB2(SCH_1):PAGE43
  J4G1   13 VSS<88> SCONN288_H44441004_PIP-SCONN,HA   I259 @BASEBOARD_FAB2_LIB.BASEBOARD_FAB2(SCH_1):PAGE43
  J4G1   11 VSS<89> SCONN288_H44441004_PIP-SCONN,HA   I259 @BASEBOARD_FAB2_LIB.BASEBOARD_FAB2(SCH_1):PAGE43
  J4G1    9 VSS<90> SCONN288_H44441004_PIP-SCONN,HA   I259 @BASEBOARD_FAB2_LIB.BASEBOARD_FAB2(SCH_1):PAGE43
  J4G1    6 VSS<91> SCONN288_H44441004_PIP-SCONN,HA   I259 @BASEBOARD_FAB2_LIB.BASEBOARD_FAB2(SCH_1):PAGE43
  J4G1    4 VSS<92> SCONN288_H44441004_PIP-SCONN,HA   I259 @BASEBOARD_FAB2_LIB.BASEBOARD_FAB2(SCH_1):PAGE43
  J4G1    2 VSS<93> SCONN288_H44441004_PIP-SCONN,HA   I259 @BASEBOARD_FAB2_LIB.BASEBOARD_FAB2(SCH_1):PAGE43
 C4F10    2      B CAP_A_0402V-0.01UF,25V,10%,X7RA   I272 @BASEBOARD_FAB2_LIB.BASEBOARD_FAB2(SCH_1):PAGE43
  C6T1    2      B CAP_A_0402V-0.01UF,25V,10%,X7RA     I2 @BASEBOARD_FAB2_LIB.BASEBOARD_FAB2(SCH_1):PAGE44
  J6T1  140  SA<1> SCONN288_H44441003_PIP-SCONN,HA    I13 @BASEBOARD_FAB2_LIB.BASEBOARD_FAB2(SCH_1):PAGE44
  J6T1  238  SA<2> SCONN288_H44441003_PIP-SCONN,HA    I13 @BASEBOARD_FAB2_LIB.BASEBOARD_FAB2(SCH_1):PAGE44
  J6T1  283 VSS<0> SCONN288_H44441003_PIP-SCONN,HA   I139 @BASEBOARD_FAB2_LIB.BASEBOARD_FAB2(SCH_1):PAGE44
  J6T1  281 VSS<1> SCONN288_H44441003_PIP-SCONN,HA   I139 @BASEBOARD_FAB2_LIB.BASEBOARD_FAB2(SCH_1):PAGE44
  J6T1  279 VSS<2> SCONN288_H44441003_PIP-SCONN,HA   I139 @BASEBOARD_FAB2_LIB.BASEBOARD_FAB2(SCH_1):PAGE44
  J6T1  276 VSS<3> SCONN288_H44441003_PIP-SCONN,HA   I139 @BASEBOARD_FAB2_LIB.BASEBOARD_FAB2(SCH_1):PAGE44
  J6T1  274 VSS<4> SCONN288_H44441003_PIP-SCONN,HA   I139 @BASEBOARD_FAB2_LIB.BASEBOARD_FAB2(SCH_1):PAGE44
  J6T1  272 VSS<5> SCONN288_H44441003_PIP-SCONN,HA   I139 @BASEBOARD_FAB2_LIB.BASEBOARD_FAB2(SCH_1):PAGE44
  J6T1  270 VSS<6> SCONN288_H44441003_PIP-SCONN,HA   I139 @BASEBOARD_FAB2_LIB.BASEBOARD_FAB2(SCH_1):PAGE44
  J6T1  268 VSS<7> SCONN288_H44441003_PIP-SCONN,HA   I139 @BASEBOARD_FAB2_LIB.BASEBOARD_FAB2(SCH_1):PAGE44
  J6T1  265 VSS<8> SCONN288_H44441003_PIP-SCONN,HA   I139 @BASEBOARD_FAB2_LIB.BASEBOARD_FAB2(SCH_1):PAGE44
  J6T1  263 VSS<9> SCONN288_H44441003_PIP-SCONN,HA   I139 @BASEBOARD_FAB2_LIB.BASEBOARD_FAB2(SCH_1):PAGE44
  J6T1  261 VSS<10> SCONN288_H44441003_PIP-SCONN,HA   I139 @BASEBOARD_FAB2_LIB.BASEBOARD_FAB2(SCH_1):PAGE44
  J6T1  259 VSS<11> SCONN288_H44441003_PIP-SCONN,HA   I139 @BASEBOARD_FAB2_LIB.BASEBOARD_FAB2(SCH_1):PAGE44
  J6T1  257 VSS<12> SCONN288_H44441003_PIP-SCONN,HA   I139 @BASEBOARD_FAB2_LIB.BASEBOARD_FAB2(SCH_1):PAGE44
  J6T1  254 VSS<13> SCONN288_H44441003_PIP-SCONN,HA   I139 @BASEBOARD_FAB2_LIB.BASEBOARD_FAB2(SCH_1):PAGE44
  J6T1  252 VSS<14> SCONN288_H44441003_PIP-SCONN,HA   I139 @BASEBOARD_FAB2_LIB.BASEBOARD_FAB2(SCH_1):PAGE44
  J6T1  250 VSS<15> SCONN288_H44441003_PIP-SCONN,HA   I139 @BASEBOARD_FAB2_LIB.BASEBOARD_FAB2(SCH_1):PAGE44
  J6T1  248 VSS<16> SCONN288_H44441003_PIP-SCONN,HA   I139 @BASEBOARD_FAB2_LIB.BASEBOARD_FAB2(SCH_1):PAGE44
  J6T1  246 VSS<17> SCONN288_H44441003_PIP-SCONN,HA   I139 @BASEBOARD_FAB2_LIB.BASEBOARD_FAB2(SCH_1):PAGE44
  J6T1  243 VSS<18> SCONN288_H44441003_PIP-SCONN,HA   I139 @BASEBOARD_FAB2_LIB.BASEBOARD_FAB2(SCH_1):PAGE44
  J6T1  241 VSS<19> SCONN288_H44441003_PIP-SCONN,HA   I139 @BASEBOARD_FAB2_LIB.BASEBOARD_FAB2(SCH_1):PAGE44
  J6T1  239 VSS<20> SCONN288_H44441003_PIP-SCONN,HA   I139 @BASEBOARD_FAB2_LIB.BASEBOARD_FAB2(SCH_1):PAGE44
  J6T1  202 VSS<21> SCONN288_H44441003_PIP-SCONN,HA   I139 @BASEBOARD_FAB2_LIB.BASEBOARD_FAB2(SCH_1):PAGE44
  J6T1  200 VSS<22> SCONN288_H44441003_PIP-SCONN,HA   I139 @BASEBOARD_FAB2_LIB.BASEBOARD_FAB2(SCH_1):PAGE44
  J6T1  198 VSS<23> SCONN288_H44441003_PIP-SCONN,HA   I139 @BASEBOARD_FAB2_LIB.BASEBOARD_FAB2(SCH_1):PAGE44
  J6T1  195 VSS<24> SCONN288_H44441003_PIP-SCONN,HA   I139 @BASEBOARD_FAB2_LIB.BASEBOARD_FAB2(SCH_1):PAGE44
  J6T1  193 VSS<25> SCONN288_H44441003_PIP-SCONN,HA   I139 @BASEBOARD_FAB2_LIB.BASEBOARD_FAB2(SCH_1):PAGE44
  J6T1  191 VSS<26> SCONN288_H44441003_PIP-SCONN,HA   I139 @BASEBOARD_FAB2_LIB.BASEBOARD_FAB2(SCH_1):PAGE44
  J6T1  189 VSS<27> SCONN288_H44441003_PIP-SCONN,HA   I139 @BASEBOARD_FAB2_LIB.BASEBOARD_FAB2(SCH_1):PAGE44
  J6T1  187 VSS<28> SCONN288_H44441003_PIP-SCONN,HA   I139 @BASEBOARD_FAB2_LIB.BASEBOARD_FAB2(SCH_1):PAGE44
  J6T1  184 VSS<29> SCONN288_H44441003_PIP-SCONN,HA   I139 @BASEBOARD_FAB2_LIB.BASEBOARD_FAB2(SCH_1):PAGE44
  J6T1  182 VSS<30> SCONN288_H44441003_PIP-SCONN,HA   I139 @BASEBOARD_FAB2_LIB.BASEBOARD_FAB2(SCH_1):PAGE44
  J6T1  180 VSS<31> SCONN288_H44441003_PIP-SCONN,HA   I139 @BASEBOARD_FAB2_LIB.BASEBOARD_FAB2(SCH_1):PAGE44
  J6T1  178 VSS<32> SCONN288_H44441003_PIP-SCONN,HA   I139 @BASEBOARD_FAB2_LIB.BASEBOARD_FAB2(SCH_1):PAGE44
  J6T1  176 VSS<33> SCONN288_H44441003_PIP-SCONN,HA   I139 @BASEBOARD_FAB2_LIB.BASEBOARD_FAB2(SCH_1):PAGE44
  J6T1  173 VSS<34> SCONN288_H44441003_PIP-SCONN,HA   I139 @BASEBOARD_FAB2_LIB.BASEBOARD_FAB2(SCH_1):PAGE44
  J6T1  171 VSS<35> SCONN288_H44441003_PIP-SCONN,HA   I139 @BASEBOARD_FAB2_LIB.BASEBOARD_FAB2(SCH_1):PAGE44
  J6T1  169 VSS<36> SCONN288_H44441003_PIP-SCONN,HA   I139 @BASEBOARD_FAB2_LIB.BASEBOARD_FAB2(SCH_1):PAGE44
  J6T1  167 VSS<37> SCONN288_H44441003_PIP-SCONN,HA   I139 @BASEBOARD_FAB2_LIB.BASEBOARD_FAB2(SCH_1):PAGE44
  J6T1  165 VSS<38> SCONN288_H44441003_PIP-SCONN,HA   I139 @BASEBOARD_FAB2_LIB.BASEBOARD_FAB2(SCH_1):PAGE44
  J6T1  162 VSS<39> SCONN288_H44441003_PIP-SCONN,HA   I139 @BASEBOARD_FAB2_LIB.BASEBOARD_FAB2(SCH_1):PAGE44
  J6T1  160 VSS<40> SCONN288_H44441003_PIP-SCONN,HA   I139 @BASEBOARD_FAB2_LIB.BASEBOARD_FAB2(SCH_1):PAGE44
  J6T1  158 VSS<41> SCONN288_H44441003_PIP-SCONN,HA   I139 @BASEBOARD_FAB2_LIB.BASEBOARD_FAB2(SCH_1):PAGE44
  J6T1  156 VSS<42> SCONN288_H44441003_PIP-SCONN,HA   I139 @BASEBOARD_FAB2_LIB.BASEBOARD_FAB2(SCH_1):PAGE44
  J6T1  154 VSS<43> SCONN288_H44441003_PIP-SCONN,HA   I139 @BASEBOARD_FAB2_LIB.BASEBOARD_FAB2(SCH_1):PAGE44
  J6T1  151 VSS<44> SCONN288_H44441003_PIP-SCONN,HA   I139 @BASEBOARD_FAB2_LIB.BASEBOARD_FAB2(SCH_1):PAGE44
  J6T1  149 VSS<45> SCONN288_H44441003_PIP-SCONN,HA   I139 @BASEBOARD_FAB2_LIB.BASEBOARD_FAB2(SCH_1):PAGE44
  J6T1  147 VSS<46> SCONN288_H44441003_PIP-SCONN,HA   I139 @BASEBOARD_FAB2_LIB.BASEBOARD_FAB2(SCH_1):PAGE44
  J6T1  138 VSS<47> SCONN288_H44441003_PIP-SCONN,HA   I139 @BASEBOARD_FAB2_LIB.BASEBOARD_FAB2(SCH_1):PAGE44
  J6T1  136 VSS<48> SCONN288_H44441003_PIP-SCONN,HA   I139 @BASEBOARD_FAB2_LIB.BASEBOARD_FAB2(SCH_1):PAGE44
  J6T1  134 VSS<49> SCONN288_H44441003_PIP-SCONN,HA   I139 @BASEBOARD_FAB2_LIB.BASEBOARD_FAB2(SCH_1):PAGE44
  J6T1  131 VSS<50> SCONN288_H44441003_PIP-SCONN,HA   I139 @BASEBOARD_FAB2_LIB.BASEBOARD_FAB2(SCH_1):PAGE44
  J6T1  129 VSS<51> SCONN288_H44441003_PIP-SCONN,HA   I139 @BASEBOARD_FAB2_LIB.BASEBOARD_FAB2(SCH_1):PAGE44
  J6T1  127 VSS<52> SCONN288_H44441003_PIP-SCONN,HA   I139 @BASEBOARD_FAB2_LIB.BASEBOARD_FAB2(SCH_1):PAGE44
  J6T1  125 VSS<53> SCONN288_H44441003_PIP-SCONN,HA   I139 @BASEBOARD_FAB2_LIB.BASEBOARD_FAB2(SCH_1):PAGE44
  J6T1  123 VSS<54> SCONN288_H44441003_PIP-SCONN,HA   I139 @BASEBOARD_FAB2_LIB.BASEBOARD_FAB2(SCH_1):PAGE44
  J6T1  120 VSS<55> SCONN288_H44441003_PIP-SCONN,HA   I139 @BASEBOARD_FAB2_LIB.BASEBOARD_FAB2(SCH_1):PAGE44
  J6T1  118 VSS<56> SCONN288_H44441003_PIP-SCONN,HA   I139 @BASEBOARD_FAB2_LIB.BASEBOARD_FAB2(SCH_1):PAGE44
  J6T1  116 VSS<57> SCONN288_H44441003_PIP-SCONN,HA   I139 @BASEBOARD_FAB2_LIB.BASEBOARD_FAB2(SCH_1):PAGE44
  J6T1  114 VSS<58> SCONN288_H44441003_PIP-SCONN,HA   I139 @BASEBOARD_FAB2_LIB.BASEBOARD_FAB2(SCH_1):PAGE44
  J6T1  112 VSS<59> SCONN288_H44441003_PIP-SCONN,HA   I139 @BASEBOARD_FAB2_LIB.BASEBOARD_FAB2(SCH_1):PAGE44
  J6T1  109 VSS<60> SCONN288_H44441003_PIP-SCONN,HA   I139 @BASEBOARD_FAB2_LIB.BASEBOARD_FAB2(SCH_1):PAGE44
  J6T1  107 VSS<61> SCONN288_H44441003_PIP-SCONN,HA   I139 @BASEBOARD_FAB2_LIB.BASEBOARD_FAB2(SCH_1):PAGE44
  J6T1  105 VSS<62> SCONN288_H44441003_PIP-SCONN,HA   I139 @BASEBOARD_FAB2_LIB.BASEBOARD_FAB2(SCH_1):PAGE44
  J6T1  103 VSS<63> SCONN288_H44441003_PIP-SCONN,HA   I139 @BASEBOARD_FAB2_LIB.BASEBOARD_FAB2(SCH_1):PAGE44
  J6T1  101 VSS<64> SCONN288_H44441003_PIP-SCONN,HA   I139 @BASEBOARD_FAB2_LIB.BASEBOARD_FAB2(SCH_1):PAGE44
  J6T1   98 VSS<65> SCONN288_H44441003_PIP-SCONN,HA   I139 @BASEBOARD_FAB2_LIB.BASEBOARD_FAB2(SCH_1):PAGE44
  J6T1   96 VSS<66> SCONN288_H44441003_PIP-SCONN,HA   I139 @BASEBOARD_FAB2_LIB.BASEBOARD_FAB2(SCH_1):PAGE44
  J6T1   94 VSS<67> SCONN288_H44441003_PIP-SCONN,HA   I139 @BASEBOARD_FAB2_LIB.BASEBOARD_FAB2(SCH_1):PAGE44
  J6T1   57 VSS<68> SCONN288_H44441003_PIP-SCONN,HA   I139 @BASEBOARD_FAB2_LIB.BASEBOARD_FAB2(SCH_1):PAGE44
  J6T1   55 VSS<69> SCONN288_H44441003_PIP-SCONN,HA   I139 @BASEBOARD_FAB2_LIB.BASEBOARD_FAB2(SCH_1):PAGE44
  J6T1   53 VSS<70> SCONN288_H44441003_PIP-SCONN,HA   I139 @BASEBOARD_FAB2_LIB.BASEBOARD_FAB2(SCH_1):PAGE44
  J6T1   50 VSS<71> SCONN288_H44441003_PIP-SCONN,HA   I139 @BASEBOARD_FAB2_LIB.BASEBOARD_FAB2(SCH_1):PAGE44
  J6T1   48 VSS<72> SCONN288_H44441003_PIP-SCONN,HA   I139 @BASEBOARD_FAB2_LIB.BASEBOARD_FAB2(SCH_1):PAGE44
  J6T1   46 VSS<73> SCONN288_H44441003_PIP-SCONN,HA   I139 @BASEBOARD_FAB2_LIB.BASEBOARD_FAB2(SCH_1):PAGE44
  J6T1   44 VSS<74> SCONN288_H44441003_PIP-SCONN,HA   I139 @BASEBOARD_FAB2_LIB.BASEBOARD_FAB2(SCH_1):PAGE44
  J6T1   42 VSS<75> SCONN288_H44441003_PIP-SCONN,HA   I139 @BASEBOARD_FAB2_LIB.BASEBOARD_FAB2(SCH_1):PAGE44
  J6T1   39 VSS<76> SCONN288_H44441003_PIP-SCONN,HA   I139 @BASEBOARD_FAB2_LIB.BASEBOARD_FAB2(SCH_1):PAGE44
  J6T1   37 VSS<77> SCONN288_H44441003_PIP-SCONN,HA   I139 @BASEBOARD_FAB2_LIB.BASEBOARD_FAB2(SCH_1):PAGE44
  J6T1   35 VSS<78> SCONN288_H44441003_PIP-SCONN,HA   I139 @BASEBOARD_FAB2_LIB.BASEBOARD_FAB2(SCH_1):PAGE44
  J6T1   33 VSS<79> SCONN288_H44441003_PIP-SCONN,HA   I139 @BASEBOARD_FAB2_LIB.BASEBOARD_FAB2(SCH_1):PAGE44
  J6T1   31 VSS<80> SCONN288_H44441003_PIP-SCONN,HA   I139 @BASEBOARD_FAB2_LIB.BASEBOARD_FAB2(SCH_1):PAGE44
  J6T1   28 VSS<81> SCONN288_H44441003_PIP-SCONN,HA   I139 @BASEBOARD_FAB2_LIB.BASEBOARD_FAB2(SCH_1):PAGE44
  J6T1   26 VSS<82> SCONN288_H44441003_PIP-SCONN,HA   I139 @BASEBOARD_FAB2_LIB.BASEBOARD_FAB2(SCH_1):PAGE44
  J6T1   24 VSS<83> SCONN288_H44441003_PIP-SCONN,HA   I139 @BASEBOARD_FAB2_LIB.BASEBOARD_FAB2(SCH_1):PAGE44
  J6T1   22 VSS<84> SCONN288_H44441003_PIP-SCONN,HA   I139 @BASEBOARD_FAB2_LIB.BASEBOARD_FAB2(SCH_1):PAGE44
  J6T1   20 VSS<85> SCONN288_H44441003_PIP-SCONN,HA   I139 @BASEBOARD_FAB2_LIB.BASEBOARD_FAB2(SCH_1):PAGE44
  J6T1   17 VSS<86> SCONN288_H44441003_PIP-SCONN,HA   I139 @BASEBOARD_FAB2_LIB.BASEBOARD_FAB2(SCH_1):PAGE44
  J6T1   15 VSS<87> SCONN288_H44441003_PIP-SCONN,HA   I139 @BASEBOARD_FAB2_LIB.BASEBOARD_FAB2(SCH_1):PAGE44
  J6T1   13 VSS<88> SCONN288_H44441003_PIP-SCONN,HA   I139 @BASEBOARD_FAB2_LIB.BASEBOARD_FAB2(SCH_1):PAGE44
  J6T1   11 VSS<89> SCONN288_H44441003_PIP-SCONN,HA   I139 @BASEBOARD_FAB2_LIB.BASEBOARD_FAB2(SCH_1):PAGE44
  J6T1    9 VSS<90> SCONN288_H44441003_PIP-SCONN,HA   I139 @BASEBOARD_FAB2_LIB.BASEBOARD_FAB2(SCH_1):PAGE44
  J6T1    6 VSS<91> SCONN288_H44441003_PIP-SCONN,HA   I139 @BASEBOARD_FAB2_LIB.BASEBOARD_FAB2(SCH_1):PAGE44
  J6T1    4 VSS<92> SCONN288_H44441003_PIP-SCONN,HA   I139 @BASEBOARD_FAB2_LIB.BASEBOARD_FAB2(SCH_1):PAGE44
  J6T1    2 VSS<93> SCONN288_H44441003_PIP-SCONN,HA   I139 @BASEBOARD_FAB2_LIB.BASEBOARD_FAB2(SCH_1):PAGE44
  J4G2  283 VSS<0> SCONN288_H44441004_PIP-SCONN,HA    I43 @BASEBOARD_FAB2_LIB.BASEBOARD_FAB2(SCH_1):PAGE45
  J4G2  281 VSS<1> SCONN288_H44441004_PIP-SCONN,HA    I43 @BASEBOARD_FAB2_LIB.BASEBOARD_FAB2(SCH_1):PAGE45
  J4G2  279 VSS<2> SCONN288_H44441004_PIP-SCONN,HA    I43 @BASEBOARD_FAB2_LIB.BASEBOARD_FAB2(SCH_1):PAGE45
  J4G2  276 VSS<3> SCONN288_H44441004_PIP-SCONN,HA    I43 @BASEBOARD_FAB2_LIB.BASEBOARD_FAB2(SCH_1):PAGE45
  J4G2  274 VSS<4> SCONN288_H44441004_PIP-SCONN,HA    I43 @BASEBOARD_FAB2_LIB.BASEBOARD_FAB2(SCH_1):PAGE45
  J4G2  272 VSS<5> SCONN288_H44441004_PIP-SCONN,HA    I43 @BASEBOARD_FAB2_LIB.BASEBOARD_FAB2(SCH_1):PAGE45
  J4G2  270 VSS<6> SCONN288_H44441004_PIP-SCONN,HA    I43 @BASEBOARD_FAB2_LIB.BASEBOARD_FAB2(SCH_1):PAGE45
  J4G2  268 VSS<7> SCONN288_H44441004_PIP-SCONN,HA    I43 @BASEBOARD_FAB2_LIB.BASEBOARD_FAB2(SCH_1):PAGE45
  J4G2  265 VSS<8> SCONN288_H44441004_PIP-SCONN,HA    I43 @BASEBOARD_FAB2_LIB.BASEBOARD_FAB2(SCH_1):PAGE45
  J4G2  263 VSS<9> SCONN288_H44441004_PIP-SCONN,HA    I43 @BASEBOARD_FAB2_LIB.BASEBOARD_FAB2(SCH_1):PAGE45
  J4G2  261 VSS<10> SCONN288_H44441004_PIP-SCONN,HA    I43 @BASEBOARD_FAB2_LIB.BASEBOARD_FAB2(SCH_1):PAGE45
  J4G2  259 VSS<11> SCONN288_H44441004_PIP-SCONN,HA    I43 @BASEBOARD_FAB2_LIB.BASEBOARD_FAB2(SCH_1):PAGE45
  J4G2  257 VSS<12> SCONN288_H44441004_PIP-SCONN,HA    I43 @BASEBOARD_FAB2_LIB.BASEBOARD_FAB2(SCH_1):PAGE45
  J4G2  254 VSS<13> SCONN288_H44441004_PIP-SCONN,HA    I43 @BASEBOARD_FAB2_LIB.BASEBOARD_FAB2(SCH_1):PAGE45
  J4G2  252 VSS<14> SCONN288_H44441004_PIP-SCONN,HA    I43 @BASEBOARD_FAB2_LIB.BASEBOARD_FAB2(SCH_1):PAGE45
  J4G2  250 VSS<15> SCONN288_H44441004_PIP-SCONN,HA    I43 @BASEBOARD_FAB2_LIB.BASEBOARD_FAB2(SCH_1):PAGE45
  J4G2  248 VSS<16> SCONN288_H44441004_PIP-SCONN,HA    I43 @BASEBOARD_FAB2_LIB.BASEBOARD_FAB2(SCH_1):PAGE45
  J4G2  246 VSS<17> SCONN288_H44441004_PIP-SCONN,HA    I43 @BASEBOARD_FAB2_LIB.BASEBOARD_FAB2(SCH_1):PAGE45
  J4G2  243 VSS<18> SCONN288_H44441004_PIP-SCONN,HA    I43 @BASEBOARD_FAB2_LIB.BASEBOARD_FAB2(SCH_1):PAGE45
  J4G2  241 VSS<19> SCONN288_H44441004_PIP-SCONN,HA    I43 @BASEBOARD_FAB2_LIB.BASEBOARD_FAB2(SCH_1):PAGE45
  J4G2  239 VSS<20> SCONN288_H44441004_PIP-SCONN,HA    I43 @BASEBOARD_FAB2_LIB.BASEBOARD_FAB2(SCH_1):PAGE45
  J4G2  202 VSS<21> SCONN288_H44441004_PIP-SCONN,HA    I43 @BASEBOARD_FAB2_LIB.BASEBOARD_FAB2(SCH_1):PAGE45
  J4G2  200 VSS<22> SCONN288_H44441004_PIP-SCONN,HA    I43 @BASEBOARD_FAB2_LIB.BASEBOARD_FAB2(SCH_1):PAGE45
  J4G2  198 VSS<23> SCONN288_H44441004_PIP-SCONN,HA    I43 @BASEBOARD_FAB2_LIB.BASEBOARD_FAB2(SCH_1):PAGE45
  J4G2  195 VSS<24> SCONN288_H44441004_PIP-SCONN,HA    I43 @BASEBOARD_FAB2_LIB.BASEBOARD_FAB2(SCH_1):PAGE45
  J4G2  193 VSS<25> SCONN288_H44441004_PIP-SCONN,HA    I43 @BASEBOARD_FAB2_LIB.BASEBOARD_FAB2(SCH_1):PAGE45
  J4G2  191 VSS<26> SCONN288_H44441004_PIP-SCONN,HA    I43 @BASEBOARD_FAB2_LIB.BASEBOARD_FAB2(SCH_1):PAGE45
  J4G2  189 VSS<27> SCONN288_H44441004_PIP-SCONN,HA    I43 @BASEBOARD_FAB2_LIB.BASEBOARD_FAB2(SCH_1):PAGE45
  J4G2  187 VSS<28> SCONN288_H44441004_PIP-SCONN,HA    I43 @BASEBOARD_FAB2_LIB.BASEBOARD_FAB2(SCH_1):PAGE45
  J4G2  184 VSS<29> SCONN288_H44441004_PIP-SCONN,HA    I43 @BASEBOARD_FAB2_LIB.BASEBOARD_FAB2(SCH_1):PAGE45
  J4G2  182 VSS<30> SCONN288_H44441004_PIP-SCONN,HA    I43 @BASEBOARD_FAB2_LIB.BASEBOARD_FAB2(SCH_1):PAGE45
  J4G2  180 VSS<31> SCONN288_H44441004_PIP-SCONN,HA    I43 @BASEBOARD_FAB2_LIB.BASEBOARD_FAB2(SCH_1):PAGE45
  J4G2  178 VSS<32> SCONN288_H44441004_PIP-SCONN,HA    I43 @BASEBOARD_FAB2_LIB.BASEBOARD_FAB2(SCH_1):PAGE45
  J4G2  176 VSS<33> SCONN288_H44441004_PIP-SCONN,HA    I43 @BASEBOARD_FAB2_LIB.BASEBOARD_FAB2(SCH_1):PAGE45
  J4G2  173 VSS<34> SCONN288_H44441004_PIP-SCONN,HA    I43 @BASEBOARD_FAB2_LIB.BASEBOARD_FAB2(SCH_1):PAGE45
  J4G2  171 VSS<35> SCONN288_H44441004_PIP-SCONN,HA    I43 @BASEBOARD_FAB2_LIB.BASEBOARD_FAB2(SCH_1):PAGE45
  J4G2  169 VSS<36> SCONN288_H44441004_PIP-SCONN,HA    I43 @BASEBOARD_FAB2_LIB.BASEBOARD_FAB2(SCH_1):PAGE45
  J4G2  167 VSS<37> SCONN288_H44441004_PIP-SCONN,HA    I43 @BASEBOARD_FAB2_LIB.BASEBOARD_FAB2(SCH_1):PAGE45
  J4G2  165 VSS<38> SCONN288_H44441004_PIP-SCONN,HA    I43 @BASEBOARD_FAB2_LIB.BASEBOARD_FAB2(SCH_1):PAGE45
  J4G2  162 VSS<39> SCONN288_H44441004_PIP-SCONN,HA    I43 @BASEBOARD_FAB2_LIB.BASEBOARD_FAB2(SCH_1):PAGE45
  J4G2  160 VSS<40> SCONN288_H44441004_PIP-SCONN,HA    I43 @BASEBOARD_FAB2_LIB.BASEBOARD_FAB2(SCH_1):PAGE45
  J4G2  158 VSS<41> SCONN288_H44441004_PIP-SCONN,HA    I43 @BASEBOARD_FAB2_LIB.BASEBOARD_FAB2(SCH_1):PAGE45
  J4G2  156 VSS<42> SCONN288_H44441004_PIP-SCONN,HA    I43 @BASEBOARD_FAB2_LIB.BASEBOARD_FAB2(SCH_1):PAGE45
  J4G2  154 VSS<43> SCONN288_H44441004_PIP-SCONN,HA    I43 @BASEBOARD_FAB2_LIB.BASEBOARD_FAB2(SCH_1):PAGE45
  J4G2  151 VSS<44> SCONN288_H44441004_PIP-SCONN,HA    I43 @BASEBOARD_FAB2_LIB.BASEBOARD_FAB2(SCH_1):PAGE45
  J4G2  149 VSS<45> SCONN288_H44441004_PIP-SCONN,HA    I43 @BASEBOARD_FAB2_LIB.BASEBOARD_FAB2(SCH_1):PAGE45
  J4G2  147 VSS<46> SCONN288_H44441004_PIP-SCONN,HA    I43 @BASEBOARD_FAB2_LIB.BASEBOARD_FAB2(SCH_1):PAGE45
  J4G2  138 VSS<47> SCONN288_H44441004_PIP-SCONN,HA    I43 @BASEBOARD_FAB2_LIB.BASEBOARD_FAB2(SCH_1):PAGE45
  J4G2  136 VSS<48> SCONN288_H44441004_PIP-SCONN,HA    I43 @BASEBOARD_FAB2_LIB.BASEBOARD_FAB2(SCH_1):PAGE45
  J4G2  134 VSS<49> SCONN288_H44441004_PIP-SCONN,HA    I43 @BASEBOARD_FAB2_LIB.BASEBOARD_FAB2(SCH_1):PAGE45
  J4G2  131 VSS<50> SCONN288_H44441004_PIP-SCONN,HA    I43 @BASEBOARD_FAB2_LIB.BASEBOARD_FAB2(SCH_1):PAGE45
  J4G2  129 VSS<51> SCONN288_H44441004_PIP-SCONN,HA    I43 @BASEBOARD_FAB2_LIB.BASEBOARD_FAB2(SCH_1):PAGE45
  J4G2  127 VSS<52> SCONN288_H44441004_PIP-SCONN,HA    I43 @BASEBOARD_FAB2_LIB.BASEBOARD_FAB2(SCH_1):PAGE45
  J4G2  125 VSS<53> SCONN288_H44441004_PIP-SCONN,HA    I43 @BASEBOARD_FAB2_LIB.BASEBOARD_FAB2(SCH_1):PAGE45
  J4G2  123 VSS<54> SCONN288_H44441004_PIP-SCONN,HA    I43 @BASEBOARD_FAB2_LIB.BASEBOARD_FAB2(SCH_1):PAGE45
  J4G2  120 VSS<55> SCONN288_H44441004_PIP-SCONN,HA    I43 @BASEBOARD_FAB2_LIB.BASEBOARD_FAB2(SCH_1):PAGE45
  J4G2  118 VSS<56> SCONN288_H44441004_PIP-SCONN,HA    I43 @BASEBOARD_FAB2_LIB.BASEBOARD_FAB2(SCH_1):PAGE45
  J4G2  116 VSS<57> SCONN288_H44441004_PIP-SCONN,HA    I43 @BASEBOARD_FAB2_LIB.BASEBOARD_FAB2(SCH_1):PAGE45
  J4G2  114 VSS<58> SCONN288_H44441004_PIP-SCONN,HA    I43 @BASEBOARD_FAB2_LIB.BASEBOARD_FAB2(SCH_1):PAGE45
  J4G2  112 VSS<59> SCONN288_H44441004_PIP-SCONN,HA    I43 @BASEBOARD_FAB2_LIB.BASEBOARD_FAB2(SCH_1):PAGE45
  J4G2  109 VSS<60> SCONN288_H44441004_PIP-SCONN,HA    I43 @BASEBOARD_FAB2_LIB.BASEBOARD_FAB2(SCH_1):PAGE45
  J4G2  107 VSS<61> SCONN288_H44441004_PIP-SCONN,HA    I43 @BASEBOARD_FAB2_LIB.BASEBOARD_FAB2(SCH_1):PAGE45
  J4G2  105 VSS<62> SCONN288_H44441004_PIP-SCONN,HA    I43 @BASEBOARD_FAB2_LIB.BASEBOARD_FAB2(SCH_1):PAGE45
  J4G2  103 VSS<63> SCONN288_H44441004_PIP-SCONN,HA    I43 @BASEBOARD_FAB2_LIB.BASEBOARD_FAB2(SCH_1):PAGE45
  J4G2  101 VSS<64> SCONN288_H44441004_PIP-SCONN,HA    I43 @BASEBOARD_FAB2_LIB.BASEBOARD_FAB2(SCH_1):PAGE45
  J4G2   98 VSS<65> SCONN288_H44441004_PIP-SCONN,HA    I43 @BASEBOARD_FAB2_LIB.BASEBOARD_FAB2(SCH_1):PAGE45
  J4G2   96 VSS<66> SCONN288_H44441004_PIP-SCONN,HA    I43 @BASEBOARD_FAB2_LIB.BASEBOARD_FAB2(SCH_1):PAGE45
  J4G2   94 VSS<67> SCONN288_H44441004_PIP-SCONN,HA    I43 @BASEBOARD_FAB2_LIB.BASEBOARD_FAB2(SCH_1):PAGE45
  J4G2   57 VSS<68> SCONN288_H44441004_PIP-SCONN,HA    I43 @BASEBOARD_FAB2_LIB.BASEBOARD_FAB2(SCH_1):PAGE45
  J4G2   55 VSS<69> SCONN288_H44441004_PIP-SCONN,HA    I43 @BASEBOARD_FAB2_LIB.BASEBOARD_FAB2(SCH_1):PAGE45
  J4G2   53 VSS<70> SCONN288_H44441004_PIP-SCONN,HA    I43 @BASEBOARD_FAB2_LIB.BASEBOARD_FAB2(SCH_1):PAGE45
  J4G2   50 VSS<71> SCONN288_H44441004_PIP-SCONN,HA    I43 @BASEBOARD_FAB2_LIB.BASEBOARD_FAB2(SCH_1):PAGE45
  J4G2   48 VSS<72> SCONN288_H44441004_PIP-SCONN,HA    I43 @BASEBOARD_FAB2_LIB.BASEBOARD_FAB2(SCH_1):PAGE45
  J4G2   46 VSS<73> SCONN288_H44441004_PIP-SCONN,HA    I43 @BASEBOARD_FAB2_LIB.BASEBOARD_FAB2(SCH_1):PAGE45
  J4G2   44 VSS<74> SCONN288_H44441004_PIP-SCONN,HA    I43 @BASEBOARD_FAB2_LIB.BASEBOARD_FAB2(SCH_1):PAGE45
  J4G2   42 VSS<75> SCONN288_H44441004_PIP-SCONN,HA    I43 @BASEBOARD_FAB2_LIB.BASEBOARD_FAB2(SCH_1):PAGE45
  J4G2   39 VSS<76> SCONN288_H44441004_PIP-SCONN,HA    I43 @BASEBOARD_FAB2_LIB.BASEBOARD_FAB2(SCH_1):PAGE45
  J4G2   37 VSS<77> SCONN288_H44441004_PIP-SCONN,HA    I43 @BASEBOARD_FAB2_LIB.BASEBOARD_FAB2(SCH_1):PAGE45
  J4G2   35 VSS<78> SCONN288_H44441004_PIP-SCONN,HA    I43 @BASEBOARD_FAB2_LIB.BASEBOARD_FAB2(SCH_1):PAGE45
  J4G2   33 VSS<79> SCONN288_H44441004_PIP-SCONN,HA    I43 @BASEBOARD_FAB2_LIB.BASEBOARD_FAB2(SCH_1):PAGE45
  J4G2   31 VSS<80> SCONN288_H44441004_PIP-SCONN,HA    I43 @BASEBOARD_FAB2_LIB.BASEBOARD_FAB2(SCH_1):PAGE45
  J4G2   28 VSS<81> SCONN288_H44441004_PIP-SCONN,HA    I43 @BASEBOARD_FAB2_LIB.BASEBOARD_FAB2(SCH_1):PAGE45
  J4G2   26 VSS<82> SCONN288_H44441004_PIP-SCONN,HA    I43 @BASEBOARD_FAB2_LIB.BASEBOARD_FAB2(SCH_1):PAGE45
  J4G2   24 VSS<83> SCONN288_H44441004_PIP-SCONN,HA    I43 @BASEBOARD_FAB2_LIB.BASEBOARD_FAB2(SCH_1):PAGE45
  J4G2   22 VSS<84> SCONN288_H44441004_PIP-SCONN,HA    I43 @BASEBOARD_FAB2_LIB.BASEBOARD_FAB2(SCH_1):PAGE45
  J4G2   20 VSS<85> SCONN288_H44441004_PIP-SCONN,HA    I43 @BASEBOARD_FAB2_LIB.BASEBOARD_FAB2(SCH_1):PAGE45
  J4G2   17 VSS<86> SCONN288_H44441004_PIP-SCONN,HA    I43 @BASEBOARD_FAB2_LIB.BASEBOARD_FAB2(SCH_1):PAGE45
  J4G2   15 VSS<87> SCONN288_H44441004_PIP-SCONN,HA    I43 @BASEBOARD_FAB2_LIB.BASEBOARD_FAB2(SCH_1):PAGE45
  J4G2   13 VSS<88> SCONN288_H44441004_PIP-SCONN,HA    I43 @BASEBOARD_FAB2_LIB.BASEBOARD_FAB2(SCH_1):PAGE45
  J4G2   11 VSS<89> SCONN288_H44441004_PIP-SCONN,HA    I43 @BASEBOARD_FAB2_LIB.BASEBOARD_FAB2(SCH_1):PAGE45
  J4G2    9 VSS<90> SCONN288_H44441004_PIP-SCONN,HA    I43 @BASEBOARD_FAB2_LIB.BASEBOARD_FAB2(SCH_1):PAGE45
  J4G2    6 VSS<91> SCONN288_H44441004_PIP-SCONN,HA    I43 @BASEBOARD_FAB2_LIB.BASEBOARD_FAB2(SCH_1):PAGE45
  J4G2    4 VSS<92> SCONN288_H44441004_PIP-SCONN,HA    I43 @BASEBOARD_FAB2_LIB.BASEBOARD_FAB2(SCH_1):PAGE45
  J4G2    2 VSS<93> SCONN288_H44441004_PIP-SCONN,HA    I43 @BASEBOARD_FAB2_LIB.BASEBOARD_FAB2(SCH_1):PAGE45
  J4G2  139  SA<0> SCONN288_H44441004_PIP-SCONN,HA   I111 @BASEBOARD_FAB2_LIB.BASEBOARD_FAB2(SCH_1):PAGE45
  J4G2  238  SA<2> SCONN288_H44441004_PIP-SCONN,HA   I111 @BASEBOARD_FAB2_LIB.BASEBOARD_FAB2(SCH_1):PAGE45
  C4G3    2      B CAP_A_0402V-0.01UF,25V,10%,X7RA   I179 @BASEBOARD_FAB2_LIB.BASEBOARD_FAB2(SCH_1):PAGE45
  C6U9    2      B CAP_A_0402V-0.01UF,25V,10%,X7RA     I5 @BASEBOARD_FAB2_LIB.BASEBOARD_FAB2(SCH_1):PAGE46
  J6U1  238  SA<2> SCONN288_H44441003_PIP-SCONN,HA    I14 @BASEBOARD_FAB2_LIB.BASEBOARD_FAB2(SCH_1):PAGE46
  J6U1  283 VSS<0> SCONN288_H44441003_PIP-SCONN,HA   I138 @BASEBOARD_FAB2_LIB.BASEBOARD_FAB2(SCH_1):PAGE46
  J6U1  281 VSS<1> SCONN288_H44441003_PIP-SCONN,HA   I138 @BASEBOARD_FAB2_LIB.BASEBOARD_FAB2(SCH_1):PAGE46
  J6U1  279 VSS<2> SCONN288_H44441003_PIP-SCONN,HA   I138 @BASEBOARD_FAB2_LIB.BASEBOARD_FAB2(SCH_1):PAGE46
  J6U1  276 VSS<3> SCONN288_H44441003_PIP-SCONN,HA   I138 @BASEBOARD_FAB2_LIB.BASEBOARD_FAB2(SCH_1):PAGE46
  J6U1  274 VSS<4> SCONN288_H44441003_PIP-SCONN,HA   I138 @BASEBOARD_FAB2_LIB.BASEBOARD_FAB2(SCH_1):PAGE46
  J6U1  272 VSS<5> SCONN288_H44441003_PIP-SCONN,HA   I138 @BASEBOARD_FAB2_LIB.BASEBOARD_FAB2(SCH_1):PAGE46
  J6U1  270 VSS<6> SCONN288_H44441003_PIP-SCONN,HA   I138 @BASEBOARD_FAB2_LIB.BASEBOARD_FAB2(SCH_1):PAGE46
  J6U1  268 VSS<7> SCONN288_H44441003_PIP-SCONN,HA   I138 @BASEBOARD_FAB2_LIB.BASEBOARD_FAB2(SCH_1):PAGE46
  J6U1  265 VSS<8> SCONN288_H44441003_PIP-SCONN,HA   I138 @BASEBOARD_FAB2_LIB.BASEBOARD_FAB2(SCH_1):PAGE46
  J6U1  263 VSS<9> SCONN288_H44441003_PIP-SCONN,HA   I138 @BASEBOARD_FAB2_LIB.BASEBOARD_FAB2(SCH_1):PAGE46
  J6U1  261 VSS<10> SCONN288_H44441003_PIP-SCONN,HA   I138 @BASEBOARD_FAB2_LIB.BASEBOARD_FAB2(SCH_1):PAGE46
  J6U1  259 VSS<11> SCONN288_H44441003_PIP-SCONN,HA   I138 @BASEBOARD_FAB2_LIB.BASEBOARD_FAB2(SCH_1):PAGE46
  J6U1  257 VSS<12> SCONN288_H44441003_PIP-SCONN,HA   I138 @BASEBOARD_FAB2_LIB.BASEBOARD_FAB2(SCH_1):PAGE46
  J6U1  254 VSS<13> SCONN288_H44441003_PIP-SCONN,HA   I138 @BASEBOARD_FAB2_LIB.BASEBOARD_FAB2(SCH_1):PAGE46
  J6U1  252 VSS<14> SCONN288_H44441003_PIP-SCONN,HA   I138 @BASEBOARD_FAB2_LIB.BASEBOARD_FAB2(SCH_1):PAGE46
  J6U1  250 VSS<15> SCONN288_H44441003_PIP-SCONN,HA   I138 @BASEBOARD_FAB2_LIB.BASEBOARD_FAB2(SCH_1):PAGE46
  J6U1  248 VSS<16> SCONN288_H44441003_PIP-SCONN,HA   I138 @BASEBOARD_FAB2_LIB.BASEBOARD_FAB2(SCH_1):PAGE46
  J6U1  246 VSS<17> SCONN288_H44441003_PIP-SCONN,HA   I138 @BASEBOARD_FAB2_LIB.BASEBOARD_FAB2(SCH_1):PAGE46
  J6U1  243 VSS<18> SCONN288_H44441003_PIP-SCONN,HA   I138 @BASEBOARD_FAB2_LIB.BASEBOARD_FAB2(SCH_1):PAGE46
  J6U1  241 VSS<19> SCONN288_H44441003_PIP-SCONN,HA   I138 @BASEBOARD_FAB2_LIB.BASEBOARD_FAB2(SCH_1):PAGE46
  J6U1  239 VSS<20> SCONN288_H44441003_PIP-SCONN,HA   I138 @BASEBOARD_FAB2_LIB.BASEBOARD_FAB2(SCH_1):PAGE46
  J6U1  202 VSS<21> SCONN288_H44441003_PIP-SCONN,HA   I138 @BASEBOARD_FAB2_LIB.BASEBOARD_FAB2(SCH_1):PAGE46
  J6U1  200 VSS<22> SCONN288_H44441003_PIP-SCONN,HA   I138 @BASEBOARD_FAB2_LIB.BASEBOARD_FAB2(SCH_1):PAGE46
  J6U1  198 VSS<23> SCONN288_H44441003_PIP-SCONN,HA   I138 @BASEBOARD_FAB2_LIB.BASEBOARD_FAB2(SCH_1):PAGE46
  J6U1  195 VSS<24> SCONN288_H44441003_PIP-SCONN,HA   I138 @BASEBOARD_FAB2_LIB.BASEBOARD_FAB2(SCH_1):PAGE46
  J6U1  193 VSS<25> SCONN288_H44441003_PIP-SCONN,HA   I138 @BASEBOARD_FAB2_LIB.BASEBOARD_FAB2(SCH_1):PAGE46
  J6U1  191 VSS<26> SCONN288_H44441003_PIP-SCONN,HA   I138 @BASEBOARD_FAB2_LIB.BASEBOARD_FAB2(SCH_1):PAGE46
  J6U1  189 VSS<27> SCONN288_H44441003_PIP-SCONN,HA   I138 @BASEBOARD_FAB2_LIB.BASEBOARD_FAB2(SCH_1):PAGE46
  J6U1  187 VSS<28> SCONN288_H44441003_PIP-SCONN,HA   I138 @BASEBOARD_FAB2_LIB.BASEBOARD_FAB2(SCH_1):PAGE46
  J6U1  184 VSS<29> SCONN288_H44441003_PIP-SCONN,HA   I138 @BASEBOARD_FAB2_LIB.BASEBOARD_FAB2(SCH_1):PAGE46
  J6U1  182 VSS<30> SCONN288_H44441003_PIP-SCONN,HA   I138 @BASEBOARD_FAB2_LIB.BASEBOARD_FAB2(SCH_1):PAGE46
  J6U1  180 VSS<31> SCONN288_H44441003_PIP-SCONN,HA   I138 @BASEBOARD_FAB2_LIB.BASEBOARD_FAB2(SCH_1):PAGE46
  J6U1  178 VSS<32> SCONN288_H44441003_PIP-SCONN,HA   I138 @BASEBOARD_FAB2_LIB.BASEBOARD_FAB2(SCH_1):PAGE46
  J6U1  176 VSS<33> SCONN288_H44441003_PIP-SCONN,HA   I138 @BASEBOARD_FAB2_LIB.BASEBOARD_FAB2(SCH_1):PAGE46
  J6U1  173 VSS<34> SCONN288_H44441003_PIP-SCONN,HA   I138 @BASEBOARD_FAB2_LIB.BASEBOARD_FAB2(SCH_1):PAGE46
  J6U1  171 VSS<35> SCONN288_H44441003_PIP-SCONN,HA   I138 @BASEBOARD_FAB2_LIB.BASEBOARD_FAB2(SCH_1):PAGE46
  J6U1  169 VSS<36> SCONN288_H44441003_PIP-SCONN,HA   I138 @BASEBOARD_FAB2_LIB.BASEBOARD_FAB2(SCH_1):PAGE46
  J6U1  167 VSS<37> SCONN288_H44441003_PIP-SCONN,HA   I138 @BASEBOARD_FAB2_LIB.BASEBOARD_FAB2(SCH_1):PAGE46
  J6U1  165 VSS<38> SCONN288_H44441003_PIP-SCONN,HA   I138 @BASEBOARD_FAB2_LIB.BASEBOARD_FAB2(SCH_1):PAGE46
  J6U1  162 VSS<39> SCONN288_H44441003_PIP-SCONN,HA   I138 @BASEBOARD_FAB2_LIB.BASEBOARD_FAB2(SCH_1):PAGE46
  J6U1  160 VSS<40> SCONN288_H44441003_PIP-SCONN,HA   I138 @BASEBOARD_FAB2_LIB.BASEBOARD_FAB2(SCH_1):PAGE46
  J6U1  158 VSS<41> SCONN288_H44441003_PIP-SCONN,HA   I138 @BASEBOARD_FAB2_LIB.BASEBOARD_FAB2(SCH_1):PAGE46
  J6U1  156 VSS<42> SCONN288_H44441003_PIP-SCONN,HA   I138 @BASEBOARD_FAB2_LIB.BASEBOARD_FAB2(SCH_1):PAGE46
  J6U1  154 VSS<43> SCONN288_H44441003_PIP-SCONN,HA   I138 @BASEBOARD_FAB2_LIB.BASEBOARD_FAB2(SCH_1):PAGE46
  J6U1  151 VSS<44> SCONN288_H44441003_PIP-SCONN,HA   I138 @BASEBOARD_FAB2_LIB.BASEBOARD_FAB2(SCH_1):PAGE46
  J6U1  149 VSS<45> SCONN288_H44441003_PIP-SCONN,HA   I138 @BASEBOARD_FAB2_LIB.BASEBOARD_FAB2(SCH_1):PAGE46
  J6U1  147 VSS<46> SCONN288_H44441003_PIP-SCONN,HA   I138 @BASEBOARD_FAB2_LIB.BASEBOARD_FAB2(SCH_1):PAGE46
  J6U1  138 VSS<47> SCONN288_H44441003_PIP-SCONN,HA   I138 @BASEBOARD_FAB2_LIB.BASEBOARD_FAB2(SCH_1):PAGE46
  J6U1  136 VSS<48> SCONN288_H44441003_PIP-SCONN,HA   I138 @BASEBOARD_FAB2_LIB.BASEBOARD_FAB2(SCH_1):PAGE46
  J6U1  134 VSS<49> SCONN288_H44441003_PIP-SCONN,HA   I138 @BASEBOARD_FAB2_LIB.BASEBOARD_FAB2(SCH_1):PAGE46
  J6U1  131 VSS<50> SCONN288_H44441003_PIP-SCONN,HA   I138 @BASEBOARD_FAB2_LIB.BASEBOARD_FAB2(SCH_1):PAGE46
  J6U1  129 VSS<51> SCONN288_H44441003_PIP-SCONN,HA   I138 @BASEBOARD_FAB2_LIB.BASEBOARD_FAB2(SCH_1):PAGE46
  J6U1  127 VSS<52> SCONN288_H44441003_PIP-SCONN,HA   I138 @BASEBOARD_FAB2_LIB.BASEBOARD_FAB2(SCH_1):PAGE46
  J6U1  125 VSS<53> SCONN288_H44441003_PIP-SCONN,HA   I138 @BASEBOARD_FAB2_LIB.BASEBOARD_FAB2(SCH_1):PAGE46
  J6U1  123 VSS<54> SCONN288_H44441003_PIP-SCONN,HA   I138 @BASEBOARD_FAB2_LIB.BASEBOARD_FAB2(SCH_1):PAGE46
  J6U1  120 VSS<55> SCONN288_H44441003_PIP-SCONN,HA   I138 @BASEBOARD_FAB2_LIB.BASEBOARD_FAB2(SCH_1):PAGE46
  J6U1  118 VSS<56> SCONN288_H44441003_PIP-SCONN,HA   I138 @BASEBOARD_FAB2_LIB.BASEBOARD_FAB2(SCH_1):PAGE46
  J6U1  116 VSS<57> SCONN288_H44441003_PIP-SCONN,HA   I138 @BASEBOARD_FAB2_LIB.BASEBOARD_FAB2(SCH_1):PAGE46
  J6U1  114 VSS<58> SCONN288_H44441003_PIP-SCONN,HA   I138 @BASEBOARD_FAB2_LIB.BASEBOARD_FAB2(SCH_1):PAGE46
  J6U1  112 VSS<59> SCONN288_H44441003_PIP-SCONN,HA   I138 @BASEBOARD_FAB2_LIB.BASEBOARD_FAB2(SCH_1):PAGE46
  J6U1  109 VSS<60> SCONN288_H44441003_PIP-SCONN,HA   I138 @BASEBOARD_FAB2_LIB.BASEBOARD_FAB2(SCH_1):PAGE46
  J6U1  107 VSS<61> SCONN288_H44441003_PIP-SCONN,HA   I138 @BASEBOARD_FAB2_LIB.BASEBOARD_FAB2(SCH_1):PAGE46
  J6U1  105 VSS<62> SCONN288_H44441003_PIP-SCONN,HA   I138 @BASEBOARD_FAB2_LIB.BASEBOARD_FAB2(SCH_1):PAGE46
  J6U1  103 VSS<63> SCONN288_H44441003_PIP-SCONN,HA   I138 @BASEBOARD_FAB2_LIB.BASEBOARD_FAB2(SCH_1):PAGE46
  J6U1  101 VSS<64> SCONN288_H44441003_PIP-SCONN,HA   I138 @BASEBOARD_FAB2_LIB.BASEBOARD_FAB2(SCH_1):PAGE46
  J6U1   98 VSS<65> SCONN288_H44441003_PIP-SCONN,HA   I138 @BASEBOARD_FAB2_LIB.BASEBOARD_FAB2(SCH_1):PAGE46
  J6U1   96 VSS<66> SCONN288_H44441003_PIP-SCONN,HA   I138 @BASEBOARD_FAB2_LIB.BASEBOARD_FAB2(SCH_1):PAGE46
  J6U1   94 VSS<67> SCONN288_H44441003_PIP-SCONN,HA   I138 @BASEBOARD_FAB2_LIB.BASEBOARD_FAB2(SCH_1):PAGE46
  J6U1   57 VSS<68> SCONN288_H44441003_PIP-SCONN,HA   I138 @BASEBOARD_FAB2_LIB.BASEBOARD_FAB2(SCH_1):PAGE46
  J6U1   55 VSS<69> SCONN288_H44441003_PIP-SCONN,HA   I138 @BASEBOARD_FAB2_LIB.BASEBOARD_FAB2(SCH_1):PAGE46
  J6U1   53 VSS<70> SCONN288_H44441003_PIP-SCONN,HA   I138 @BASEBOARD_FAB2_LIB.BASEBOARD_FAB2(SCH_1):PAGE46
  J6U1   50 VSS<71> SCONN288_H44441003_PIP-SCONN,HA   I138 @BASEBOARD_FAB2_LIB.BASEBOARD_FAB2(SCH_1):PAGE46
  J6U1   48 VSS<72> SCONN288_H44441003_PIP-SCONN,HA   I138 @BASEBOARD_FAB2_LIB.BASEBOARD_FAB2(SCH_1):PAGE46
  J6U1   46 VSS<73> SCONN288_H44441003_PIP-SCONN,HA   I138 @BASEBOARD_FAB2_LIB.BASEBOARD_FAB2(SCH_1):PAGE46
  J6U1   44 VSS<74> SCONN288_H44441003_PIP-SCONN,HA   I138 @BASEBOARD_FAB2_LIB.BASEBOARD_FAB2(SCH_1):PAGE46
  J6U1   42 VSS<75> SCONN288_H44441003_PIP-SCONN,HA   I138 @BASEBOARD_FAB2_LIB.BASEBOARD_FAB2(SCH_1):PAGE46
  J6U1   39 VSS<76> SCONN288_H44441003_PIP-SCONN,HA   I138 @BASEBOARD_FAB2_LIB.BASEBOARD_FAB2(SCH_1):PAGE46
  J6U1   37 VSS<77> SCONN288_H44441003_PIP-SCONN,HA   I138 @BASEBOARD_FAB2_LIB.BASEBOARD_FAB2(SCH_1):PAGE46
  J6U1   35 VSS<78> SCONN288_H44441003_PIP-SCONN,HA   I138 @BASEBOARD_FAB2_LIB.BASEBOARD_FAB2(SCH_1):PAGE46
  J6U1   33 VSS<79> SCONN288_H44441003_PIP-SCONN,HA   I138 @BASEBOARD_FAB2_LIB.BASEBOARD_FAB2(SCH_1):PAGE46
  J6U1   31 VSS<80> SCONN288_H44441003_PIP-SCONN,HA   I138 @BASEBOARD_FAB2_LIB.BASEBOARD_FAB2(SCH_1):PAGE46
  J6U1   28 VSS<81> SCONN288_H44441003_PIP-SCONN,HA   I138 @BASEBOARD_FAB2_LIB.BASEBOARD_FAB2(SCH_1):PAGE46
  J6U1   26 VSS<82> SCONN288_H44441003_PIP-SCONN,HA   I138 @BASEBOARD_FAB2_LIB.BASEBOARD_FAB2(SCH_1):PAGE46
  J6U1   24 VSS<83> SCONN288_H44441003_PIP-SCONN,HA   I138 @BASEBOARD_FAB2_LIB.BASEBOARD_FAB2(SCH_1):PAGE46
  J6U1   22 VSS<84> SCONN288_H44441003_PIP-SCONN,HA   I138 @BASEBOARD_FAB2_LIB.BASEBOARD_FAB2(SCH_1):PAGE46
  J6U1   20 VSS<85> SCONN288_H44441003_PIP-SCONN,HA   I138 @BASEBOARD_FAB2_LIB.BASEBOARD_FAB2(SCH_1):PAGE46
  J6U1   17 VSS<86> SCONN288_H44441003_PIP-SCONN,HA   I138 @BASEBOARD_FAB2_LIB.BASEBOARD_FAB2(SCH_1):PAGE46
  J6U1   15 VSS<87> SCONN288_H44441003_PIP-SCONN,HA   I138 @BASEBOARD_FAB2_LIB.BASEBOARD_FAB2(SCH_1):PAGE46
  J6U1   13 VSS<88> SCONN288_H44441003_PIP-SCONN,HA   I138 @BASEBOARD_FAB2_LIB.BASEBOARD_FAB2(SCH_1):PAGE46
  J6U1   11 VSS<89> SCONN288_H44441003_PIP-SCONN,HA   I138 @BASEBOARD_FAB2_LIB.BASEBOARD_FAB2(SCH_1):PAGE46
  J6U1    9 VSS<90> SCONN288_H44441003_PIP-SCONN,HA   I138 @BASEBOARD_FAB2_LIB.BASEBOARD_FAB2(SCH_1):PAGE46
  J6U1    6 VSS<91> SCONN288_H44441003_PIP-SCONN,HA   I138 @BASEBOARD_FAB2_LIB.BASEBOARD_FAB2(SCH_1):PAGE46
  J6U1    4 VSS<92> SCONN288_H44441003_PIP-SCONN,HA   I138 @BASEBOARD_FAB2_LIB.BASEBOARD_FAB2(SCH_1):PAGE46
  J6U1    2 VSS<93> SCONN288_H44441003_PIP-SCONN,HA   I138 @BASEBOARD_FAB2_LIB.BASEBOARD_FAB2(SCH_1):PAGE46
  J4G3  283 VSS<0> SCONN288_H44441004_PIP-SCONN,HA    I43 @BASEBOARD_FAB2_LIB.BASEBOARD_FAB2(SCH_1):PAGE47
  J4G3  281 VSS<1> SCONN288_H44441004_PIP-SCONN,HA    I43 @BASEBOARD_FAB2_LIB.BASEBOARD_FAB2(SCH_1):PAGE47
  J4G3  279 VSS<2> SCONN288_H44441004_PIP-SCONN,HA    I43 @BASEBOARD_FAB2_LIB.BASEBOARD_FAB2(SCH_1):PAGE47
  J4G3  276 VSS<3> SCONN288_H44441004_PIP-SCONN,HA    I43 @BASEBOARD_FAB2_LIB.BASEBOARD_FAB2(SCH_1):PAGE47
  J4G3  274 VSS<4> SCONN288_H44441004_PIP-SCONN,HA    I43 @BASEBOARD_FAB2_LIB.BASEBOARD_FAB2(SCH_1):PAGE47
  J4G3  272 VSS<5> SCONN288_H44441004_PIP-SCONN,HA    I43 @BASEBOARD_FAB2_LIB.BASEBOARD_FAB2(SCH_1):PAGE47
  J4G3  270 VSS<6> SCONN288_H44441004_PIP-SCONN,HA    I43 @BASEBOARD_FAB2_LIB.BASEBOARD_FAB2(SCH_1):PAGE47
  J4G3  268 VSS<7> SCONN288_H44441004_PIP-SCONN,HA    I43 @BASEBOARD_FAB2_LIB.BASEBOARD_FAB2(SCH_1):PAGE47
  J4G3  265 VSS<8> SCONN288_H44441004_PIP-SCONN,HA    I43 @BASEBOARD_FAB2_LIB.BASEBOARD_FAB2(SCH_1):PAGE47
  J4G3  263 VSS<9> SCONN288_H44441004_PIP-SCONN,HA    I43 @BASEBOARD_FAB2_LIB.BASEBOARD_FAB2(SCH_1):PAGE47
  J4G3  261 VSS<10> SCONN288_H44441004_PIP-SCONN,HA    I43 @BASEBOARD_FAB2_LIB.BASEBOARD_FAB2(SCH_1):PAGE47
  J4G3  259 VSS<11> SCONN288_H44441004_PIP-SCONN,HA    I43 @BASEBOARD_FAB2_LIB.BASEBOARD_FAB2(SCH_1):PAGE47
  J4G3  257 VSS<12> SCONN288_H44441004_PIP-SCONN,HA    I43 @BASEBOARD_FAB2_LIB.BASEBOARD_FAB2(SCH_1):PAGE47
  J4G3  254 VSS<13> SCONN288_H44441004_PIP-SCONN,HA    I43 @BASEBOARD_FAB2_LIB.BASEBOARD_FAB2(SCH_1):PAGE47
  J4G3  252 VSS<14> SCONN288_H44441004_PIP-SCONN,HA    I43 @BASEBOARD_FAB2_LIB.BASEBOARD_FAB2(SCH_1):PAGE47
  J4G3  250 VSS<15> SCONN288_H44441004_PIP-SCONN,HA    I43 @BASEBOARD_FAB2_LIB.BASEBOARD_FAB2(SCH_1):PAGE47
  J4G3  248 VSS<16> SCONN288_H44441004_PIP-SCONN,HA    I43 @BASEBOARD_FAB2_LIB.BASEBOARD_FAB2(SCH_1):PAGE47
  J4G3  246 VSS<17> SCONN288_H44441004_PIP-SCONN,HA    I43 @BASEBOARD_FAB2_LIB.BASEBOARD_FAB2(SCH_1):PAGE47
  J4G3  243 VSS<18> SCONN288_H44441004_PIP-SCONN,HA    I43 @BASEBOARD_FAB2_LIB.BASEBOARD_FAB2(SCH_1):PAGE47
  J4G3  241 VSS<19> SCONN288_H44441004_PIP-SCONN,HA    I43 @BASEBOARD_FAB2_LIB.BASEBOARD_FAB2(SCH_1):PAGE47
  J4G3  239 VSS<20> SCONN288_H44441004_PIP-SCONN,HA    I43 @BASEBOARD_FAB2_LIB.BASEBOARD_FAB2(SCH_1):PAGE47
  J4G3  202 VSS<21> SCONN288_H44441004_PIP-SCONN,HA    I43 @BASEBOARD_FAB2_LIB.BASEBOARD_FAB2(SCH_1):PAGE47
  J4G3  200 VSS<22> SCONN288_H44441004_PIP-SCONN,HA    I43 @BASEBOARD_FAB2_LIB.BASEBOARD_FAB2(SCH_1):PAGE47
  J4G3  198 VSS<23> SCONN288_H44441004_PIP-SCONN,HA    I43 @BASEBOARD_FAB2_LIB.BASEBOARD_FAB2(SCH_1):PAGE47
  J4G3  195 VSS<24> SCONN288_H44441004_PIP-SCONN,HA    I43 @BASEBOARD_FAB2_LIB.BASEBOARD_FAB2(SCH_1):PAGE47
  J4G3  193 VSS<25> SCONN288_H44441004_PIP-SCONN,HA    I43 @BASEBOARD_FAB2_LIB.BASEBOARD_FAB2(SCH_1):PAGE47
  J4G3  191 VSS<26> SCONN288_H44441004_PIP-SCONN,HA    I43 @BASEBOARD_FAB2_LIB.BASEBOARD_FAB2(SCH_1):PAGE47
  J4G3  189 VSS<27> SCONN288_H44441004_PIP-SCONN,HA    I43 @BASEBOARD_FAB2_LIB.BASEBOARD_FAB2(SCH_1):PAGE47
  J4G3  187 VSS<28> SCONN288_H44441004_PIP-SCONN,HA    I43 @BASEBOARD_FAB2_LIB.BASEBOARD_FAB2(SCH_1):PAGE47
  J4G3  184 VSS<29> SCONN288_H44441004_PIP-SCONN,HA    I43 @BASEBOARD_FAB2_LIB.BASEBOARD_FAB2(SCH_1):PAGE47
  J4G3  182 VSS<30> SCONN288_H44441004_PIP-SCONN,HA    I43 @BASEBOARD_FAB2_LIB.BASEBOARD_FAB2(SCH_1):PAGE47
  J4G3  180 VSS<31> SCONN288_H44441004_PIP-SCONN,HA    I43 @BASEBOARD_FAB2_LIB.BASEBOARD_FAB2(SCH_1):PAGE47
  J4G3  178 VSS<32> SCONN288_H44441004_PIP-SCONN,HA    I43 @BASEBOARD_FAB2_LIB.BASEBOARD_FAB2(SCH_1):PAGE47
  J4G3  176 VSS<33> SCONN288_H44441004_PIP-SCONN,HA    I43 @BASEBOARD_FAB2_LIB.BASEBOARD_FAB2(SCH_1):PAGE47
  J4G3  173 VSS<34> SCONN288_H44441004_PIP-SCONN,HA    I43 @BASEBOARD_FAB2_LIB.BASEBOARD_FAB2(SCH_1):PAGE47
  J4G3  171 VSS<35> SCONN288_H44441004_PIP-SCONN,HA    I43 @BASEBOARD_FAB2_LIB.BASEBOARD_FAB2(SCH_1):PAGE47
  J4G3  169 VSS<36> SCONN288_H44441004_PIP-SCONN,HA    I43 @BASEBOARD_FAB2_LIB.BASEBOARD_FAB2(SCH_1):PAGE47
  J4G3  167 VSS<37> SCONN288_H44441004_PIP-SCONN,HA    I43 @BASEBOARD_FAB2_LIB.BASEBOARD_FAB2(SCH_1):PAGE47
  J4G3  165 VSS<38> SCONN288_H44441004_PIP-SCONN,HA    I43 @BASEBOARD_FAB2_LIB.BASEBOARD_FAB2(SCH_1):PAGE47
  J4G3  162 VSS<39> SCONN288_H44441004_PIP-SCONN,HA    I43 @BASEBOARD_FAB2_LIB.BASEBOARD_FAB2(SCH_1):PAGE47
  J4G3  160 VSS<40> SCONN288_H44441004_PIP-SCONN,HA    I43 @BASEBOARD_FAB2_LIB.BASEBOARD_FAB2(SCH_1):PAGE47
  J4G3  158 VSS<41> SCONN288_H44441004_PIP-SCONN,HA    I43 @BASEBOARD_FAB2_LIB.BASEBOARD_FAB2(SCH_1):PAGE47
  J4G3  156 VSS<42> SCONN288_H44441004_PIP-SCONN,HA    I43 @BASEBOARD_FAB2_LIB.BASEBOARD_FAB2(SCH_1):PAGE47
  J4G3  154 VSS<43> SCONN288_H44441004_PIP-SCONN,HA    I43 @BASEBOARD_FAB2_LIB.BASEBOARD_FAB2(SCH_1):PAGE47
  J4G3  151 VSS<44> SCONN288_H44441004_PIP-SCONN,HA    I43 @BASEBOARD_FAB2_LIB.BASEBOARD_FAB2(SCH_1):PAGE47
  J4G3  149 VSS<45> SCONN288_H44441004_PIP-SCONN,HA    I43 @BASEBOARD_FAB2_LIB.BASEBOARD_FAB2(SCH_1):PAGE47
  J4G3  147 VSS<46> SCONN288_H44441004_PIP-SCONN,HA    I43 @BASEBOARD_FAB2_LIB.BASEBOARD_FAB2(SCH_1):PAGE47
  J4G3  138 VSS<47> SCONN288_H44441004_PIP-SCONN,HA    I43 @BASEBOARD_FAB2_LIB.BASEBOARD_FAB2(SCH_1):PAGE47
  J4G3  136 VSS<48> SCONN288_H44441004_PIP-SCONN,HA    I43 @BASEBOARD_FAB2_LIB.BASEBOARD_FAB2(SCH_1):PAGE47
  J4G3  134 VSS<49> SCONN288_H44441004_PIP-SCONN,HA    I43 @BASEBOARD_FAB2_LIB.BASEBOARD_FAB2(SCH_1):PAGE47
  J4G3  131 VSS<50> SCONN288_H44441004_PIP-SCONN,HA    I43 @BASEBOARD_FAB2_LIB.BASEBOARD_FAB2(SCH_1):PAGE47
  J4G3  129 VSS<51> SCONN288_H44441004_PIP-SCONN,HA    I43 @BASEBOARD_FAB2_LIB.BASEBOARD_FAB2(SCH_1):PAGE47
  J4G3  127 VSS<52> SCONN288_H44441004_PIP-SCONN,HA    I43 @BASEBOARD_FAB2_LIB.BASEBOARD_FAB2(SCH_1):PAGE47
  J4G3  125 VSS<53> SCONN288_H44441004_PIP-SCONN,HA    I43 @BASEBOARD_FAB2_LIB.BASEBOARD_FAB2(SCH_1):PAGE47
  J4G3  123 VSS<54> SCONN288_H44441004_PIP-SCONN,HA    I43 @BASEBOARD_FAB2_LIB.BASEBOARD_FAB2(SCH_1):PAGE47
  J4G3  120 VSS<55> SCONN288_H44441004_PIP-SCONN,HA    I43 @BASEBOARD_FAB2_LIB.BASEBOARD_FAB2(SCH_1):PAGE47
  J4G3  118 VSS<56> SCONN288_H44441004_PIP-SCONN,HA    I43 @BASEBOARD_FAB2_LIB.BASEBOARD_FAB2(SCH_1):PAGE47
  J4G3  116 VSS<57> SCONN288_H44441004_PIP-SCONN,HA    I43 @BASEBOARD_FAB2_LIB.BASEBOARD_FAB2(SCH_1):PAGE47
  J4G3  114 VSS<58> SCONN288_H44441004_PIP-SCONN,HA    I43 @BASEBOARD_FAB2_LIB.BASEBOARD_FAB2(SCH_1):PAGE47
  J4G3  112 VSS<59> SCONN288_H44441004_PIP-SCONN,HA    I43 @BASEBOARD_FAB2_LIB.BASEBOARD_FAB2(SCH_1):PAGE47
  J4G3  109 VSS<60> SCONN288_H44441004_PIP-SCONN,HA    I43 @BASEBOARD_FAB2_LIB.BASEBOARD_FAB2(SCH_1):PAGE47
  J4G3  107 VSS<61> SCONN288_H44441004_PIP-SCONN,HA    I43 @BASEBOARD_FAB2_LIB.BASEBOARD_FAB2(SCH_1):PAGE47
  J4G3  105 VSS<62> SCONN288_H44441004_PIP-SCONN,HA    I43 @BASEBOARD_FAB2_LIB.BASEBOARD_FAB2(SCH_1):PAGE47
  J4G3  103 VSS<63> SCONN288_H44441004_PIP-SCONN,HA    I43 @BASEBOARD_FAB2_LIB.BASEBOARD_FAB2(SCH_1):PAGE47
  J4G3  101 VSS<64> SCONN288_H44441004_PIP-SCONN,HA    I43 @BASEBOARD_FAB2_LIB.BASEBOARD_FAB2(SCH_1):PAGE47
  J4G3   98 VSS<65> SCONN288_H44441004_PIP-SCONN,HA    I43 @BASEBOARD_FAB2_LIB.BASEBOARD_FAB2(SCH_1):PAGE47
  J4G3   96 VSS<66> SCONN288_H44441004_PIP-SCONN,HA    I43 @BASEBOARD_FAB2_LIB.BASEBOARD_FAB2(SCH_1):PAGE47
  J4G3   94 VSS<67> SCONN288_H44441004_PIP-SCONN,HA    I43 @BASEBOARD_FAB2_LIB.BASEBOARD_FAB2(SCH_1):PAGE47
  J4G3   57 VSS<68> SCONN288_H44441004_PIP-SCONN,HA    I43 @BASEBOARD_FAB2_LIB.BASEBOARD_FAB2(SCH_1):PAGE47
  J4G3   55 VSS<69> SCONN288_H44441004_PIP-SCONN,HA    I43 @BASEBOARD_FAB2_LIB.BASEBOARD_FAB2(SCH_1):PAGE47
  J4G3   53 VSS<70> SCONN288_H44441004_PIP-SCONN,HA    I43 @BASEBOARD_FAB2_LIB.BASEBOARD_FAB2(SCH_1):PAGE47
  J4G3   50 VSS<71> SCONN288_H44441004_PIP-SCONN,HA    I43 @BASEBOARD_FAB2_LIB.BASEBOARD_FAB2(SCH_1):PAGE47
  J4G3   48 VSS<72> SCONN288_H44441004_PIP-SCONN,HA    I43 @BASEBOARD_FAB2_LIB.BASEBOARD_FAB2(SCH_1):PAGE47
  J4G3   46 VSS<73> SCONN288_H44441004_PIP-SCONN,HA    I43 @BASEBOARD_FAB2_LIB.BASEBOARD_FAB2(SCH_1):PAGE47
  J4G3   44 VSS<74> SCONN288_H44441004_PIP-SCONN,HA    I43 @BASEBOARD_FAB2_LIB.BASEBOARD_FAB2(SCH_1):PAGE47
  J4G3   42 VSS<75> SCONN288_H44441004_PIP-SCONN,HA    I43 @BASEBOARD_FAB2_LIB.BASEBOARD_FAB2(SCH_1):PAGE47
  J4G3   39 VSS<76> SCONN288_H44441004_PIP-SCONN,HA    I43 @BASEBOARD_FAB2_LIB.BASEBOARD_FAB2(SCH_1):PAGE47
  J4G3   37 VSS<77> SCONN288_H44441004_PIP-SCONN,HA    I43 @BASEBOARD_FAB2_LIB.BASEBOARD_FAB2(SCH_1):PAGE47
  J4G3   35 VSS<78> SCONN288_H44441004_PIP-SCONN,HA    I43 @BASEBOARD_FAB2_LIB.BASEBOARD_FAB2(SCH_1):PAGE47
  J4G3   33 VSS<79> SCONN288_H44441004_PIP-SCONN,HA    I43 @BASEBOARD_FAB2_LIB.BASEBOARD_FAB2(SCH_1):PAGE47
  J4G3   31 VSS<80> SCONN288_H44441004_PIP-SCONN,HA    I43 @BASEBOARD_FAB2_LIB.BASEBOARD_FAB2(SCH_1):PAGE47
  J4G3   28 VSS<81> SCONN288_H44441004_PIP-SCONN,HA    I43 @BASEBOARD_FAB2_LIB.BASEBOARD_FAB2(SCH_1):PAGE47
  J4G3   26 VSS<82> SCONN288_H44441004_PIP-SCONN,HA    I43 @BASEBOARD_FAB2_LIB.BASEBOARD_FAB2(SCH_1):PAGE47
  J4G3   24 VSS<83> SCONN288_H44441004_PIP-SCONN,HA    I43 @BASEBOARD_FAB2_LIB.BASEBOARD_FAB2(SCH_1):PAGE47
  J4G3   22 VSS<84> SCONN288_H44441004_PIP-SCONN,HA    I43 @BASEBOARD_FAB2_LIB.BASEBOARD_FAB2(SCH_1):PAGE47
  J4G3   20 VSS<85> SCONN288_H44441004_PIP-SCONN,HA    I43 @BASEBOARD_FAB2_LIB.BASEBOARD_FAB2(SCH_1):PAGE47
  J4G3   17 VSS<86> SCONN288_H44441004_PIP-SCONN,HA    I43 @BASEBOARD_FAB2_LIB.BASEBOARD_FAB2(SCH_1):PAGE47
  J4G3   15 VSS<87> SCONN288_H44441004_PIP-SCONN,HA    I43 @BASEBOARD_FAB2_LIB.BASEBOARD_FAB2(SCH_1):PAGE47
  J4G3   13 VSS<88> SCONN288_H44441004_PIP-SCONN,HA    I43 @BASEBOARD_FAB2_LIB.BASEBOARD_FAB2(SCH_1):PAGE47
  J4G3   11 VSS<89> SCONN288_H44441004_PIP-SCONN,HA    I43 @BASEBOARD_FAB2_LIB.BASEBOARD_FAB2(SCH_1):PAGE47
  J4G3    9 VSS<90> SCONN288_H44441004_PIP-SCONN,HA    I43 @BASEBOARD_FAB2_LIB.BASEBOARD_FAB2(SCH_1):PAGE47
  J4G3    6 VSS<91> SCONN288_H44441004_PIP-SCONN,HA    I43 @BASEBOARD_FAB2_LIB.BASEBOARD_FAB2(SCH_1):PAGE47
  J4G3    4 VSS<92> SCONN288_H44441004_PIP-SCONN,HA    I43 @BASEBOARD_FAB2_LIB.BASEBOARD_FAB2(SCH_1):PAGE47
  J4G3    2 VSS<93> SCONN288_H44441004_PIP-SCONN,HA    I43 @BASEBOARD_FAB2_LIB.BASEBOARD_FAB2(SCH_1):PAGE47
  J4G3  139  SA<0> SCONN288_H44441004_PIP-SCONN,HA   I111 @BASEBOARD_FAB2_LIB.BASEBOARD_FAB2(SCH_1):PAGE47
  J4G3  140  SA<1> SCONN288_H44441004_PIP-SCONN,HA   I111 @BASEBOARD_FAB2_LIB.BASEBOARD_FAB2(SCH_1):PAGE47
 C4G19    2      B CAP_A_0402V-0.01UF,25V,10%,X7RA   I188 @BASEBOARD_FAB2_LIB.BASEBOARD_FAB2(SCH_1):PAGE47
  J6U2  283 VSS<0> SCONN288_H44441003_PIP-SCONN,HA    I43 @BASEBOARD_FAB2_LIB.BASEBOARD_FAB2(SCH_1):PAGE48
  J6U2  281 VSS<1> SCONN288_H44441003_PIP-SCONN,HA    I43 @BASEBOARD_FAB2_LIB.BASEBOARD_FAB2(SCH_1):PAGE48
  J6U2  279 VSS<2> SCONN288_H44441003_PIP-SCONN,HA    I43 @BASEBOARD_FAB2_LIB.BASEBOARD_FAB2(SCH_1):PAGE48
  J6U2  276 VSS<3> SCONN288_H44441003_PIP-SCONN,HA    I43 @BASEBOARD_FAB2_LIB.BASEBOARD_FAB2(SCH_1):PAGE48
  J6U2  274 VSS<4> SCONN288_H44441003_PIP-SCONN,HA    I43 @BASEBOARD_FAB2_LIB.BASEBOARD_FAB2(SCH_1):PAGE48
  J6U2  272 VSS<5> SCONN288_H44441003_PIP-SCONN,HA    I43 @BASEBOARD_FAB2_LIB.BASEBOARD_FAB2(SCH_1):PAGE48
  J6U2  270 VSS<6> SCONN288_H44441003_PIP-SCONN,HA    I43 @BASEBOARD_FAB2_LIB.BASEBOARD_FAB2(SCH_1):PAGE48
  J6U2  268 VSS<7> SCONN288_H44441003_PIP-SCONN,HA    I43 @BASEBOARD_FAB2_LIB.BASEBOARD_FAB2(SCH_1):PAGE48
  J6U2  265 VSS<8> SCONN288_H44441003_PIP-SCONN,HA    I43 @BASEBOARD_FAB2_LIB.BASEBOARD_FAB2(SCH_1):PAGE48
  J6U2  263 VSS<9> SCONN288_H44441003_PIP-SCONN,HA    I43 @BASEBOARD_FAB2_LIB.BASEBOARD_FAB2(SCH_1):PAGE48
  J6U2  261 VSS<10> SCONN288_H44441003_PIP-SCONN,HA    I43 @BASEBOARD_FAB2_LIB.BASEBOARD_FAB2(SCH_1):PAGE48
  J6U2  259 VSS<11> SCONN288_H44441003_PIP-SCONN,HA    I43 @BASEBOARD_FAB2_LIB.BASEBOARD_FAB2(SCH_1):PAGE48
  J6U2  257 VSS<12> SCONN288_H44441003_PIP-SCONN,HA    I43 @BASEBOARD_FAB2_LIB.BASEBOARD_FAB2(SCH_1):PAGE48
  J6U2  254 VSS<13> SCONN288_H44441003_PIP-SCONN,HA    I43 @BASEBOARD_FAB2_LIB.BASEBOARD_FAB2(SCH_1):PAGE48
  J6U2  252 VSS<14> SCONN288_H44441003_PIP-SCONN,HA    I43 @BASEBOARD_FAB2_LIB.BASEBOARD_FAB2(SCH_1):PAGE48
  J6U2  250 VSS<15> SCONN288_H44441003_PIP-SCONN,HA    I43 @BASEBOARD_FAB2_LIB.BASEBOARD_FAB2(SCH_1):PAGE48
  J6U2  248 VSS<16> SCONN288_H44441003_PIP-SCONN,HA    I43 @BASEBOARD_FAB2_LIB.BASEBOARD_FAB2(SCH_1):PAGE48
  J6U2  246 VSS<17> SCONN288_H44441003_PIP-SCONN,HA    I43 @BASEBOARD_FAB2_LIB.BASEBOARD_FAB2(SCH_1):PAGE48
  J6U2  243 VSS<18> SCONN288_H44441003_PIP-SCONN,HA    I43 @BASEBOARD_FAB2_LIB.BASEBOARD_FAB2(SCH_1):PAGE48
  J6U2  241 VSS<19> SCONN288_H44441003_PIP-SCONN,HA    I43 @BASEBOARD_FAB2_LIB.BASEBOARD_FAB2(SCH_1):PAGE48
  J6U2  239 VSS<20> SCONN288_H44441003_PIP-SCONN,HA    I43 @BASEBOARD_FAB2_LIB.BASEBOARD_FAB2(SCH_1):PAGE48
  J6U2  202 VSS<21> SCONN288_H44441003_PIP-SCONN,HA    I43 @BASEBOARD_FAB2_LIB.BASEBOARD_FAB2(SCH_1):PAGE48
  J6U2  200 VSS<22> SCONN288_H44441003_PIP-SCONN,HA    I43 @BASEBOARD_FAB2_LIB.BASEBOARD_FAB2(SCH_1):PAGE48
  J6U2  198 VSS<23> SCONN288_H44441003_PIP-SCONN,HA    I43 @BASEBOARD_FAB2_LIB.BASEBOARD_FAB2(SCH_1):PAGE48
  J6U2  195 VSS<24> SCONN288_H44441003_PIP-SCONN,HA    I43 @BASEBOARD_FAB2_LIB.BASEBOARD_FAB2(SCH_1):PAGE48
  J6U2  193 VSS<25> SCONN288_H44441003_PIP-SCONN,HA    I43 @BASEBOARD_FAB2_LIB.BASEBOARD_FAB2(SCH_1):PAGE48
  J6U2  191 VSS<26> SCONN288_H44441003_PIP-SCONN,HA    I43 @BASEBOARD_FAB2_LIB.BASEBOARD_FAB2(SCH_1):PAGE48
  J6U2  189 VSS<27> SCONN288_H44441003_PIP-SCONN,HA    I43 @BASEBOARD_FAB2_LIB.BASEBOARD_FAB2(SCH_1):PAGE48
  J6U2  187 VSS<28> SCONN288_H44441003_PIP-SCONN,HA    I43 @BASEBOARD_FAB2_LIB.BASEBOARD_FAB2(SCH_1):PAGE48
  J6U2  184 VSS<29> SCONN288_H44441003_PIP-SCONN,HA    I43 @BASEBOARD_FAB2_LIB.BASEBOARD_FAB2(SCH_1):PAGE48
  J6U2  182 VSS<30> SCONN288_H44441003_PIP-SCONN,HA    I43 @BASEBOARD_FAB2_LIB.BASEBOARD_FAB2(SCH_1):PAGE48
  J6U2  180 VSS<31> SCONN288_H44441003_PIP-SCONN,HA    I43 @BASEBOARD_FAB2_LIB.BASEBOARD_FAB2(SCH_1):PAGE48
  J6U2  178 VSS<32> SCONN288_H44441003_PIP-SCONN,HA    I43 @BASEBOARD_FAB2_LIB.BASEBOARD_FAB2(SCH_1):PAGE48
  J6U2  176 VSS<33> SCONN288_H44441003_PIP-SCONN,HA    I43 @BASEBOARD_FAB2_LIB.BASEBOARD_FAB2(SCH_1):PAGE48
  J6U2  173 VSS<34> SCONN288_H44441003_PIP-SCONN,HA    I43 @BASEBOARD_FAB2_LIB.BASEBOARD_FAB2(SCH_1):PAGE48
  J6U2  171 VSS<35> SCONN288_H44441003_PIP-SCONN,HA    I43 @BASEBOARD_FAB2_LIB.BASEBOARD_FAB2(SCH_1):PAGE48
  J6U2  169 VSS<36> SCONN288_H44441003_PIP-SCONN,HA    I43 @BASEBOARD_FAB2_LIB.BASEBOARD_FAB2(SCH_1):PAGE48
  J6U2  167 VSS<37> SCONN288_H44441003_PIP-SCONN,HA    I43 @BASEBOARD_FAB2_LIB.BASEBOARD_FAB2(SCH_1):PAGE48
  J6U2  165 VSS<38> SCONN288_H44441003_PIP-SCONN,HA    I43 @BASEBOARD_FAB2_LIB.BASEBOARD_FAB2(SCH_1):PAGE48
  J6U2  162 VSS<39> SCONN288_H44441003_PIP-SCONN,HA    I43 @BASEBOARD_FAB2_LIB.BASEBOARD_FAB2(SCH_1):PAGE48
  J6U2  160 VSS<40> SCONN288_H44441003_PIP-SCONN,HA    I43 @BASEBOARD_FAB2_LIB.BASEBOARD_FAB2(SCH_1):PAGE48
  J6U2  158 VSS<41> SCONN288_H44441003_PIP-SCONN,HA    I43 @BASEBOARD_FAB2_LIB.BASEBOARD_FAB2(SCH_1):PAGE48
  J6U2  156 VSS<42> SCONN288_H44441003_PIP-SCONN,HA    I43 @BASEBOARD_FAB2_LIB.BASEBOARD_FAB2(SCH_1):PAGE48
  J6U2  154 VSS<43> SCONN288_H44441003_PIP-SCONN,HA    I43 @BASEBOARD_FAB2_LIB.BASEBOARD_FAB2(SCH_1):PAGE48
  J6U2  151 VSS<44> SCONN288_H44441003_PIP-SCONN,HA    I43 @BASEBOARD_FAB2_LIB.BASEBOARD_FAB2(SCH_1):PAGE48
  J6U2  149 VSS<45> SCONN288_H44441003_PIP-SCONN,HA    I43 @BASEBOARD_FAB2_LIB.BASEBOARD_FAB2(SCH_1):PAGE48
  J6U2  147 VSS<46> SCONN288_H44441003_PIP-SCONN,HA    I43 @BASEBOARD_FAB2_LIB.BASEBOARD_FAB2(SCH_1):PAGE48
  J6U2  138 VSS<47> SCONN288_H44441003_PIP-SCONN,HA    I43 @BASEBOARD_FAB2_LIB.BASEBOARD_FAB2(SCH_1):PAGE48
  J6U2  136 VSS<48> SCONN288_H44441003_PIP-SCONN,HA    I43 @BASEBOARD_FAB2_LIB.BASEBOARD_FAB2(SCH_1):PAGE48
  J6U2  134 VSS<49> SCONN288_H44441003_PIP-SCONN,HA    I43 @BASEBOARD_FAB2_LIB.BASEBOARD_FAB2(SCH_1):PAGE48
  J6U2  131 VSS<50> SCONN288_H44441003_PIP-SCONN,HA    I43 @BASEBOARD_FAB2_LIB.BASEBOARD_FAB2(SCH_1):PAGE48
  J6U2  129 VSS<51> SCONN288_H44441003_PIP-SCONN,HA    I43 @BASEBOARD_FAB2_LIB.BASEBOARD_FAB2(SCH_1):PAGE48
  J6U2  127 VSS<52> SCONN288_H44441003_PIP-SCONN,HA    I43 @BASEBOARD_FAB2_LIB.BASEBOARD_FAB2(SCH_1):PAGE48
  J6U2  125 VSS<53> SCONN288_H44441003_PIP-SCONN,HA    I43 @BASEBOARD_FAB2_LIB.BASEBOARD_FAB2(SCH_1):PAGE48
  J6U2  123 VSS<54> SCONN288_H44441003_PIP-SCONN,HA    I43 @BASEBOARD_FAB2_LIB.BASEBOARD_FAB2(SCH_1):PAGE48
  J6U2  120 VSS<55> SCONN288_H44441003_PIP-SCONN,HA    I43 @BASEBOARD_FAB2_LIB.BASEBOARD_FAB2(SCH_1):PAGE48
  J6U2  118 VSS<56> SCONN288_H44441003_PIP-SCONN,HA    I43 @BASEBOARD_FAB2_LIB.BASEBOARD_FAB2(SCH_1):PAGE48
  J6U2  116 VSS<57> SCONN288_H44441003_PIP-SCONN,HA    I43 @BASEBOARD_FAB2_LIB.BASEBOARD_FAB2(SCH_1):PAGE48
  J6U2  114 VSS<58> SCONN288_H44441003_PIP-SCONN,HA    I43 @BASEBOARD_FAB2_LIB.BASEBOARD_FAB2(SCH_1):PAGE48
  J6U2  112 VSS<59> SCONN288_H44441003_PIP-SCONN,HA    I43 @BASEBOARD_FAB2_LIB.BASEBOARD_FAB2(SCH_1):PAGE48
  J6U2  109 VSS<60> SCONN288_H44441003_PIP-SCONN,HA    I43 @BASEBOARD_FAB2_LIB.BASEBOARD_FAB2(SCH_1):PAGE48
  J6U2  107 VSS<61> SCONN288_H44441003_PIP-SCONN,HA    I43 @BASEBOARD_FAB2_LIB.BASEBOARD_FAB2(SCH_1):PAGE48
  J6U2  105 VSS<62> SCONN288_H44441003_PIP-SCONN,HA    I43 @BASEBOARD_FAB2_LIB.BASEBOARD_FAB2(SCH_1):PAGE48
  J6U2  103 VSS<63> SCONN288_H44441003_PIP-SCONN,HA    I43 @BASEBOARD_FAB2_LIB.BASEBOARD_FAB2(SCH_1):PAGE48
  J6U2  101 VSS<64> SCONN288_H44441003_PIP-SCONN,HA    I43 @BASEBOARD_FAB2_LIB.BASEBOARD_FAB2(SCH_1):PAGE48
  J6U2   98 VSS<65> SCONN288_H44441003_PIP-SCONN,HA    I43 @BASEBOARD_FAB2_LIB.BASEBOARD_FAB2(SCH_1):PAGE48
  J6U2   96 VSS<66> SCONN288_H44441003_PIP-SCONN,HA    I43 @BASEBOARD_FAB2_LIB.BASEBOARD_FAB2(SCH_1):PAGE48
  J6U2   94 VSS<67> SCONN288_H44441003_PIP-SCONN,HA    I43 @BASEBOARD_FAB2_LIB.BASEBOARD_FAB2(SCH_1):PAGE48
  J6U2   57 VSS<68> SCONN288_H44441003_PIP-SCONN,HA    I43 @BASEBOARD_FAB2_LIB.BASEBOARD_FAB2(SCH_1):PAGE48
  J6U2   55 VSS<69> SCONN288_H44441003_PIP-SCONN,HA    I43 @BASEBOARD_FAB2_LIB.BASEBOARD_FAB2(SCH_1):PAGE48
  J6U2   53 VSS<70> SCONN288_H44441003_PIP-SCONN,HA    I43 @BASEBOARD_FAB2_LIB.BASEBOARD_FAB2(SCH_1):PAGE48
  J6U2   50 VSS<71> SCONN288_H44441003_PIP-SCONN,HA    I43 @BASEBOARD_FAB2_LIB.BASEBOARD_FAB2(SCH_1):PAGE48
  J6U2   48 VSS<72> SCONN288_H44441003_PIP-SCONN,HA    I43 @BASEBOARD_FAB2_LIB.BASEBOARD_FAB2(SCH_1):PAGE48
  J6U2   46 VSS<73> SCONN288_H44441003_PIP-SCONN,HA    I43 @BASEBOARD_FAB2_LIB.BASEBOARD_FAB2(SCH_1):PAGE48
  J6U2   44 VSS<74> SCONN288_H44441003_PIP-SCONN,HA    I43 @BASEBOARD_FAB2_LIB.BASEBOARD_FAB2(SCH_1):PAGE48
  J6U2   42 VSS<75> SCONN288_H44441003_PIP-SCONN,HA    I43 @BASEBOARD_FAB2_LIB.BASEBOARD_FAB2(SCH_1):PAGE48
  J6U2   39 VSS<76> SCONN288_H44441003_PIP-SCONN,HA    I43 @BASEBOARD_FAB2_LIB.BASEBOARD_FAB2(SCH_1):PAGE48
  J6U2   37 VSS<77> SCONN288_H44441003_PIP-SCONN,HA    I43 @BASEBOARD_FAB2_LIB.BASEBOARD_FAB2(SCH_1):PAGE48
  J6U2   35 VSS<78> SCONN288_H44441003_PIP-SCONN,HA    I43 @BASEBOARD_FAB2_LIB.BASEBOARD_FAB2(SCH_1):PAGE48
  J6U2   33 VSS<79> SCONN288_H44441003_PIP-SCONN,HA    I43 @BASEBOARD_FAB2_LIB.BASEBOARD_FAB2(SCH_1):PAGE48
  J6U2   31 VSS<80> SCONN288_H44441003_PIP-SCONN,HA    I43 @BASEBOARD_FAB2_LIB.BASEBOARD_FAB2(SCH_1):PAGE48
  J6U2   28 VSS<81> SCONN288_H44441003_PIP-SCONN,HA    I43 @BASEBOARD_FAB2_LIB.BASEBOARD_FAB2(SCH_1):PAGE48
  J6U2   26 VSS<82> SCONN288_H44441003_PIP-SCONN,HA    I43 @BASEBOARD_FAB2_LIB.BASEBOARD_FAB2(SCH_1):PAGE48
  J6U2   24 VSS<83> SCONN288_H44441003_PIP-SCONN,HA    I43 @BASEBOARD_FAB2_LIB.BASEBOARD_FAB2(SCH_1):PAGE48
  J6U2   22 VSS<84> SCONN288_H44441003_PIP-SCONN,HA    I43 @BASEBOARD_FAB2_LIB.BASEBOARD_FAB2(SCH_1):PAGE48
  J6U2   20 VSS<85> SCONN288_H44441003_PIP-SCONN,HA    I43 @BASEBOARD_FAB2_LIB.BASEBOARD_FAB2(SCH_1):PAGE48
  J6U2   17 VSS<86> SCONN288_H44441003_PIP-SCONN,HA    I43 @BASEBOARD_FAB2_LIB.BASEBOARD_FAB2(SCH_1):PAGE48
  J6U2   15 VSS<87> SCONN288_H44441003_PIP-SCONN,HA    I43 @BASEBOARD_FAB2_LIB.BASEBOARD_FAB2(SCH_1):PAGE48
  J6U2   13 VSS<88> SCONN288_H44441003_PIP-SCONN,HA    I43 @BASEBOARD_FAB2_LIB.BASEBOARD_FAB2(SCH_1):PAGE48
  J6U2   11 VSS<89> SCONN288_H44441003_PIP-SCONN,HA    I43 @BASEBOARD_FAB2_LIB.BASEBOARD_FAB2(SCH_1):PAGE48
  J6U2    9 VSS<90> SCONN288_H44441003_PIP-SCONN,HA    I43 @BASEBOARD_FAB2_LIB.BASEBOARD_FAB2(SCH_1):PAGE48
  J6U2    6 VSS<91> SCONN288_H44441003_PIP-SCONN,HA    I43 @BASEBOARD_FAB2_LIB.BASEBOARD_FAB2(SCH_1):PAGE48
  J6U2    4 VSS<92> SCONN288_H44441003_PIP-SCONN,HA    I43 @BASEBOARD_FAB2_LIB.BASEBOARD_FAB2(SCH_1):PAGE48
  J6U2    2 VSS<93> SCONN288_H44441003_PIP-SCONN,HA    I43 @BASEBOARD_FAB2_LIB.BASEBOARD_FAB2(SCH_1):PAGE48
  J6U2  140  SA<1> SCONN288_H44441003_PIP-SCONN,HA   I111 @BASEBOARD_FAB2_LIB.BASEBOARD_FAB2(SCH_1):PAGE48
 C6U17    2      B CAP_A_0402V-0.01UF,25V,10%,X7RA   I176 @BASEBOARD_FAB2_LIB.BASEBOARD_FAB2(SCH_1):PAGE48
  J4B1  283 VSS<0> SCONN288_H44441004_PIP-SCONN,HA    I43 @BASEBOARD_FAB2_LIB.BASEBOARD_FAB2(SCH_1):PAGE49
  J4B1  281 VSS<1> SCONN288_H44441004_PIP-SCONN,HA    I43 @BASEBOARD_FAB2_LIB.BASEBOARD_FAB2(SCH_1):PAGE49
  J4B1  279 VSS<2> SCONN288_H44441004_PIP-SCONN,HA    I43 @BASEBOARD_FAB2_LIB.BASEBOARD_FAB2(SCH_1):PAGE49
  J4B1  276 VSS<3> SCONN288_H44441004_PIP-SCONN,HA    I43 @BASEBOARD_FAB2_LIB.BASEBOARD_FAB2(SCH_1):PAGE49
  J4B1  274 VSS<4> SCONN288_H44441004_PIP-SCONN,HA    I43 @BASEBOARD_FAB2_LIB.BASEBOARD_FAB2(SCH_1):PAGE49
  J4B1  272 VSS<5> SCONN288_H44441004_PIP-SCONN,HA    I43 @BASEBOARD_FAB2_LIB.BASEBOARD_FAB2(SCH_1):PAGE49
  J4B1  270 VSS<6> SCONN288_H44441004_PIP-SCONN,HA    I43 @BASEBOARD_FAB2_LIB.BASEBOARD_FAB2(SCH_1):PAGE49
  J4B1  268 VSS<7> SCONN288_H44441004_PIP-SCONN,HA    I43 @BASEBOARD_FAB2_LIB.BASEBOARD_FAB2(SCH_1):PAGE49
  J4B1  265 VSS<8> SCONN288_H44441004_PIP-SCONN,HA    I43 @BASEBOARD_FAB2_LIB.BASEBOARD_FAB2(SCH_1):PAGE49
  J4B1  263 VSS<9> SCONN288_H44441004_PIP-SCONN,HA    I43 @BASEBOARD_FAB2_LIB.BASEBOARD_FAB2(SCH_1):PAGE49
  J4B1  261 VSS<10> SCONN288_H44441004_PIP-SCONN,HA    I43 @BASEBOARD_FAB2_LIB.BASEBOARD_FAB2(SCH_1):PAGE49
  J4B1  259 VSS<11> SCONN288_H44441004_PIP-SCONN,HA    I43 @BASEBOARD_FAB2_LIB.BASEBOARD_FAB2(SCH_1):PAGE49
  J4B1  257 VSS<12> SCONN288_H44441004_PIP-SCONN,HA    I43 @BASEBOARD_FAB2_LIB.BASEBOARD_FAB2(SCH_1):PAGE49
  J4B1  254 VSS<13> SCONN288_H44441004_PIP-SCONN,HA    I43 @BASEBOARD_FAB2_LIB.BASEBOARD_FAB2(SCH_1):PAGE49
  J4B1  252 VSS<14> SCONN288_H44441004_PIP-SCONN,HA    I43 @BASEBOARD_FAB2_LIB.BASEBOARD_FAB2(SCH_1):PAGE49
  J4B1  250 VSS<15> SCONN288_H44441004_PIP-SCONN,HA    I43 @BASEBOARD_FAB2_LIB.BASEBOARD_FAB2(SCH_1):PAGE49
  J4B1  248 VSS<16> SCONN288_H44441004_PIP-SCONN,HA    I43 @BASEBOARD_FAB2_LIB.BASEBOARD_FAB2(SCH_1):PAGE49
  J4B1  246 VSS<17> SCONN288_H44441004_PIP-SCONN,HA    I43 @BASEBOARD_FAB2_LIB.BASEBOARD_FAB2(SCH_1):PAGE49
  J4B1  243 VSS<18> SCONN288_H44441004_PIP-SCONN,HA    I43 @BASEBOARD_FAB2_LIB.BASEBOARD_FAB2(SCH_1):PAGE49
  J4B1  241 VSS<19> SCONN288_H44441004_PIP-SCONN,HA    I43 @BASEBOARD_FAB2_LIB.BASEBOARD_FAB2(SCH_1):PAGE49
  J4B1  239 VSS<20> SCONN288_H44441004_PIP-SCONN,HA    I43 @BASEBOARD_FAB2_LIB.BASEBOARD_FAB2(SCH_1):PAGE49
  J4B1  202 VSS<21> SCONN288_H44441004_PIP-SCONN,HA    I43 @BASEBOARD_FAB2_LIB.BASEBOARD_FAB2(SCH_1):PAGE49
  J4B1  200 VSS<22> SCONN288_H44441004_PIP-SCONN,HA    I43 @BASEBOARD_FAB2_LIB.BASEBOARD_FAB2(SCH_1):PAGE49
  J4B1  198 VSS<23> SCONN288_H44441004_PIP-SCONN,HA    I43 @BASEBOARD_FAB2_LIB.BASEBOARD_FAB2(SCH_1):PAGE49
  J4B1  195 VSS<24> SCONN288_H44441004_PIP-SCONN,HA    I43 @BASEBOARD_FAB2_LIB.BASEBOARD_FAB2(SCH_1):PAGE49
  J4B1  193 VSS<25> SCONN288_H44441004_PIP-SCONN,HA    I43 @BASEBOARD_FAB2_LIB.BASEBOARD_FAB2(SCH_1):PAGE49
  J4B1  191 VSS<26> SCONN288_H44441004_PIP-SCONN,HA    I43 @BASEBOARD_FAB2_LIB.BASEBOARD_FAB2(SCH_1):PAGE49
  J4B1  189 VSS<27> SCONN288_H44441004_PIP-SCONN,HA    I43 @BASEBOARD_FAB2_LIB.BASEBOARD_FAB2(SCH_1):PAGE49
  J4B1  187 VSS<28> SCONN288_H44441004_PIP-SCONN,HA    I43 @BASEBOARD_FAB2_LIB.BASEBOARD_FAB2(SCH_1):PAGE49
  J4B1  184 VSS<29> SCONN288_H44441004_PIP-SCONN,HA    I43 @BASEBOARD_FAB2_LIB.BASEBOARD_FAB2(SCH_1):PAGE49
  J4B1  182 VSS<30> SCONN288_H44441004_PIP-SCONN,HA    I43 @BASEBOARD_FAB2_LIB.BASEBOARD_FAB2(SCH_1):PAGE49
  J4B1  180 VSS<31> SCONN288_H44441004_PIP-SCONN,HA    I43 @BASEBOARD_FAB2_LIB.BASEBOARD_FAB2(SCH_1):PAGE49
  J4B1  178 VSS<32> SCONN288_H44441004_PIP-SCONN,HA    I43 @BASEBOARD_FAB2_LIB.BASEBOARD_FAB2(SCH_1):PAGE49
  J4B1  176 VSS<33> SCONN288_H44441004_PIP-SCONN,HA    I43 @BASEBOARD_FAB2_LIB.BASEBOARD_FAB2(SCH_1):PAGE49
  J4B1  173 VSS<34> SCONN288_H44441004_PIP-SCONN,HA    I43 @BASEBOARD_FAB2_LIB.BASEBOARD_FAB2(SCH_1):PAGE49
  J4B1  171 VSS<35> SCONN288_H44441004_PIP-SCONN,HA    I43 @BASEBOARD_FAB2_LIB.BASEBOARD_FAB2(SCH_1):PAGE49
  J4B1  169 VSS<36> SCONN288_H44441004_PIP-SCONN,HA    I43 @BASEBOARD_FAB2_LIB.BASEBOARD_FAB2(SCH_1):PAGE49
  J4B1  167 VSS<37> SCONN288_H44441004_PIP-SCONN,HA    I43 @BASEBOARD_FAB2_LIB.BASEBOARD_FAB2(SCH_1):PAGE49
  J4B1  165 VSS<38> SCONN288_H44441004_PIP-SCONN,HA    I43 @BASEBOARD_FAB2_LIB.BASEBOARD_FAB2(SCH_1):PAGE49
  J4B1  162 VSS<39> SCONN288_H44441004_PIP-SCONN,HA    I43 @BASEBOARD_FAB2_LIB.BASEBOARD_FAB2(SCH_1):PAGE49
  J4B1  160 VSS<40> SCONN288_H44441004_PIP-SCONN,HA    I43 @BASEBOARD_FAB2_LIB.BASEBOARD_FAB2(SCH_1):PAGE49
  J4B1  158 VSS<41> SCONN288_H44441004_PIP-SCONN,HA    I43 @BASEBOARD_FAB2_LIB.BASEBOARD_FAB2(SCH_1):PAGE49
  J4B1  156 VSS<42> SCONN288_H44441004_PIP-SCONN,HA    I43 @BASEBOARD_FAB2_LIB.BASEBOARD_FAB2(SCH_1):PAGE49
  J4B1  154 VSS<43> SCONN288_H44441004_PIP-SCONN,HA    I43 @BASEBOARD_FAB2_LIB.BASEBOARD_FAB2(SCH_1):PAGE49
  J4B1  151 VSS<44> SCONN288_H44441004_PIP-SCONN,HA    I43 @BASEBOARD_FAB2_LIB.BASEBOARD_FAB2(SCH_1):PAGE49
  J4B1  149 VSS<45> SCONN288_H44441004_PIP-SCONN,HA    I43 @BASEBOARD_FAB2_LIB.BASEBOARD_FAB2(SCH_1):PAGE49
  J4B1  147 VSS<46> SCONN288_H44441004_PIP-SCONN,HA    I43 @BASEBOARD_FAB2_LIB.BASEBOARD_FAB2(SCH_1):PAGE49
  J4B1  138 VSS<47> SCONN288_H44441004_PIP-SCONN,HA    I43 @BASEBOARD_FAB2_LIB.BASEBOARD_FAB2(SCH_1):PAGE49
  J4B1  136 VSS<48> SCONN288_H44441004_PIP-SCONN,HA    I43 @BASEBOARD_FAB2_LIB.BASEBOARD_FAB2(SCH_1):PAGE49
  J4B1  134 VSS<49> SCONN288_H44441004_PIP-SCONN,HA    I43 @BASEBOARD_FAB2_LIB.BASEBOARD_FAB2(SCH_1):PAGE49
  J4B1  131 VSS<50> SCONN288_H44441004_PIP-SCONN,HA    I43 @BASEBOARD_FAB2_LIB.BASEBOARD_FAB2(SCH_1):PAGE49
  J4B1  129 VSS<51> SCONN288_H44441004_PIP-SCONN,HA    I43 @BASEBOARD_FAB2_LIB.BASEBOARD_FAB2(SCH_1):PAGE49
  J4B1  127 VSS<52> SCONN288_H44441004_PIP-SCONN,HA    I43 @BASEBOARD_FAB2_LIB.BASEBOARD_FAB2(SCH_1):PAGE49
  J4B1  125 VSS<53> SCONN288_H44441004_PIP-SCONN,HA    I43 @BASEBOARD_FAB2_LIB.BASEBOARD_FAB2(SCH_1):PAGE49
  J4B1  123 VSS<54> SCONN288_H44441004_PIP-SCONN,HA    I43 @BASEBOARD_FAB2_LIB.BASEBOARD_FAB2(SCH_1):PAGE49
  J4B1  120 VSS<55> SCONN288_H44441004_PIP-SCONN,HA    I43 @BASEBOARD_FAB2_LIB.BASEBOARD_FAB2(SCH_1):PAGE49
  J4B1  118 VSS<56> SCONN288_H44441004_PIP-SCONN,HA    I43 @BASEBOARD_FAB2_LIB.BASEBOARD_FAB2(SCH_1):PAGE49
  J4B1  116 VSS<57> SCONN288_H44441004_PIP-SCONN,HA    I43 @BASEBOARD_FAB2_LIB.BASEBOARD_FAB2(SCH_1):PAGE49
  J4B1  114 VSS<58> SCONN288_H44441004_PIP-SCONN,HA    I43 @BASEBOARD_FAB2_LIB.BASEBOARD_FAB2(SCH_1):PAGE49
  J4B1  112 VSS<59> SCONN288_H44441004_PIP-SCONN,HA    I43 @BASEBOARD_FAB2_LIB.BASEBOARD_FAB2(SCH_1):PAGE49
  J4B1  109 VSS<60> SCONN288_H44441004_PIP-SCONN,HA    I43 @BASEBOARD_FAB2_LIB.BASEBOARD_FAB2(SCH_1):PAGE49
  J4B1  107 VSS<61> SCONN288_H44441004_PIP-SCONN,HA    I43 @BASEBOARD_FAB2_LIB.BASEBOARD_FAB2(SCH_1):PAGE49
  J4B1  105 VSS<62> SCONN288_H44441004_PIP-SCONN,HA    I43 @BASEBOARD_FAB2_LIB.BASEBOARD_FAB2(SCH_1):PAGE49
  J4B1  103 VSS<63> SCONN288_H44441004_PIP-SCONN,HA    I43 @BASEBOARD_FAB2_LIB.BASEBOARD_FAB2(SCH_1):PAGE49
  J4B1  101 VSS<64> SCONN288_H44441004_PIP-SCONN,HA    I43 @BASEBOARD_FAB2_LIB.BASEBOARD_FAB2(SCH_1):PAGE49
  J4B1   98 VSS<65> SCONN288_H44441004_PIP-SCONN,HA    I43 @BASEBOARD_FAB2_LIB.BASEBOARD_FAB2(SCH_1):PAGE49
  J4B1   96 VSS<66> SCONN288_H44441004_PIP-SCONN,HA    I43 @BASEBOARD_FAB2_LIB.BASEBOARD_FAB2(SCH_1):PAGE49
  J4B1   94 VSS<67> SCONN288_H44441004_PIP-SCONN,HA    I43 @BASEBOARD_FAB2_LIB.BASEBOARD_FAB2(SCH_1):PAGE49
  J4B1   57 VSS<68> SCONN288_H44441004_PIP-SCONN,HA    I43 @BASEBOARD_FAB2_LIB.BASEBOARD_FAB2(SCH_1):PAGE49
  J4B1   55 VSS<69> SCONN288_H44441004_PIP-SCONN,HA    I43 @BASEBOARD_FAB2_LIB.BASEBOARD_FAB2(SCH_1):PAGE49
  J4B1   53 VSS<70> SCONN288_H44441004_PIP-SCONN,HA    I43 @BASEBOARD_FAB2_LIB.BASEBOARD_FAB2(SCH_1):PAGE49
  J4B1   50 VSS<71> SCONN288_H44441004_PIP-SCONN,HA    I43 @BASEBOARD_FAB2_LIB.BASEBOARD_FAB2(SCH_1):PAGE49
  J4B1   48 VSS<72> SCONN288_H44441004_PIP-SCONN,HA    I43 @BASEBOARD_FAB2_LIB.BASEBOARD_FAB2(SCH_1):PAGE49
  J4B1   46 VSS<73> SCONN288_H44441004_PIP-SCONN,HA    I43 @BASEBOARD_FAB2_LIB.BASEBOARD_FAB2(SCH_1):PAGE49
  J4B1   44 VSS<74> SCONN288_H44441004_PIP-SCONN,HA    I43 @BASEBOARD_FAB2_LIB.BASEBOARD_FAB2(SCH_1):PAGE49
  J4B1   42 VSS<75> SCONN288_H44441004_PIP-SCONN,HA    I43 @BASEBOARD_FAB2_LIB.BASEBOARD_FAB2(SCH_1):PAGE49
  J4B1   39 VSS<76> SCONN288_H44441004_PIP-SCONN,HA    I43 @BASEBOARD_FAB2_LIB.BASEBOARD_FAB2(SCH_1):PAGE49
  J4B1   37 VSS<77> SCONN288_H44441004_PIP-SCONN,HA    I43 @BASEBOARD_FAB2_LIB.BASEBOARD_FAB2(SCH_1):PAGE49
  J4B1   35 VSS<78> SCONN288_H44441004_PIP-SCONN,HA    I43 @BASEBOARD_FAB2_LIB.BASEBOARD_FAB2(SCH_1):PAGE49
  J4B1   33 VSS<79> SCONN288_H44441004_PIP-SCONN,HA    I43 @BASEBOARD_FAB2_LIB.BASEBOARD_FAB2(SCH_1):PAGE49
  J4B1   31 VSS<80> SCONN288_H44441004_PIP-SCONN,HA    I43 @BASEBOARD_FAB2_LIB.BASEBOARD_FAB2(SCH_1):PAGE49
  J4B1   28 VSS<81> SCONN288_H44441004_PIP-SCONN,HA    I43 @BASEBOARD_FAB2_LIB.BASEBOARD_FAB2(SCH_1):PAGE49
  J4B1   26 VSS<82> SCONN288_H44441004_PIP-SCONN,HA    I43 @BASEBOARD_FAB2_LIB.BASEBOARD_FAB2(SCH_1):PAGE49
  J4B1   24 VSS<83> SCONN288_H44441004_PIP-SCONN,HA    I43 @BASEBOARD_FAB2_LIB.BASEBOARD_FAB2(SCH_1):PAGE49
  J4B1   22 VSS<84> SCONN288_H44441004_PIP-SCONN,HA    I43 @BASEBOARD_FAB2_LIB.BASEBOARD_FAB2(SCH_1):PAGE49
  J4B1   20 VSS<85> SCONN288_H44441004_PIP-SCONN,HA    I43 @BASEBOARD_FAB2_LIB.BASEBOARD_FAB2(SCH_1):PAGE49
  J4B1   17 VSS<86> SCONN288_H44441004_PIP-SCONN,HA    I43 @BASEBOARD_FAB2_LIB.BASEBOARD_FAB2(SCH_1):PAGE49
  J4B1   15 VSS<87> SCONN288_H44441004_PIP-SCONN,HA    I43 @BASEBOARD_FAB2_LIB.BASEBOARD_FAB2(SCH_1):PAGE49
  J4B1   13 VSS<88> SCONN288_H44441004_PIP-SCONN,HA    I43 @BASEBOARD_FAB2_LIB.BASEBOARD_FAB2(SCH_1):PAGE49
  J4B1   11 VSS<89> SCONN288_H44441004_PIP-SCONN,HA    I43 @BASEBOARD_FAB2_LIB.BASEBOARD_FAB2(SCH_1):PAGE49
  J4B1    9 VSS<90> SCONN288_H44441004_PIP-SCONN,HA    I43 @BASEBOARD_FAB2_LIB.BASEBOARD_FAB2(SCH_1):PAGE49
  J4B1    6 VSS<91> SCONN288_H44441004_PIP-SCONN,HA    I43 @BASEBOARD_FAB2_LIB.BASEBOARD_FAB2(SCH_1):PAGE49
  J4B1    4 VSS<92> SCONN288_H44441004_PIP-SCONN,HA    I43 @BASEBOARD_FAB2_LIB.BASEBOARD_FAB2(SCH_1):PAGE49
  J4B1    2 VSS<93> SCONN288_H44441004_PIP-SCONN,HA    I43 @BASEBOARD_FAB2_LIB.BASEBOARD_FAB2(SCH_1):PAGE49
  J4B1  139  SA<0> SCONN288_H44441004_PIP-SCONN,HA   I111 @BASEBOARD_FAB2_LIB.BASEBOARD_FAB2(SCH_1):PAGE49
  J4B1  140  SA<1> SCONN288_H44441004_PIP-SCONN,HA   I111 @BASEBOARD_FAB2_LIB.BASEBOARD_FAB2(SCH_1):PAGE49
  J4B1  238  SA<2> SCONN288_H44441004_PIP-SCONN,HA   I111 @BASEBOARD_FAB2_LIB.BASEBOARD_FAB2(SCH_1):PAGE49
 C4B12    2      B CAP_A_0402V-0.01UF,25V,10%,X7RA   I179 @BASEBOARD_FAB2_LIB.BASEBOARD_FAB2(SCH_1):PAGE49
  J6M1  283 VSS<0> SCONN288_H44441003_PIP-SCONN,HA    I44 @BASEBOARD_FAB2_LIB.BASEBOARD_FAB2(SCH_1):PAGE50
  J6M1  281 VSS<1> SCONN288_H44441003_PIP-SCONN,HA    I44 @BASEBOARD_FAB2_LIB.BASEBOARD_FAB2(SCH_1):PAGE50
  J6M1  279 VSS<2> SCONN288_H44441003_PIP-SCONN,HA    I44 @BASEBOARD_FAB2_LIB.BASEBOARD_FAB2(SCH_1):PAGE50
  J6M1  276 VSS<3> SCONN288_H44441003_PIP-SCONN,HA    I44 @BASEBOARD_FAB2_LIB.BASEBOARD_FAB2(SCH_1):PAGE50
  J6M1  274 VSS<4> SCONN288_H44441003_PIP-SCONN,HA    I44 @BASEBOARD_FAB2_LIB.BASEBOARD_FAB2(SCH_1):PAGE50
  J6M1  272 VSS<5> SCONN288_H44441003_PIP-SCONN,HA    I44 @BASEBOARD_FAB2_LIB.BASEBOARD_FAB2(SCH_1):PAGE50
  J6M1  270 VSS<6> SCONN288_H44441003_PIP-SCONN,HA    I44 @BASEBOARD_FAB2_LIB.BASEBOARD_FAB2(SCH_1):PAGE50
  J6M1  268 VSS<7> SCONN288_H44441003_PIP-SCONN,HA    I44 @BASEBOARD_FAB2_LIB.BASEBOARD_FAB2(SCH_1):PAGE50
  J6M1  265 VSS<8> SCONN288_H44441003_PIP-SCONN,HA    I44 @BASEBOARD_FAB2_LIB.BASEBOARD_FAB2(SCH_1):PAGE50
  J6M1  263 VSS<9> SCONN288_H44441003_PIP-SCONN,HA    I44 @BASEBOARD_FAB2_LIB.BASEBOARD_FAB2(SCH_1):PAGE50
  J6M1  261 VSS<10> SCONN288_H44441003_PIP-SCONN,HA    I44 @BASEBOARD_FAB2_LIB.BASEBOARD_FAB2(SCH_1):PAGE50
  J6M1  259 VSS<11> SCONN288_H44441003_PIP-SCONN,HA    I44 @BASEBOARD_FAB2_LIB.BASEBOARD_FAB2(SCH_1):PAGE50
  J6M1  257 VSS<12> SCONN288_H44441003_PIP-SCONN,HA    I44 @BASEBOARD_FAB2_LIB.BASEBOARD_FAB2(SCH_1):PAGE50
  J6M1  254 VSS<13> SCONN288_H44441003_PIP-SCONN,HA    I44 @BASEBOARD_FAB2_LIB.BASEBOARD_FAB2(SCH_1):PAGE50
  J6M1  252 VSS<14> SCONN288_H44441003_PIP-SCONN,HA    I44 @BASEBOARD_FAB2_LIB.BASEBOARD_FAB2(SCH_1):PAGE50
  J6M1  250 VSS<15> SCONN288_H44441003_PIP-SCONN,HA    I44 @BASEBOARD_FAB2_LIB.BASEBOARD_FAB2(SCH_1):PAGE50
  J6M1  248 VSS<16> SCONN288_H44441003_PIP-SCONN,HA    I44 @BASEBOARD_FAB2_LIB.BASEBOARD_FAB2(SCH_1):PAGE50
  J6M1  246 VSS<17> SCONN288_H44441003_PIP-SCONN,HA    I44 @BASEBOARD_FAB2_LIB.BASEBOARD_FAB2(SCH_1):PAGE50
  J6M1  243 VSS<18> SCONN288_H44441003_PIP-SCONN,HA    I44 @BASEBOARD_FAB2_LIB.BASEBOARD_FAB2(SCH_1):PAGE50
  J6M1  241 VSS<19> SCONN288_H44441003_PIP-SCONN,HA    I44 @BASEBOARD_FAB2_LIB.BASEBOARD_FAB2(SCH_1):PAGE50
  J6M1  239 VSS<20> SCONN288_H44441003_PIP-SCONN,HA    I44 @BASEBOARD_FAB2_LIB.BASEBOARD_FAB2(SCH_1):PAGE50
  J6M1  202 VSS<21> SCONN288_H44441003_PIP-SCONN,HA    I44 @BASEBOARD_FAB2_LIB.BASEBOARD_FAB2(SCH_1):PAGE50
  J6M1  200 VSS<22> SCONN288_H44441003_PIP-SCONN,HA    I44 @BASEBOARD_FAB2_LIB.BASEBOARD_FAB2(SCH_1):PAGE50
  J6M1  198 VSS<23> SCONN288_H44441003_PIP-SCONN,HA    I44 @BASEBOARD_FAB2_LIB.BASEBOARD_FAB2(SCH_1):PAGE50
  J6M1  195 VSS<24> SCONN288_H44441003_PIP-SCONN,HA    I44 @BASEBOARD_FAB2_LIB.BASEBOARD_FAB2(SCH_1):PAGE50
  J6M1  193 VSS<25> SCONN288_H44441003_PIP-SCONN,HA    I44 @BASEBOARD_FAB2_LIB.BASEBOARD_FAB2(SCH_1):PAGE50
  J6M1  191 VSS<26> SCONN288_H44441003_PIP-SCONN,HA    I44 @BASEBOARD_FAB2_LIB.BASEBOARD_FAB2(SCH_1):PAGE50
  J6M1  189 VSS<27> SCONN288_H44441003_PIP-SCONN,HA    I44 @BASEBOARD_FAB2_LIB.BASEBOARD_FAB2(SCH_1):PAGE50
  J6M1  187 VSS<28> SCONN288_H44441003_PIP-SCONN,HA    I44 @BASEBOARD_FAB2_LIB.BASEBOARD_FAB2(SCH_1):PAGE50
  J6M1  184 VSS<29> SCONN288_H44441003_PIP-SCONN,HA    I44 @BASEBOARD_FAB2_LIB.BASEBOARD_FAB2(SCH_1):PAGE50
  J6M1  182 VSS<30> SCONN288_H44441003_PIP-SCONN,HA    I44 @BASEBOARD_FAB2_LIB.BASEBOARD_FAB2(SCH_1):PAGE50
  J6M1  180 VSS<31> SCONN288_H44441003_PIP-SCONN,HA    I44 @BASEBOARD_FAB2_LIB.BASEBOARD_FAB2(SCH_1):PAGE50
  J6M1  178 VSS<32> SCONN288_H44441003_PIP-SCONN,HA    I44 @BASEBOARD_FAB2_LIB.BASEBOARD_FAB2(SCH_1):PAGE50
  J6M1  176 VSS<33> SCONN288_H44441003_PIP-SCONN,HA    I44 @BASEBOARD_FAB2_LIB.BASEBOARD_FAB2(SCH_1):PAGE50
  J6M1  173 VSS<34> SCONN288_H44441003_PIP-SCONN,HA    I44 @BASEBOARD_FAB2_LIB.BASEBOARD_FAB2(SCH_1):PAGE50
  J6M1  171 VSS<35> SCONN288_H44441003_PIP-SCONN,HA    I44 @BASEBOARD_FAB2_LIB.BASEBOARD_FAB2(SCH_1):PAGE50
  J6M1  169 VSS<36> SCONN288_H44441003_PIP-SCONN,HA    I44 @BASEBOARD_FAB2_LIB.BASEBOARD_FAB2(SCH_1):PAGE50
  J6M1  167 VSS<37> SCONN288_H44441003_PIP-SCONN,HA    I44 @BASEBOARD_FAB2_LIB.BASEBOARD_FAB2(SCH_1):PAGE50
  J6M1  165 VSS<38> SCONN288_H44441003_PIP-SCONN,HA    I44 @BASEBOARD_FAB2_LIB.BASEBOARD_FAB2(SCH_1):PAGE50
  J6M1  162 VSS<39> SCONN288_H44441003_PIP-SCONN,HA    I44 @BASEBOARD_FAB2_LIB.BASEBOARD_FAB2(SCH_1):PAGE50
  J6M1  160 VSS<40> SCONN288_H44441003_PIP-SCONN,HA    I44 @BASEBOARD_FAB2_LIB.BASEBOARD_FAB2(SCH_1):PAGE50
  J6M1  158 VSS<41> SCONN288_H44441003_PIP-SCONN,HA    I44 @BASEBOARD_FAB2_LIB.BASEBOARD_FAB2(SCH_1):PAGE50
  J6M1  156 VSS<42> SCONN288_H44441003_PIP-SCONN,HA    I44 @BASEBOARD_FAB2_LIB.BASEBOARD_FAB2(SCH_1):PAGE50
  J6M1  154 VSS<43> SCONN288_H44441003_PIP-SCONN,HA    I44 @BASEBOARD_FAB2_LIB.BASEBOARD_FAB2(SCH_1):PAGE50
  J6M1  151 VSS<44> SCONN288_H44441003_PIP-SCONN,HA    I44 @BASEBOARD_FAB2_LIB.BASEBOARD_FAB2(SCH_1):PAGE50
  J6M1  149 VSS<45> SCONN288_H44441003_PIP-SCONN,HA    I44 @BASEBOARD_FAB2_LIB.BASEBOARD_FAB2(SCH_1):PAGE50
  J6M1  147 VSS<46> SCONN288_H44441003_PIP-SCONN,HA    I44 @BASEBOARD_FAB2_LIB.BASEBOARD_FAB2(SCH_1):PAGE50
  J6M1  138 VSS<47> SCONN288_H44441003_PIP-SCONN,HA    I44 @BASEBOARD_FAB2_LIB.BASEBOARD_FAB2(SCH_1):PAGE50
  J6M1  136 VSS<48> SCONN288_H44441003_PIP-SCONN,HA    I44 @BASEBOARD_FAB2_LIB.BASEBOARD_FAB2(SCH_1):PAGE50
  J6M1  134 VSS<49> SCONN288_H44441003_PIP-SCONN,HA    I44 @BASEBOARD_FAB2_LIB.BASEBOARD_FAB2(SCH_1):PAGE50
  J6M1  131 VSS<50> SCONN288_H44441003_PIP-SCONN,HA    I44 @BASEBOARD_FAB2_LIB.BASEBOARD_FAB2(SCH_1):PAGE50
  J6M1  129 VSS<51> SCONN288_H44441003_PIP-SCONN,HA    I44 @BASEBOARD_FAB2_LIB.BASEBOARD_FAB2(SCH_1):PAGE50
  J6M1  127 VSS<52> SCONN288_H44441003_PIP-SCONN,HA    I44 @BASEBOARD_FAB2_LIB.BASEBOARD_FAB2(SCH_1):PAGE50
  J6M1  125 VSS<53> SCONN288_H44441003_PIP-SCONN,HA    I44 @BASEBOARD_FAB2_LIB.BASEBOARD_FAB2(SCH_1):PAGE50
  J6M1  123 VSS<54> SCONN288_H44441003_PIP-SCONN,HA    I44 @BASEBOARD_FAB2_LIB.BASEBOARD_FAB2(SCH_1):PAGE50
  J6M1  120 VSS<55> SCONN288_H44441003_PIP-SCONN,HA    I44 @BASEBOARD_FAB2_LIB.BASEBOARD_FAB2(SCH_1):PAGE50
  J6M1  118 VSS<56> SCONN288_H44441003_PIP-SCONN,HA    I44 @BASEBOARD_FAB2_LIB.BASEBOARD_FAB2(SCH_1):PAGE50
  J6M1  116 VSS<57> SCONN288_H44441003_PIP-SCONN,HA    I44 @BASEBOARD_FAB2_LIB.BASEBOARD_FAB2(SCH_1):PAGE50
  J6M1  114 VSS<58> SCONN288_H44441003_PIP-SCONN,HA    I44 @BASEBOARD_FAB2_LIB.BASEBOARD_FAB2(SCH_1):PAGE50
  J6M1  112 VSS<59> SCONN288_H44441003_PIP-SCONN,HA    I44 @BASEBOARD_FAB2_LIB.BASEBOARD_FAB2(SCH_1):PAGE50
  J6M1  109 VSS<60> SCONN288_H44441003_PIP-SCONN,HA    I44 @BASEBOARD_FAB2_LIB.BASEBOARD_FAB2(SCH_1):PAGE50
  J6M1  107 VSS<61> SCONN288_H44441003_PIP-SCONN,HA    I44 @BASEBOARD_FAB2_LIB.BASEBOARD_FAB2(SCH_1):PAGE50
  J6M1  105 VSS<62> SCONN288_H44441003_PIP-SCONN,HA    I44 @BASEBOARD_FAB2_LIB.BASEBOARD_FAB2(SCH_1):PAGE50
  J6M1  103 VSS<63> SCONN288_H44441003_PIP-SCONN,HA    I44 @BASEBOARD_FAB2_LIB.BASEBOARD_FAB2(SCH_1):PAGE50
  J6M1  101 VSS<64> SCONN288_H44441003_PIP-SCONN,HA    I44 @BASEBOARD_FAB2_LIB.BASEBOARD_FAB2(SCH_1):PAGE50
  J6M1   98 VSS<65> SCONN288_H44441003_PIP-SCONN,HA    I44 @BASEBOARD_FAB2_LIB.BASEBOARD_FAB2(SCH_1):PAGE50
  J6M1   96 VSS<66> SCONN288_H44441003_PIP-SCONN,HA    I44 @BASEBOARD_FAB2_LIB.BASEBOARD_FAB2(SCH_1):PAGE50
  J6M1   94 VSS<67> SCONN288_H44441003_PIP-SCONN,HA    I44 @BASEBOARD_FAB2_LIB.BASEBOARD_FAB2(SCH_1):PAGE50
  J6M1   57 VSS<68> SCONN288_H44441003_PIP-SCONN,HA    I44 @BASEBOARD_FAB2_LIB.BASEBOARD_FAB2(SCH_1):PAGE50
  J6M1   55 VSS<69> SCONN288_H44441003_PIP-SCONN,HA    I44 @BASEBOARD_FAB2_LIB.BASEBOARD_FAB2(SCH_1):PAGE50
  J6M1   53 VSS<70> SCONN288_H44441003_PIP-SCONN,HA    I44 @BASEBOARD_FAB2_LIB.BASEBOARD_FAB2(SCH_1):PAGE50
  J6M1   50 VSS<71> SCONN288_H44441003_PIP-SCONN,HA    I44 @BASEBOARD_FAB2_LIB.BASEBOARD_FAB2(SCH_1):PAGE50
  J6M1   48 VSS<72> SCONN288_H44441003_PIP-SCONN,HA    I44 @BASEBOARD_FAB2_LIB.BASEBOARD_FAB2(SCH_1):PAGE50
  J6M1   46 VSS<73> SCONN288_H44441003_PIP-SCONN,HA    I44 @BASEBOARD_FAB2_LIB.BASEBOARD_FAB2(SCH_1):PAGE50
  J6M1   44 VSS<74> SCONN288_H44441003_PIP-SCONN,HA    I44 @BASEBOARD_FAB2_LIB.BASEBOARD_FAB2(SCH_1):PAGE50
  J6M1   42 VSS<75> SCONN288_H44441003_PIP-SCONN,HA    I44 @BASEBOARD_FAB2_LIB.BASEBOARD_FAB2(SCH_1):PAGE50
  J6M1   39 VSS<76> SCONN288_H44441003_PIP-SCONN,HA    I44 @BASEBOARD_FAB2_LIB.BASEBOARD_FAB2(SCH_1):PAGE50
  J6M1   37 VSS<77> SCONN288_H44441003_PIP-SCONN,HA    I44 @BASEBOARD_FAB2_LIB.BASEBOARD_FAB2(SCH_1):PAGE50
  J6M1   35 VSS<78> SCONN288_H44441003_PIP-SCONN,HA    I44 @BASEBOARD_FAB2_LIB.BASEBOARD_FAB2(SCH_1):PAGE50
  J6M1   33 VSS<79> SCONN288_H44441003_PIP-SCONN,HA    I44 @BASEBOARD_FAB2_LIB.BASEBOARD_FAB2(SCH_1):PAGE50
  J6M1   31 VSS<80> SCONN288_H44441003_PIP-SCONN,HA    I44 @BASEBOARD_FAB2_LIB.BASEBOARD_FAB2(SCH_1):PAGE50
  J6M1   28 VSS<81> SCONN288_H44441003_PIP-SCONN,HA    I44 @BASEBOARD_FAB2_LIB.BASEBOARD_FAB2(SCH_1):PAGE50
  J6M1   26 VSS<82> SCONN288_H44441003_PIP-SCONN,HA    I44 @BASEBOARD_FAB2_LIB.BASEBOARD_FAB2(SCH_1):PAGE50
  J6M1   24 VSS<83> SCONN288_H44441003_PIP-SCONN,HA    I44 @BASEBOARD_FAB2_LIB.BASEBOARD_FAB2(SCH_1):PAGE50
  J6M1   22 VSS<84> SCONN288_H44441003_PIP-SCONN,HA    I44 @BASEBOARD_FAB2_LIB.BASEBOARD_FAB2(SCH_1):PAGE50
  J6M1   20 VSS<85> SCONN288_H44441003_PIP-SCONN,HA    I44 @BASEBOARD_FAB2_LIB.BASEBOARD_FAB2(SCH_1):PAGE50
  J6M1   17 VSS<86> SCONN288_H44441003_PIP-SCONN,HA    I44 @BASEBOARD_FAB2_LIB.BASEBOARD_FAB2(SCH_1):PAGE50
  J6M1   15 VSS<87> SCONN288_H44441003_PIP-SCONN,HA    I44 @BASEBOARD_FAB2_LIB.BASEBOARD_FAB2(SCH_1):PAGE50
  J6M1   13 VSS<88> SCONN288_H44441003_PIP-SCONN,HA    I44 @BASEBOARD_FAB2_LIB.BASEBOARD_FAB2(SCH_1):PAGE50
  J6M1   11 VSS<89> SCONN288_H44441003_PIP-SCONN,HA    I44 @BASEBOARD_FAB2_LIB.BASEBOARD_FAB2(SCH_1):PAGE50
  J6M1    9 VSS<90> SCONN288_H44441003_PIP-SCONN,HA    I44 @BASEBOARD_FAB2_LIB.BASEBOARD_FAB2(SCH_1):PAGE50
  J6M1    6 VSS<91> SCONN288_H44441003_PIP-SCONN,HA    I44 @BASEBOARD_FAB2_LIB.BASEBOARD_FAB2(SCH_1):PAGE50
  J6M1    4 VSS<92> SCONN288_H44441003_PIP-SCONN,HA    I44 @BASEBOARD_FAB2_LIB.BASEBOARD_FAB2(SCH_1):PAGE50
  J6M1    2 VSS<93> SCONN288_H44441003_PIP-SCONN,HA    I44 @BASEBOARD_FAB2_LIB.BASEBOARD_FAB2(SCH_1):PAGE50
  J6M1  140  SA<1> SCONN288_H44441003_PIP-SCONN,HA   I158 @BASEBOARD_FAB2_LIB.BASEBOARD_FAB2(SCH_1):PAGE50
  J6M1  238  SA<2> SCONN288_H44441003_PIP-SCONN,HA   I158 @BASEBOARD_FAB2_LIB.BASEBOARD_FAB2(SCH_1):PAGE50
  C6M1    2      B CAP_A_0402V-0.01UF,25V,10%,X7RA   I177 @BASEBOARD_FAB2_LIB.BASEBOARD_FAB2(SCH_1):PAGE50
  J4A2  283 VSS<0> SCONN288_H44441004_PIP-SCONN,HA    I43 @BASEBOARD_FAB2_LIB.BASEBOARD_FAB2(SCH_1):PAGE51
  J4A2  281 VSS<1> SCONN288_H44441004_PIP-SCONN,HA    I43 @BASEBOARD_FAB2_LIB.BASEBOARD_FAB2(SCH_1):PAGE51
  J4A2  279 VSS<2> SCONN288_H44441004_PIP-SCONN,HA    I43 @BASEBOARD_FAB2_LIB.BASEBOARD_FAB2(SCH_1):PAGE51
  J4A2  276 VSS<3> SCONN288_H44441004_PIP-SCONN,HA    I43 @BASEBOARD_FAB2_LIB.BASEBOARD_FAB2(SCH_1):PAGE51
  J4A2  274 VSS<4> SCONN288_H44441004_PIP-SCONN,HA    I43 @BASEBOARD_FAB2_LIB.BASEBOARD_FAB2(SCH_1):PAGE51
  J4A2  272 VSS<5> SCONN288_H44441004_PIP-SCONN,HA    I43 @BASEBOARD_FAB2_LIB.BASEBOARD_FAB2(SCH_1):PAGE51
  J4A2  270 VSS<6> SCONN288_H44441004_PIP-SCONN,HA    I43 @BASEBOARD_FAB2_LIB.BASEBOARD_FAB2(SCH_1):PAGE51
  J4A2  268 VSS<7> SCONN288_H44441004_PIP-SCONN,HA    I43 @BASEBOARD_FAB2_LIB.BASEBOARD_FAB2(SCH_1):PAGE51
  J4A2  265 VSS<8> SCONN288_H44441004_PIP-SCONN,HA    I43 @BASEBOARD_FAB2_LIB.BASEBOARD_FAB2(SCH_1):PAGE51
  J4A2  263 VSS<9> SCONN288_H44441004_PIP-SCONN,HA    I43 @BASEBOARD_FAB2_LIB.BASEBOARD_FAB2(SCH_1):PAGE51
  J4A2  261 VSS<10> SCONN288_H44441004_PIP-SCONN,HA    I43 @BASEBOARD_FAB2_LIB.BASEBOARD_FAB2(SCH_1):PAGE51
  J4A2  259 VSS<11> SCONN288_H44441004_PIP-SCONN,HA    I43 @BASEBOARD_FAB2_LIB.BASEBOARD_FAB2(SCH_1):PAGE51
  J4A2  257 VSS<12> SCONN288_H44441004_PIP-SCONN,HA    I43 @BASEBOARD_FAB2_LIB.BASEBOARD_FAB2(SCH_1):PAGE51
  J4A2  254 VSS<13> SCONN288_H44441004_PIP-SCONN,HA    I43 @BASEBOARD_FAB2_LIB.BASEBOARD_FAB2(SCH_1):PAGE51
  J4A2  252 VSS<14> SCONN288_H44441004_PIP-SCONN,HA    I43 @BASEBOARD_FAB2_LIB.BASEBOARD_FAB2(SCH_1):PAGE51
  J4A2  250 VSS<15> SCONN288_H44441004_PIP-SCONN,HA    I43 @BASEBOARD_FAB2_LIB.BASEBOARD_FAB2(SCH_1):PAGE51
  J4A2  248 VSS<16> SCONN288_H44441004_PIP-SCONN,HA    I43 @BASEBOARD_FAB2_LIB.BASEBOARD_FAB2(SCH_1):PAGE51
  J4A2  246 VSS<17> SCONN288_H44441004_PIP-SCONN,HA    I43 @BASEBOARD_FAB2_LIB.BASEBOARD_FAB2(SCH_1):PAGE51
  J4A2  243 VSS<18> SCONN288_H44441004_PIP-SCONN,HA    I43 @BASEBOARD_FAB2_LIB.BASEBOARD_FAB2(SCH_1):PAGE51
  J4A2  241 VSS<19> SCONN288_H44441004_PIP-SCONN,HA    I43 @BASEBOARD_FAB2_LIB.BASEBOARD_FAB2(SCH_1):PAGE51
  J4A2  239 VSS<20> SCONN288_H44441004_PIP-SCONN,HA    I43 @BASEBOARD_FAB2_LIB.BASEBOARD_FAB2(SCH_1):PAGE51
  J4A2  202 VSS<21> SCONN288_H44441004_PIP-SCONN,HA    I43 @BASEBOARD_FAB2_LIB.BASEBOARD_FAB2(SCH_1):PAGE51
  J4A2  200 VSS<22> SCONN288_H44441004_PIP-SCONN,HA    I43 @BASEBOARD_FAB2_LIB.BASEBOARD_FAB2(SCH_1):PAGE51
  J4A2  198 VSS<23> SCONN288_H44441004_PIP-SCONN,HA    I43 @BASEBOARD_FAB2_LIB.BASEBOARD_FAB2(SCH_1):PAGE51
  J4A2  195 VSS<24> SCONN288_H44441004_PIP-SCONN,HA    I43 @BASEBOARD_FAB2_LIB.BASEBOARD_FAB2(SCH_1):PAGE51
  J4A2  193 VSS<25> SCONN288_H44441004_PIP-SCONN,HA    I43 @BASEBOARD_FAB2_LIB.BASEBOARD_FAB2(SCH_1):PAGE51
  J4A2  191 VSS<26> SCONN288_H44441004_PIP-SCONN,HA    I43 @BASEBOARD_FAB2_LIB.BASEBOARD_FAB2(SCH_1):PAGE51
  J4A2  189 VSS<27> SCONN288_H44441004_PIP-SCONN,HA    I43 @BASEBOARD_FAB2_LIB.BASEBOARD_FAB2(SCH_1):PAGE51
  J4A2  187 VSS<28> SCONN288_H44441004_PIP-SCONN,HA    I43 @BASEBOARD_FAB2_LIB.BASEBOARD_FAB2(SCH_1):PAGE51
  J4A2  184 VSS<29> SCONN288_H44441004_PIP-SCONN,HA    I43 @BASEBOARD_FAB2_LIB.BASEBOARD_FAB2(SCH_1):PAGE51
  J4A2  182 VSS<30> SCONN288_H44441004_PIP-SCONN,HA    I43 @BASEBOARD_FAB2_LIB.BASEBOARD_FAB2(SCH_1):PAGE51
  J4A2  180 VSS<31> SCONN288_H44441004_PIP-SCONN,HA    I43 @BASEBOARD_FAB2_LIB.BASEBOARD_FAB2(SCH_1):PAGE51
  J4A2  178 VSS<32> SCONN288_H44441004_PIP-SCONN,HA    I43 @BASEBOARD_FAB2_LIB.BASEBOARD_FAB2(SCH_1):PAGE51
  J4A2  176 VSS<33> SCONN288_H44441004_PIP-SCONN,HA    I43 @BASEBOARD_FAB2_LIB.BASEBOARD_FAB2(SCH_1):PAGE51
  J4A2  173 VSS<34> SCONN288_H44441004_PIP-SCONN,HA    I43 @BASEBOARD_FAB2_LIB.BASEBOARD_FAB2(SCH_1):PAGE51
  J4A2  171 VSS<35> SCONN288_H44441004_PIP-SCONN,HA    I43 @BASEBOARD_FAB2_LIB.BASEBOARD_FAB2(SCH_1):PAGE51
  J4A2  169 VSS<36> SCONN288_H44441004_PIP-SCONN,HA    I43 @BASEBOARD_FAB2_LIB.BASEBOARD_FAB2(SCH_1):PAGE51
  J4A2  167 VSS<37> SCONN288_H44441004_PIP-SCONN,HA    I43 @BASEBOARD_FAB2_LIB.BASEBOARD_FAB2(SCH_1):PAGE51
  J4A2  165 VSS<38> SCONN288_H44441004_PIP-SCONN,HA    I43 @BASEBOARD_FAB2_LIB.BASEBOARD_FAB2(SCH_1):PAGE51
  J4A2  162 VSS<39> SCONN288_H44441004_PIP-SCONN,HA    I43 @BASEBOARD_FAB2_LIB.BASEBOARD_FAB2(SCH_1):PAGE51
  J4A2  160 VSS<40> SCONN288_H44441004_PIP-SCONN,HA    I43 @BASEBOARD_FAB2_LIB.BASEBOARD_FAB2(SCH_1):PAGE51
  J4A2  158 VSS<41> SCONN288_H44441004_PIP-SCONN,HA    I43 @BASEBOARD_FAB2_LIB.BASEBOARD_FAB2(SCH_1):PAGE51
  J4A2  156 VSS<42> SCONN288_H44441004_PIP-SCONN,HA    I43 @BASEBOARD_FAB2_LIB.BASEBOARD_FAB2(SCH_1):PAGE51
  J4A2  154 VSS<43> SCONN288_H44441004_PIP-SCONN,HA    I43 @BASEBOARD_FAB2_LIB.BASEBOARD_FAB2(SCH_1):PAGE51
  J4A2  151 VSS<44> SCONN288_H44441004_PIP-SCONN,HA    I43 @BASEBOARD_FAB2_LIB.BASEBOARD_FAB2(SCH_1):PAGE51
  J4A2  149 VSS<45> SCONN288_H44441004_PIP-SCONN,HA    I43 @BASEBOARD_FAB2_LIB.BASEBOARD_FAB2(SCH_1):PAGE51
  J4A2  147 VSS<46> SCONN288_H44441004_PIP-SCONN,HA    I43 @BASEBOARD_FAB2_LIB.BASEBOARD_FAB2(SCH_1):PAGE51
  J4A2  138 VSS<47> SCONN288_H44441004_PIP-SCONN,HA    I43 @BASEBOARD_FAB2_LIB.BASEBOARD_FAB2(SCH_1):PAGE51
  J4A2  136 VSS<48> SCONN288_H44441004_PIP-SCONN,HA    I43 @BASEBOARD_FAB2_LIB.BASEBOARD_FAB2(SCH_1):PAGE51
  J4A2  134 VSS<49> SCONN288_H44441004_PIP-SCONN,HA    I43 @BASEBOARD_FAB2_LIB.BASEBOARD_FAB2(SCH_1):PAGE51
  J4A2  131 VSS<50> SCONN288_H44441004_PIP-SCONN,HA    I43 @BASEBOARD_FAB2_LIB.BASEBOARD_FAB2(SCH_1):PAGE51
  J4A2  129 VSS<51> SCONN288_H44441004_PIP-SCONN,HA    I43 @BASEBOARD_FAB2_LIB.BASEBOARD_FAB2(SCH_1):PAGE51
  J4A2  127 VSS<52> SCONN288_H44441004_PIP-SCONN,HA    I43 @BASEBOARD_FAB2_LIB.BASEBOARD_FAB2(SCH_1):PAGE51
  J4A2  125 VSS<53> SCONN288_H44441004_PIP-SCONN,HA    I43 @BASEBOARD_FAB2_LIB.BASEBOARD_FAB2(SCH_1):PAGE51
  J4A2  123 VSS<54> SCONN288_H44441004_PIP-SCONN,HA    I43 @BASEBOARD_FAB2_LIB.BASEBOARD_FAB2(SCH_1):PAGE51
  J4A2  120 VSS<55> SCONN288_H44441004_PIP-SCONN,HA    I43 @BASEBOARD_FAB2_LIB.BASEBOARD_FAB2(SCH_1):PAGE51
  J4A2  118 VSS<56> SCONN288_H44441004_PIP-SCONN,HA    I43 @BASEBOARD_FAB2_LIB.BASEBOARD_FAB2(SCH_1):PAGE51
  J4A2  116 VSS<57> SCONN288_H44441004_PIP-SCONN,HA    I43 @BASEBOARD_FAB2_LIB.BASEBOARD_FAB2(SCH_1):PAGE51
  J4A2  114 VSS<58> SCONN288_H44441004_PIP-SCONN,HA    I43 @BASEBOARD_FAB2_LIB.BASEBOARD_FAB2(SCH_1):PAGE51
  J4A2  112 VSS<59> SCONN288_H44441004_PIP-SCONN,HA    I43 @BASEBOARD_FAB2_LIB.BASEBOARD_FAB2(SCH_1):PAGE51
  J4A2  109 VSS<60> SCONN288_H44441004_PIP-SCONN,HA    I43 @BASEBOARD_FAB2_LIB.BASEBOARD_FAB2(SCH_1):PAGE51
  J4A2  107 VSS<61> SCONN288_H44441004_PIP-SCONN,HA    I43 @BASEBOARD_FAB2_LIB.BASEBOARD_FAB2(SCH_1):PAGE51
  J4A2  105 VSS<62> SCONN288_H44441004_PIP-SCONN,HA    I43 @BASEBOARD_FAB2_LIB.BASEBOARD_FAB2(SCH_1):PAGE51
  J4A2  103 VSS<63> SCONN288_H44441004_PIP-SCONN,HA    I43 @BASEBOARD_FAB2_LIB.BASEBOARD_FAB2(SCH_1):PAGE51
  J4A2  101 VSS<64> SCONN288_H44441004_PIP-SCONN,HA    I43 @BASEBOARD_FAB2_LIB.BASEBOARD_FAB2(SCH_1):PAGE51
  J4A2   98 VSS<65> SCONN288_H44441004_PIP-SCONN,HA    I43 @BASEBOARD_FAB2_LIB.BASEBOARD_FAB2(SCH_1):PAGE51
  J4A2   96 VSS<66> SCONN288_H44441004_PIP-SCONN,HA    I43 @BASEBOARD_FAB2_LIB.BASEBOARD_FAB2(SCH_1):PAGE51
  J4A2   94 VSS<67> SCONN288_H44441004_PIP-SCONN,HA    I43 @BASEBOARD_FAB2_LIB.BASEBOARD_FAB2(SCH_1):PAGE51
  J4A2   57 VSS<68> SCONN288_H44441004_PIP-SCONN,HA    I43 @BASEBOARD_FAB2_LIB.BASEBOARD_FAB2(SCH_1):PAGE51
  J4A2   55 VSS<69> SCONN288_H44441004_PIP-SCONN,HA    I43 @BASEBOARD_FAB2_LIB.BASEBOARD_FAB2(SCH_1):PAGE51
  J4A2   53 VSS<70> SCONN288_H44441004_PIP-SCONN,HA    I43 @BASEBOARD_FAB2_LIB.BASEBOARD_FAB2(SCH_1):PAGE51
  J4A2   50 VSS<71> SCONN288_H44441004_PIP-SCONN,HA    I43 @BASEBOARD_FAB2_LIB.BASEBOARD_FAB2(SCH_1):PAGE51
  J4A2   48 VSS<72> SCONN288_H44441004_PIP-SCONN,HA    I43 @BASEBOARD_FAB2_LIB.BASEBOARD_FAB2(SCH_1):PAGE51
  J4A2   46 VSS<73> SCONN288_H44441004_PIP-SCONN,HA    I43 @BASEBOARD_FAB2_LIB.BASEBOARD_FAB2(SCH_1):PAGE51
  J4A2   44 VSS<74> SCONN288_H44441004_PIP-SCONN,HA    I43 @BASEBOARD_FAB2_LIB.BASEBOARD_FAB2(SCH_1):PAGE51
  J4A2   42 VSS<75> SCONN288_H44441004_PIP-SCONN,HA    I43 @BASEBOARD_FAB2_LIB.BASEBOARD_FAB2(SCH_1):PAGE51
  J4A2   39 VSS<76> SCONN288_H44441004_PIP-SCONN,HA    I43 @BASEBOARD_FAB2_LIB.BASEBOARD_FAB2(SCH_1):PAGE51
  J4A2   37 VSS<77> SCONN288_H44441004_PIP-SCONN,HA    I43 @BASEBOARD_FAB2_LIB.BASEBOARD_FAB2(SCH_1):PAGE51
  J4A2   35 VSS<78> SCONN288_H44441004_PIP-SCONN,HA    I43 @BASEBOARD_FAB2_LIB.BASEBOARD_FAB2(SCH_1):PAGE51
  J4A2   33 VSS<79> SCONN288_H44441004_PIP-SCONN,HA    I43 @BASEBOARD_FAB2_LIB.BASEBOARD_FAB2(SCH_1):PAGE51
  J4A2   31 VSS<80> SCONN288_H44441004_PIP-SCONN,HA    I43 @BASEBOARD_FAB2_LIB.BASEBOARD_FAB2(SCH_1):PAGE51
  J4A2   28 VSS<81> SCONN288_H44441004_PIP-SCONN,HA    I43 @BASEBOARD_FAB2_LIB.BASEBOARD_FAB2(SCH_1):PAGE51
  J4A2   26 VSS<82> SCONN288_H44441004_PIP-SCONN,HA    I43 @BASEBOARD_FAB2_LIB.BASEBOARD_FAB2(SCH_1):PAGE51
  J4A2   24 VSS<83> SCONN288_H44441004_PIP-SCONN,HA    I43 @BASEBOARD_FAB2_LIB.BASEBOARD_FAB2(SCH_1):PAGE51
  J4A2   22 VSS<84> SCONN288_H44441004_PIP-SCONN,HA    I43 @BASEBOARD_FAB2_LIB.BASEBOARD_FAB2(SCH_1):PAGE51
  J4A2   20 VSS<85> SCONN288_H44441004_PIP-SCONN,HA    I43 @BASEBOARD_FAB2_LIB.BASEBOARD_FAB2(SCH_1):PAGE51
  J4A2   17 VSS<86> SCONN288_H44441004_PIP-SCONN,HA    I43 @BASEBOARD_FAB2_LIB.BASEBOARD_FAB2(SCH_1):PAGE51
  J4A2   15 VSS<87> SCONN288_H44441004_PIP-SCONN,HA    I43 @BASEBOARD_FAB2_LIB.BASEBOARD_FAB2(SCH_1):PAGE51
  J4A2   13 VSS<88> SCONN288_H44441004_PIP-SCONN,HA    I43 @BASEBOARD_FAB2_LIB.BASEBOARD_FAB2(SCH_1):PAGE51
  J4A2   11 VSS<89> SCONN288_H44441004_PIP-SCONN,HA    I43 @BASEBOARD_FAB2_LIB.BASEBOARD_FAB2(SCH_1):PAGE51
  J4A2    9 VSS<90> SCONN288_H44441004_PIP-SCONN,HA    I43 @BASEBOARD_FAB2_LIB.BASEBOARD_FAB2(SCH_1):PAGE51
  J4A2    6 VSS<91> SCONN288_H44441004_PIP-SCONN,HA    I43 @BASEBOARD_FAB2_LIB.BASEBOARD_FAB2(SCH_1):PAGE51
  J4A2    4 VSS<92> SCONN288_H44441004_PIP-SCONN,HA    I43 @BASEBOARD_FAB2_LIB.BASEBOARD_FAB2(SCH_1):PAGE51
  J4A2    2 VSS<93> SCONN288_H44441004_PIP-SCONN,HA    I43 @BASEBOARD_FAB2_LIB.BASEBOARD_FAB2(SCH_1):PAGE51
  J4A2  139  SA<0> SCONN288_H44441004_PIP-SCONN,HA   I111 @BASEBOARD_FAB2_LIB.BASEBOARD_FAB2(SCH_1):PAGE51
  J4A2  238  SA<2> SCONN288_H44441004_PIP-SCONN,HA   I111 @BASEBOARD_FAB2_LIB.BASEBOARD_FAB2(SCH_1):PAGE51
  C6L6    2      B CAP_A_0402V-0.01UF,25V,10%,X7RA   I175 @BASEBOARD_FAB2_LIB.BASEBOARD_FAB2(SCH_1):PAGE51
 C4A18    2      B CAP_A_0402V-0.01UF,25V,10%,X7RA     I3 @BASEBOARD_FAB2_LIB.BASEBOARD_FAB2(SCH_1):PAGE52
  J6L2  238  SA<2> SCONN288_H44441003_PIP-SCONN,HA    I12 @BASEBOARD_FAB2_LIB.BASEBOARD_FAB2(SCH_1):PAGE52
  J6L2  283 VSS<0> SCONN288_H44441003_PIP-SCONN,HA   I138 @BASEBOARD_FAB2_LIB.BASEBOARD_FAB2(SCH_1):PAGE52
  J6L2  281 VSS<1> SCONN288_H44441003_PIP-SCONN,HA   I138 @BASEBOARD_FAB2_LIB.BASEBOARD_FAB2(SCH_1):PAGE52
  J6L2  279 VSS<2> SCONN288_H44441003_PIP-SCONN,HA   I138 @BASEBOARD_FAB2_LIB.BASEBOARD_FAB2(SCH_1):PAGE52
  J6L2  276 VSS<3> SCONN288_H44441003_PIP-SCONN,HA   I138 @BASEBOARD_FAB2_LIB.BASEBOARD_FAB2(SCH_1):PAGE52
  J6L2  274 VSS<4> SCONN288_H44441003_PIP-SCONN,HA   I138 @BASEBOARD_FAB2_LIB.BASEBOARD_FAB2(SCH_1):PAGE52
  J6L2  272 VSS<5> SCONN288_H44441003_PIP-SCONN,HA   I138 @BASEBOARD_FAB2_LIB.BASEBOARD_FAB2(SCH_1):PAGE52
  J6L2  270 VSS<6> SCONN288_H44441003_PIP-SCONN,HA   I138 @BASEBOARD_FAB2_LIB.BASEBOARD_FAB2(SCH_1):PAGE52
  J6L2  268 VSS<7> SCONN288_H44441003_PIP-SCONN,HA   I138 @BASEBOARD_FAB2_LIB.BASEBOARD_FAB2(SCH_1):PAGE52
  J6L2  265 VSS<8> SCONN288_H44441003_PIP-SCONN,HA   I138 @BASEBOARD_FAB2_LIB.BASEBOARD_FAB2(SCH_1):PAGE52
  J6L2  263 VSS<9> SCONN288_H44441003_PIP-SCONN,HA   I138 @BASEBOARD_FAB2_LIB.BASEBOARD_FAB2(SCH_1):PAGE52
  J6L2  261 VSS<10> SCONN288_H44441003_PIP-SCONN,HA   I138 @BASEBOARD_FAB2_LIB.BASEBOARD_FAB2(SCH_1):PAGE52
  J6L2  259 VSS<11> SCONN288_H44441003_PIP-SCONN,HA   I138 @BASEBOARD_FAB2_LIB.BASEBOARD_FAB2(SCH_1):PAGE52
  J6L2  257 VSS<12> SCONN288_H44441003_PIP-SCONN,HA   I138 @BASEBOARD_FAB2_LIB.BASEBOARD_FAB2(SCH_1):PAGE52
  J6L2  254 VSS<13> SCONN288_H44441003_PIP-SCONN,HA   I138 @BASEBOARD_FAB2_LIB.BASEBOARD_FAB2(SCH_1):PAGE52
  J6L2  252 VSS<14> SCONN288_H44441003_PIP-SCONN,HA   I138 @BASEBOARD_FAB2_LIB.BASEBOARD_FAB2(SCH_1):PAGE52
  J6L2  250 VSS<15> SCONN288_H44441003_PIP-SCONN,HA   I138 @BASEBOARD_FAB2_LIB.BASEBOARD_FAB2(SCH_1):PAGE52
  J6L2  248 VSS<16> SCONN288_H44441003_PIP-SCONN,HA   I138 @BASEBOARD_FAB2_LIB.BASEBOARD_FAB2(SCH_1):PAGE52
  J6L2  246 VSS<17> SCONN288_H44441003_PIP-SCONN,HA   I138 @BASEBOARD_FAB2_LIB.BASEBOARD_FAB2(SCH_1):PAGE52
  J6L2  243 VSS<18> SCONN288_H44441003_PIP-SCONN,HA   I138 @BASEBOARD_FAB2_LIB.BASEBOARD_FAB2(SCH_1):PAGE52
  J6L2  241 VSS<19> SCONN288_H44441003_PIP-SCONN,HA   I138 @BASEBOARD_FAB2_LIB.BASEBOARD_FAB2(SCH_1):PAGE52
  J6L2  239 VSS<20> SCONN288_H44441003_PIP-SCONN,HA   I138 @BASEBOARD_FAB2_LIB.BASEBOARD_FAB2(SCH_1):PAGE52
  J6L2  202 VSS<21> SCONN288_H44441003_PIP-SCONN,HA   I138 @BASEBOARD_FAB2_LIB.BASEBOARD_FAB2(SCH_1):PAGE52
  J6L2  200 VSS<22> SCONN288_H44441003_PIP-SCONN,HA   I138 @BASEBOARD_FAB2_LIB.BASEBOARD_FAB2(SCH_1):PAGE52
  J6L2  198 VSS<23> SCONN288_H44441003_PIP-SCONN,HA   I138 @BASEBOARD_FAB2_LIB.BASEBOARD_FAB2(SCH_1):PAGE52
  J6L2  195 VSS<24> SCONN288_H44441003_PIP-SCONN,HA   I138 @BASEBOARD_FAB2_LIB.BASEBOARD_FAB2(SCH_1):PAGE52
  J6L2  193 VSS<25> SCONN288_H44441003_PIP-SCONN,HA   I138 @BASEBOARD_FAB2_LIB.BASEBOARD_FAB2(SCH_1):PAGE52
  J6L2  191 VSS<26> SCONN288_H44441003_PIP-SCONN,HA   I138 @BASEBOARD_FAB2_LIB.BASEBOARD_FAB2(SCH_1):PAGE52
  J6L2  189 VSS<27> SCONN288_H44441003_PIP-SCONN,HA   I138 @BASEBOARD_FAB2_LIB.BASEBOARD_FAB2(SCH_1):PAGE52
  J6L2  187 VSS<28> SCONN288_H44441003_PIP-SCONN,HA   I138 @BASEBOARD_FAB2_LIB.BASEBOARD_FAB2(SCH_1):PAGE52
  J6L2  184 VSS<29> SCONN288_H44441003_PIP-SCONN,HA   I138 @BASEBOARD_FAB2_LIB.BASEBOARD_FAB2(SCH_1):PAGE52
  J6L2  182 VSS<30> SCONN288_H44441003_PIP-SCONN,HA   I138 @BASEBOARD_FAB2_LIB.BASEBOARD_FAB2(SCH_1):PAGE52
  J6L2  180 VSS<31> SCONN288_H44441003_PIP-SCONN,HA   I138 @BASEBOARD_FAB2_LIB.BASEBOARD_FAB2(SCH_1):PAGE52
  J6L2  178 VSS<32> SCONN288_H44441003_PIP-SCONN,HA   I138 @BASEBOARD_FAB2_LIB.BASEBOARD_FAB2(SCH_1):PAGE52
  J6L2  176 VSS<33> SCONN288_H44441003_PIP-SCONN,HA   I138 @BASEBOARD_FAB2_LIB.BASEBOARD_FAB2(SCH_1):PAGE52
  J6L2  173 VSS<34> SCONN288_H44441003_PIP-SCONN,HA   I138 @BASEBOARD_FAB2_LIB.BASEBOARD_FAB2(SCH_1):PAGE52
  J6L2  171 VSS<35> SCONN288_H44441003_PIP-SCONN,HA   I138 @BASEBOARD_FAB2_LIB.BASEBOARD_FAB2(SCH_1):PAGE52
  J6L2  169 VSS<36> SCONN288_H44441003_PIP-SCONN,HA   I138 @BASEBOARD_FAB2_LIB.BASEBOARD_FAB2(SCH_1):PAGE52
  J6L2  167 VSS<37> SCONN288_H44441003_PIP-SCONN,HA   I138 @BASEBOARD_FAB2_LIB.BASEBOARD_FAB2(SCH_1):PAGE52
  J6L2  165 VSS<38> SCONN288_H44441003_PIP-SCONN,HA   I138 @BASEBOARD_FAB2_LIB.BASEBOARD_FAB2(SCH_1):PAGE52
  J6L2  162 VSS<39> SCONN288_H44441003_PIP-SCONN,HA   I138 @BASEBOARD_FAB2_LIB.BASEBOARD_FAB2(SCH_1):PAGE52
  J6L2  160 VSS<40> SCONN288_H44441003_PIP-SCONN,HA   I138 @BASEBOARD_FAB2_LIB.BASEBOARD_FAB2(SCH_1):PAGE52
  J6L2  158 VSS<41> SCONN288_H44441003_PIP-SCONN,HA   I138 @BASEBOARD_FAB2_LIB.BASEBOARD_FAB2(SCH_1):PAGE52
  J6L2  156 VSS<42> SCONN288_H44441003_PIP-SCONN,HA   I138 @BASEBOARD_FAB2_LIB.BASEBOARD_FAB2(SCH_1):PAGE52
  J6L2  154 VSS<43> SCONN288_H44441003_PIP-SCONN,HA   I138 @BASEBOARD_FAB2_LIB.BASEBOARD_FAB2(SCH_1):PAGE52
  J6L2  151 VSS<44> SCONN288_H44441003_PIP-SCONN,HA   I138 @BASEBOARD_FAB2_LIB.BASEBOARD_FAB2(SCH_1):PAGE52
  J6L2  149 VSS<45> SCONN288_H44441003_PIP-SCONN,HA   I138 @BASEBOARD_FAB2_LIB.BASEBOARD_FAB2(SCH_1):PAGE52
  J6L2  147 VSS<46> SCONN288_H44441003_PIP-SCONN,HA   I138 @BASEBOARD_FAB2_LIB.BASEBOARD_FAB2(SCH_1):PAGE52
  J6L2  138 VSS<47> SCONN288_H44441003_PIP-SCONN,HA   I138 @BASEBOARD_FAB2_LIB.BASEBOARD_FAB2(SCH_1):PAGE52
  J6L2  136 VSS<48> SCONN288_H44441003_PIP-SCONN,HA   I138 @BASEBOARD_FAB2_LIB.BASEBOARD_FAB2(SCH_1):PAGE52
  J6L2  134 VSS<49> SCONN288_H44441003_PIP-SCONN,HA   I138 @BASEBOARD_FAB2_LIB.BASEBOARD_FAB2(SCH_1):PAGE52
  J6L2  131 VSS<50> SCONN288_H44441003_PIP-SCONN,HA   I138 @BASEBOARD_FAB2_LIB.BASEBOARD_FAB2(SCH_1):PAGE52
  J6L2  129 VSS<51> SCONN288_H44441003_PIP-SCONN,HA   I138 @BASEBOARD_FAB2_LIB.BASEBOARD_FAB2(SCH_1):PAGE52
  J6L2  127 VSS<52> SCONN288_H44441003_PIP-SCONN,HA   I138 @BASEBOARD_FAB2_LIB.BASEBOARD_FAB2(SCH_1):PAGE52
  J6L2  125 VSS<53> SCONN288_H44441003_PIP-SCONN,HA   I138 @BASEBOARD_FAB2_LIB.BASEBOARD_FAB2(SCH_1):PAGE52
  J6L2  123 VSS<54> SCONN288_H44441003_PIP-SCONN,HA   I138 @BASEBOARD_FAB2_LIB.BASEBOARD_FAB2(SCH_1):PAGE52
  J6L2  120 VSS<55> SCONN288_H44441003_PIP-SCONN,HA   I138 @BASEBOARD_FAB2_LIB.BASEBOARD_FAB2(SCH_1):PAGE52
  J6L2  118 VSS<56> SCONN288_H44441003_PIP-SCONN,HA   I138 @BASEBOARD_FAB2_LIB.BASEBOARD_FAB2(SCH_1):PAGE52
  J6L2  116 VSS<57> SCONN288_H44441003_PIP-SCONN,HA   I138 @BASEBOARD_FAB2_LIB.BASEBOARD_FAB2(SCH_1):PAGE52
  J6L2  114 VSS<58> SCONN288_H44441003_PIP-SCONN,HA   I138 @BASEBOARD_FAB2_LIB.BASEBOARD_FAB2(SCH_1):PAGE52
  J6L2  112 VSS<59> SCONN288_H44441003_PIP-SCONN,HA   I138 @BASEBOARD_FAB2_LIB.BASEBOARD_FAB2(SCH_1):PAGE52
  J6L2  109 VSS<60> SCONN288_H44441003_PIP-SCONN,HA   I138 @BASEBOARD_FAB2_LIB.BASEBOARD_FAB2(SCH_1):PAGE52
  J6L2  107 VSS<61> SCONN288_H44441003_PIP-SCONN,HA   I138 @BASEBOARD_FAB2_LIB.BASEBOARD_FAB2(SCH_1):PAGE52
  J6L2  105 VSS<62> SCONN288_H44441003_PIP-SCONN,HA   I138 @BASEBOARD_FAB2_LIB.BASEBOARD_FAB2(SCH_1):PAGE52
  J6L2  103 VSS<63> SCONN288_H44441003_PIP-SCONN,HA   I138 @BASEBOARD_FAB2_LIB.BASEBOARD_FAB2(SCH_1):PAGE52
  J6L2  101 VSS<64> SCONN288_H44441003_PIP-SCONN,HA   I138 @BASEBOARD_FAB2_LIB.BASEBOARD_FAB2(SCH_1):PAGE52
  J6L2   98 VSS<65> SCONN288_H44441003_PIP-SCONN,HA   I138 @BASEBOARD_FAB2_LIB.BASEBOARD_FAB2(SCH_1):PAGE52
  J6L2   96 VSS<66> SCONN288_H44441003_PIP-SCONN,HA   I138 @BASEBOARD_FAB2_LIB.BASEBOARD_FAB2(SCH_1):PAGE52
  J6L2   94 VSS<67> SCONN288_H44441003_PIP-SCONN,HA   I138 @BASEBOARD_FAB2_LIB.BASEBOARD_FAB2(SCH_1):PAGE52
  J6L2   57 VSS<68> SCONN288_H44441003_PIP-SCONN,HA   I138 @BASEBOARD_FAB2_LIB.BASEBOARD_FAB2(SCH_1):PAGE52
  J6L2   55 VSS<69> SCONN288_H44441003_PIP-SCONN,HA   I138 @BASEBOARD_FAB2_LIB.BASEBOARD_FAB2(SCH_1):PAGE52
  J6L2   53 VSS<70> SCONN288_H44441003_PIP-SCONN,HA   I138 @BASEBOARD_FAB2_LIB.BASEBOARD_FAB2(SCH_1):PAGE52
  J6L2   50 VSS<71> SCONN288_H44441003_PIP-SCONN,HA   I138 @BASEBOARD_FAB2_LIB.BASEBOARD_FAB2(SCH_1):PAGE52
  J6L2   48 VSS<72> SCONN288_H44441003_PIP-SCONN,HA   I138 @BASEBOARD_FAB2_LIB.BASEBOARD_FAB2(SCH_1):PAGE52
  J6L2   46 VSS<73> SCONN288_H44441003_PIP-SCONN,HA   I138 @BASEBOARD_FAB2_LIB.BASEBOARD_FAB2(SCH_1):PAGE52
  J6L2   44 VSS<74> SCONN288_H44441003_PIP-SCONN,HA   I138 @BASEBOARD_FAB2_LIB.BASEBOARD_FAB2(SCH_1):PAGE52
  J6L2   42 VSS<75> SCONN288_H44441003_PIP-SCONN,HA   I138 @BASEBOARD_FAB2_LIB.BASEBOARD_FAB2(SCH_1):PAGE52
  J6L2   39 VSS<76> SCONN288_H44441003_PIP-SCONN,HA   I138 @BASEBOARD_FAB2_LIB.BASEBOARD_FAB2(SCH_1):PAGE52
  J6L2   37 VSS<77> SCONN288_H44441003_PIP-SCONN,HA   I138 @BASEBOARD_FAB2_LIB.BASEBOARD_FAB2(SCH_1):PAGE52
  J6L2   35 VSS<78> SCONN288_H44441003_PIP-SCONN,HA   I138 @BASEBOARD_FAB2_LIB.BASEBOARD_FAB2(SCH_1):PAGE52
  J6L2   33 VSS<79> SCONN288_H44441003_PIP-SCONN,HA   I138 @BASEBOARD_FAB2_LIB.BASEBOARD_FAB2(SCH_1):PAGE52
  J6L2   31 VSS<80> SCONN288_H44441003_PIP-SCONN,HA   I138 @BASEBOARD_FAB2_LIB.BASEBOARD_FAB2(SCH_1):PAGE52
  J6L2   28 VSS<81> SCONN288_H44441003_PIP-SCONN,HA   I138 @BASEBOARD_FAB2_LIB.BASEBOARD_FAB2(SCH_1):PAGE52
  J6L2   26 VSS<82> SCONN288_H44441003_PIP-SCONN,HA   I138 @BASEBOARD_FAB2_LIB.BASEBOARD_FAB2(SCH_1):PAGE52
  J6L2   24 VSS<83> SCONN288_H44441003_PIP-SCONN,HA   I138 @BASEBOARD_FAB2_LIB.BASEBOARD_FAB2(SCH_1):PAGE52
  J6L2   22 VSS<84> SCONN288_H44441003_PIP-SCONN,HA   I138 @BASEBOARD_FAB2_LIB.BASEBOARD_FAB2(SCH_1):PAGE52
  J6L2   20 VSS<85> SCONN288_H44441003_PIP-SCONN,HA   I138 @BASEBOARD_FAB2_LIB.BASEBOARD_FAB2(SCH_1):PAGE52
  J6L2   17 VSS<86> SCONN288_H44441003_PIP-SCONN,HA   I138 @BASEBOARD_FAB2_LIB.BASEBOARD_FAB2(SCH_1):PAGE52
  J6L2   15 VSS<87> SCONN288_H44441003_PIP-SCONN,HA   I138 @BASEBOARD_FAB2_LIB.BASEBOARD_FAB2(SCH_1):PAGE52
  J6L2   13 VSS<88> SCONN288_H44441003_PIP-SCONN,HA   I138 @BASEBOARD_FAB2_LIB.BASEBOARD_FAB2(SCH_1):PAGE52
  J6L2   11 VSS<89> SCONN288_H44441003_PIP-SCONN,HA   I138 @BASEBOARD_FAB2_LIB.BASEBOARD_FAB2(SCH_1):PAGE52
  J6L2    9 VSS<90> SCONN288_H44441003_PIP-SCONN,HA   I138 @BASEBOARD_FAB2_LIB.BASEBOARD_FAB2(SCH_1):PAGE52
  J6L2    6 VSS<91> SCONN288_H44441003_PIP-SCONN,HA   I138 @BASEBOARD_FAB2_LIB.BASEBOARD_FAB2(SCH_1):PAGE52
  J6L2    4 VSS<92> SCONN288_H44441003_PIP-SCONN,HA   I138 @BASEBOARD_FAB2_LIB.BASEBOARD_FAB2(SCH_1):PAGE52
  J6L2    2 VSS<93> SCONN288_H44441003_PIP-SCONN,HA   I138 @BASEBOARD_FAB2_LIB.BASEBOARD_FAB2(SCH_1):PAGE52
  J4A1  283 VSS<0> SCONN288_H44441004_PIP-SCONN,HA    I43 @BASEBOARD_FAB2_LIB.BASEBOARD_FAB2(SCH_1):PAGE53
  J4A1  281 VSS<1> SCONN288_H44441004_PIP-SCONN,HA    I43 @BASEBOARD_FAB2_LIB.BASEBOARD_FAB2(SCH_1):PAGE53
  J4A1  279 VSS<2> SCONN288_H44441004_PIP-SCONN,HA    I43 @BASEBOARD_FAB2_LIB.BASEBOARD_FAB2(SCH_1):PAGE53
  J4A1  276 VSS<3> SCONN288_H44441004_PIP-SCONN,HA    I43 @BASEBOARD_FAB2_LIB.BASEBOARD_FAB2(SCH_1):PAGE53
  J4A1  274 VSS<4> SCONN288_H44441004_PIP-SCONN,HA    I43 @BASEBOARD_FAB2_LIB.BASEBOARD_FAB2(SCH_1):PAGE53
  J4A1  272 VSS<5> SCONN288_H44441004_PIP-SCONN,HA    I43 @BASEBOARD_FAB2_LIB.BASEBOARD_FAB2(SCH_1):PAGE53
  J4A1  270 VSS<6> SCONN288_H44441004_PIP-SCONN,HA    I43 @BASEBOARD_FAB2_LIB.BASEBOARD_FAB2(SCH_1):PAGE53
  J4A1  268 VSS<7> SCONN288_H44441004_PIP-SCONN,HA    I43 @BASEBOARD_FAB2_LIB.BASEBOARD_FAB2(SCH_1):PAGE53
  J4A1  265 VSS<8> SCONN288_H44441004_PIP-SCONN,HA    I43 @BASEBOARD_FAB2_LIB.BASEBOARD_FAB2(SCH_1):PAGE53
  J4A1  263 VSS<9> SCONN288_H44441004_PIP-SCONN,HA    I43 @BASEBOARD_FAB2_LIB.BASEBOARD_FAB2(SCH_1):PAGE53
  J4A1  261 VSS<10> SCONN288_H44441004_PIP-SCONN,HA    I43 @BASEBOARD_FAB2_LIB.BASEBOARD_FAB2(SCH_1):PAGE53
  J4A1  259 VSS<11> SCONN288_H44441004_PIP-SCONN,HA    I43 @BASEBOARD_FAB2_LIB.BASEBOARD_FAB2(SCH_1):PAGE53
  J4A1  257 VSS<12> SCONN288_H44441004_PIP-SCONN,HA    I43 @BASEBOARD_FAB2_LIB.BASEBOARD_FAB2(SCH_1):PAGE53
  J4A1  254 VSS<13> SCONN288_H44441004_PIP-SCONN,HA    I43 @BASEBOARD_FAB2_LIB.BASEBOARD_FAB2(SCH_1):PAGE53
  J4A1  252 VSS<14> SCONN288_H44441004_PIP-SCONN,HA    I43 @BASEBOARD_FAB2_LIB.BASEBOARD_FAB2(SCH_1):PAGE53
  J4A1  250 VSS<15> SCONN288_H44441004_PIP-SCONN,HA    I43 @BASEBOARD_FAB2_LIB.BASEBOARD_FAB2(SCH_1):PAGE53
  J4A1  248 VSS<16> SCONN288_H44441004_PIP-SCONN,HA    I43 @BASEBOARD_FAB2_LIB.BASEBOARD_FAB2(SCH_1):PAGE53
  J4A1  246 VSS<17> SCONN288_H44441004_PIP-SCONN,HA    I43 @BASEBOARD_FAB2_LIB.BASEBOARD_FAB2(SCH_1):PAGE53
  J4A1  243 VSS<18> SCONN288_H44441004_PIP-SCONN,HA    I43 @BASEBOARD_FAB2_LIB.BASEBOARD_FAB2(SCH_1):PAGE53
  J4A1  241 VSS<19> SCONN288_H44441004_PIP-SCONN,HA    I43 @BASEBOARD_FAB2_LIB.BASEBOARD_FAB2(SCH_1):PAGE53
  J4A1  239 VSS<20> SCONN288_H44441004_PIP-SCONN,HA    I43 @BASEBOARD_FAB2_LIB.BASEBOARD_FAB2(SCH_1):PAGE53
  J4A1  202 VSS<21> SCONN288_H44441004_PIP-SCONN,HA    I43 @BASEBOARD_FAB2_LIB.BASEBOARD_FAB2(SCH_1):PAGE53
  J4A1  200 VSS<22> SCONN288_H44441004_PIP-SCONN,HA    I43 @BASEBOARD_FAB2_LIB.BASEBOARD_FAB2(SCH_1):PAGE53
  J4A1  198 VSS<23> SCONN288_H44441004_PIP-SCONN,HA    I43 @BASEBOARD_FAB2_LIB.BASEBOARD_FAB2(SCH_1):PAGE53
  J4A1  195 VSS<24> SCONN288_H44441004_PIP-SCONN,HA    I43 @BASEBOARD_FAB2_LIB.BASEBOARD_FAB2(SCH_1):PAGE53
  J4A1  193 VSS<25> SCONN288_H44441004_PIP-SCONN,HA    I43 @BASEBOARD_FAB2_LIB.BASEBOARD_FAB2(SCH_1):PAGE53
  J4A1  191 VSS<26> SCONN288_H44441004_PIP-SCONN,HA    I43 @BASEBOARD_FAB2_LIB.BASEBOARD_FAB2(SCH_1):PAGE53
  J4A1  189 VSS<27> SCONN288_H44441004_PIP-SCONN,HA    I43 @BASEBOARD_FAB2_LIB.BASEBOARD_FAB2(SCH_1):PAGE53
  J4A1  187 VSS<28> SCONN288_H44441004_PIP-SCONN,HA    I43 @BASEBOARD_FAB2_LIB.BASEBOARD_FAB2(SCH_1):PAGE53
  J4A1  184 VSS<29> SCONN288_H44441004_PIP-SCONN,HA    I43 @BASEBOARD_FAB2_LIB.BASEBOARD_FAB2(SCH_1):PAGE53
  J4A1  182 VSS<30> SCONN288_H44441004_PIP-SCONN,HA    I43 @BASEBOARD_FAB2_LIB.BASEBOARD_FAB2(SCH_1):PAGE53
  J4A1  180 VSS<31> SCONN288_H44441004_PIP-SCONN,HA    I43 @BASEBOARD_FAB2_LIB.BASEBOARD_FAB2(SCH_1):PAGE53
  J4A1  178 VSS<32> SCONN288_H44441004_PIP-SCONN,HA    I43 @BASEBOARD_FAB2_LIB.BASEBOARD_FAB2(SCH_1):PAGE53
  J4A1  176 VSS<33> SCONN288_H44441004_PIP-SCONN,HA    I43 @BASEBOARD_FAB2_LIB.BASEBOARD_FAB2(SCH_1):PAGE53
  J4A1  173 VSS<34> SCONN288_H44441004_PIP-SCONN,HA    I43 @BASEBOARD_FAB2_LIB.BASEBOARD_FAB2(SCH_1):PAGE53
  J4A1  171 VSS<35> SCONN288_H44441004_PIP-SCONN,HA    I43 @BASEBOARD_FAB2_LIB.BASEBOARD_FAB2(SCH_1):PAGE53
  J4A1  169 VSS<36> SCONN288_H44441004_PIP-SCONN,HA    I43 @BASEBOARD_FAB2_LIB.BASEBOARD_FAB2(SCH_1):PAGE53
  J4A1  167 VSS<37> SCONN288_H44441004_PIP-SCONN,HA    I43 @BASEBOARD_FAB2_LIB.BASEBOARD_FAB2(SCH_1):PAGE53
  J4A1  165 VSS<38> SCONN288_H44441004_PIP-SCONN,HA    I43 @BASEBOARD_FAB2_LIB.BASEBOARD_FAB2(SCH_1):PAGE53
  J4A1  162 VSS<39> SCONN288_H44441004_PIP-SCONN,HA    I43 @BASEBOARD_FAB2_LIB.BASEBOARD_FAB2(SCH_1):PAGE53
  J4A1  160 VSS<40> SCONN288_H44441004_PIP-SCONN,HA    I43 @BASEBOARD_FAB2_LIB.BASEBOARD_FAB2(SCH_1):PAGE53
  J4A1  158 VSS<41> SCONN288_H44441004_PIP-SCONN,HA    I43 @BASEBOARD_FAB2_LIB.BASEBOARD_FAB2(SCH_1):PAGE53
  J4A1  156 VSS<42> SCONN288_H44441004_PIP-SCONN,HA    I43 @BASEBOARD_FAB2_LIB.BASEBOARD_FAB2(SCH_1):PAGE53
  J4A1  154 VSS<43> SCONN288_H44441004_PIP-SCONN,HA    I43 @BASEBOARD_FAB2_LIB.BASEBOARD_FAB2(SCH_1):PAGE53
  J4A1  151 VSS<44> SCONN288_H44441004_PIP-SCONN,HA    I43 @BASEBOARD_FAB2_LIB.BASEBOARD_FAB2(SCH_1):PAGE53
  J4A1  149 VSS<45> SCONN288_H44441004_PIP-SCONN,HA    I43 @BASEBOARD_FAB2_LIB.BASEBOARD_FAB2(SCH_1):PAGE53
  J4A1  147 VSS<46> SCONN288_H44441004_PIP-SCONN,HA    I43 @BASEBOARD_FAB2_LIB.BASEBOARD_FAB2(SCH_1):PAGE53
  J4A1  138 VSS<47> SCONN288_H44441004_PIP-SCONN,HA    I43 @BASEBOARD_FAB2_LIB.BASEBOARD_FAB2(SCH_1):PAGE53
  J4A1  136 VSS<48> SCONN288_H44441004_PIP-SCONN,HA    I43 @BASEBOARD_FAB2_LIB.BASEBOARD_FAB2(SCH_1):PAGE53
  J4A1  134 VSS<49> SCONN288_H44441004_PIP-SCONN,HA    I43 @BASEBOARD_FAB2_LIB.BASEBOARD_FAB2(SCH_1):PAGE53
  J4A1  131 VSS<50> SCONN288_H44441004_PIP-SCONN,HA    I43 @BASEBOARD_FAB2_LIB.BASEBOARD_FAB2(SCH_1):PAGE53
  J4A1  129 VSS<51> SCONN288_H44441004_PIP-SCONN,HA    I43 @BASEBOARD_FAB2_LIB.BASEBOARD_FAB2(SCH_1):PAGE53
  J4A1  127 VSS<52> SCONN288_H44441004_PIP-SCONN,HA    I43 @BASEBOARD_FAB2_LIB.BASEBOARD_FAB2(SCH_1):PAGE53
  J4A1  125 VSS<53> SCONN288_H44441004_PIP-SCONN,HA    I43 @BASEBOARD_FAB2_LIB.BASEBOARD_FAB2(SCH_1):PAGE53
  J4A1  123 VSS<54> SCONN288_H44441004_PIP-SCONN,HA    I43 @BASEBOARD_FAB2_LIB.BASEBOARD_FAB2(SCH_1):PAGE53
  J4A1  120 VSS<55> SCONN288_H44441004_PIP-SCONN,HA    I43 @BASEBOARD_FAB2_LIB.BASEBOARD_FAB2(SCH_1):PAGE53
  J4A1  118 VSS<56> SCONN288_H44441004_PIP-SCONN,HA    I43 @BASEBOARD_FAB2_LIB.BASEBOARD_FAB2(SCH_1):PAGE53
  J4A1  116 VSS<57> SCONN288_H44441004_PIP-SCONN,HA    I43 @BASEBOARD_FAB2_LIB.BASEBOARD_FAB2(SCH_1):PAGE53
  J4A1  114 VSS<58> SCONN288_H44441004_PIP-SCONN,HA    I43 @BASEBOARD_FAB2_LIB.BASEBOARD_FAB2(SCH_1):PAGE53
  J4A1  112 VSS<59> SCONN288_H44441004_PIP-SCONN,HA    I43 @BASEBOARD_FAB2_LIB.BASEBOARD_FAB2(SCH_1):PAGE53
  J4A1  109 VSS<60> SCONN288_H44441004_PIP-SCONN,HA    I43 @BASEBOARD_FAB2_LIB.BASEBOARD_FAB2(SCH_1):PAGE53
  J4A1  107 VSS<61> SCONN288_H44441004_PIP-SCONN,HA    I43 @BASEBOARD_FAB2_LIB.BASEBOARD_FAB2(SCH_1):PAGE53
  J4A1  105 VSS<62> SCONN288_H44441004_PIP-SCONN,HA    I43 @BASEBOARD_FAB2_LIB.BASEBOARD_FAB2(SCH_1):PAGE53
  J4A1  103 VSS<63> SCONN288_H44441004_PIP-SCONN,HA    I43 @BASEBOARD_FAB2_LIB.BASEBOARD_FAB2(SCH_1):PAGE53
  J4A1  101 VSS<64> SCONN288_H44441004_PIP-SCONN,HA    I43 @BASEBOARD_FAB2_LIB.BASEBOARD_FAB2(SCH_1):PAGE53
  J4A1   98 VSS<65> SCONN288_H44441004_PIP-SCONN,HA    I43 @BASEBOARD_FAB2_LIB.BASEBOARD_FAB2(SCH_1):PAGE53
  J4A1   96 VSS<66> SCONN288_H44441004_PIP-SCONN,HA    I43 @BASEBOARD_FAB2_LIB.BASEBOARD_FAB2(SCH_1):PAGE53
  J4A1   94 VSS<67> SCONN288_H44441004_PIP-SCONN,HA    I43 @BASEBOARD_FAB2_LIB.BASEBOARD_FAB2(SCH_1):PAGE53
  J4A1   57 VSS<68> SCONN288_H44441004_PIP-SCONN,HA    I43 @BASEBOARD_FAB2_LIB.BASEBOARD_FAB2(SCH_1):PAGE53
  J4A1   55 VSS<69> SCONN288_H44441004_PIP-SCONN,HA    I43 @BASEBOARD_FAB2_LIB.BASEBOARD_FAB2(SCH_1):PAGE53
  J4A1   53 VSS<70> SCONN288_H44441004_PIP-SCONN,HA    I43 @BASEBOARD_FAB2_LIB.BASEBOARD_FAB2(SCH_1):PAGE53
  J4A1   50 VSS<71> SCONN288_H44441004_PIP-SCONN,HA    I43 @BASEBOARD_FAB2_LIB.BASEBOARD_FAB2(SCH_1):PAGE53
  J4A1   48 VSS<72> SCONN288_H44441004_PIP-SCONN,HA    I43 @BASEBOARD_FAB2_LIB.BASEBOARD_FAB2(SCH_1):PAGE53
  J4A1   46 VSS<73> SCONN288_H44441004_PIP-SCONN,HA    I43 @BASEBOARD_FAB2_LIB.BASEBOARD_FAB2(SCH_1):PAGE53
  J4A1   44 VSS<74> SCONN288_H44441004_PIP-SCONN,HA    I43 @BASEBOARD_FAB2_LIB.BASEBOARD_FAB2(SCH_1):PAGE53
  J4A1   42 VSS<75> SCONN288_H44441004_PIP-SCONN,HA    I43 @BASEBOARD_FAB2_LIB.BASEBOARD_FAB2(SCH_1):PAGE53
  J4A1   39 VSS<76> SCONN288_H44441004_PIP-SCONN,HA    I43 @BASEBOARD_FAB2_LIB.BASEBOARD_FAB2(SCH_1):PAGE53
  J4A1   37 VSS<77> SCONN288_H44441004_PIP-SCONN,HA    I43 @BASEBOARD_FAB2_LIB.BASEBOARD_FAB2(SCH_1):PAGE53
  J4A1   35 VSS<78> SCONN288_H44441004_PIP-SCONN,HA    I43 @BASEBOARD_FAB2_LIB.BASEBOARD_FAB2(SCH_1):PAGE53
  J4A1   33 VSS<79> SCONN288_H44441004_PIP-SCONN,HA    I43 @BASEBOARD_FAB2_LIB.BASEBOARD_FAB2(SCH_1):PAGE53
  J4A1   31 VSS<80> SCONN288_H44441004_PIP-SCONN,HA    I43 @BASEBOARD_FAB2_LIB.BASEBOARD_FAB2(SCH_1):PAGE53
  J4A1   28 VSS<81> SCONN288_H44441004_PIP-SCONN,HA    I43 @BASEBOARD_FAB2_LIB.BASEBOARD_FAB2(SCH_1):PAGE53
  J4A1   26 VSS<82> SCONN288_H44441004_PIP-SCONN,HA    I43 @BASEBOARD_FAB2_LIB.BASEBOARD_FAB2(SCH_1):PAGE53
  J4A1   24 VSS<83> SCONN288_H44441004_PIP-SCONN,HA    I43 @BASEBOARD_FAB2_LIB.BASEBOARD_FAB2(SCH_1):PAGE53
  J4A1   22 VSS<84> SCONN288_H44441004_PIP-SCONN,HA    I43 @BASEBOARD_FAB2_LIB.BASEBOARD_FAB2(SCH_1):PAGE53
  J4A1   20 VSS<85> SCONN288_H44441004_PIP-SCONN,HA    I43 @BASEBOARD_FAB2_LIB.BASEBOARD_FAB2(SCH_1):PAGE53
  J4A1   17 VSS<86> SCONN288_H44441004_PIP-SCONN,HA    I43 @BASEBOARD_FAB2_LIB.BASEBOARD_FAB2(SCH_1):PAGE53
  J4A1   15 VSS<87> SCONN288_H44441004_PIP-SCONN,HA    I43 @BASEBOARD_FAB2_LIB.BASEBOARD_FAB2(SCH_1):PAGE53
  J4A1   13 VSS<88> SCONN288_H44441004_PIP-SCONN,HA    I43 @BASEBOARD_FAB2_LIB.BASEBOARD_FAB2(SCH_1):PAGE53
  J4A1   11 VSS<89> SCONN288_H44441004_PIP-SCONN,HA    I43 @BASEBOARD_FAB2_LIB.BASEBOARD_FAB2(SCH_1):PAGE53
  J4A1    9 VSS<90> SCONN288_H44441004_PIP-SCONN,HA    I43 @BASEBOARD_FAB2_LIB.BASEBOARD_FAB2(SCH_1):PAGE53
  J4A1    6 VSS<91> SCONN288_H44441004_PIP-SCONN,HA    I43 @BASEBOARD_FAB2_LIB.BASEBOARD_FAB2(SCH_1):PAGE53
  J4A1    4 VSS<92> SCONN288_H44441004_PIP-SCONN,HA    I43 @BASEBOARD_FAB2_LIB.BASEBOARD_FAB2(SCH_1):PAGE53
  J4A1    2 VSS<93> SCONN288_H44441004_PIP-SCONN,HA    I43 @BASEBOARD_FAB2_LIB.BASEBOARD_FAB2(SCH_1):PAGE53
  J4A1  139  SA<0> SCONN288_H44441004_PIP-SCONN,HA   I111 @BASEBOARD_FAB2_LIB.BASEBOARD_FAB2(SCH_1):PAGE53
  J4A1  140  SA<1> SCONN288_H44441004_PIP-SCONN,HA   I111 @BASEBOARD_FAB2_LIB.BASEBOARD_FAB2(SCH_1):PAGE53
  C6L1    2      B CAP_A_0402V-0.01UF,25V,10%,X7RA   I178 @BASEBOARD_FAB2_LIB.BASEBOARD_FAB2(SCH_1):PAGE53
  J6L1  283 VSS<0> SCONN288_H44441003_PIP-SCONN,HA    I43 @BASEBOARD_FAB2_LIB.BASEBOARD_FAB2(SCH_1):PAGE54
  J6L1  281 VSS<1> SCONN288_H44441003_PIP-SCONN,HA    I43 @BASEBOARD_FAB2_LIB.BASEBOARD_FAB2(SCH_1):PAGE54
  J6L1  279 VSS<2> SCONN288_H44441003_PIP-SCONN,HA    I43 @BASEBOARD_FAB2_LIB.BASEBOARD_FAB2(SCH_1):PAGE54
  J6L1  276 VSS<3> SCONN288_H44441003_PIP-SCONN,HA    I43 @BASEBOARD_FAB2_LIB.BASEBOARD_FAB2(SCH_1):PAGE54
  J6L1  274 VSS<4> SCONN288_H44441003_PIP-SCONN,HA    I43 @BASEBOARD_FAB2_LIB.BASEBOARD_FAB2(SCH_1):PAGE54
  J6L1  272 VSS<5> SCONN288_H44441003_PIP-SCONN,HA    I43 @BASEBOARD_FAB2_LIB.BASEBOARD_FAB2(SCH_1):PAGE54
  J6L1  270 VSS<6> SCONN288_H44441003_PIP-SCONN,HA    I43 @BASEBOARD_FAB2_LIB.BASEBOARD_FAB2(SCH_1):PAGE54
  J6L1  268 VSS<7> SCONN288_H44441003_PIP-SCONN,HA    I43 @BASEBOARD_FAB2_LIB.BASEBOARD_FAB2(SCH_1):PAGE54
  J6L1  265 VSS<8> SCONN288_H44441003_PIP-SCONN,HA    I43 @BASEBOARD_FAB2_LIB.BASEBOARD_FAB2(SCH_1):PAGE54
  J6L1  263 VSS<9> SCONN288_H44441003_PIP-SCONN,HA    I43 @BASEBOARD_FAB2_LIB.BASEBOARD_FAB2(SCH_1):PAGE54
  J6L1  261 VSS<10> SCONN288_H44441003_PIP-SCONN,HA    I43 @BASEBOARD_FAB2_LIB.BASEBOARD_FAB2(SCH_1):PAGE54
  J6L1  259 VSS<11> SCONN288_H44441003_PIP-SCONN,HA    I43 @BASEBOARD_FAB2_LIB.BASEBOARD_FAB2(SCH_1):PAGE54
  J6L1  257 VSS<12> SCONN288_H44441003_PIP-SCONN,HA    I43 @BASEBOARD_FAB2_LIB.BASEBOARD_FAB2(SCH_1):PAGE54
  J6L1  254 VSS<13> SCONN288_H44441003_PIP-SCONN,HA    I43 @BASEBOARD_FAB2_LIB.BASEBOARD_FAB2(SCH_1):PAGE54
  J6L1  252 VSS<14> SCONN288_H44441003_PIP-SCONN,HA    I43 @BASEBOARD_FAB2_LIB.BASEBOARD_FAB2(SCH_1):PAGE54
  J6L1  250 VSS<15> SCONN288_H44441003_PIP-SCONN,HA    I43 @BASEBOARD_FAB2_LIB.BASEBOARD_FAB2(SCH_1):PAGE54
  J6L1  248 VSS<16> SCONN288_H44441003_PIP-SCONN,HA    I43 @BASEBOARD_FAB2_LIB.BASEBOARD_FAB2(SCH_1):PAGE54
  J6L1  246 VSS<17> SCONN288_H44441003_PIP-SCONN,HA    I43 @BASEBOARD_FAB2_LIB.BASEBOARD_FAB2(SCH_1):PAGE54
  J6L1  243 VSS<18> SCONN288_H44441003_PIP-SCONN,HA    I43 @BASEBOARD_FAB2_LIB.BASEBOARD_FAB2(SCH_1):PAGE54
  J6L1  241 VSS<19> SCONN288_H44441003_PIP-SCONN,HA    I43 @BASEBOARD_FAB2_LIB.BASEBOARD_FAB2(SCH_1):PAGE54
  J6L1  239 VSS<20> SCONN288_H44441003_PIP-SCONN,HA    I43 @BASEBOARD_FAB2_LIB.BASEBOARD_FAB2(SCH_1):PAGE54
  J6L1  202 VSS<21> SCONN288_H44441003_PIP-SCONN,HA    I43 @BASEBOARD_FAB2_LIB.BASEBOARD_FAB2(SCH_1):PAGE54
  J6L1  200 VSS<22> SCONN288_H44441003_PIP-SCONN,HA    I43 @BASEBOARD_FAB2_LIB.BASEBOARD_FAB2(SCH_1):PAGE54
  J6L1  198 VSS<23> SCONN288_H44441003_PIP-SCONN,HA    I43 @BASEBOARD_FAB2_LIB.BASEBOARD_FAB2(SCH_1):PAGE54
  J6L1  195 VSS<24> SCONN288_H44441003_PIP-SCONN,HA    I43 @BASEBOARD_FAB2_LIB.BASEBOARD_FAB2(SCH_1):PAGE54
  J6L1  193 VSS<25> SCONN288_H44441003_PIP-SCONN,HA    I43 @BASEBOARD_FAB2_LIB.BASEBOARD_FAB2(SCH_1):PAGE54
  J6L1  191 VSS<26> SCONN288_H44441003_PIP-SCONN,HA    I43 @BASEBOARD_FAB2_LIB.BASEBOARD_FAB2(SCH_1):PAGE54
  J6L1  189 VSS<27> SCONN288_H44441003_PIP-SCONN,HA    I43 @BASEBOARD_FAB2_LIB.BASEBOARD_FAB2(SCH_1):PAGE54
  J6L1  187 VSS<28> SCONN288_H44441003_PIP-SCONN,HA    I43 @BASEBOARD_FAB2_LIB.BASEBOARD_FAB2(SCH_1):PAGE54
  J6L1  184 VSS<29> SCONN288_H44441003_PIP-SCONN,HA    I43 @BASEBOARD_FAB2_LIB.BASEBOARD_FAB2(SCH_1):PAGE54
  J6L1  182 VSS<30> SCONN288_H44441003_PIP-SCONN,HA    I43 @BASEBOARD_FAB2_LIB.BASEBOARD_FAB2(SCH_1):PAGE54
  J6L1  180 VSS<31> SCONN288_H44441003_PIP-SCONN,HA    I43 @BASEBOARD_FAB2_LIB.BASEBOARD_FAB2(SCH_1):PAGE54
  J6L1  178 VSS<32> SCONN288_H44441003_PIP-SCONN,HA    I43 @BASEBOARD_FAB2_LIB.BASEBOARD_FAB2(SCH_1):PAGE54
  J6L1  176 VSS<33> SCONN288_H44441003_PIP-SCONN,HA    I43 @BASEBOARD_FAB2_LIB.BASEBOARD_FAB2(SCH_1):PAGE54
  J6L1  173 VSS<34> SCONN288_H44441003_PIP-SCONN,HA    I43 @BASEBOARD_FAB2_LIB.BASEBOARD_FAB2(SCH_1):PAGE54
  J6L1  171 VSS<35> SCONN288_H44441003_PIP-SCONN,HA    I43 @BASEBOARD_FAB2_LIB.BASEBOARD_FAB2(SCH_1):PAGE54
  J6L1  169 VSS<36> SCONN288_H44441003_PIP-SCONN,HA    I43 @BASEBOARD_FAB2_LIB.BASEBOARD_FAB2(SCH_1):PAGE54
  J6L1  167 VSS<37> SCONN288_H44441003_PIP-SCONN,HA    I43 @BASEBOARD_FAB2_LIB.BASEBOARD_FAB2(SCH_1):PAGE54
  J6L1  165 VSS<38> SCONN288_H44441003_PIP-SCONN,HA    I43 @BASEBOARD_FAB2_LIB.BASEBOARD_FAB2(SCH_1):PAGE54
  J6L1  162 VSS<39> SCONN288_H44441003_PIP-SCONN,HA    I43 @BASEBOARD_FAB2_LIB.BASEBOARD_FAB2(SCH_1):PAGE54
  J6L1  160 VSS<40> SCONN288_H44441003_PIP-SCONN,HA    I43 @BASEBOARD_FAB2_LIB.BASEBOARD_FAB2(SCH_1):PAGE54
  J6L1  158 VSS<41> SCONN288_H44441003_PIP-SCONN,HA    I43 @BASEBOARD_FAB2_LIB.BASEBOARD_FAB2(SCH_1):PAGE54
  J6L1  156 VSS<42> SCONN288_H44441003_PIP-SCONN,HA    I43 @BASEBOARD_FAB2_LIB.BASEBOARD_FAB2(SCH_1):PAGE54
  J6L1  154 VSS<43> SCONN288_H44441003_PIP-SCONN,HA    I43 @BASEBOARD_FAB2_LIB.BASEBOARD_FAB2(SCH_1):PAGE54
  J6L1  151 VSS<44> SCONN288_H44441003_PIP-SCONN,HA    I43 @BASEBOARD_FAB2_LIB.BASEBOARD_FAB2(SCH_1):PAGE54
  J6L1  149 VSS<45> SCONN288_H44441003_PIP-SCONN,HA    I43 @BASEBOARD_FAB2_LIB.BASEBOARD_FAB2(SCH_1):PAGE54
  J6L1  147 VSS<46> SCONN288_H44441003_PIP-SCONN,HA    I43 @BASEBOARD_FAB2_LIB.BASEBOARD_FAB2(SCH_1):PAGE54
  J6L1  138 VSS<47> SCONN288_H44441003_PIP-SCONN,HA    I43 @BASEBOARD_FAB2_LIB.BASEBOARD_FAB2(SCH_1):PAGE54
  J6L1  136 VSS<48> SCONN288_H44441003_PIP-SCONN,HA    I43 @BASEBOARD_FAB2_LIB.BASEBOARD_FAB2(SCH_1):PAGE54
  J6L1  134 VSS<49> SCONN288_H44441003_PIP-SCONN,HA    I43 @BASEBOARD_FAB2_LIB.BASEBOARD_FAB2(SCH_1):PAGE54
  J6L1  131 VSS<50> SCONN288_H44441003_PIP-SCONN,HA    I43 @BASEBOARD_FAB2_LIB.BASEBOARD_FAB2(SCH_1):PAGE54
  J6L1  129 VSS<51> SCONN288_H44441003_PIP-SCONN,HA    I43 @BASEBOARD_FAB2_LIB.BASEBOARD_FAB2(SCH_1):PAGE54
  J6L1  127 VSS<52> SCONN288_H44441003_PIP-SCONN,HA    I43 @BASEBOARD_FAB2_LIB.BASEBOARD_FAB2(SCH_1):PAGE54
  J6L1  125 VSS<53> SCONN288_H44441003_PIP-SCONN,HA    I43 @BASEBOARD_FAB2_LIB.BASEBOARD_FAB2(SCH_1):PAGE54
  J6L1  123 VSS<54> SCONN288_H44441003_PIP-SCONN,HA    I43 @BASEBOARD_FAB2_LIB.BASEBOARD_FAB2(SCH_1):PAGE54
  J6L1  120 VSS<55> SCONN288_H44441003_PIP-SCONN,HA    I43 @BASEBOARD_FAB2_LIB.BASEBOARD_FAB2(SCH_1):PAGE54
  J6L1  118 VSS<56> SCONN288_H44441003_PIP-SCONN,HA    I43 @BASEBOARD_FAB2_LIB.BASEBOARD_FAB2(SCH_1):PAGE54
  J6L1  116 VSS<57> SCONN288_H44441003_PIP-SCONN,HA    I43 @BASEBOARD_FAB2_LIB.BASEBOARD_FAB2(SCH_1):PAGE54
  J6L1  114 VSS<58> SCONN288_H44441003_PIP-SCONN,HA    I43 @BASEBOARD_FAB2_LIB.BASEBOARD_FAB2(SCH_1):PAGE54
  J6L1  112 VSS<59> SCONN288_H44441003_PIP-SCONN,HA    I43 @BASEBOARD_FAB2_LIB.BASEBOARD_FAB2(SCH_1):PAGE54
  J6L1  109 VSS<60> SCONN288_H44441003_PIP-SCONN,HA    I43 @BASEBOARD_FAB2_LIB.BASEBOARD_FAB2(SCH_1):PAGE54
  J6L1  107 VSS<61> SCONN288_H44441003_PIP-SCONN,HA    I43 @BASEBOARD_FAB2_LIB.BASEBOARD_FAB2(SCH_1):PAGE54
  J6L1  105 VSS<62> SCONN288_H44441003_PIP-SCONN,HA    I43 @BASEBOARD_FAB2_LIB.BASEBOARD_FAB2(SCH_1):PAGE54
  J6L1  103 VSS<63> SCONN288_H44441003_PIP-SCONN,HA    I43 @BASEBOARD_FAB2_LIB.BASEBOARD_FAB2(SCH_1):PAGE54
  J6L1  101 VSS<64> SCONN288_H44441003_PIP-SCONN,HA    I43 @BASEBOARD_FAB2_LIB.BASEBOARD_FAB2(SCH_1):PAGE54
  J6L1   98 VSS<65> SCONN288_H44441003_PIP-SCONN,HA    I43 @BASEBOARD_FAB2_LIB.BASEBOARD_FAB2(SCH_1):PAGE54
  J6L1   96 VSS<66> SCONN288_H44441003_PIP-SCONN,HA    I43 @BASEBOARD_FAB2_LIB.BASEBOARD_FAB2(SCH_1):PAGE54
  J6L1   94 VSS<67> SCONN288_H44441003_PIP-SCONN,HA    I43 @BASEBOARD_FAB2_LIB.BASEBOARD_FAB2(SCH_1):PAGE54
  J6L1   57 VSS<68> SCONN288_H44441003_PIP-SCONN,HA    I43 @BASEBOARD_FAB2_LIB.BASEBOARD_FAB2(SCH_1):PAGE54
  J6L1   55 VSS<69> SCONN288_H44441003_PIP-SCONN,HA    I43 @BASEBOARD_FAB2_LIB.BASEBOARD_FAB2(SCH_1):PAGE54
  J6L1   53 VSS<70> SCONN288_H44441003_PIP-SCONN,HA    I43 @BASEBOARD_FAB2_LIB.BASEBOARD_FAB2(SCH_1):PAGE54
  J6L1   50 VSS<71> SCONN288_H44441003_PIP-SCONN,HA    I43 @BASEBOARD_FAB2_LIB.BASEBOARD_FAB2(SCH_1):PAGE54
  J6L1   48 VSS<72> SCONN288_H44441003_PIP-SCONN,HA    I43 @BASEBOARD_FAB2_LIB.BASEBOARD_FAB2(SCH_1):PAGE54
  J6L1   46 VSS<73> SCONN288_H44441003_PIP-SCONN,HA    I43 @BASEBOARD_FAB2_LIB.BASEBOARD_FAB2(SCH_1):PAGE54
  J6L1   44 VSS<74> SCONN288_H44441003_PIP-SCONN,HA    I43 @BASEBOARD_FAB2_LIB.BASEBOARD_FAB2(SCH_1):PAGE54
  J6L1   42 VSS<75> SCONN288_H44441003_PIP-SCONN,HA    I43 @BASEBOARD_FAB2_LIB.BASEBOARD_FAB2(SCH_1):PAGE54
  J6L1   39 VSS<76> SCONN288_H44441003_PIP-SCONN,HA    I43 @BASEBOARD_FAB2_LIB.BASEBOARD_FAB2(SCH_1):PAGE54
  J6L1   37 VSS<77> SCONN288_H44441003_PIP-SCONN,HA    I43 @BASEBOARD_FAB2_LIB.BASEBOARD_FAB2(SCH_1):PAGE54
  J6L1   35 VSS<78> SCONN288_H44441003_PIP-SCONN,HA    I43 @BASEBOARD_FAB2_LIB.BASEBOARD_FAB2(SCH_1):PAGE54
  J6L1   33 VSS<79> SCONN288_H44441003_PIP-SCONN,HA    I43 @BASEBOARD_FAB2_LIB.BASEBOARD_FAB2(SCH_1):PAGE54
  J6L1   31 VSS<80> SCONN288_H44441003_PIP-SCONN,HA    I43 @BASEBOARD_FAB2_LIB.BASEBOARD_FAB2(SCH_1):PAGE54
  J6L1   28 VSS<81> SCONN288_H44441003_PIP-SCONN,HA    I43 @BASEBOARD_FAB2_LIB.BASEBOARD_FAB2(SCH_1):PAGE54
  J6L1   26 VSS<82> SCONN288_H44441003_PIP-SCONN,HA    I43 @BASEBOARD_FAB2_LIB.BASEBOARD_FAB2(SCH_1):PAGE54
  J6L1   24 VSS<83> SCONN288_H44441003_PIP-SCONN,HA    I43 @BASEBOARD_FAB2_LIB.BASEBOARD_FAB2(SCH_1):PAGE54
  J6L1   22 VSS<84> SCONN288_H44441003_PIP-SCONN,HA    I43 @BASEBOARD_FAB2_LIB.BASEBOARD_FAB2(SCH_1):PAGE54
  J6L1   20 VSS<85> SCONN288_H44441003_PIP-SCONN,HA    I43 @BASEBOARD_FAB2_LIB.BASEBOARD_FAB2(SCH_1):PAGE54
  J6L1   17 VSS<86> SCONN288_H44441003_PIP-SCONN,HA    I43 @BASEBOARD_FAB2_LIB.BASEBOARD_FAB2(SCH_1):PAGE54
  J6L1   15 VSS<87> SCONN288_H44441003_PIP-SCONN,HA    I43 @BASEBOARD_FAB2_LIB.BASEBOARD_FAB2(SCH_1):PAGE54
  J6L1   13 VSS<88> SCONN288_H44441003_PIP-SCONN,HA    I43 @BASEBOARD_FAB2_LIB.BASEBOARD_FAB2(SCH_1):PAGE54
  J6L1   11 VSS<89> SCONN288_H44441003_PIP-SCONN,HA    I43 @BASEBOARD_FAB2_LIB.BASEBOARD_FAB2(SCH_1):PAGE54
  J6L1    9 VSS<90> SCONN288_H44441003_PIP-SCONN,HA    I43 @BASEBOARD_FAB2_LIB.BASEBOARD_FAB2(SCH_1):PAGE54
  J6L1    6 VSS<91> SCONN288_H44441003_PIP-SCONN,HA    I43 @BASEBOARD_FAB2_LIB.BASEBOARD_FAB2(SCH_1):PAGE54
  J6L1    4 VSS<92> SCONN288_H44441003_PIP-SCONN,HA    I43 @BASEBOARD_FAB2_LIB.BASEBOARD_FAB2(SCH_1):PAGE54
  J6L1    2 VSS<93> SCONN288_H44441003_PIP-SCONN,HA    I43 @BASEBOARD_FAB2_LIB.BASEBOARD_FAB2(SCH_1):PAGE54
  J6L1  140  SA<1> SCONN288_H44441003_PIP-SCONN,HA   I111 @BASEBOARD_FAB2_LIB.BASEBOARD_FAB2(SCH_1):PAGE54
  C4A5    2      B CAP_A_0402V-0.01UF,25V,10%,X7RA   I179 @BASEBOARD_FAB2_LIB.BASEBOARD_FAB2(SCH_1):PAGE54
 R7P19    2      B RES_0402-100.0,1%,1/16W,CHIP,GA   I115 @BASEBOARD_FAB2_LIB.BASEBOARD_FAB2(SCH_1):PAGE55
  R3D1    2      B RES_0402-90.9,1%,1/16W,CHIP,G2A   I116 @BASEBOARD_FAB2_LIB.BASEBOARD_FAB2(SCH_1):PAGE55
  R3D2    2      B RES_0402-90.9,1%,1/16W,CHIP,G2A   I117 @BASEBOARD_FAB2_LIB.BASEBOARD_FAB2(SCH_1):PAGE55
  R3D3    2      B RES_0402-100.0,1%,1/16W,CHIP,GA   I118 @BASEBOARD_FAB2_LIB.BASEBOARD_FAB2(SCH_1):PAGE55
 R7P16    2      B RES_0402-90.9,1%,1/16W,CHIP,G2A   I119 @BASEBOARD_FAB2_LIB.BASEBOARD_FAB2(SCH_1):PAGE55
  R7P8    2      B RES_0402-49.9,1%,1/16W,CHIP,G2A   I123 @BASEBOARD_FAB2_LIB.BASEBOARD_FAB2(SCH_1):PAGE55
 R7P10    2      B RES_0402-49.9,1%,1/16W,CHIP,G2A   I124 @BASEBOARD_FAB2_LIB.BASEBOARD_FAB2(SCH_1):PAGE55
 R3D19    2      B RES_0402-49.9,1%,1/16W,CHIP,G2A   I125 @BASEBOARD_FAB2_LIB.BASEBOARD_FAB2(SCH_1):PAGE55
 R7P11    2      B RES_0402-49.9,1%,1/16W,CHIP,G2A   I126 @BASEBOARD_FAB2_LIB.BASEBOARD_FAB2(SCH_1):PAGE55
 R7P17    2      B RES_0402-90.9,1%,1/16W,CHIP,G2A   I140 @BASEBOARD_FAB2_LIB.BASEBOARD_FAB2(SCH_1):PAGE55
  R3D4    2      B RES_0402-49.9,1%,1/16W,CHIP,G2A   I155 @BASEBOARD_FAB2_LIB.BASEBOARD_FAB2(SCH_1):PAGE55
  R8P3    2      B RES_0402-49.9,1%,1/16W,CHIP,G2A   I173 @BASEBOARD_FAB2_LIB.BASEBOARD_FAB2(SCH_1):PAGE56
  R8R1    2      B RES_0402-49.9,1%,1/16W,CHIP,G2A   I174 @BASEBOARD_FAB2_LIB.BASEBOARD_FAB2(SCH_1):PAGE56
  U2D1 DF23 UPI2_RX_DN<0> SKX_EXT_B_BGA1-IC,TBD     I1 @BASEBOARD_FAB2_LIB.BASEBOARD_FAB2(SCH_1):PAGE69
  U2D1 DE22 UPI2_RX_DN<1> SKX_EXT_B_BGA1-IC,TBD     I1 @BASEBOARD_FAB2_LIB.BASEBOARD_FAB2(SCH_1):PAGE69
  U2D1 DC22 UPI2_RX_DN<2> SKX_EXT_B_BGA1-IC,TBD     I1 @BASEBOARD_FAB2_LIB.BASEBOARD_FAB2(SCH_1):PAGE69
  U2D1 DB21 UPI2_RX_DN<3> SKX_EXT_B_BGA1-IC,TBD     I1 @BASEBOARD_FAB2_LIB.BASEBOARD_FAB2(SCH_1):PAGE69
  U2D1 DD19 UPI2_RX_DN<4> SKX_EXT_B_BGA1-IC,TBD     I1 @BASEBOARD_FAB2_LIB.BASEBOARD_FAB2(SCH_1):PAGE69
  U2D1 DA20 UPI2_RX_DN<5> SKX_EXT_B_BGA1-IC,TBD     I1 @BASEBOARD_FAB2_LIB.BASEBOARD_FAB2(SCH_1):PAGE69
  U2D1 CW20 UPI2_RX_DN<6> SKX_EXT_B_BGA1-IC,TBD     I1 @BASEBOARD_FAB2_LIB.BASEBOARD_FAB2(SCH_1):PAGE69
  U2D1 CV19 UPI2_RX_DN<7> SKX_EXT_B_BGA1-IC,TBD     I1 @BASEBOARD_FAB2_LIB.BASEBOARD_FAB2(SCH_1):PAGE69
  U2D1 CT21 UPI2_RX_DN<8> SKX_EXT_B_BGA1-IC,TBD     I1 @BASEBOARD_FAB2_LIB.BASEBOARD_FAB2(SCH_1):PAGE69
  U2D1 CR18 UPI2_RX_DN<9> SKX_EXT_B_BGA1-IC,TBD     I1 @BASEBOARD_FAB2_LIB.BASEBOARD_FAB2(SCH_1):PAGE69
  U2D1 CN20 UPI2_RX_DN<10> SKX_EXT_B_BGA1-IC,TBD     I1 @BASEBOARD_FAB2_LIB.BASEBOARD_FAB2(SCH_1):PAGE69
  U2D1 CP21 UPI2_RX_DN<11> SKX_EXT_B_BGA1-IC,TBD     I1 @BASEBOARD_FAB2_LIB.BASEBOARD_FAB2(SCH_1):PAGE69
  U2D1 CL16 UPI2_RX_DN<12> SKX_EXT_B_BGA1-IC,TBD     I1 @BASEBOARD_FAB2_LIB.BASEBOARD_FAB2(SCH_1):PAGE69
  U2D1 CJ18 UPI2_RX_DN<13> SKX_EXT_B_BGA1-IC,TBD     I1 @BASEBOARD_FAB2_LIB.BASEBOARD_FAB2(SCH_1):PAGE69
  U2D1 CH17 UPI2_RX_DN<14> SKX_EXT_B_BGA1-IC,TBD     I1 @BASEBOARD_FAB2_LIB.BASEBOARD_FAB2(SCH_1):PAGE69
  U2D1 CE16 UPI2_RX_DN<15> SKX_EXT_B_BGA1-IC,TBD     I1 @BASEBOARD_FAB2_LIB.BASEBOARD_FAB2(SCH_1):PAGE69
  U2D1 CD15 UPI2_RX_DN<16> SKX_EXT_B_BGA1-IC,TBD     I1 @BASEBOARD_FAB2_LIB.BASEBOARD_FAB2(SCH_1):PAGE69
  U2D1 CF17 UPI2_RX_DN<17> SKX_EXT_B_BGA1-IC,TBD     I1 @BASEBOARD_FAB2_LIB.BASEBOARD_FAB2(SCH_1):PAGE69
  U2D1 CB15 UPI2_RX_DN<18> SKX_EXT_B_BGA1-IC,TBD     I1 @BASEBOARD_FAB2_LIB.BASEBOARD_FAB2(SCH_1):PAGE69
  U2D1 BY17 UPI2_RX_DN<19> SKX_EXT_B_BGA1-IC,TBD     I1 @BASEBOARD_FAB2_LIB.BASEBOARD_FAB2(SCH_1):PAGE69
  U2D1 DG22 UPI2_RX_DP<0> SKX_EXT_B_BGA1-IC,TBD     I1 @BASEBOARD_FAB2_LIB.BASEBOARD_FAB2(SCH_1):PAGE69
  U2D1 DD21 UPI2_RX_DP<1> SKX_EXT_B_BGA1-IC,TBD     I1 @BASEBOARD_FAB2_LIB.BASEBOARD_FAB2(SCH_1):PAGE69
  U2D1 DA22 UPI2_RX_DP<2> SKX_EXT_B_BGA1-IC,TBD     I1 @BASEBOARD_FAB2_LIB.BASEBOARD_FAB2(SCH_1):PAGE69
  U2D1 DC20 UPI2_RX_DP<3> SKX_EXT_B_BGA1-IC,TBD     I1 @BASEBOARD_FAB2_LIB.BASEBOARD_FAB2(SCH_1):PAGE69
  U2D1 DB19 UPI2_RX_DP<4> SKX_EXT_B_BGA1-IC,TBD     I1 @BASEBOARD_FAB2_LIB.BASEBOARD_FAB2(SCH_1):PAGE69
  U2D1 CY19 UPI2_RX_DP<5> SKX_EXT_B_BGA1-IC,TBD     I1 @BASEBOARD_FAB2_LIB.BASEBOARD_FAB2(SCH_1):PAGE69
  U2D1 CU20 UPI2_RX_DP<6> SKX_EXT_B_BGA1-IC,TBD     I1 @BASEBOARD_FAB2_LIB.BASEBOARD_FAB2(SCH_1):PAGE69
  U2D1 CW18 UPI2_RX_DP<7> SKX_EXT_B_BGA1-IC,TBD     I1 @BASEBOARD_FAB2_LIB.BASEBOARD_FAB2(SCH_1):PAGE69
  U2D1 CR20 UPI2_RX_DP<8> SKX_EXT_B_BGA1-IC,TBD     I1 @BASEBOARD_FAB2_LIB.BASEBOARD_FAB2(SCH_1):PAGE69
  U2D1 CN18 UPI2_RX_DP<9> SKX_EXT_B_BGA1-IC,TBD     I1 @BASEBOARD_FAB2_LIB.BASEBOARD_FAB2(SCH_1):PAGE69
  U2D1 CP19 UPI2_RX_DP<10> SKX_EXT_B_BGA1-IC,TBD     I1 @BASEBOARD_FAB2_LIB.BASEBOARD_FAB2(SCH_1):PAGE69
  U2D1 CM21 UPI2_RX_DP<11> SKX_EXT_B_BGA1-IC,TBD     I1 @BASEBOARD_FAB2_LIB.BASEBOARD_FAB2(SCH_1):PAGE69
  U2D1 CJ16 UPI2_RX_DP<12> SKX_EXT_B_BGA1-IC,TBD     I1 @BASEBOARD_FAB2_LIB.BASEBOARD_FAB2(SCH_1):PAGE69
  U2D1 CK17 UPI2_RX_DP<13> SKX_EXT_B_BGA1-IC,TBD     I1 @BASEBOARD_FAB2_LIB.BASEBOARD_FAB2(SCH_1):PAGE69
  U2D1 CG16 UPI2_RX_DP<14> SKX_EXT_B_BGA1-IC,TBD     I1 @BASEBOARD_FAB2_LIB.BASEBOARD_FAB2(SCH_1):PAGE69
  U2D1 CF15 UPI2_RX_DP<15> SKX_EXT_B_BGA1-IC,TBD     I1 @BASEBOARD_FAB2_LIB.BASEBOARD_FAB2(SCH_1):PAGE69
  U2D1 CC14 UPI2_RX_DP<16> SKX_EXT_B_BGA1-IC,TBD     I1 @BASEBOARD_FAB2_LIB.BASEBOARD_FAB2(SCH_1):PAGE69
  U2D1 CD17 UPI2_RX_DP<17> SKX_EXT_B_BGA1-IC,TBD     I1 @BASEBOARD_FAB2_LIB.BASEBOARD_FAB2(SCH_1):PAGE69
  U2D1 BY15 UPI2_RX_DP<18> SKX_EXT_B_BGA1-IC,TBD     I1 @BASEBOARD_FAB2_LIB.BASEBOARD_FAB2(SCH_1):PAGE69
  U2D1 CA16 UPI2_RX_DP<19> SKX_EXT_B_BGA1-IC,TBD     I1 @BASEBOARD_FAB2_LIB.BASEBOARD_FAB2(SCH_1):PAGE69
 R3D27    2      B RES_0402-249,0.1%,1/16W,CHIP,GA    I43 @BASEBOARD_FAB2_LIB.BASEBOARD_FAB2(SCH_1):PAGE71
  C3D3    2      B CAP_0603LF-10UF,4V,20%,X6S,E15A    I25 @BASEBOARD_FAB2_LIB.BASEBOARD_FAB2(SCH_1):PAGE72
  U2D1  J74 VSS<1094> SKX_EXT_B_BGA1-IC,TBD    I20 @BASEBOARD_FAB2_LIB.BASEBOARD_FAB2(SCH_1):PAGE74
  U2D1  J72 VSS<1095> SKX_EXT_B_BGA1-IC,TBD    I20 @BASEBOARD_FAB2_LIB.BASEBOARD_FAB2(SCH_1):PAGE74
  U2D1  J40 VSS<1096> SKX_EXT_B_BGA1-IC,TBD    I20 @BASEBOARD_FAB2_LIB.BASEBOARD_FAB2(SCH_1):PAGE74
  U2D1  J38 VSS<1097> SKX_EXT_B_BGA1-IC,TBD    I20 @BASEBOARD_FAB2_LIB.BASEBOARD_FAB2(SCH_1):PAGE74
  U2D1  J34 VSS<1098> SKX_EXT_B_BGA1-IC,TBD    I20 @BASEBOARD_FAB2_LIB.BASEBOARD_FAB2(SCH_1):PAGE74
  U2D1  J32 VSS<1099> SKX_EXT_B_BGA1-IC,TBD    I20 @BASEBOARD_FAB2_LIB.BASEBOARD_FAB2(SCH_1):PAGE74
  U2D1  J28 VSS<1100> SKX_EXT_B_BGA1-IC,TBD    I20 @BASEBOARD_FAB2_LIB.BASEBOARD_FAB2(SCH_1):PAGE74
  U2D1  J26 VSS<1101> SKX_EXT_B_BGA1-IC,TBD    I20 @BASEBOARD_FAB2_LIB.BASEBOARD_FAB2(SCH_1):PAGE74
  U2D1  J22 VSS<1102> SKX_EXT_B_BGA1-IC,TBD    I20 @BASEBOARD_FAB2_LIB.BASEBOARD_FAB2(SCH_1):PAGE74
  U2D1  J14 VSS<1103> SKX_EXT_B_BGA1-IC,TBD    I20 @BASEBOARD_FAB2_LIB.BASEBOARD_FAB2(SCH_1):PAGE74
  U2D1  J12 VSS<1104> SKX_EXT_B_BGA1-IC,TBD    I20 @BASEBOARD_FAB2_LIB.BASEBOARD_FAB2(SCH_1):PAGE74
  U2D1   J4 VSS<1105> SKX_EXT_B_BGA1-IC,TBD    I20 @BASEBOARD_FAB2_LIB.BASEBOARD_FAB2(SCH_1):PAGE74
  U2D1 DN44 VSS<1106> SKX_EXT_B_BGA1-IC,TBD    I20 @BASEBOARD_FAB2_LIB.BASEBOARD_FAB2(SCH_1):PAGE74
  U2D1  H75 VSS<1107> SKX_EXT_B_BGA1-IC,TBD    I20 @BASEBOARD_FAB2_LIB.BASEBOARD_FAB2(SCH_1):PAGE74
  U2D1  H71 VSS<1108> SKX_EXT_B_BGA1-IC,TBD    I20 @BASEBOARD_FAB2_LIB.BASEBOARD_FAB2(SCH_1):PAGE74
  U2D1  H65 VSS<1109> SKX_EXT_B_BGA1-IC,TBD    I20 @BASEBOARD_FAB2_LIB.BASEBOARD_FAB2(SCH_1):PAGE74
  U2D1  H41 VSS<1110> SKX_EXT_B_BGA1-IC,TBD    I20 @BASEBOARD_FAB2_LIB.BASEBOARD_FAB2(SCH_1):PAGE74
  U2D1  H39 VSS<1111> SKX_EXT_B_BGA1-IC,TBD    I20 @BASEBOARD_FAB2_LIB.BASEBOARD_FAB2(SCH_1):PAGE74
  U2D1  H37 VSS<1112> SKX_EXT_B_BGA1-IC,TBD    I20 @BASEBOARD_FAB2_LIB.BASEBOARD_FAB2(SCH_1):PAGE74
  U2D1  H35 VSS<1113> SKX_EXT_B_BGA1-IC,TBD    I20 @BASEBOARD_FAB2_LIB.BASEBOARD_FAB2(SCH_1):PAGE74
  U2D1  H33 VSS<1114> SKX_EXT_B_BGA1-IC,TBD    I20 @BASEBOARD_FAB2_LIB.BASEBOARD_FAB2(SCH_1):PAGE74
  U2D1  H31 VSS<1115> SKX_EXT_B_BGA1-IC,TBD    I20 @BASEBOARD_FAB2_LIB.BASEBOARD_FAB2(SCH_1):PAGE74
  U2D1  H29 VSS<1116> SKX_EXT_B_BGA1-IC,TBD    I20 @BASEBOARD_FAB2_LIB.BASEBOARD_FAB2(SCH_1):PAGE74
  U2D1  H27 VSS<1117> SKX_EXT_B_BGA1-IC,TBD    I20 @BASEBOARD_FAB2_LIB.BASEBOARD_FAB2(SCH_1):PAGE74
  U2D1  H25 VSS<1118> SKX_EXT_B_BGA1-IC,TBD    I20 @BASEBOARD_FAB2_LIB.BASEBOARD_FAB2(SCH_1):PAGE74
  U2D1  H11 VSS<1119> SKX_EXT_B_BGA1-IC,TBD    I20 @BASEBOARD_FAB2_LIB.BASEBOARD_FAB2(SCH_1):PAGE74
  U2D1   H3 VSS<1120> SKX_EXT_B_BGA1-IC,TBD    I20 @BASEBOARD_FAB2_LIB.BASEBOARD_FAB2(SCH_1):PAGE74
  U2D1  G82 VSS<1121> SKX_EXT_B_BGA1-IC,TBD    I20 @BASEBOARD_FAB2_LIB.BASEBOARD_FAB2(SCH_1):PAGE74
  U2D1  G80 VSS<1122> SKX_EXT_B_BGA1-IC,TBD    I20 @BASEBOARD_FAB2_LIB.BASEBOARD_FAB2(SCH_1):PAGE74
  U2D1  G78 VSS<1123> SKX_EXT_B_BGA1-IC,TBD    I20 @BASEBOARD_FAB2_LIB.BASEBOARD_FAB2(SCH_1):PAGE74
  U2D1  G76 VSS<1124> SKX_EXT_B_BGA1-IC,TBD    I20 @BASEBOARD_FAB2_LIB.BASEBOARD_FAB2(SCH_1):PAGE74
  U2D1  G70 VSS<1125> SKX_EXT_B_BGA1-IC,TBD    I20 @BASEBOARD_FAB2_LIB.BASEBOARD_FAB2(SCH_1):PAGE74
  U2D1  G66 VSS<1126> SKX_EXT_B_BGA1-IC,TBD    I20 @BASEBOARD_FAB2_LIB.BASEBOARD_FAB2(SCH_1):PAGE74
  U2D1  G42 VSS<1127> SKX_EXT_B_BGA1-IC,TBD    I20 @BASEBOARD_FAB2_LIB.BASEBOARD_FAB2(SCH_1):PAGE74
  U2D1  G38 VSS<1128> SKX_EXT_B_BGA1-IC,TBD    I20 @BASEBOARD_FAB2_LIB.BASEBOARD_FAB2(SCH_1):PAGE74
  U2D1  G36 VSS<1129> SKX_EXT_B_BGA1-IC,TBD    I20 @BASEBOARD_FAB2_LIB.BASEBOARD_FAB2(SCH_1):PAGE74
  U2D1  G32 VSS<1130> SKX_EXT_B_BGA1-IC,TBD    I20 @BASEBOARD_FAB2_LIB.BASEBOARD_FAB2(SCH_1):PAGE74
  U2D1  G30 VSS<1131> SKX_EXT_B_BGA1-IC,TBD    I20 @BASEBOARD_FAB2_LIB.BASEBOARD_FAB2(SCH_1):PAGE74
  U2D1  G26 VSS<1132> SKX_EXT_B_BGA1-IC,TBD    I20 @BASEBOARD_FAB2_LIB.BASEBOARD_FAB2(SCH_1):PAGE74
  U2D1  G24 VSS<1133> SKX_EXT_B_BGA1-IC,TBD    I20 @BASEBOARD_FAB2_LIB.BASEBOARD_FAB2(SCH_1):PAGE74
  U2D1  G22 VSS<1134> SKX_EXT_B_BGA1-IC,TBD    I20 @BASEBOARD_FAB2_LIB.BASEBOARD_FAB2(SCH_1):PAGE74
  U2D1   G8 VSS<1135> SKX_EXT_B_BGA1-IC,TBD    I20 @BASEBOARD_FAB2_LIB.BASEBOARD_FAB2(SCH_1):PAGE74
  U2D1   G4 VSS<1136> SKX_EXT_B_BGA1-IC,TBD    I20 @BASEBOARD_FAB2_LIB.BASEBOARD_FAB2(SCH_1):PAGE74
  U2D1  F69 VSS<1137> SKX_EXT_B_BGA1-IC,TBD    I20 @BASEBOARD_FAB2_LIB.BASEBOARD_FAB2(SCH_1):PAGE74
  U2D1  F67 VSS<1138> SKX_EXT_B_BGA1-IC,TBD    I20 @BASEBOARD_FAB2_LIB.BASEBOARD_FAB2(SCH_1):PAGE74
  U2D1  F43 VSS<1139> SKX_EXT_B_BGA1-IC,TBD    I20 @BASEBOARD_FAB2_LIB.BASEBOARD_FAB2(SCH_1):PAGE74
  U2D1  F37 VSS<1140> SKX_EXT_B_BGA1-IC,TBD    I20 @BASEBOARD_FAB2_LIB.BASEBOARD_FAB2(SCH_1):PAGE74
  U2D1  F31 VSS<1141> SKX_EXT_B_BGA1-IC,TBD    I20 @BASEBOARD_FAB2_LIB.BASEBOARD_FAB2(SCH_1):PAGE74
  U2D1  F25 VSS<1142> SKX_EXT_B_BGA1-IC,TBD    I20 @BASEBOARD_FAB2_LIB.BASEBOARD_FAB2(SCH_1):PAGE74
  U2D1  F19 VSS<1143> SKX_EXT_B_BGA1-IC,TBD    I20 @BASEBOARD_FAB2_LIB.BASEBOARD_FAB2(SCH_1):PAGE74
  U2D1  F17 VSS<1144> SKX_EXT_B_BGA1-IC,TBD    I20 @BASEBOARD_FAB2_LIB.BASEBOARD_FAB2(SCH_1):PAGE74
  U2D1   F5 VSS<1145> SKX_EXT_B_BGA1-IC,TBD    I20 @BASEBOARD_FAB2_LIB.BASEBOARD_FAB2(SCH_1):PAGE74
  U2D1  E76 VSS<1146> SKX_EXT_B_BGA1-IC,TBD    I20 @BASEBOARD_FAB2_LIB.BASEBOARD_FAB2(SCH_1):PAGE74
  U2D1  E74 VSS<1147> SKX_EXT_B_BGA1-IC,TBD    I20 @BASEBOARD_FAB2_LIB.BASEBOARD_FAB2(SCH_1):PAGE74
  U2D1  E72 VSS<1148> SKX_EXT_B_BGA1-IC,TBD    I20 @BASEBOARD_FAB2_LIB.BASEBOARD_FAB2(SCH_1):PAGE74
  U2D1  E22 VSS<1149> SKX_EXT_B_BGA1-IC,TBD    I20 @BASEBOARD_FAB2_LIB.BASEBOARD_FAB2(SCH_1):PAGE74
  U2D1  E20 VSS<1150> SKX_EXT_B_BGA1-IC,TBD    I20 @BASEBOARD_FAB2_LIB.BASEBOARD_FAB2(SCH_1):PAGE74
  U2D1  E18 VSS<1151> SKX_EXT_B_BGA1-IC,TBD    I20 @BASEBOARD_FAB2_LIB.BASEBOARD_FAB2(SCH_1):PAGE74
  U2D1  E16 VSS<1152> SKX_EXT_B_BGA1-IC,TBD    I20 @BASEBOARD_FAB2_LIB.BASEBOARD_FAB2(SCH_1):PAGE74
  U2D1   E8 VSS<1153> SKX_EXT_B_BGA1-IC,TBD    I20 @BASEBOARD_FAB2_LIB.BASEBOARD_FAB2(SCH_1):PAGE74
  U2D1   E6 VSS<1154> SKX_EXT_B_BGA1-IC,TBD    I20 @BASEBOARD_FAB2_LIB.BASEBOARD_FAB2(SCH_1):PAGE74
  U2D1  D77 VSS<1155> SKX_EXT_B_BGA1-IC,TBD    I20 @BASEBOARD_FAB2_LIB.BASEBOARD_FAB2(SCH_1):PAGE74
  U2D1  D43 VSS<1156> SKX_EXT_B_BGA1-IC,TBD    I20 @BASEBOARD_FAB2_LIB.BASEBOARD_FAB2(SCH_1):PAGE74
  U2D1  D41 VSS<1157> SKX_EXT_B_BGA1-IC,TBD    I20 @BASEBOARD_FAB2_LIB.BASEBOARD_FAB2(SCH_1):PAGE74
  U2D1  D39 VSS<1158> SKX_EXT_B_BGA1-IC,TBD    I20 @BASEBOARD_FAB2_LIB.BASEBOARD_FAB2(SCH_1):PAGE74
  U2D1  D37 VSS<1159> SKX_EXT_B_BGA1-IC,TBD    I20 @BASEBOARD_FAB2_LIB.BASEBOARD_FAB2(SCH_1):PAGE74
  U2D1  D35 VSS<1160> SKX_EXT_B_BGA1-IC,TBD    I20 @BASEBOARD_FAB2_LIB.BASEBOARD_FAB2(SCH_1):PAGE74
  U2D1  D33 VSS<1161> SKX_EXT_B_BGA1-IC,TBD    I20 @BASEBOARD_FAB2_LIB.BASEBOARD_FAB2(SCH_1):PAGE74
  U2D1  D31 VSS<1162> SKX_EXT_B_BGA1-IC,TBD    I20 @BASEBOARD_FAB2_LIB.BASEBOARD_FAB2(SCH_1):PAGE74
  U2D1  D29 VSS<1163> SKX_EXT_B_BGA1-IC,TBD    I20 @BASEBOARD_FAB2_LIB.BASEBOARD_FAB2(SCH_1):PAGE74
  U2D1  D27 VSS<1164> SKX_EXT_B_BGA1-IC,TBD    I20 @BASEBOARD_FAB2_LIB.BASEBOARD_FAB2(SCH_1):PAGE74
  U2D1  D25 VSS<1165> SKX_EXT_B_BGA1-IC,TBD    I20 @BASEBOARD_FAB2_LIB.BASEBOARD_FAB2(SCH_1):PAGE74
  U2D1  D13 VSS<1166> SKX_EXT_B_BGA1-IC,TBD    I20 @BASEBOARD_FAB2_LIB.BASEBOARD_FAB2(SCH_1):PAGE74
  U2D1  D11 VSS<1167> SKX_EXT_B_BGA1-IC,TBD    I20 @BASEBOARD_FAB2_LIB.BASEBOARD_FAB2(SCH_1):PAGE74
  U2D1 CM27 VSS<1168> SKX_EXT_B_BGA1-IC,TBD    I20 @BASEBOARD_FAB2_LIB.BASEBOARD_FAB2(SCH_1):PAGE74
  U2D1  C78 VSS<1169> SKX_EXT_B_BGA1-IC,TBD    I20 @BASEBOARD_FAB2_LIB.BASEBOARD_FAB2(SCH_1):PAGE74
  U2D1  C76 VSS<1170> SKX_EXT_B_BGA1-IC,TBD    I20 @BASEBOARD_FAB2_LIB.BASEBOARD_FAB2(SCH_1):PAGE74
  U2D1  C16 VSS<1171> SKX_EXT_B_BGA1-IC,TBD    I20 @BASEBOARD_FAB2_LIB.BASEBOARD_FAB2(SCH_1):PAGE74
  U2D1  C14 VSS<1172> SKX_EXT_B_BGA1-IC,TBD    I20 @BASEBOARD_FAB2_LIB.BASEBOARD_FAB2(SCH_1):PAGE74
  U2D1  C12 VSS<1173> SKX_EXT_B_BGA1-IC,TBD    I20 @BASEBOARD_FAB2_LIB.BASEBOARD_FAB2(SCH_1):PAGE74
  U2D1  C10 VSS<1174> SKX_EXT_B_BGA1-IC,TBD    I20 @BASEBOARD_FAB2_LIB.BASEBOARD_FAB2(SCH_1):PAGE74
  U2D1   C8 VSS<1175> SKX_EXT_B_BGA1-IC,TBD    I20 @BASEBOARD_FAB2_LIB.BASEBOARD_FAB2(SCH_1):PAGE74
  U2D1  B75 VSS<1176> SKX_EXT_B_BGA1-IC,TBD    I20 @BASEBOARD_FAB2_LIB.BASEBOARD_FAB2(SCH_1):PAGE74
  U2D1  B71 VSS<1177> SKX_EXT_B_BGA1-IC,TBD    I20 @BASEBOARD_FAB2_LIB.BASEBOARD_FAB2(SCH_1):PAGE74
  U2D1  B37 VSS<1178> SKX_EXT_B_BGA1-IC,TBD    I20 @BASEBOARD_FAB2_LIB.BASEBOARD_FAB2(SCH_1):PAGE74
  U2D1  B31 VSS<1179> SKX_EXT_B_BGA1-IC,TBD    I20 @BASEBOARD_FAB2_LIB.BASEBOARD_FAB2(SCH_1):PAGE74
  U2D1  B25 VSS<1180> SKX_EXT_B_BGA1-IC,TBD    I20 @BASEBOARD_FAB2_LIB.BASEBOARD_FAB2(SCH_1):PAGE74
  U2D1  A38 VSS<1181> SKX_EXT_B_BGA1-IC,TBD    I20 @BASEBOARD_FAB2_LIB.BASEBOARD_FAB2(SCH_1):PAGE74
  U2D1  A36 VSS<1182> SKX_EXT_B_BGA1-IC,TBD    I20 @BASEBOARD_FAB2_LIB.BASEBOARD_FAB2(SCH_1):PAGE74
  U2D1  A32 VSS<1183> SKX_EXT_B_BGA1-IC,TBD    I20 @BASEBOARD_FAB2_LIB.BASEBOARD_FAB2(SCH_1):PAGE74
  U2D1  A30 VSS<1184> SKX_EXT_B_BGA1-IC,TBD    I20 @BASEBOARD_FAB2_LIB.BASEBOARD_FAB2(SCH_1):PAGE74
  U2D1  A26 VSS<1185> SKX_EXT_B_BGA1-IC,TBD    I20 @BASEBOARD_FAB2_LIB.BASEBOARD_FAB2(SCH_1):PAGE74
  U2D1 AC58 VSS<1186> SKX_EXT_B_BGA1-IC,TBD    I20 @BASEBOARD_FAB2_LIB.BASEBOARD_FAB2(SCH_1):PAGE74
  U2D1 AC60 VSS<1187> SKX_EXT_B_BGA1-IC,TBD    I20 @BASEBOARD_FAB2_LIB.BASEBOARD_FAB2(SCH_1):PAGE74
  U2D1 AC62 VSS<1188> SKX_EXT_B_BGA1-IC,TBD    I20 @BASEBOARD_FAB2_LIB.BASEBOARD_FAB2(SCH_1):PAGE74
  U2D1  AJ4 VSS<1189> SKX_EXT_B_BGA1-IC,TBD    I20 @BASEBOARD_FAB2_LIB.BASEBOARD_FAB2(SCH_1):PAGE74
  U2D1  AR6 VSS<1190> SKX_EXT_B_BGA1-IC,TBD    I20 @BASEBOARD_FAB2_LIB.BASEBOARD_FAB2(SCH_1):PAGE74
  U2D1  CG6 VSS<1191> SKX_EXT_B_BGA1-IC,TBD    I20 @BASEBOARD_FAB2_LIB.BASEBOARD_FAB2(SCH_1):PAGE74
  U2D1  CW6 VSS<1192> SKX_EXT_B_BGA1-IC,TBD    I20 @BASEBOARD_FAB2_LIB.BASEBOARD_FAB2(SCH_1):PAGE74
  U2D1 DE48 VSS<1193> SKX_EXT_B_BGA1-IC,TBD    I20 @BASEBOARD_FAB2_LIB.BASEBOARD_FAB2(SCH_1):PAGE74
  U2D1 DE50 VSS<1194> SKX_EXT_B_BGA1-IC,TBD    I20 @BASEBOARD_FAB2_LIB.BASEBOARD_FAB2(SCH_1):PAGE74
  U2D1 DE52 VSS<1195> SKX_EXT_B_BGA1-IC,TBD    I20 @BASEBOARD_FAB2_LIB.BASEBOARD_FAB2(SCH_1):PAGE74
  U2D1 DE54 VSS<1196> SKX_EXT_B_BGA1-IC,TBD    I20 @BASEBOARD_FAB2_LIB.BASEBOARD_FAB2(SCH_1):PAGE74
  U2D1 DE56 VSS<1197> SKX_EXT_B_BGA1-IC,TBD    I20 @BASEBOARD_FAB2_LIB.BASEBOARD_FAB2(SCH_1):PAGE74
  U2D1 DE58 VSS<1198> SKX_EXT_B_BGA1-IC,TBD    I20 @BASEBOARD_FAB2_LIB.BASEBOARD_FAB2(SCH_1):PAGE74
  U2D1 DE60 VSS<1199> SKX_EXT_B_BGA1-IC,TBD    I20 @BASEBOARD_FAB2_LIB.BASEBOARD_FAB2(SCH_1):PAGE74
  U2D1 DE62 VSS<1200> SKX_EXT_B_BGA1-IC,TBD    I20 @BASEBOARD_FAB2_LIB.BASEBOARD_FAB2(SCH_1):PAGE74
  U2D1  DL8 VSS<1201> SKX_EXT_B_BGA1-IC,TBD    I20 @BASEBOARD_FAB2_LIB.BASEBOARD_FAB2(SCH_1):PAGE74
  U2D1 DN18 VSS<1202> SKX_EXT_B_BGA1-IC,TBD    I20 @BASEBOARD_FAB2_LIB.BASEBOARD_FAB2(SCH_1):PAGE74
  U2D1 DP45 VSS<1203> SKX_EXT_B_BGA1-IC,TBD    I20 @BASEBOARD_FAB2_LIB.BASEBOARD_FAB2(SCH_1):PAGE74
  U2D1 DP47 VSS<1204> SKX_EXT_B_BGA1-IC,TBD    I20 @BASEBOARD_FAB2_LIB.BASEBOARD_FAB2(SCH_1):PAGE74
  U2D1 DP49 VSS<1205> SKX_EXT_B_BGA1-IC,TBD    I20 @BASEBOARD_FAB2_LIB.BASEBOARD_FAB2(SCH_1):PAGE74
  U2D1 DP51 VSS<1206> SKX_EXT_B_BGA1-IC,TBD    I20 @BASEBOARD_FAB2_LIB.BASEBOARD_FAB2(SCH_1):PAGE74
  U2D1 DP53 VSS<1207> SKX_EXT_B_BGA1-IC,TBD    I20 @BASEBOARD_FAB2_LIB.BASEBOARD_FAB2(SCH_1):PAGE74
  U2D1 DP55 VSS<1208> SKX_EXT_B_BGA1-IC,TBD    I20 @BASEBOARD_FAB2_LIB.BASEBOARD_FAB2(SCH_1):PAGE74
  U2D1 DP57 VSS<1209> SKX_EXT_B_BGA1-IC,TBD    I20 @BASEBOARD_FAB2_LIB.BASEBOARD_FAB2(SCH_1):PAGE74
  U2D1 DP59 VSS<1210> SKX_EXT_B_BGA1-IC,TBD    I20 @BASEBOARD_FAB2_LIB.BASEBOARD_FAB2(SCH_1):PAGE74
  U2D1 DP61 VSS<1211> SKX_EXT_B_BGA1-IC,TBD    I20 @BASEBOARD_FAB2_LIB.BASEBOARD_FAB2(SCH_1):PAGE74
  U2D1 DP63 VSS<1212> SKX_EXT_B_BGA1-IC,TBD    I20 @BASEBOARD_FAB2_LIB.BASEBOARD_FAB2(SCH_1):PAGE74
  U2D1  DP9 VSS<1213> SKX_EXT_B_BGA1-IC,TBD    I20 @BASEBOARD_FAB2_LIB.BASEBOARD_FAB2(SCH_1):PAGE74
  U2D1 DV19 VSS<1214> SKX_EXT_B_BGA1-IC,TBD    I20 @BASEBOARD_FAB2_LIB.BASEBOARD_FAB2(SCH_1):PAGE74
  U2D1 DY45 VSS<1215> SKX_EXT_B_BGA1-IC,TBD    I20 @BASEBOARD_FAB2_LIB.BASEBOARD_FAB2(SCH_1):PAGE74
  U2D1 DY47 VSS<1216> SKX_EXT_B_BGA1-IC,TBD    I20 @BASEBOARD_FAB2_LIB.BASEBOARD_FAB2(SCH_1):PAGE74
  U2D1 DY49 VSS<1217> SKX_EXT_B_BGA1-IC,TBD    I20 @BASEBOARD_FAB2_LIB.BASEBOARD_FAB2(SCH_1):PAGE74
  U2D1 DY51 VSS<1218> SKX_EXT_B_BGA1-IC,TBD    I20 @BASEBOARD_FAB2_LIB.BASEBOARD_FAB2(SCH_1):PAGE74
  U2D1 DY53 VSS<1219> SKX_EXT_B_BGA1-IC,TBD    I20 @BASEBOARD_FAB2_LIB.BASEBOARD_FAB2(SCH_1):PAGE74
  U2D1 DY55 VSS<1220> SKX_EXT_B_BGA1-IC,TBD    I20 @BASEBOARD_FAB2_LIB.BASEBOARD_FAB2(SCH_1):PAGE74
  U2D1 DY57 VSS<1221> SKX_EXT_B_BGA1-IC,TBD    I20 @BASEBOARD_FAB2_LIB.BASEBOARD_FAB2(SCH_1):PAGE74
  U2D1 DY59 VSS<1222> SKX_EXT_B_BGA1-IC,TBD    I20 @BASEBOARD_FAB2_LIB.BASEBOARD_FAB2(SCH_1):PAGE74
  U2D1 DY61 VSS<1223> SKX_EXT_B_BGA1-IC,TBD    I20 @BASEBOARD_FAB2_LIB.BASEBOARD_FAB2(SCH_1):PAGE74
  U2D1 DY63 VSS<1224> SKX_EXT_B_BGA1-IC,TBD    I20 @BASEBOARD_FAB2_LIB.BASEBOARD_FAB2(SCH_1):PAGE74
  U2D1 EA14 VSS<1225> SKX_EXT_B_BGA1-IC,TBD    I20 @BASEBOARD_FAB2_LIB.BASEBOARD_FAB2(SCH_1):PAGE74
  U2D1   L8 VSS<1226> SKX_EXT_B_BGA1-IC,TBD    I20 @BASEBOARD_FAB2_LIB.BASEBOARD_FAB2(SCH_1):PAGE74
  U2D1  V11 VSS<1227> SKX_EXT_B_BGA1-IC,TBD    I20 @BASEBOARD_FAB2_LIB.BASEBOARD_FAB2(SCH_1):PAGE74
  U2D1  E66 VSS<1228> SKX_EXT_B_BGA1-IC,TBD    I20 @BASEBOARD_FAB2_LIB.BASEBOARD_FAB2(SCH_1):PAGE74
  U2D1 ED69 VSS<1229> SKX_EXT_B_BGA1-IC,TBD    I20 @BASEBOARD_FAB2_LIB.BASEBOARD_FAB2(SCH_1):PAGE74
  U2D1 EE80 VSS<1230> SKX_EXT_B_BGA1-IC,TBD    I20 @BASEBOARD_FAB2_LIB.BASEBOARD_FAB2(SCH_1):PAGE74
  U2D1  EE8 VSS<1231> SKX_EXT_B_BGA1-IC,TBD    I20 @BASEBOARD_FAB2_LIB.BASEBOARD_FAB2(SCH_1):PAGE74
  U2D1 EE40 VSS<1232> SKX_EXT_B_BGA1-IC,TBD    I20 @BASEBOARD_FAB2_LIB.BASEBOARD_FAB2(SCH_1):PAGE74
  U2D1 ED81 VSS<1233> SKX_EXT_B_BGA1-IC,TBD    I20 @BASEBOARD_FAB2_LIB.BASEBOARD_FAB2(SCH_1):PAGE74
  U2D1  ED7 VSS<1234> SKX_EXT_B_BGA1-IC,TBD    I20 @BASEBOARD_FAB2_LIB.BASEBOARD_FAB2(SCH_1):PAGE74
  U2D1 ED41 VSS<1235> SKX_EXT_B_BGA1-IC,TBD    I20 @BASEBOARD_FAB2_LIB.BASEBOARD_FAB2(SCH_1):PAGE74
  U2D1 EC82 VSS<1236> SKX_EXT_B_BGA1-IC,TBD    I20 @BASEBOARD_FAB2_LIB.BASEBOARD_FAB2(SCH_1):PAGE74
  U2D1  EC6 VSS<1237> SKX_EXT_B_BGA1-IC,TBD    I20 @BASEBOARD_FAB2_LIB.BASEBOARD_FAB2(SCH_1):PAGE74
  U2D1 EC42 VSS<1238> SKX_EXT_B_BGA1-IC,TBD    I20 @BASEBOARD_FAB2_LIB.BASEBOARD_FAB2(SCH_1):PAGE74
  U2D1  DW2 VSS<1239> SKX_EXT_B_BGA1-IC,TBD    I20 @BASEBOARD_FAB2_LIB.BASEBOARD_FAB2(SCH_1):PAGE74
  U2D1 EB83 VSS<1240> SKX_EXT_B_BGA1-IC,TBD    I20 @BASEBOARD_FAB2_LIB.BASEBOARD_FAB2(SCH_1):PAGE74
  U2D1 EA84 VSS<1241> SKX_EXT_B_BGA1-IC,TBD    I20 @BASEBOARD_FAB2_LIB.BASEBOARD_FAB2(SCH_1):PAGE74
  U2D1 DY85 VSS<1242> SKX_EXT_B_BGA1-IC,TBD    I20 @BASEBOARD_FAB2_LIB.BASEBOARD_FAB2(SCH_1):PAGE74
  U2D1  J86 VSS<1243> SKX_EXT_B_BGA1-IC,TBD    I20 @BASEBOARD_FAB2_LIB.BASEBOARD_FAB2(SCH_1):PAGE74
  U2D1  E82 VSS<1244> SKX_EXT_B_BGA1-IC,TBD    I20 @BASEBOARD_FAB2_LIB.BASEBOARD_FAB2(SCH_1):PAGE74
  U2D1  D81 VSS<1245> SKX_EXT_B_BGA1-IC,TBD    I20 @BASEBOARD_FAB2_LIB.BASEBOARD_FAB2(SCH_1):PAGE74
  U2D1   D3 VSS<1246> SKX_EXT_B_BGA1-IC,TBD    I20 @BASEBOARD_FAB2_LIB.BASEBOARD_FAB2(SCH_1):PAGE74
  U2D1  C80 VSS<1247> SKX_EXT_B_BGA1-IC,TBD    I20 @BASEBOARD_FAB2_LIB.BASEBOARD_FAB2(SCH_1):PAGE74
  U2D1   C4 VSS<1248> SKX_EXT_B_BGA1-IC,TBD    I20 @BASEBOARD_FAB2_LIB.BASEBOARD_FAB2(SCH_1):PAGE74
  U2D1  B79 VSS<1249> SKX_EXT_B_BGA1-IC,TBD    I20 @BASEBOARD_FAB2_LIB.BASEBOARD_FAB2(SCH_1):PAGE74
  U2D1   B5 VSS<1250> SKX_EXT_B_BGA1-IC,TBD    I20 @BASEBOARD_FAB2_LIB.BASEBOARD_FAB2(SCH_1):PAGE74
  U2D1  B43 VSS<1251> SKX_EXT_B_BGA1-IC,TBD    I20 @BASEBOARD_FAB2_LIB.BASEBOARD_FAB2(SCH_1):PAGE74
  U2D1  A42 VSS<1252> SKX_EXT_B_BGA1-IC,TBD    I20 @BASEBOARD_FAB2_LIB.BASEBOARD_FAB2(SCH_1):PAGE74
  U2D1   B9 VSS<1253> SKX_EXT_B_BGA1-IC,TBD    I20 @BASEBOARD_FAB2_LIB.BASEBOARD_FAB2(SCH_1):PAGE74
  U2D1 AA16 VSS<934> SKX_EXT_B_BGA1-IC,TBD    I21 @BASEBOARD_FAB2_LIB.BASEBOARD_FAB2(SCH_1):PAGE74
  U2D1  AA4 VSS<935> SKX_EXT_B_BGA1-IC,TBD    I21 @BASEBOARD_FAB2_LIB.BASEBOARD_FAB2(SCH_1):PAGE74
  U2D1  Y85 VSS<936> SKX_EXT_B_BGA1-IC,TBD    I21 @BASEBOARD_FAB2_LIB.BASEBOARD_FAB2(SCH_1):PAGE74
  U2D1  Y83 VSS<937> SKX_EXT_B_BGA1-IC,TBD    I21 @BASEBOARD_FAB2_LIB.BASEBOARD_FAB2(SCH_1):PAGE74
  U2D1  Y81 VSS<938> SKX_EXT_B_BGA1-IC,TBD    I21 @BASEBOARD_FAB2_LIB.BASEBOARD_FAB2(SCH_1):PAGE74
  U2D1  Y79 VSS<939> SKX_EXT_B_BGA1-IC,TBD    I21 @BASEBOARD_FAB2_LIB.BASEBOARD_FAB2(SCH_1):PAGE74
  U2D1  Y73 VSS<940> SKX_EXT_B_BGA1-IC,TBD    I21 @BASEBOARD_FAB2_LIB.BASEBOARD_FAB2(SCH_1):PAGE74
  U2D1  Y71 VSS<941> SKX_EXT_B_BGA1-IC,TBD    I21 @BASEBOARD_FAB2_LIB.BASEBOARD_FAB2(SCH_1):PAGE74
  U2D1   Y9 VSS<942> SKX_EXT_B_BGA1-IC,TBD    I21 @BASEBOARD_FAB2_LIB.BASEBOARD_FAB2(SCH_1):PAGE74
  U2D1   Y7 VSS<943> SKX_EXT_B_BGA1-IC,TBD    I21 @BASEBOARD_FAB2_LIB.BASEBOARD_FAB2(SCH_1):PAGE74
  U2D1  Y67 VSS<944> SKX_EXT_B_BGA1-IC,TBD    I21 @BASEBOARD_FAB2_LIB.BASEBOARD_FAB2(SCH_1):PAGE74
  U2D1   Y5 VSS<945> SKX_EXT_B_BGA1-IC,TBD    I21 @BASEBOARD_FAB2_LIB.BASEBOARD_FAB2(SCH_1):PAGE74
  U2D1  Y17 VSS<946> SKX_EXT_B_BGA1-IC,TBD    I21 @BASEBOARD_FAB2_LIB.BASEBOARD_FAB2(SCH_1):PAGE74
  U2D1  Y15 VSS<947> SKX_EXT_B_BGA1-IC,TBD    I21 @BASEBOARD_FAB2_LIB.BASEBOARD_FAB2(SCH_1):PAGE74
  U2D1  W82 VSS<948> SKX_EXT_B_BGA1-IC,TBD    I21 @BASEBOARD_FAB2_LIB.BASEBOARD_FAB2(SCH_1):PAGE74
  U2D1  W78 VSS<949> SKX_EXT_B_BGA1-IC,TBD    I21 @BASEBOARD_FAB2_LIB.BASEBOARD_FAB2(SCH_1):PAGE74
  U2D1  W74 VSS<950> SKX_EXT_B_BGA1-IC,TBD    I21 @BASEBOARD_FAB2_LIB.BASEBOARD_FAB2(SCH_1):PAGE74
  U2D1  W68 VSS<951> SKX_EXT_B_BGA1-IC,TBD    I21 @BASEBOARD_FAB2_LIB.BASEBOARD_FAB2(SCH_1):PAGE74
  U2D1  W42 VSS<952> SKX_EXT_B_BGA1-IC,TBD    I21 @BASEBOARD_FAB2_LIB.BASEBOARD_FAB2(SCH_1):PAGE74
  U2D1  W40 VSS<953> SKX_EXT_B_BGA1-IC,TBD    I21 @BASEBOARD_FAB2_LIB.BASEBOARD_FAB2(SCH_1):PAGE74
  U2D1  W38 VSS<954> SKX_EXT_B_BGA1-IC,TBD    I21 @BASEBOARD_FAB2_LIB.BASEBOARD_FAB2(SCH_1):PAGE74
  U2D1  W36 VSS<955> SKX_EXT_B_BGA1-IC,TBD    I21 @BASEBOARD_FAB2_LIB.BASEBOARD_FAB2(SCH_1):PAGE74
  U2D1  W34 VSS<956> SKX_EXT_B_BGA1-IC,TBD    I21 @BASEBOARD_FAB2_LIB.BASEBOARD_FAB2(SCH_1):PAGE74
  U2D1  W32 VSS<957> SKX_EXT_B_BGA1-IC,TBD    I21 @BASEBOARD_FAB2_LIB.BASEBOARD_FAB2(SCH_1):PAGE74
  U2D1  W30 VSS<958> SKX_EXT_B_BGA1-IC,TBD    I21 @BASEBOARD_FAB2_LIB.BASEBOARD_FAB2(SCH_1):PAGE74
  U2D1  W28 VSS<959> SKX_EXT_B_BGA1-IC,TBD    I21 @BASEBOARD_FAB2_LIB.BASEBOARD_FAB2(SCH_1):PAGE74
  U2D1  W26 VSS<960> SKX_EXT_B_BGA1-IC,TBD    I21 @BASEBOARD_FAB2_LIB.BASEBOARD_FAB2(SCH_1):PAGE74
  U2D1  W24 VSS<961> SKX_EXT_B_BGA1-IC,TBD    I21 @BASEBOARD_FAB2_LIB.BASEBOARD_FAB2(SCH_1):PAGE74
  U2D1  W22 VSS<962> SKX_EXT_B_BGA1-IC,TBD    I21 @BASEBOARD_FAB2_LIB.BASEBOARD_FAB2(SCH_1):PAGE74
  U2D1  W12 VSS<963> SKX_EXT_B_BGA1-IC,TBD    I21 @BASEBOARD_FAB2_LIB.BASEBOARD_FAB2(SCH_1):PAGE74
  U2D1 AC56 VSS<964> SKX_EXT_B_BGA1-IC,TBD    I21 @BASEBOARD_FAB2_LIB.BASEBOARD_FAB2(SCH_1):PAGE74
  U2D1   W8 VSS<965> SKX_EXT_B_BGA1-IC,TBD    I21 @BASEBOARD_FAB2_LIB.BASEBOARD_FAB2(SCH_1):PAGE74
  U2D1  V83 VSS<966> SKX_EXT_B_BGA1-IC,TBD    I21 @BASEBOARD_FAB2_LIB.BASEBOARD_FAB2(SCH_1):PAGE74
  U2D1  V77 VSS<967> SKX_EXT_B_BGA1-IC,TBD    I21 @BASEBOARD_FAB2_LIB.BASEBOARD_FAB2(SCH_1):PAGE74
  U2D1  V75 VSS<968> SKX_EXT_B_BGA1-IC,TBD    I21 @BASEBOARD_FAB2_LIB.BASEBOARD_FAB2(SCH_1):PAGE74
  U2D1  V73 VSS<969> SKX_EXT_B_BGA1-IC,TBD    I21 @BASEBOARD_FAB2_LIB.BASEBOARD_FAB2(SCH_1):PAGE74
  U2D1  V43 VSS<970> SKX_EXT_B_BGA1-IC,TBD    I21 @BASEBOARD_FAB2_LIB.BASEBOARD_FAB2(SCH_1):PAGE74
  U2D1  V23 VSS<971> SKX_EXT_B_BGA1-IC,TBD    I21 @BASEBOARD_FAB2_LIB.BASEBOARD_FAB2(SCH_1):PAGE74
  U2D1  V21 VSS<972> SKX_EXT_B_BGA1-IC,TBD    I21 @BASEBOARD_FAB2_LIB.BASEBOARD_FAB2(SCH_1):PAGE74
  U2D1  V15 VSS<973> SKX_EXT_B_BGA1-IC,TBD    I21 @BASEBOARD_FAB2_LIB.BASEBOARD_FAB2(SCH_1):PAGE74
  U2D1  V13 VSS<974> SKX_EXT_B_BGA1-IC,TBD    I21 @BASEBOARD_FAB2_LIB.BASEBOARD_FAB2(SCH_1):PAGE74
  U2D1   V9 VSS<975> SKX_EXT_B_BGA1-IC,TBD    I21 @BASEBOARD_FAB2_LIB.BASEBOARD_FAB2(SCH_1):PAGE74
  U2D1   V5 VSS<976> SKX_EXT_B_BGA1-IC,TBD    I21 @BASEBOARD_FAB2_LIB.BASEBOARD_FAB2(SCH_1):PAGE74
  U2D1   V1 VSS<977> SKX_EXT_B_BGA1-IC,TBD    I21 @BASEBOARD_FAB2_LIB.BASEBOARD_FAB2(SCH_1):PAGE74
  U2D1  U86 VSS<978> SKX_EXT_B_BGA1-IC,TBD    I21 @BASEBOARD_FAB2_LIB.BASEBOARD_FAB2(SCH_1):PAGE74
  U2D1  U80 VSS<979> SKX_EXT_B_BGA1-IC,TBD    I21 @BASEBOARD_FAB2_LIB.BASEBOARD_FAB2(SCH_1):PAGE74
  U2D1  U78 VSS<980> SKX_EXT_B_BGA1-IC,TBD    I21 @BASEBOARD_FAB2_LIB.BASEBOARD_FAB2(SCH_1):PAGE74
  U2D1  U76 VSS<981> SKX_EXT_B_BGA1-IC,TBD    I21 @BASEBOARD_FAB2_LIB.BASEBOARD_FAB2(SCH_1):PAGE74
  U2D1  U74 VSS<982> SKX_EXT_B_BGA1-IC,TBD    I21 @BASEBOARD_FAB2_LIB.BASEBOARD_FAB2(SCH_1):PAGE74
  U2D1  U70 VSS<983> SKX_EXT_B_BGA1-IC,TBD    I21 @BASEBOARD_FAB2_LIB.BASEBOARD_FAB2(SCH_1):PAGE74
  U2D1  U68 VSS<984> SKX_EXT_B_BGA1-IC,TBD    I21 @BASEBOARD_FAB2_LIB.BASEBOARD_FAB2(SCH_1):PAGE74
  U2D1  U42 VSS<985> SKX_EXT_B_BGA1-IC,TBD    I21 @BASEBOARD_FAB2_LIB.BASEBOARD_FAB2(SCH_1):PAGE74
  U2D1  U36 VSS<986> SKX_EXT_B_BGA1-IC,TBD    I21 @BASEBOARD_FAB2_LIB.BASEBOARD_FAB2(SCH_1):PAGE74
  U2D1  U30 VSS<987> SKX_EXT_B_BGA1-IC,TBD    I21 @BASEBOARD_FAB2_LIB.BASEBOARD_FAB2(SCH_1):PAGE74
  U2D1  U24 VSS<988> SKX_EXT_B_BGA1-IC,TBD    I21 @BASEBOARD_FAB2_LIB.BASEBOARD_FAB2(SCH_1):PAGE74
  U2D1  U22 VSS<989> SKX_EXT_B_BGA1-IC,TBD    I21 @BASEBOARD_FAB2_LIB.BASEBOARD_FAB2(SCH_1):PAGE74
  U2D1  U20 VSS<990> SKX_EXT_B_BGA1-IC,TBD    I21 @BASEBOARD_FAB2_LIB.BASEBOARD_FAB2(SCH_1):PAGE74
  U2D1   U6 VSS<991> SKX_EXT_B_BGA1-IC,TBD    I21 @BASEBOARD_FAB2_LIB.BASEBOARD_FAB2(SCH_1):PAGE74
  U2D1   U4 VSS<992> SKX_EXT_B_BGA1-IC,TBD    I21 @BASEBOARD_FAB2_LIB.BASEBOARD_FAB2(SCH_1):PAGE74
  U2D1   U2 VSS<993> SKX_EXT_B_BGA1-IC,TBD    I21 @BASEBOARD_FAB2_LIB.BASEBOARD_FAB2(SCH_1):PAGE74
  U2D1  T85 VSS<994> SKX_EXT_B_BGA1-IC,TBD    I21 @BASEBOARD_FAB2_LIB.BASEBOARD_FAB2(SCH_1):PAGE74
  U2D1  T83 VSS<995> SKX_EXT_B_BGA1-IC,TBD    I21 @BASEBOARD_FAB2_LIB.BASEBOARD_FAB2(SCH_1):PAGE74
  U2D1  T77 VSS<996> SKX_EXT_B_BGA1-IC,TBD    I21 @BASEBOARD_FAB2_LIB.BASEBOARD_FAB2(SCH_1):PAGE74
  U2D1  T73 VSS<997> SKX_EXT_B_BGA1-IC,TBD    I21 @BASEBOARD_FAB2_LIB.BASEBOARD_FAB2(SCH_1):PAGE74
  U2D1  T65 VSS<998> SKX_EXT_B_BGA1-IC,TBD    I21 @BASEBOARD_FAB2_LIB.BASEBOARD_FAB2(SCH_1):PAGE74
  U2D1  T41 VSS<999> SKX_EXT_B_BGA1-IC,TBD    I21 @BASEBOARD_FAB2_LIB.BASEBOARD_FAB2(SCH_1):PAGE74
  U2D1  T37 VSS<1000> SKX_EXT_B_BGA1-IC,TBD    I21 @BASEBOARD_FAB2_LIB.BASEBOARD_FAB2(SCH_1):PAGE74
  U2D1  T35 VSS<1001> SKX_EXT_B_BGA1-IC,TBD    I21 @BASEBOARD_FAB2_LIB.BASEBOARD_FAB2(SCH_1):PAGE74
  U2D1  T31 VSS<1002> SKX_EXT_B_BGA1-IC,TBD    I21 @BASEBOARD_FAB2_LIB.BASEBOARD_FAB2(SCH_1):PAGE74
  U2D1  T29 VSS<1003> SKX_EXT_B_BGA1-IC,TBD    I21 @BASEBOARD_FAB2_LIB.BASEBOARD_FAB2(SCH_1):PAGE74
  U2D1  T25 VSS<1004> SKX_EXT_B_BGA1-IC,TBD    I21 @BASEBOARD_FAB2_LIB.BASEBOARD_FAB2(SCH_1):PAGE74
  U2D1  T17 VSS<1005> SKX_EXT_B_BGA1-IC,TBD    I21 @BASEBOARD_FAB2_LIB.BASEBOARD_FAB2(SCH_1):PAGE74
  U2D1  T13 VSS<1006> SKX_EXT_B_BGA1-IC,TBD    I21 @BASEBOARD_FAB2_LIB.BASEBOARD_FAB2(SCH_1):PAGE74
  U2D1  R86 VSS<1007> SKX_EXT_B_BGA1-IC,TBD    I21 @BASEBOARD_FAB2_LIB.BASEBOARD_FAB2(SCH_1):PAGE74
  U2D1  R78 VSS<1008> SKX_EXT_B_BGA1-IC,TBD    I21 @BASEBOARD_FAB2_LIB.BASEBOARD_FAB2(SCH_1):PAGE74
  U2D1  R72 VSS<1009> SKX_EXT_B_BGA1-IC,TBD    I21 @BASEBOARD_FAB2_LIB.BASEBOARD_FAB2(SCH_1):PAGE74
  U2D1  R68 VSS<1010> SKX_EXT_B_BGA1-IC,TBD    I21 @BASEBOARD_FAB2_LIB.BASEBOARD_FAB2(SCH_1):PAGE74
  U2D1  R40 VSS<1011> SKX_EXT_B_BGA1-IC,TBD    I21 @BASEBOARD_FAB2_LIB.BASEBOARD_FAB2(SCH_1):PAGE74
  U2D1  R38 VSS<1012> SKX_EXT_B_BGA1-IC,TBD    I21 @BASEBOARD_FAB2_LIB.BASEBOARD_FAB2(SCH_1):PAGE74
  U2D1  R34 VSS<1013> SKX_EXT_B_BGA1-IC,TBD    I21 @BASEBOARD_FAB2_LIB.BASEBOARD_FAB2(SCH_1):PAGE74
  U2D1  R32 VSS<1014> SKX_EXT_B_BGA1-IC,TBD    I21 @BASEBOARD_FAB2_LIB.BASEBOARD_FAB2(SCH_1):PAGE74
  U2D1  R28 VSS<1015> SKX_EXT_B_BGA1-IC,TBD    I21 @BASEBOARD_FAB2_LIB.BASEBOARD_FAB2(SCH_1):PAGE74
  U2D1  R26 VSS<1016> SKX_EXT_B_BGA1-IC,TBD    I21 @BASEBOARD_FAB2_LIB.BASEBOARD_FAB2(SCH_1):PAGE74
  U2D1  R22 VSS<1017> SKX_EXT_B_BGA1-IC,TBD    I21 @BASEBOARD_FAB2_LIB.BASEBOARD_FAB2(SCH_1):PAGE74
  U2D1   R4 VSS<1018> SKX_EXT_B_BGA1-IC,TBD    I21 @BASEBOARD_FAB2_LIB.BASEBOARD_FAB2(SCH_1):PAGE74
  U2D1   R2 VSS<1019> SKX_EXT_B_BGA1-IC,TBD    I21 @BASEBOARD_FAB2_LIB.BASEBOARD_FAB2(SCH_1):PAGE74
  U2D1  R18 VSS<1020> SKX_EXT_B_BGA1-IC,TBD    I21 @BASEBOARD_FAB2_LIB.BASEBOARD_FAB2(SCH_1):PAGE74
  U2D1  R14 VSS<1021> SKX_EXT_B_BGA1-IC,TBD    I21 @BASEBOARD_FAB2_LIB.BASEBOARD_FAB2(SCH_1):PAGE74
  U2D1  P83 VSS<1022> SKX_EXT_B_BGA1-IC,TBD    I21 @BASEBOARD_FAB2_LIB.BASEBOARD_FAB2(SCH_1):PAGE74
  U2D1  P81 VSS<1023> SKX_EXT_B_BGA1-IC,TBD    I21 @BASEBOARD_FAB2_LIB.BASEBOARD_FAB2(SCH_1):PAGE74
  U2D1  P71 VSS<1024> SKX_EXT_B_BGA1-IC,TBD    I21 @BASEBOARD_FAB2_LIB.BASEBOARD_FAB2(SCH_1):PAGE74
  U2D1  P69 VSS<1025> SKX_EXT_B_BGA1-IC,TBD    I21 @BASEBOARD_FAB2_LIB.BASEBOARD_FAB2(SCH_1):PAGE74
  U2D1  P67 VSS<1026> SKX_EXT_B_BGA1-IC,TBD    I21 @BASEBOARD_FAB2_LIB.BASEBOARD_FAB2(SCH_1):PAGE74
  U2D1  P39 VSS<1027> SKX_EXT_B_BGA1-IC,TBD    I21 @BASEBOARD_FAB2_LIB.BASEBOARD_FAB2(SCH_1):PAGE74
  U2D1  P33 VSS<1028> SKX_EXT_B_BGA1-IC,TBD    I21 @BASEBOARD_FAB2_LIB.BASEBOARD_FAB2(SCH_1):PAGE74
  U2D1  P27 VSS<1029> SKX_EXT_B_BGA1-IC,TBD    I21 @BASEBOARD_FAB2_LIB.BASEBOARD_FAB2(SCH_1):PAGE74
  U2D1  P15 VSS<1030> SKX_EXT_B_BGA1-IC,TBD    I21 @BASEBOARD_FAB2_LIB.BASEBOARD_FAB2(SCH_1):PAGE74
  U2D1  P11 VSS<1031> SKX_EXT_B_BGA1-IC,TBD    I21 @BASEBOARD_FAB2_LIB.BASEBOARD_FAB2(SCH_1):PAGE74
  U2D1   N8 VSS<1032> SKX_EXT_B_BGA1-IC,TBD    I21 @BASEBOARD_FAB2_LIB.BASEBOARD_FAB2(SCH_1):PAGE74
  U2D1   N4 VSS<1033> SKX_EXT_B_BGA1-IC,TBD    I21 @BASEBOARD_FAB2_LIB.BASEBOARD_FAB2(SCH_1):PAGE74
  U2D1  N78 VSS<1034> SKX_EXT_B_BGA1-IC,TBD    I21 @BASEBOARD_FAB2_LIB.BASEBOARD_FAB2(SCH_1):PAGE74
  U2D1  N76 VSS<1035> SKX_EXT_B_BGA1-IC,TBD    I21 @BASEBOARD_FAB2_LIB.BASEBOARD_FAB2(SCH_1):PAGE74
  U2D1  N74 VSS<1036> SKX_EXT_B_BGA1-IC,TBD    I21 @BASEBOARD_FAB2_LIB.BASEBOARD_FAB2(SCH_1):PAGE74
  U2D1  N72 VSS<1037> SKX_EXT_B_BGA1-IC,TBD    I21 @BASEBOARD_FAB2_LIB.BASEBOARD_FAB2(SCH_1):PAGE74
  U2D1  N70 VSS<1038> SKX_EXT_B_BGA1-IC,TBD    I21 @BASEBOARD_FAB2_LIB.BASEBOARD_FAB2(SCH_1):PAGE74
  U2D1  N66 VSS<1039> SKX_EXT_B_BGA1-IC,TBD    I21 @BASEBOARD_FAB2_LIB.BASEBOARD_FAB2(SCH_1):PAGE74
  U2D1   N6 VSS<1040> SKX_EXT_B_BGA1-IC,TBD    I21 @BASEBOARD_FAB2_LIB.BASEBOARD_FAB2(SCH_1):PAGE74
  U2D1  N22 VSS<1041> SKX_EXT_B_BGA1-IC,TBD    I21 @BASEBOARD_FAB2_LIB.BASEBOARD_FAB2(SCH_1):PAGE74
  U2D1  N20 VSS<1042> SKX_EXT_B_BGA1-IC,TBD    I21 @BASEBOARD_FAB2_LIB.BASEBOARD_FAB2(SCH_1):PAGE74
  U2D1 DM19 VSS<1043> SKX_EXT_B_BGA1-IC,TBD    I21 @BASEBOARD_FAB2_LIB.BASEBOARD_FAB2(SCH_1):PAGE74
  U2D1  M85 VSS<1044> SKX_EXT_B_BGA1-IC,TBD    I21 @BASEBOARD_FAB2_LIB.BASEBOARD_FAB2(SCH_1):PAGE74
  U2D1  M83 VSS<1045> SKX_EXT_B_BGA1-IC,TBD    I21 @BASEBOARD_FAB2_LIB.BASEBOARD_FAB2(SCH_1):PAGE74
  U2D1  M79 VSS<1046> SKX_EXT_B_BGA1-IC,TBD    I21 @BASEBOARD_FAB2_LIB.BASEBOARD_FAB2(SCH_1):PAGE74
  U2D1  M71 VSS<1047> SKX_EXT_B_BGA1-IC,TBD    I21 @BASEBOARD_FAB2_LIB.BASEBOARD_FAB2(SCH_1):PAGE74
  U2D1  M65 VSS<1048> SKX_EXT_B_BGA1-IC,TBD    I21 @BASEBOARD_FAB2_LIB.BASEBOARD_FAB2(SCH_1):PAGE74
  U2D1  M43 VSS<1049> SKX_EXT_B_BGA1-IC,TBD    I21 @BASEBOARD_FAB2_LIB.BASEBOARD_FAB2(SCH_1):PAGE74
  U2D1  M41 VSS<1050> SKX_EXT_B_BGA1-IC,TBD    I21 @BASEBOARD_FAB2_LIB.BASEBOARD_FAB2(SCH_1):PAGE74
  U2D1  M39 VSS<1051> SKX_EXT_B_BGA1-IC,TBD    I21 @BASEBOARD_FAB2_LIB.BASEBOARD_FAB2(SCH_1):PAGE74
  U2D1  M37 VSS<1052> SKX_EXT_B_BGA1-IC,TBD    I21 @BASEBOARD_FAB2_LIB.BASEBOARD_FAB2(SCH_1):PAGE74
  U2D1  M35 VSS<1053> SKX_EXT_B_BGA1-IC,TBD    I21 @BASEBOARD_FAB2_LIB.BASEBOARD_FAB2(SCH_1):PAGE74
  U2D1  M33 VSS<1054> SKX_EXT_B_BGA1-IC,TBD    I21 @BASEBOARD_FAB2_LIB.BASEBOARD_FAB2(SCH_1):PAGE74
  U2D1  M31 VSS<1055> SKX_EXT_B_BGA1-IC,TBD    I21 @BASEBOARD_FAB2_LIB.BASEBOARD_FAB2(SCH_1):PAGE74
  U2D1  M29 VSS<1056> SKX_EXT_B_BGA1-IC,TBD    I21 @BASEBOARD_FAB2_LIB.BASEBOARD_FAB2(SCH_1):PAGE74
  U2D1  M27 VSS<1057> SKX_EXT_B_BGA1-IC,TBD    I21 @BASEBOARD_FAB2_LIB.BASEBOARD_FAB2(SCH_1):PAGE74
  U2D1  M25 VSS<1058> SKX_EXT_B_BGA1-IC,TBD    I21 @BASEBOARD_FAB2_LIB.BASEBOARD_FAB2(SCH_1):PAGE74
  U2D1  M23 VSS<1059> SKX_EXT_B_BGA1-IC,TBD    I21 @BASEBOARD_FAB2_LIB.BASEBOARD_FAB2(SCH_1):PAGE74
  U2D1  M19 VSS<1060> SKX_EXT_B_BGA1-IC,TBD    I21 @BASEBOARD_FAB2_LIB.BASEBOARD_FAB2(SCH_1):PAGE74
  U2D1  M17 VSS<1061> SKX_EXT_B_BGA1-IC,TBD    I21 @BASEBOARD_FAB2_LIB.BASEBOARD_FAB2(SCH_1):PAGE74
  U2D1  M15 VSS<1062> SKX_EXT_B_BGA1-IC,TBD    I21 @BASEBOARD_FAB2_LIB.BASEBOARD_FAB2(SCH_1):PAGE74
  U2D1  CT7 VSS<1063> SKX_EXT_B_BGA1-IC,TBD    I21 @BASEBOARD_FAB2_LIB.BASEBOARD_FAB2(SCH_1):PAGE74
  U2D1  BT9 VSS<1064> SKX_EXT_B_BGA1-IC,TBD    I21 @BASEBOARD_FAB2_LIB.BASEBOARD_FAB2(SCH_1):PAGE74
  U2D1  L82 VSS<1065> SKX_EXT_B_BGA1-IC,TBD    I21 @BASEBOARD_FAB2_LIB.BASEBOARD_FAB2(SCH_1):PAGE74
  U2D1  L80 VSS<1066> SKX_EXT_B_BGA1-IC,TBD    I21 @BASEBOARD_FAB2_LIB.BASEBOARD_FAB2(SCH_1):PAGE74
  U2D1  L78 VSS<1067> SKX_EXT_B_BGA1-IC,TBD    I21 @BASEBOARD_FAB2_LIB.BASEBOARD_FAB2(SCH_1):PAGE74
  U2D1  L72 VSS<1068> SKX_EXT_B_BGA1-IC,TBD    I21 @BASEBOARD_FAB2_LIB.BASEBOARD_FAB2(SCH_1):PAGE74
  U2D1  L22 VSS<1069> SKX_EXT_B_BGA1-IC,TBD    I21 @BASEBOARD_FAB2_LIB.BASEBOARD_FAB2(SCH_1):PAGE74
  U2D1  L20 VSS<1070> SKX_EXT_B_BGA1-IC,TBD    I21 @BASEBOARD_FAB2_LIB.BASEBOARD_FAB2(SCH_1):PAGE74
  U2D1   L6 VSS<1071> SKX_EXT_B_BGA1-IC,TBD    I21 @BASEBOARD_FAB2_LIB.BASEBOARD_FAB2(SCH_1):PAGE74
  U2D1   L2 VSS<1072> SKX_EXT_B_BGA1-IC,TBD    I21 @BASEBOARD_FAB2_LIB.BASEBOARD_FAB2(SCH_1):PAGE74
  U2D1  L10 VSS<1073> SKX_EXT_B_BGA1-IC,TBD    I21 @BASEBOARD_FAB2_LIB.BASEBOARD_FAB2(SCH_1):PAGE74
  U2D1  K85 VSS<1074> SKX_EXT_B_BGA1-IC,TBD    I21 @BASEBOARD_FAB2_LIB.BASEBOARD_FAB2(SCH_1):PAGE74
  U2D1  K83 VSS<1075> SKX_EXT_B_BGA1-IC,TBD    I21 @BASEBOARD_FAB2_LIB.BASEBOARD_FAB2(SCH_1):PAGE74
  U2D1  K81 VSS<1076> SKX_EXT_B_BGA1-IC,TBD    I21 @BASEBOARD_FAB2_LIB.BASEBOARD_FAB2(SCH_1):PAGE74
  U2D1  K77 VSS<1077> SKX_EXT_B_BGA1-IC,TBD    I21 @BASEBOARD_FAB2_LIB.BASEBOARD_FAB2(SCH_1):PAGE74
  U2D1  K73 VSS<1078> SKX_EXT_B_BGA1-IC,TBD    I21 @BASEBOARD_FAB2_LIB.BASEBOARD_FAB2(SCH_1):PAGE74
  U2D1  K71 VSS<1079> SKX_EXT_B_BGA1-IC,TBD    I21 @BASEBOARD_FAB2_LIB.BASEBOARD_FAB2(SCH_1):PAGE74
  U2D1  K69 VSS<1080> SKX_EXT_B_BGA1-IC,TBD    I21 @BASEBOARD_FAB2_LIB.BASEBOARD_FAB2(SCH_1):PAGE74
  U2D1  K67 VSS<1081> SKX_EXT_B_BGA1-IC,TBD    I21 @BASEBOARD_FAB2_LIB.BASEBOARD_FAB2(SCH_1):PAGE74
  U2D1  K65 VSS<1082> SKX_EXT_B_BGA1-IC,TBD    I21 @BASEBOARD_FAB2_LIB.BASEBOARD_FAB2(SCH_1):PAGE74
  U2D1  K39 VSS<1083> SKX_EXT_B_BGA1-IC,TBD    I21 @BASEBOARD_FAB2_LIB.BASEBOARD_FAB2(SCH_1):PAGE74
  U2D1  K33 VSS<1084> SKX_EXT_B_BGA1-IC,TBD    I21 @BASEBOARD_FAB2_LIB.BASEBOARD_FAB2(SCH_1):PAGE74
  U2D1  K27 VSS<1085> SKX_EXT_B_BGA1-IC,TBD    I21 @BASEBOARD_FAB2_LIB.BASEBOARD_FAB2(SCH_1):PAGE74
  U2D1  DB7 VSS<1086> SKX_EXT_B_BGA1-IC,TBD    I21 @BASEBOARD_FAB2_LIB.BASEBOARD_FAB2(SCH_1):PAGE74
  U2D1  K17 VSS<1087> SKX_EXT_B_BGA1-IC,TBD    I21 @BASEBOARD_FAB2_LIB.BASEBOARD_FAB2(SCH_1):PAGE74
  U2D1  K13 VSS<1088> SKX_EXT_B_BGA1-IC,TBD    I21 @BASEBOARD_FAB2_LIB.BASEBOARD_FAB2(SCH_1):PAGE74
  U2D1  K11 VSS<1089> SKX_EXT_B_BGA1-IC,TBD    I21 @BASEBOARD_FAB2_LIB.BASEBOARD_FAB2(SCH_1):PAGE74
  U2D1   K1 VSS<1090> SKX_EXT_B_BGA1-IC,TBD    I21 @BASEBOARD_FAB2_LIB.BASEBOARD_FAB2(SCH_1):PAGE74
  U2D1  J84 VSS<1091> SKX_EXT_B_BGA1-IC,TBD    I21 @BASEBOARD_FAB2_LIB.BASEBOARD_FAB2(SCH_1):PAGE74
  U2D1  J82 VSS<1092> SKX_EXT_B_BGA1-IC,TBD    I21 @BASEBOARD_FAB2_LIB.BASEBOARD_FAB2(SCH_1):PAGE74
  U2D1  J76 VSS<1093> SKX_EXT_B_BGA1-IC,TBD    I21 @BASEBOARD_FAB2_LIB.BASEBOARD_FAB2(SCH_1):PAGE74
  U2D1 AL68 VSS<774> SKX_EXT_B_BGA1-IC,TBD    I22 @BASEBOARD_FAB2_LIB.BASEBOARD_FAB2(SCH_1):PAGE74
  U2D1 AL64 VSS<775> SKX_EXT_B_BGA1-IC,TBD    I22 @BASEBOARD_FAB2_LIB.BASEBOARD_FAB2(SCH_1):PAGE74
  U2D1 AL56 VSS<776> SKX_EXT_B_BGA1-IC,TBD    I22 @BASEBOARD_FAB2_LIB.BASEBOARD_FAB2(SCH_1):PAGE74
  U2D1 AL32 VSS<777> SKX_EXT_B_BGA1-IC,TBD    I22 @BASEBOARD_FAB2_LIB.BASEBOARD_FAB2(SCH_1):PAGE74
  U2D1 AL30 VSS<778> SKX_EXT_B_BGA1-IC,TBD    I22 @BASEBOARD_FAB2_LIB.BASEBOARD_FAB2(SCH_1):PAGE74
  U2D1 AL24 VSS<779> SKX_EXT_B_BGA1-IC,TBD    I22 @BASEBOARD_FAB2_LIB.BASEBOARD_FAB2(SCH_1):PAGE74
  U2D1 AL10 VSS<780> SKX_EXT_B_BGA1-IC,TBD    I22 @BASEBOARD_FAB2_LIB.BASEBOARD_FAB2(SCH_1):PAGE74
  U2D1  AL4 VSS<781> SKX_EXT_B_BGA1-IC,TBD    I22 @BASEBOARD_FAB2_LIB.BASEBOARD_FAB2(SCH_1):PAGE74
  U2D1 AK85 VSS<782> SKX_EXT_B_BGA1-IC,TBD    I22 @BASEBOARD_FAB2_LIB.BASEBOARD_FAB2(SCH_1):PAGE74
  U2D1 AK83 VSS<783> SKX_EXT_B_BGA1-IC,TBD    I22 @BASEBOARD_FAB2_LIB.BASEBOARD_FAB2(SCH_1):PAGE74
  U2D1 AK81 VSS<784> SKX_EXT_B_BGA1-IC,TBD    I22 @BASEBOARD_FAB2_LIB.BASEBOARD_FAB2(SCH_1):PAGE74
  U2D1 AK79 VSS<785> SKX_EXT_B_BGA1-IC,TBD    I22 @BASEBOARD_FAB2_LIB.BASEBOARD_FAB2(SCH_1):PAGE74
  U2D1 AK73 VSS<786> SKX_EXT_B_BGA1-IC,TBD    I22 @BASEBOARD_FAB2_LIB.BASEBOARD_FAB2(SCH_1):PAGE74
  U2D1 AK67 VSS<787> SKX_EXT_B_BGA1-IC,TBD    I22 @BASEBOARD_FAB2_LIB.BASEBOARD_FAB2(SCH_1):PAGE74
  U2D1 AK65 VSS<788> SKX_EXT_B_BGA1-IC,TBD    I22 @BASEBOARD_FAB2_LIB.BASEBOARD_FAB2(SCH_1):PAGE74
  U2D1 AK55 VSS<789> SKX_EXT_B_BGA1-IC,TBD    I22 @BASEBOARD_FAB2_LIB.BASEBOARD_FAB2(SCH_1):PAGE74
  U2D1 AK33 VSS<790> SKX_EXT_B_BGA1-IC,TBD    I22 @BASEBOARD_FAB2_LIB.BASEBOARD_FAB2(SCH_1):PAGE74
  U2D1 AK31 VSS<791> SKX_EXT_B_BGA1-IC,TBD    I22 @BASEBOARD_FAB2_LIB.BASEBOARD_FAB2(SCH_1):PAGE74
  U2D1 AK29 VSS<792> SKX_EXT_B_BGA1-IC,TBD    I22 @BASEBOARD_FAB2_LIB.BASEBOARD_FAB2(SCH_1):PAGE74
  U2D1 AK25 VSS<793> SKX_EXT_B_BGA1-IC,TBD    I22 @BASEBOARD_FAB2_LIB.BASEBOARD_FAB2(SCH_1):PAGE74
  U2D1 AK23 VSS<794> SKX_EXT_B_BGA1-IC,TBD    I22 @BASEBOARD_FAB2_LIB.BASEBOARD_FAB2(SCH_1):PAGE74
  U2D1 AK19 VSS<795> SKX_EXT_B_BGA1-IC,TBD    I22 @BASEBOARD_FAB2_LIB.BASEBOARD_FAB2(SCH_1):PAGE74
  U2D1 AK13 VSS<796> SKX_EXT_B_BGA1-IC,TBD    I22 @BASEBOARD_FAB2_LIB.BASEBOARD_FAB2(SCH_1):PAGE74
  U2D1  AK9 VSS<797> SKX_EXT_B_BGA1-IC,TBD    I22 @BASEBOARD_FAB2_LIB.BASEBOARD_FAB2(SCH_1):PAGE74
  U2D1 AJ86 VSS<798> SKX_EXT_B_BGA1-IC,TBD    I22 @BASEBOARD_FAB2_LIB.BASEBOARD_FAB2(SCH_1):PAGE74
  U2D1 AJ82 VSS<799> SKX_EXT_B_BGA1-IC,TBD    I22 @BASEBOARD_FAB2_LIB.BASEBOARD_FAB2(SCH_1):PAGE74
  U2D1 AJ78 VSS<800> SKX_EXT_B_BGA1-IC,TBD    I22 @BASEBOARD_FAB2_LIB.BASEBOARD_FAB2(SCH_1):PAGE74
  U2D1 AJ74 VSS<801> SKX_EXT_B_BGA1-IC,TBD    I22 @BASEBOARD_FAB2_LIB.BASEBOARD_FAB2(SCH_1):PAGE74
  U2D1 AJ68 VSS<802> SKX_EXT_B_BGA1-IC,TBD    I22 @BASEBOARD_FAB2_LIB.BASEBOARD_FAB2(SCH_1):PAGE74
  U2D1 AJ66 VSS<803> SKX_EXT_B_BGA1-IC,TBD    I22 @BASEBOARD_FAB2_LIB.BASEBOARD_FAB2(SCH_1):PAGE74
  U2D1 AJ54 VSS<804> SKX_EXT_B_BGA1-IC,TBD    I22 @BASEBOARD_FAB2_LIB.BASEBOARD_FAB2(SCH_1):PAGE74
  U2D1 AJ52 VSS<805> SKX_EXT_B_BGA1-IC,TBD    I22 @BASEBOARD_FAB2_LIB.BASEBOARD_FAB2(SCH_1):PAGE74
  U2D1 AJ50 VSS<806> SKX_EXT_B_BGA1-IC,TBD    I22 @BASEBOARD_FAB2_LIB.BASEBOARD_FAB2(SCH_1):PAGE74
  U2D1 AJ48 VSS<807> SKX_EXT_B_BGA1-IC,TBD    I22 @BASEBOARD_FAB2_LIB.BASEBOARD_FAB2(SCH_1):PAGE74
  U2D1 AJ46 VSS<808> SKX_EXT_B_BGA1-IC,TBD    I22 @BASEBOARD_FAB2_LIB.BASEBOARD_FAB2(SCH_1):PAGE74
  U2D1 AJ34 VSS<809> SKX_EXT_B_BGA1-IC,TBD    I22 @BASEBOARD_FAB2_LIB.BASEBOARD_FAB2(SCH_1):PAGE74
  U2D1 AJ32 VSS<810> SKX_EXT_B_BGA1-IC,TBD    I22 @BASEBOARD_FAB2_LIB.BASEBOARD_FAB2(SCH_1):PAGE74
  U2D1 AJ28 VSS<811> SKX_EXT_B_BGA1-IC,TBD    I22 @BASEBOARD_FAB2_LIB.BASEBOARD_FAB2(SCH_1):PAGE74
  U2D1 AJ26 VSS<812> SKX_EXT_B_BGA1-IC,TBD    I22 @BASEBOARD_FAB2_LIB.BASEBOARD_FAB2(SCH_1):PAGE74
  U2D1 AJ22 VSS<813> SKX_EXT_B_BGA1-IC,TBD    I22 @BASEBOARD_FAB2_LIB.BASEBOARD_FAB2(SCH_1):PAGE74
  U2D1  AJ8 VSS<814> SKX_EXT_B_BGA1-IC,TBD    I22 @BASEBOARD_FAB2_LIB.BASEBOARD_FAB2(SCH_1):PAGE74
  U2D1 AH83 VSS<815> SKX_EXT_B_BGA1-IC,TBD    I22 @BASEBOARD_FAB2_LIB.BASEBOARD_FAB2(SCH_1):PAGE74
  U2D1 AH77 VSS<816> SKX_EXT_B_BGA1-IC,TBD    I22 @BASEBOARD_FAB2_LIB.BASEBOARD_FAB2(SCH_1):PAGE74
  U2D1 AH75 VSS<817> SKX_EXT_B_BGA1-IC,TBD    I22 @BASEBOARD_FAB2_LIB.BASEBOARD_FAB2(SCH_1):PAGE74
  U2D1 AH69 VSS<818> SKX_EXT_B_BGA1-IC,TBD    I22 @BASEBOARD_FAB2_LIB.BASEBOARD_FAB2(SCH_1):PAGE74
  U2D1 AH65 VSS<819> SKX_EXT_B_BGA1-IC,TBD    I22 @BASEBOARD_FAB2_LIB.BASEBOARD_FAB2(SCH_1):PAGE74
  U2D1 AH61 VSS<820> SKX_EXT_B_BGA1-IC,TBD    I22 @BASEBOARD_FAB2_LIB.BASEBOARD_FAB2(SCH_1):PAGE74
  U2D1 AH59 VSS<821> SKX_EXT_B_BGA1-IC,TBD    I22 @BASEBOARD_FAB2_LIB.BASEBOARD_FAB2(SCH_1):PAGE74
  U2D1 AH53 VSS<822> SKX_EXT_B_BGA1-IC,TBD    I22 @BASEBOARD_FAB2_LIB.BASEBOARD_FAB2(SCH_1):PAGE74
  U2D1 AH51 VSS<823> SKX_EXT_B_BGA1-IC,TBD    I22 @BASEBOARD_FAB2_LIB.BASEBOARD_FAB2(SCH_1):PAGE74
  U2D1 AH49 VSS<824> SKX_EXT_B_BGA1-IC,TBD    I22 @BASEBOARD_FAB2_LIB.BASEBOARD_FAB2(SCH_1):PAGE74
  U2D1 AH47 VSS<825> SKX_EXT_B_BGA1-IC,TBD    I22 @BASEBOARD_FAB2_LIB.BASEBOARD_FAB2(SCH_1):PAGE74
  U2D1 AH45 VSS<826> SKX_EXT_B_BGA1-IC,TBD    I22 @BASEBOARD_FAB2_LIB.BASEBOARD_FAB2(SCH_1):PAGE74
  U2D1 AH35 VSS<827> SKX_EXT_B_BGA1-IC,TBD    I22 @BASEBOARD_FAB2_LIB.BASEBOARD_FAB2(SCH_1):PAGE74
  U2D1 AH33 VSS<828> SKX_EXT_B_BGA1-IC,TBD    I22 @BASEBOARD_FAB2_LIB.BASEBOARD_FAB2(SCH_1):PAGE74
  U2D1 AH27 VSS<829> SKX_EXT_B_BGA1-IC,TBD    I22 @BASEBOARD_FAB2_LIB.BASEBOARD_FAB2(SCH_1):PAGE74
  U2D1 AH21 VSS<830> SKX_EXT_B_BGA1-IC,TBD    I22 @BASEBOARD_FAB2_LIB.BASEBOARD_FAB2(SCH_1):PAGE74
  U2D1  AH5 VSS<831> SKX_EXT_B_BGA1-IC,TBD    I22 @BASEBOARD_FAB2_LIB.BASEBOARD_FAB2(SCH_1):PAGE74
  U2D1  AH1 VSS<832> SKX_EXT_B_BGA1-IC,TBD    I22 @BASEBOARD_FAB2_LIB.BASEBOARD_FAB2(SCH_1):PAGE74
  U2D1 AG80 VSS<833> SKX_EXT_B_BGA1-IC,TBD    I22 @BASEBOARD_FAB2_LIB.BASEBOARD_FAB2(SCH_1):PAGE74
  U2D1 AG78 VSS<834> SKX_EXT_B_BGA1-IC,TBD    I22 @BASEBOARD_FAB2_LIB.BASEBOARD_FAB2(SCH_1):PAGE74
  U2D1 AG76 VSS<835> SKX_EXT_B_BGA1-IC,TBD    I22 @BASEBOARD_FAB2_LIB.BASEBOARD_FAB2(SCH_1):PAGE74
  U2D1 AG74 VSS<836> SKX_EXT_B_BGA1-IC,TBD    I22 @BASEBOARD_FAB2_LIB.BASEBOARD_FAB2(SCH_1):PAGE74
  U2D1 AG70 VSS<837> SKX_EXT_B_BGA1-IC,TBD    I22 @BASEBOARD_FAB2_LIB.BASEBOARD_FAB2(SCH_1):PAGE74
  U2D1 AG64 VSS<838> SKX_EXT_B_BGA1-IC,TBD    I22 @BASEBOARD_FAB2_LIB.BASEBOARD_FAB2(SCH_1):PAGE74
  U2D1 AG36 VSS<839> SKX_EXT_B_BGA1-IC,TBD    I22 @BASEBOARD_FAB2_LIB.BASEBOARD_FAB2(SCH_1):PAGE74
  U2D1 AG18 VSS<840> SKX_EXT_B_BGA1-IC,TBD    I22 @BASEBOARD_FAB2_LIB.BASEBOARD_FAB2(SCH_1):PAGE74
  U2D1 AG14 VSS<841> SKX_EXT_B_BGA1-IC,TBD    I22 @BASEBOARD_FAB2_LIB.BASEBOARD_FAB2(SCH_1):PAGE74
  U2D1 AG12 VSS<842> SKX_EXT_B_BGA1-IC,TBD    I22 @BASEBOARD_FAB2_LIB.BASEBOARD_FAB2(SCH_1):PAGE74
  U2D1 AF85 VSS<843> SKX_EXT_B_BGA1-IC,TBD    I22 @BASEBOARD_FAB2_LIB.BASEBOARD_FAB2(SCH_1):PAGE74
  U2D1 AF83 VSS<844> SKX_EXT_B_BGA1-IC,TBD    I22 @BASEBOARD_FAB2_LIB.BASEBOARD_FAB2(SCH_1):PAGE74
  U2D1 AF77 VSS<845> SKX_EXT_B_BGA1-IC,TBD    I22 @BASEBOARD_FAB2_LIB.BASEBOARD_FAB2(SCH_1):PAGE74
  U2D1 AF73 VSS<846> SKX_EXT_B_BGA1-IC,TBD    I22 @BASEBOARD_FAB2_LIB.BASEBOARD_FAB2(SCH_1):PAGE74
  U2D1 AF41 VSS<847> SKX_EXT_B_BGA1-IC,TBD    I22 @BASEBOARD_FAB2_LIB.BASEBOARD_FAB2(SCH_1):PAGE74
  U2D1 AF39 VSS<848> SKX_EXT_B_BGA1-IC,TBD    I22 @BASEBOARD_FAB2_LIB.BASEBOARD_FAB2(SCH_1):PAGE74
  U2D1 AF37 VSS<849> SKX_EXT_B_BGA1-IC,TBD    I22 @BASEBOARD_FAB2_LIB.BASEBOARD_FAB2(SCH_1):PAGE74
  U2D1 AF33 VSS<850> SKX_EXT_B_BGA1-IC,TBD    I22 @BASEBOARD_FAB2_LIB.BASEBOARD_FAB2(SCH_1):PAGE74
  U2D1 AF31 VSS<851> SKX_EXT_B_BGA1-IC,TBD    I22 @BASEBOARD_FAB2_LIB.BASEBOARD_FAB2(SCH_1):PAGE74
  U2D1 AF29 VSS<852> SKX_EXT_B_BGA1-IC,TBD    I22 @BASEBOARD_FAB2_LIB.BASEBOARD_FAB2(SCH_1):PAGE74
  U2D1 AF27 VSS<853> SKX_EXT_B_BGA1-IC,TBD    I22 @BASEBOARD_FAB2_LIB.BASEBOARD_FAB2(SCH_1):PAGE74
  U2D1 AF25 VSS<854> SKX_EXT_B_BGA1-IC,TBD    I22 @BASEBOARD_FAB2_LIB.BASEBOARD_FAB2(SCH_1):PAGE74
  U2D1 AF23 VSS<855> SKX_EXT_B_BGA1-IC,TBD    I22 @BASEBOARD_FAB2_LIB.BASEBOARD_FAB2(SCH_1):PAGE74
  U2D1 AF21 VSS<856> SKX_EXT_B_BGA1-IC,TBD    I22 @BASEBOARD_FAB2_LIB.BASEBOARD_FAB2(SCH_1):PAGE74
  U2D1  AF9 VSS<857> SKX_EXT_B_BGA1-IC,TBD    I22 @BASEBOARD_FAB2_LIB.BASEBOARD_FAB2(SCH_1):PAGE74
  U2D1 AC52 VSS<858> SKX_EXT_B_BGA1-IC,TBD    I22 @BASEBOARD_FAB2_LIB.BASEBOARD_FAB2(SCH_1):PAGE74
  U2D1  AF1 VSS<859> SKX_EXT_B_BGA1-IC,TBD    I22 @BASEBOARD_FAB2_LIB.BASEBOARD_FAB2(SCH_1):PAGE74
  U2D1 AE78 VSS<860> SKX_EXT_B_BGA1-IC,TBD    I22 @BASEBOARD_FAB2_LIB.BASEBOARD_FAB2(SCH_1):PAGE74
  U2D1 AE70 VSS<861> SKX_EXT_B_BGA1-IC,TBD    I22 @BASEBOARD_FAB2_LIB.BASEBOARD_FAB2(SCH_1):PAGE74
  U2D1 AE68 VSS<862> SKX_EXT_B_BGA1-IC,TBD    I22 @BASEBOARD_FAB2_LIB.BASEBOARD_FAB2(SCH_1):PAGE74
  U2D1 AE66 VSS<863> SKX_EXT_B_BGA1-IC,TBD    I22 @BASEBOARD_FAB2_LIB.BASEBOARD_FAB2(SCH_1):PAGE74
  U2D1 AE64 VSS<864> SKX_EXT_B_BGA1-IC,TBD    I22 @BASEBOARD_FAB2_LIB.BASEBOARD_FAB2(SCH_1):PAGE74
  U2D1 AE42 VSS<865> SKX_EXT_B_BGA1-IC,TBD    I22 @BASEBOARD_FAB2_LIB.BASEBOARD_FAB2(SCH_1):PAGE74
  U2D1 AE40 VSS<866> SKX_EXT_B_BGA1-IC,TBD    I22 @BASEBOARD_FAB2_LIB.BASEBOARD_FAB2(SCH_1):PAGE74
  U2D1 AE38 VSS<867> SKX_EXT_B_BGA1-IC,TBD    I22 @BASEBOARD_FAB2_LIB.BASEBOARD_FAB2(SCH_1):PAGE74
  U2D1 AE16 VSS<868> SKX_EXT_B_BGA1-IC,TBD    I22 @BASEBOARD_FAB2_LIB.BASEBOARD_FAB2(SCH_1):PAGE74
  U2D1 AC54 VSS<869> SKX_EXT_B_BGA1-IC,TBD    I22 @BASEBOARD_FAB2_LIB.BASEBOARD_FAB2(SCH_1):PAGE74
  U2D1  AE8 VSS<870> SKX_EXT_B_BGA1-IC,TBD    I22 @BASEBOARD_FAB2_LIB.BASEBOARD_FAB2(SCH_1):PAGE74
  U2D1  AE4 VSS<871> SKX_EXT_B_BGA1-IC,TBD    I22 @BASEBOARD_FAB2_LIB.BASEBOARD_FAB2(SCH_1):PAGE74
  U2D1 AD85 VSS<872> SKX_EXT_B_BGA1-IC,TBD    I22 @BASEBOARD_FAB2_LIB.BASEBOARD_FAB2(SCH_1):PAGE74
  U2D1 AD83 VSS<873> SKX_EXT_B_BGA1-IC,TBD    I22 @BASEBOARD_FAB2_LIB.BASEBOARD_FAB2(SCH_1):PAGE74
  U2D1 AD81 VSS<874> SKX_EXT_B_BGA1-IC,TBD    I22 @BASEBOARD_FAB2_LIB.BASEBOARD_FAB2(SCH_1):PAGE74
  U2D1 AD75 VSS<875> SKX_EXT_B_BGA1-IC,TBD    I22 @BASEBOARD_FAB2_LIB.BASEBOARD_FAB2(SCH_1):PAGE74
  U2D1 AD73 VSS<876> SKX_EXT_B_BGA1-IC,TBD    I22 @BASEBOARD_FAB2_LIB.BASEBOARD_FAB2(SCH_1):PAGE74
  U2D1 AD71 VSS<877> SKX_EXT_B_BGA1-IC,TBD    I22 @BASEBOARD_FAB2_LIB.BASEBOARD_FAB2(SCH_1):PAGE74
  U2D1 AD43 VSS<878> SKX_EXT_B_BGA1-IC,TBD    I22 @BASEBOARD_FAB2_LIB.BASEBOARD_FAB2(SCH_1):PAGE74
  U2D1 AD39 VSS<879> SKX_EXT_B_BGA1-IC,TBD    I22 @BASEBOARD_FAB2_LIB.BASEBOARD_FAB2(SCH_1):PAGE74
  U2D1 AD33 VSS<880> SKX_EXT_B_BGA1-IC,TBD    I22 @BASEBOARD_FAB2_LIB.BASEBOARD_FAB2(SCH_1):PAGE74
  U2D1 AD27 VSS<881> SKX_EXT_B_BGA1-IC,TBD    I22 @BASEBOARD_FAB2_LIB.BASEBOARD_FAB2(SCH_1):PAGE74
  U2D1 AD21 VSS<882> SKX_EXT_B_BGA1-IC,TBD    I22 @BASEBOARD_FAB2_LIB.BASEBOARD_FAB2(SCH_1):PAGE74
  U2D1 AD19 VSS<883> SKX_EXT_B_BGA1-IC,TBD    I22 @BASEBOARD_FAB2_LIB.BASEBOARD_FAB2(SCH_1):PAGE74
  U2D1 AD15 VSS<884> SKX_EXT_B_BGA1-IC,TBD    I22 @BASEBOARD_FAB2_LIB.BASEBOARD_FAB2(SCH_1):PAGE74
  U2D1 AD13 VSS<885> SKX_EXT_B_BGA1-IC,TBD    I22 @BASEBOARD_FAB2_LIB.BASEBOARD_FAB2(SCH_1):PAGE74
  U2D1 AD11 VSS<886> SKX_EXT_B_BGA1-IC,TBD    I22 @BASEBOARD_FAB2_LIB.BASEBOARD_FAB2(SCH_1):PAGE74
  U2D1  AD9 VSS<887> SKX_EXT_B_BGA1-IC,TBD    I22 @BASEBOARD_FAB2_LIB.BASEBOARD_FAB2(SCH_1):PAGE74
  U2D1  AD7 VSS<888> SKX_EXT_B_BGA1-IC,TBD    I22 @BASEBOARD_FAB2_LIB.BASEBOARD_FAB2(SCH_1):PAGE74
  U2D1  AD3 VSS<889> SKX_EXT_B_BGA1-IC,TBD    I22 @BASEBOARD_FAB2_LIB.BASEBOARD_FAB2(SCH_1):PAGE74
  U2D1 AC86 VSS<890> SKX_EXT_B_BGA1-IC,TBD    I22 @BASEBOARD_FAB2_LIB.BASEBOARD_FAB2(SCH_1):PAGE74
  U2D1 AC84 VSS<891> SKX_EXT_B_BGA1-IC,TBD    I22 @BASEBOARD_FAB2_LIB.BASEBOARD_FAB2(SCH_1):PAGE74
  U2D1 AC78 VSS<892> SKX_EXT_B_BGA1-IC,TBD    I22 @BASEBOARD_FAB2_LIB.BASEBOARD_FAB2(SCH_1):PAGE74
  U2D1 AC72 VSS<893> SKX_EXT_B_BGA1-IC,TBD    I22 @BASEBOARD_FAB2_LIB.BASEBOARD_FAB2(SCH_1):PAGE74
  U2D1 AC70 VSS<894> SKX_EXT_B_BGA1-IC,TBD    I22 @BASEBOARD_FAB2_LIB.BASEBOARD_FAB2(SCH_1):PAGE74
  U2D1 AC64 VSS<895> SKX_EXT_B_BGA1-IC,TBD    I22 @BASEBOARD_FAB2_LIB.BASEBOARD_FAB2(SCH_1):PAGE74
  U2D1 AC40 VSS<896> SKX_EXT_B_BGA1-IC,TBD    I22 @BASEBOARD_FAB2_LIB.BASEBOARD_FAB2(SCH_1):PAGE74
  U2D1 AC38 VSS<897> SKX_EXT_B_BGA1-IC,TBD    I22 @BASEBOARD_FAB2_LIB.BASEBOARD_FAB2(SCH_1):PAGE74
  U2D1 AC34 VSS<898> SKX_EXT_B_BGA1-IC,TBD    I22 @BASEBOARD_FAB2_LIB.BASEBOARD_FAB2(SCH_1):PAGE74
  U2D1 AC32 VSS<899> SKX_EXT_B_BGA1-IC,TBD    I22 @BASEBOARD_FAB2_LIB.BASEBOARD_FAB2(SCH_1):PAGE74
  U2D1 AC28 VSS<900> SKX_EXT_B_BGA1-IC,TBD    I22 @BASEBOARD_FAB2_LIB.BASEBOARD_FAB2(SCH_1):PAGE74
  U2D1 AC26 VSS<901> SKX_EXT_B_BGA1-IC,TBD    I22 @BASEBOARD_FAB2_LIB.BASEBOARD_FAB2(SCH_1):PAGE74
  U2D1 AC22 VSS<902> SKX_EXT_B_BGA1-IC,TBD    I22 @BASEBOARD_FAB2_LIB.BASEBOARD_FAB2(SCH_1):PAGE74
  U2D1 AC18 VSS<903> SKX_EXT_B_BGA1-IC,TBD    I22 @BASEBOARD_FAB2_LIB.BASEBOARD_FAB2(SCH_1):PAGE74
  U2D1 AB85 VSS<904> SKX_EXT_B_BGA1-IC,TBD    I22 @BASEBOARD_FAB2_LIB.BASEBOARD_FAB2(SCH_1):PAGE74
  U2D1 AB83 VSS<905> SKX_EXT_B_BGA1-IC,TBD    I22 @BASEBOARD_FAB2_LIB.BASEBOARD_FAB2(SCH_1):PAGE74
  U2D1 AB79 VSS<906> SKX_EXT_B_BGA1-IC,TBD    I22 @BASEBOARD_FAB2_LIB.BASEBOARD_FAB2(SCH_1):PAGE74
  U2D1 AB73 VSS<907> SKX_EXT_B_BGA1-IC,TBD    I22 @BASEBOARD_FAB2_LIB.BASEBOARD_FAB2(SCH_1):PAGE74
  U2D1 AB69 VSS<908> SKX_EXT_B_BGA1-IC,TBD    I22 @BASEBOARD_FAB2_LIB.BASEBOARD_FAB2(SCH_1):PAGE74
  U2D1 AB65 VSS<909> SKX_EXT_B_BGA1-IC,TBD    I22 @BASEBOARD_FAB2_LIB.BASEBOARD_FAB2(SCH_1):PAGE74
  U2D1 AB41 VSS<910> SKX_EXT_B_BGA1-IC,TBD    I22 @BASEBOARD_FAB2_LIB.BASEBOARD_FAB2(SCH_1):PAGE74
  U2D1 AB37 VSS<911> SKX_EXT_B_BGA1-IC,TBD    I22 @BASEBOARD_FAB2_LIB.BASEBOARD_FAB2(SCH_1):PAGE74
  U2D1 AB35 VSS<912> SKX_EXT_B_BGA1-IC,TBD    I22 @BASEBOARD_FAB2_LIB.BASEBOARD_FAB2(SCH_1):PAGE74
  U2D1 AB31 VSS<913> SKX_EXT_B_BGA1-IC,TBD    I22 @BASEBOARD_FAB2_LIB.BASEBOARD_FAB2(SCH_1):PAGE74
  U2D1 AB29 VSS<914> SKX_EXT_B_BGA1-IC,TBD    I22 @BASEBOARD_FAB2_LIB.BASEBOARD_FAB2(SCH_1):PAGE74
  U2D1 AB25 VSS<915> SKX_EXT_B_BGA1-IC,TBD    I22 @BASEBOARD_FAB2_LIB.BASEBOARD_FAB2(SCH_1):PAGE74
  U2D1 AB23 VSS<916> SKX_EXT_B_BGA1-IC,TBD    I22 @BASEBOARD_FAB2_LIB.BASEBOARD_FAB2(SCH_1):PAGE74
  U2D1 AB21 VSS<917> SKX_EXT_B_BGA1-IC,TBD    I22 @BASEBOARD_FAB2_LIB.BASEBOARD_FAB2(SCH_1):PAGE74
  U2D1 AB11 VSS<918> SKX_EXT_B_BGA1-IC,TBD    I22 @BASEBOARD_FAB2_LIB.BASEBOARD_FAB2(SCH_1):PAGE74
  U2D1  AB5 VSS<919> SKX_EXT_B_BGA1-IC,TBD    I22 @BASEBOARD_FAB2_LIB.BASEBOARD_FAB2(SCH_1):PAGE74
  U2D1  AB1 VSS<920> SKX_EXT_B_BGA1-IC,TBD    I22 @BASEBOARD_FAB2_LIB.BASEBOARD_FAB2(SCH_1):PAGE74
  U2D1 AA82 VSS<921> SKX_EXT_B_BGA1-IC,TBD    I22 @BASEBOARD_FAB2_LIB.BASEBOARD_FAB2(SCH_1):PAGE74
  U2D1 AA80 VSS<922> SKX_EXT_B_BGA1-IC,TBD    I22 @BASEBOARD_FAB2_LIB.BASEBOARD_FAB2(SCH_1):PAGE74
  U2D1 AA78 VSS<923> SKX_EXT_B_BGA1-IC,TBD    I22 @BASEBOARD_FAB2_LIB.BASEBOARD_FAB2(SCH_1):PAGE74
  U2D1 AA76 VSS<924> SKX_EXT_B_BGA1-IC,TBD    I22 @BASEBOARD_FAB2_LIB.BASEBOARD_FAB2(SCH_1):PAGE74
  U2D1 AA68 VSS<925> SKX_EXT_B_BGA1-IC,TBD    I22 @BASEBOARD_FAB2_LIB.BASEBOARD_FAB2(SCH_1):PAGE74
  U2D1 AA66 VSS<926> SKX_EXT_B_BGA1-IC,TBD    I22 @BASEBOARD_FAB2_LIB.BASEBOARD_FAB2(SCH_1):PAGE74
  U2D1 AA64 VSS<927> SKX_EXT_B_BGA1-IC,TBD    I22 @BASEBOARD_FAB2_LIB.BASEBOARD_FAB2(SCH_1):PAGE74
  U2D1 AA42 VSS<928> SKX_EXT_B_BGA1-IC,TBD    I22 @BASEBOARD_FAB2_LIB.BASEBOARD_FAB2(SCH_1):PAGE74
  U2D1 AA36 VSS<929> SKX_EXT_B_BGA1-IC,TBD    I22 @BASEBOARD_FAB2_LIB.BASEBOARD_FAB2(SCH_1):PAGE74
  U2D1 AA30 VSS<930> SKX_EXT_B_BGA1-IC,TBD    I22 @BASEBOARD_FAB2_LIB.BASEBOARD_FAB2(SCH_1):PAGE74
  U2D1 AA24 VSS<931> SKX_EXT_B_BGA1-IC,TBD    I22 @BASEBOARD_FAB2_LIB.BASEBOARD_FAB2(SCH_1):PAGE74
  U2D1 AA22 VSS<932> SKX_EXT_B_BGA1-IC,TBD    I22 @BASEBOARD_FAB2_LIB.BASEBOARD_FAB2(SCH_1):PAGE74
  U2D1 AA18 VSS<933> SKX_EXT_B_BGA1-IC,TBD    I22 @BASEBOARD_FAB2_LIB.BASEBOARD_FAB2(SCH_1):PAGE74
  U2D1 BG72 VSS<614> SKX_EXT_B_BGA1-IC,TBD    I23 @BASEBOARD_FAB2_LIB.BASEBOARD_FAB2(SCH_1):PAGE74
  U2D1 BG24 VSS<615> SKX_EXT_B_BGA1-IC,TBD    I23 @BASEBOARD_FAB2_LIB.BASEBOARD_FAB2(SCH_1):PAGE74
  U2D1 BG22 VSS<616> SKX_EXT_B_BGA1-IC,TBD    I23 @BASEBOARD_FAB2_LIB.BASEBOARD_FAB2(SCH_1):PAGE74
  U2D1 BG10 VSS<617> SKX_EXT_B_BGA1-IC,TBD    I23 @BASEBOARD_FAB2_LIB.BASEBOARD_FAB2(SCH_1):PAGE74
  U2D1  BG8 VSS<618> SKX_EXT_B_BGA1-IC,TBD    I23 @BASEBOARD_FAB2_LIB.BASEBOARD_FAB2(SCH_1):PAGE74
  U2D1  BG6 VSS<619> SKX_EXT_B_BGA1-IC,TBD    I23 @BASEBOARD_FAB2_LIB.BASEBOARD_FAB2(SCH_1):PAGE74
  U2D1 BF71 VSS<620> SKX_EXT_B_BGA1-IC,TBD    I23 @BASEBOARD_FAB2_LIB.BASEBOARD_FAB2(SCH_1):PAGE74
  U2D1 BF69 VSS<621> SKX_EXT_B_BGA1-IC,TBD    I23 @BASEBOARD_FAB2_LIB.BASEBOARD_FAB2(SCH_1):PAGE74
  U2D1 BF67 VSS<622> SKX_EXT_B_BGA1-IC,TBD    I23 @BASEBOARD_FAB2_LIB.BASEBOARD_FAB2(SCH_1):PAGE74
  U2D1 BF65 VSS<623> SKX_EXT_B_BGA1-IC,TBD    I23 @BASEBOARD_FAB2_LIB.BASEBOARD_FAB2(SCH_1):PAGE74
  U2D1 BF63 VSS<624> SKX_EXT_B_BGA1-IC,TBD    I23 @BASEBOARD_FAB2_LIB.BASEBOARD_FAB2(SCH_1):PAGE74
  U2D1 BF25 VSS<625> SKX_EXT_B_BGA1-IC,TBD    I23 @BASEBOARD_FAB2_LIB.BASEBOARD_FAB2(SCH_1):PAGE74
  U2D1 BF19 VSS<626> SKX_EXT_B_BGA1-IC,TBD    I23 @BASEBOARD_FAB2_LIB.BASEBOARD_FAB2(SCH_1):PAGE74
  U2D1 BF17 VSS<627> SKX_EXT_B_BGA1-IC,TBD    I23 @BASEBOARD_FAB2_LIB.BASEBOARD_FAB2(SCH_1):PAGE74
  U2D1 BF15 VSS<628> SKX_EXT_B_BGA1-IC,TBD    I23 @BASEBOARD_FAB2_LIB.BASEBOARD_FAB2(SCH_1):PAGE74
  U2D1  BF9 VSS<629> SKX_EXT_B_BGA1-IC,TBD    I23 @BASEBOARD_FAB2_LIB.BASEBOARD_FAB2(SCH_1):PAGE74
  U2D1 BE70 VSS<630> SKX_EXT_B_BGA1-IC,TBD    I23 @BASEBOARD_FAB2_LIB.BASEBOARD_FAB2(SCH_1):PAGE74
  U2D1 BE68 VSS<631> SKX_EXT_B_BGA1-IC,TBD    I23 @BASEBOARD_FAB2_LIB.BASEBOARD_FAB2(SCH_1):PAGE74
  U2D1 BE66 VSS<632> SKX_EXT_B_BGA1-IC,TBD    I23 @BASEBOARD_FAB2_LIB.BASEBOARD_FAB2(SCH_1):PAGE74
  U2D1 BE64 VSS<633> SKX_EXT_B_BGA1-IC,TBD    I23 @BASEBOARD_FAB2_LIB.BASEBOARD_FAB2(SCH_1):PAGE74
  U2D1 BE26 VSS<634> SKX_EXT_B_BGA1-IC,TBD    I23 @BASEBOARD_FAB2_LIB.BASEBOARD_FAB2(SCH_1):PAGE74
  U2D1 BE10 VSS<635> SKX_EXT_B_BGA1-IC,TBD    I23 @BASEBOARD_FAB2_LIB.BASEBOARD_FAB2(SCH_1):PAGE74
  U2D1  BE8 VSS<636> SKX_EXT_B_BGA1-IC,TBD    I23 @BASEBOARD_FAB2_LIB.BASEBOARD_FAB2(SCH_1):PAGE74
  U2D1  BE6 VSS<637> SKX_EXT_B_BGA1-IC,TBD    I23 @BASEBOARD_FAB2_LIB.BASEBOARD_FAB2(SCH_1):PAGE74
  U2D1  BE4 VSS<638> SKX_EXT_B_BGA1-IC,TBD    I23 @BASEBOARD_FAB2_LIB.BASEBOARD_FAB2(SCH_1):PAGE74
  U2D1 BD71 VSS<639> SKX_EXT_B_BGA1-IC,TBD    I23 @BASEBOARD_FAB2_LIB.BASEBOARD_FAB2(SCH_1):PAGE74
  U2D1 BD63 VSS<640> SKX_EXT_B_BGA1-IC,TBD    I23 @BASEBOARD_FAB2_LIB.BASEBOARD_FAB2(SCH_1):PAGE74
  U2D1 BD27 VSS<641> SKX_EXT_B_BGA1-IC,TBD    I23 @BASEBOARD_FAB2_LIB.BASEBOARD_FAB2(SCH_1):PAGE74
  U2D1 BD21 VSS<642> SKX_EXT_B_BGA1-IC,TBD    I23 @BASEBOARD_FAB2_LIB.BASEBOARD_FAB2(SCH_1):PAGE74
  U2D1 BD15 VSS<643> SKX_EXT_B_BGA1-IC,TBD    I23 @BASEBOARD_FAB2_LIB.BASEBOARD_FAB2(SCH_1):PAGE74
  U2D1 BD11 VSS<644> SKX_EXT_B_BGA1-IC,TBD    I23 @BASEBOARD_FAB2_LIB.BASEBOARD_FAB2(SCH_1):PAGE74
  U2D1  BD5 VSS<645> SKX_EXT_B_BGA1-IC,TBD    I23 @BASEBOARD_FAB2_LIB.BASEBOARD_FAB2(SCH_1):PAGE74
  U2D1 BC82 VSS<646> SKX_EXT_B_BGA1-IC,TBD    I23 @BASEBOARD_FAB2_LIB.BASEBOARD_FAB2(SCH_1):PAGE74
  U2D1 BC80 VSS<647> SKX_EXT_B_BGA1-IC,TBD    I23 @BASEBOARD_FAB2_LIB.BASEBOARD_FAB2(SCH_1):PAGE74
  U2D1 BC78 VSS<648> SKX_EXT_B_BGA1-IC,TBD    I23 @BASEBOARD_FAB2_LIB.BASEBOARD_FAB2(SCH_1):PAGE74
  U2D1 BC76 VSS<649> SKX_EXT_B_BGA1-IC,TBD    I23 @BASEBOARD_FAB2_LIB.BASEBOARD_FAB2(SCH_1):PAGE74
  U2D1 BC74 VSS<650> SKX_EXT_B_BGA1-IC,TBD    I23 @BASEBOARD_FAB2_LIB.BASEBOARD_FAB2(SCH_1):PAGE74
  U2D1 BC72 VSS<651> SKX_EXT_B_BGA1-IC,TBD    I23 @BASEBOARD_FAB2_LIB.BASEBOARD_FAB2(SCH_1):PAGE74
  U2D1 BC70 VSS<652> SKX_EXT_B_BGA1-IC,TBD    I23 @BASEBOARD_FAB2_LIB.BASEBOARD_FAB2(SCH_1):PAGE74
  U2D1 BC16 VSS<653> SKX_EXT_B_BGA1-IC,TBD    I23 @BASEBOARD_FAB2_LIB.BASEBOARD_FAB2(SCH_1):PAGE74
  U2D1 BC12 VSS<654> SKX_EXT_B_BGA1-IC,TBD    I23 @BASEBOARD_FAB2_LIB.BASEBOARD_FAB2(SCH_1):PAGE74
  U2D1  BC8 VSS<655> SKX_EXT_B_BGA1-IC,TBD    I23 @BASEBOARD_FAB2_LIB.BASEBOARD_FAB2(SCH_1):PAGE74
  U2D1  BC4 VSS<656> SKX_EXT_B_BGA1-IC,TBD    I23 @BASEBOARD_FAB2_LIB.BASEBOARD_FAB2(SCH_1):PAGE74
  U2D1 BB83 VSS<657> SKX_EXT_B_BGA1-IC,TBD    I23 @BASEBOARD_FAB2_LIB.BASEBOARD_FAB2(SCH_1):PAGE74
  U2D1 BB81 VSS<658> SKX_EXT_B_BGA1-IC,TBD    I23 @BASEBOARD_FAB2_LIB.BASEBOARD_FAB2(SCH_1):PAGE74
  U2D1 BB79 VSS<659> SKX_EXT_B_BGA1-IC,TBD    I23 @BASEBOARD_FAB2_LIB.BASEBOARD_FAB2(SCH_1):PAGE74
  U2D1 BB77 VSS<660> SKX_EXT_B_BGA1-IC,TBD    I23 @BASEBOARD_FAB2_LIB.BASEBOARD_FAB2(SCH_1):PAGE74
  U2D1 BB75 VSS<661> SKX_EXT_B_BGA1-IC,TBD    I23 @BASEBOARD_FAB2_LIB.BASEBOARD_FAB2(SCH_1):PAGE74
  U2D1 BB73 VSS<662> SKX_EXT_B_BGA1-IC,TBD    I23 @BASEBOARD_FAB2_LIB.BASEBOARD_FAB2(SCH_1):PAGE74
  U2D1 BB69 VSS<663> SKX_EXT_B_BGA1-IC,TBD    I23 @BASEBOARD_FAB2_LIB.BASEBOARD_FAB2(SCH_1):PAGE74
  U2D1 BB63 VSS<664> SKX_EXT_B_BGA1-IC,TBD    I23 @BASEBOARD_FAB2_LIB.BASEBOARD_FAB2(SCH_1):PAGE74
  U2D1 BB23 VSS<665> SKX_EXT_B_BGA1-IC,TBD    I23 @BASEBOARD_FAB2_LIB.BASEBOARD_FAB2(SCH_1):PAGE74
  U2D1 BB19 VSS<666> SKX_EXT_B_BGA1-IC,TBD    I23 @BASEBOARD_FAB2_LIB.BASEBOARD_FAB2(SCH_1):PAGE74
  U2D1 BA84 VSS<667> SKX_EXT_B_BGA1-IC,TBD    I23 @BASEBOARD_FAB2_LIB.BASEBOARD_FAB2(SCH_1):PAGE74
  U2D1 BA80 VSS<668> SKX_EXT_B_BGA1-IC,TBD    I23 @BASEBOARD_FAB2_LIB.BASEBOARD_FAB2(SCH_1):PAGE74
  U2D1 BA74 VSS<669> SKX_EXT_B_BGA1-IC,TBD    I23 @BASEBOARD_FAB2_LIB.BASEBOARD_FAB2(SCH_1):PAGE74
  U2D1 BA68 VSS<670> SKX_EXT_B_BGA1-IC,TBD    I23 @BASEBOARD_FAB2_LIB.BASEBOARD_FAB2(SCH_1):PAGE74
  U2D1 BA62 VSS<671> SKX_EXT_B_BGA1-IC,TBD    I23 @BASEBOARD_FAB2_LIB.BASEBOARD_FAB2(SCH_1):PAGE74
  U2D1 BA12 VSS<672> SKX_EXT_B_BGA1-IC,TBD    I23 @BASEBOARD_FAB2_LIB.BASEBOARD_FAB2(SCH_1):PAGE74
  U2D1  BA6 VSS<673> SKX_EXT_B_BGA1-IC,TBD    I23 @BASEBOARD_FAB2_LIB.BASEBOARD_FAB2(SCH_1):PAGE74
  U2D1  BA2 VSS<674> SKX_EXT_B_BGA1-IC,TBD    I23 @BASEBOARD_FAB2_LIB.BASEBOARD_FAB2(SCH_1):PAGE74
  U2D1 AY81 VSS<675> SKX_EXT_B_BGA1-IC,TBD    I23 @BASEBOARD_FAB2_LIB.BASEBOARD_FAB2(SCH_1):PAGE74
  U2D1 AY79 VSS<676> SKX_EXT_B_BGA1-IC,TBD    I23 @BASEBOARD_FAB2_LIB.BASEBOARD_FAB2(SCH_1):PAGE74
  U2D1 AY63 VSS<677> SKX_EXT_B_BGA1-IC,TBD    I23 @BASEBOARD_FAB2_LIB.BASEBOARD_FAB2(SCH_1):PAGE74
  U2D1 AY25 VSS<678> SKX_EXT_B_BGA1-IC,TBD    I23 @BASEBOARD_FAB2_LIB.BASEBOARD_FAB2(SCH_1):PAGE74
  U2D1 AY23 VSS<679> SKX_EXT_B_BGA1-IC,TBD    I23 @BASEBOARD_FAB2_LIB.BASEBOARD_FAB2(SCH_1):PAGE74
  U2D1 AY21 VSS<680> SKX_EXT_B_BGA1-IC,TBD    I23 @BASEBOARD_FAB2_LIB.BASEBOARD_FAB2(SCH_1):PAGE74
  U2D1 AY17 VSS<681> SKX_EXT_B_BGA1-IC,TBD    I23 @BASEBOARD_FAB2_LIB.BASEBOARD_FAB2(SCH_1):PAGE74
  U2D1 AY15 VSS<682> SKX_EXT_B_BGA1-IC,TBD    I23 @BASEBOARD_FAB2_LIB.BASEBOARD_FAB2(SCH_1):PAGE74
  U2D1  AY5 VSS<683> SKX_EXT_B_BGA1-IC,TBD    I23 @BASEBOARD_FAB2_LIB.BASEBOARD_FAB2(SCH_1):PAGE74
  U2D1 AW84 VSS<684> SKX_EXT_B_BGA1-IC,TBD    I23 @BASEBOARD_FAB2_LIB.BASEBOARD_FAB2(SCH_1):PAGE74
  U2D1 AW82 VSS<685> SKX_EXT_B_BGA1-IC,TBD    I23 @BASEBOARD_FAB2_LIB.BASEBOARD_FAB2(SCH_1):PAGE74
  U2D1 AW78 VSS<686> SKX_EXT_B_BGA1-IC,TBD    I23 @BASEBOARD_FAB2_LIB.BASEBOARD_FAB2(SCH_1):PAGE74
  U2D1 AW74 VSS<687> SKX_EXT_B_BGA1-IC,TBD    I23 @BASEBOARD_FAB2_LIB.BASEBOARD_FAB2(SCH_1):PAGE74
  U2D1 AW72 VSS<688> SKX_EXT_B_BGA1-IC,TBD    I23 @BASEBOARD_FAB2_LIB.BASEBOARD_FAB2(SCH_1):PAGE74
  U2D1 AW70 VSS<689> SKX_EXT_B_BGA1-IC,TBD    I23 @BASEBOARD_FAB2_LIB.BASEBOARD_FAB2(SCH_1):PAGE74
  U2D1 AW68 VSS<690> SKX_EXT_B_BGA1-IC,TBD    I23 @BASEBOARD_FAB2_LIB.BASEBOARD_FAB2(SCH_1):PAGE74
  U2D1 AW66 VSS<691> SKX_EXT_B_BGA1-IC,TBD    I23 @BASEBOARD_FAB2_LIB.BASEBOARD_FAB2(SCH_1):PAGE74
  U2D1 AW62 VSS<692> SKX_EXT_B_BGA1-IC,TBD    I23 @BASEBOARD_FAB2_LIB.BASEBOARD_FAB2(SCH_1):PAGE74
  U2D1 AW10 VSS<693> SKX_EXT_B_BGA1-IC,TBD    I23 @BASEBOARD_FAB2_LIB.BASEBOARD_FAB2(SCH_1):PAGE74
  U2D1  AW2 VSS<694> SKX_EXT_B_BGA1-IC,TBD    I23 @BASEBOARD_FAB2_LIB.BASEBOARD_FAB2(SCH_1):PAGE74
  U2D1 AV83 VSS<695> SKX_EXT_B_BGA1-IC,TBD    I23 @BASEBOARD_FAB2_LIB.BASEBOARD_FAB2(SCH_1):PAGE74
  U2D1 AV75 VSS<696> SKX_EXT_B_BGA1-IC,TBD    I23 @BASEBOARD_FAB2_LIB.BASEBOARD_FAB2(SCH_1):PAGE74
  U2D1 AV67 VSS<697> SKX_EXT_B_BGA1-IC,TBD    I23 @BASEBOARD_FAB2_LIB.BASEBOARD_FAB2(SCH_1):PAGE74
  U2D1 AV65 VSS<698> SKX_EXT_B_BGA1-IC,TBD    I23 @BASEBOARD_FAB2_LIB.BASEBOARD_FAB2(SCH_1):PAGE74
  U2D1 AV63 VSS<699> SKX_EXT_B_BGA1-IC,TBD    I23 @BASEBOARD_FAB2_LIB.BASEBOARD_FAB2(SCH_1):PAGE74
  U2D1 AV25 VSS<700> SKX_EXT_B_BGA1-IC,TBD    I23 @BASEBOARD_FAB2_LIB.BASEBOARD_FAB2(SCH_1):PAGE74
  U2D1 AV23 VSS<701> SKX_EXT_B_BGA1-IC,TBD    I23 @BASEBOARD_FAB2_LIB.BASEBOARD_FAB2(SCH_1):PAGE74
  U2D1 AV19 VSS<702> SKX_EXT_B_BGA1-IC,TBD    I23 @BASEBOARD_FAB2_LIB.BASEBOARD_FAB2(SCH_1):PAGE74
  U2D1 AV13 VSS<703> SKX_EXT_B_BGA1-IC,TBD    I23 @BASEBOARD_FAB2_LIB.BASEBOARD_FAB2(SCH_1):PAGE74
  U2D1 AV11 VSS<704> SKX_EXT_B_BGA1-IC,TBD    I23 @BASEBOARD_FAB2_LIB.BASEBOARD_FAB2(SCH_1):PAGE74
  U2D1  AV7 VSS<705> SKX_EXT_B_BGA1-IC,TBD    I23 @BASEBOARD_FAB2_LIB.BASEBOARD_FAB2(SCH_1):PAGE74
  U2D1  AV3 VSS<706> SKX_EXT_B_BGA1-IC,TBD    I23 @BASEBOARD_FAB2_LIB.BASEBOARD_FAB2(SCH_1):PAGE74
  U2D1  AV1 VSS<707> SKX_EXT_B_BGA1-IC,TBD    I23 @BASEBOARD_FAB2_LIB.BASEBOARD_FAB2(SCH_1):PAGE74
  U2D1 AU86 VSS<708> SKX_EXT_B_BGA1-IC,TBD    I23 @BASEBOARD_FAB2_LIB.BASEBOARD_FAB2(SCH_1):PAGE74
  U2D1 AU84 VSS<709> SKX_EXT_B_BGA1-IC,TBD    I23 @BASEBOARD_FAB2_LIB.BASEBOARD_FAB2(SCH_1):PAGE74
  U2D1 AU80 VSS<710> SKX_EXT_B_BGA1-IC,TBD    I23 @BASEBOARD_FAB2_LIB.BASEBOARD_FAB2(SCH_1):PAGE74
  U2D1 AU78 VSS<711> SKX_EXT_B_BGA1-IC,TBD    I23 @BASEBOARD_FAB2_LIB.BASEBOARD_FAB2(SCH_1):PAGE74
  U2D1 AU76 VSS<712> SKX_EXT_B_BGA1-IC,TBD    I23 @BASEBOARD_FAB2_LIB.BASEBOARD_FAB2(SCH_1):PAGE74
  U2D1 AU74 VSS<713> SKX_EXT_B_BGA1-IC,TBD    I23 @BASEBOARD_FAB2_LIB.BASEBOARD_FAB2(SCH_1):PAGE74
  U2D1 AU68 VSS<714> SKX_EXT_B_BGA1-IC,TBD    I23 @BASEBOARD_FAB2_LIB.BASEBOARD_FAB2(SCH_1):PAGE74
  U2D1 AU64 VSS<715> SKX_EXT_B_BGA1-IC,TBD    I23 @BASEBOARD_FAB2_LIB.BASEBOARD_FAB2(SCH_1):PAGE74
  U2D1 AU62 VSS<716> SKX_EXT_B_BGA1-IC,TBD    I23 @BASEBOARD_FAB2_LIB.BASEBOARD_FAB2(SCH_1):PAGE74
  U2D1 AU28 VSS<717> SKX_EXT_B_BGA1-IC,TBD    I23 @BASEBOARD_FAB2_LIB.BASEBOARD_FAB2(SCH_1):PAGE74
  U2D1 AU26 VSS<718> SKX_EXT_B_BGA1-IC,TBD    I23 @BASEBOARD_FAB2_LIB.BASEBOARD_FAB2(SCH_1):PAGE74
  U2D1  AU6 VSS<719> SKX_EXT_B_BGA1-IC,TBD    I23 @BASEBOARD_FAB2_LIB.BASEBOARD_FAB2(SCH_1):PAGE74
  U2D1  AU2 VSS<720> SKX_EXT_B_BGA1-IC,TBD    I23 @BASEBOARD_FAB2_LIB.BASEBOARD_FAB2(SCH_1):PAGE74
  U2D1 AT85 VSS<721> SKX_EXT_B_BGA1-IC,TBD    I23 @BASEBOARD_FAB2_LIB.BASEBOARD_FAB2(SCH_1):PAGE74
  U2D1 AT83 VSS<722> SKX_EXT_B_BGA1-IC,TBD    I23 @BASEBOARD_FAB2_LIB.BASEBOARD_FAB2(SCH_1):PAGE74
  U2D1 AT77 VSS<723> SKX_EXT_B_BGA1-IC,TBD    I23 @BASEBOARD_FAB2_LIB.BASEBOARD_FAB2(SCH_1):PAGE74
  U2D1 AT73 VSS<724> SKX_EXT_B_BGA1-IC,TBD    I23 @BASEBOARD_FAB2_LIB.BASEBOARD_FAB2(SCH_1):PAGE74
  U2D1 AT69 VSS<725> SKX_EXT_B_BGA1-IC,TBD    I23 @BASEBOARD_FAB2_LIB.BASEBOARD_FAB2(SCH_1):PAGE74
  U2D1 AT63 VSS<726> SKX_EXT_B_BGA1-IC,TBD    I23 @BASEBOARD_FAB2_LIB.BASEBOARD_FAB2(SCH_1):PAGE74
  U2D1 AT61 VSS<727> SKX_EXT_B_BGA1-IC,TBD    I23 @BASEBOARD_FAB2_LIB.BASEBOARD_FAB2(SCH_1):PAGE74
  U2D1 AT27 VSS<728> SKX_EXT_B_BGA1-IC,TBD    I23 @BASEBOARD_FAB2_LIB.BASEBOARD_FAB2(SCH_1):PAGE74
  U2D1 AT21 VSS<729> SKX_EXT_B_BGA1-IC,TBD    I23 @BASEBOARD_FAB2_LIB.BASEBOARD_FAB2(SCH_1):PAGE74
  U2D1 AT17 VSS<730> SKX_EXT_B_BGA1-IC,TBD    I23 @BASEBOARD_FAB2_LIB.BASEBOARD_FAB2(SCH_1):PAGE74
  U2D1 AT15 VSS<731> SKX_EXT_B_BGA1-IC,TBD    I23 @BASEBOARD_FAB2_LIB.BASEBOARD_FAB2(SCH_1):PAGE74
  U2D1  P63 VSS<732> SKX_EXT_B_BGA1-IC,TBD    I23 @BASEBOARD_FAB2_LIB.BASEBOARD_FAB2(SCH_1):PAGE74
  U2D1 AC48 VSS<733> SKX_EXT_B_BGA1-IC,TBD    I23 @BASEBOARD_FAB2_LIB.BASEBOARD_FAB2(SCH_1):PAGE74
  U2D1 AR78 VSS<734> SKX_EXT_B_BGA1-IC,TBD    I23 @BASEBOARD_FAB2_LIB.BASEBOARD_FAB2(SCH_1):PAGE74
  U2D1 AR72 VSS<735> SKX_EXT_B_BGA1-IC,TBD    I23 @BASEBOARD_FAB2_LIB.BASEBOARD_FAB2(SCH_1):PAGE74
  U2D1 AR60 VSS<736> SKX_EXT_B_BGA1-IC,TBD    I23 @BASEBOARD_FAB2_LIB.BASEBOARD_FAB2(SCH_1):PAGE74
  U2D1 AR30 VSS<737> SKX_EXT_B_BGA1-IC,TBD    I23 @BASEBOARD_FAB2_LIB.BASEBOARD_FAB2(SCH_1):PAGE74
  U2D1 AR24 VSS<738> SKX_EXT_B_BGA1-IC,TBD    I23 @BASEBOARD_FAB2_LIB.BASEBOARD_FAB2(SCH_1):PAGE74
  U2D1 AR10 VSS<739> SKX_EXT_B_BGA1-IC,TBD    I23 @BASEBOARD_FAB2_LIB.BASEBOARD_FAB2(SCH_1):PAGE74
  U2D1 AP85 VSS<740> SKX_EXT_B_BGA1-IC,TBD    I23 @BASEBOARD_FAB2_LIB.BASEBOARD_FAB2(SCH_1):PAGE74
  U2D1 AP83 VSS<741> SKX_EXT_B_BGA1-IC,TBD    I23 @BASEBOARD_FAB2_LIB.BASEBOARD_FAB2(SCH_1):PAGE74
  U2D1 AP81 VSS<742> SKX_EXT_B_BGA1-IC,TBD    I23 @BASEBOARD_FAB2_LIB.BASEBOARD_FAB2(SCH_1):PAGE74
  U2D1 AP75 VSS<743> SKX_EXT_B_BGA1-IC,TBD    I23 @BASEBOARD_FAB2_LIB.BASEBOARD_FAB2(SCH_1):PAGE74
  U2D1 AP73 VSS<744> SKX_EXT_B_BGA1-IC,TBD    I23 @BASEBOARD_FAB2_LIB.BASEBOARD_FAB2(SCH_1):PAGE74
  U2D1 AP69 VSS<745> SKX_EXT_B_BGA1-IC,TBD    I23 @BASEBOARD_FAB2_LIB.BASEBOARD_FAB2(SCH_1):PAGE74
  U2D1 AP67 VSS<746> SKX_EXT_B_BGA1-IC,TBD    I23 @BASEBOARD_FAB2_LIB.BASEBOARD_FAB2(SCH_1):PAGE74
  U2D1 AP65 VSS<747> SKX_EXT_B_BGA1-IC,TBD    I23 @BASEBOARD_FAB2_LIB.BASEBOARD_FAB2(SCH_1):PAGE74
  U2D1 AP63 VSS<748> SKX_EXT_B_BGA1-IC,TBD    I23 @BASEBOARD_FAB2_LIB.BASEBOARD_FAB2(SCH_1):PAGE74
  U2D1 AP59 VSS<749> SKX_EXT_B_BGA1-IC,TBD    I23 @BASEBOARD_FAB2_LIB.BASEBOARD_FAB2(SCH_1):PAGE74
  U2D1 AP31 VSS<750> SKX_EXT_B_BGA1-IC,TBD    I23 @BASEBOARD_FAB2_LIB.BASEBOARD_FAB2(SCH_1):PAGE74
  U2D1 AP19 VSS<751> SKX_EXT_B_BGA1-IC,TBD    I23 @BASEBOARD_FAB2_LIB.BASEBOARD_FAB2(SCH_1):PAGE74
  U2D1 AP13 VSS<752> SKX_EXT_B_BGA1-IC,TBD    I23 @BASEBOARD_FAB2_LIB.BASEBOARD_FAB2(SCH_1):PAGE74
  U2D1  AP9 VSS<753> SKX_EXT_B_BGA1-IC,TBD    I23 @BASEBOARD_FAB2_LIB.BASEBOARD_FAB2(SCH_1):PAGE74
  U2D1  AP5 VSS<754> SKX_EXT_B_BGA1-IC,TBD    I23 @BASEBOARD_FAB2_LIB.BASEBOARD_FAB2(SCH_1):PAGE74
  U2D1 AN78 VSS<755> SKX_EXT_B_BGA1-IC,TBD    I23 @BASEBOARD_FAB2_LIB.BASEBOARD_FAB2(SCH_1):PAGE74
  U2D1 AN58 VSS<756> SKX_EXT_B_BGA1-IC,TBD    I23 @BASEBOARD_FAB2_LIB.BASEBOARD_FAB2(SCH_1):PAGE74
  U2D1 AN28 VSS<757> SKX_EXT_B_BGA1-IC,TBD    I23 @BASEBOARD_FAB2_LIB.BASEBOARD_FAB2(SCH_1):PAGE74
  U2D1  AN6 VSS<758> SKX_EXT_B_BGA1-IC,TBD    I23 @BASEBOARD_FAB2_LIB.BASEBOARD_FAB2(SCH_1):PAGE74
  U2D1  AN2 VSS<759> SKX_EXT_B_BGA1-IC,TBD    I23 @BASEBOARD_FAB2_LIB.BASEBOARD_FAB2(SCH_1):PAGE74
  U2D1 AM83 VSS<760> SKX_EXT_B_BGA1-IC,TBD    I23 @BASEBOARD_FAB2_LIB.BASEBOARD_FAB2(SCH_1):PAGE74
  U2D1 AM79 VSS<761> SKX_EXT_B_BGA1-IC,TBD    I23 @BASEBOARD_FAB2_LIB.BASEBOARD_FAB2(SCH_1):PAGE74
  U2D1 AM73 VSS<762> SKX_EXT_B_BGA1-IC,TBD    I23 @BASEBOARD_FAB2_LIB.BASEBOARD_FAB2(SCH_1):PAGE74
  U2D1 AM69 VSS<763> SKX_EXT_B_BGA1-IC,TBD    I23 @BASEBOARD_FAB2_LIB.BASEBOARD_FAB2(SCH_1):PAGE74
  U2D1 AM63 VSS<764> SKX_EXT_B_BGA1-IC,TBD    I23 @BASEBOARD_FAB2_LIB.BASEBOARD_FAB2(SCH_1):PAGE74
  U2D1 AM57 VSS<765> SKX_EXT_B_BGA1-IC,TBD    I23 @BASEBOARD_FAB2_LIB.BASEBOARD_FAB2(SCH_1):PAGE74
  U2D1 AM31 VSS<766> SKX_EXT_B_BGA1-IC,TBD    I23 @BASEBOARD_FAB2_LIB.BASEBOARD_FAB2(SCH_1):PAGE74
  U2D1 AC50 VSS<767> SKX_EXT_B_BGA1-IC,TBD    I23 @BASEBOARD_FAB2_LIB.BASEBOARD_FAB2(SCH_1):PAGE74
  U2D1  AM1 VSS<768> SKX_EXT_B_BGA1-IC,TBD    I23 @BASEBOARD_FAB2_LIB.BASEBOARD_FAB2(SCH_1):PAGE74
  U2D1 AL86 VSS<769> SKX_EXT_B_BGA1-IC,TBD    I23 @BASEBOARD_FAB2_LIB.BASEBOARD_FAB2(SCH_1):PAGE74
  U2D1 AL82 VSS<770> SKX_EXT_B_BGA1-IC,TBD    I23 @BASEBOARD_FAB2_LIB.BASEBOARD_FAB2(SCH_1):PAGE74
  U2D1 AL80 VSS<771> SKX_EXT_B_BGA1-IC,TBD    I23 @BASEBOARD_FAB2_LIB.BASEBOARD_FAB2(SCH_1):PAGE74
  U2D1 AL78 VSS<772> SKX_EXT_B_BGA1-IC,TBD    I23 @BASEBOARD_FAB2_LIB.BASEBOARD_FAB2(SCH_1):PAGE74
  U2D1 AL76 VSS<773> SKX_EXT_B_BGA1-IC,TBD    I23 @BASEBOARD_FAB2_LIB.BASEBOARD_FAB2(SCH_1):PAGE74
  U2D1  P49 VSS<454> SKX_EXT_B_BGA1-IC,TBD    I17 @BASEBOARD_FAB2_LIB.BASEBOARD_FAB2(SCH_1):PAGE75
  U2D1 CJ12 VSS<455> SKX_EXT_B_BGA1-IC,TBD    I17 @BASEBOARD_FAB2_LIB.BASEBOARD_FAB2(SCH_1):PAGE75
  U2D1 CJ10 VSS<456> SKX_EXT_B_BGA1-IC,TBD    I17 @BASEBOARD_FAB2_LIB.BASEBOARD_FAB2(SCH_1):PAGE75
  U2D1  CJ8 VSS<457> SKX_EXT_B_BGA1-IC,TBD    I17 @BASEBOARD_FAB2_LIB.BASEBOARD_FAB2(SCH_1):PAGE75
  U2D1  CJ6 VSS<458> SKX_EXT_B_BGA1-IC,TBD    I17 @BASEBOARD_FAB2_LIB.BASEBOARD_FAB2(SCH_1):PAGE75
  U2D1  CJ2 VSS<459> SKX_EXT_B_BGA1-IC,TBD    I17 @BASEBOARD_FAB2_LIB.BASEBOARD_FAB2(SCH_1):PAGE75
  U2D1 CH83 VSS<460> SKX_EXT_B_BGA1-IC,TBD    I17 @BASEBOARD_FAB2_LIB.BASEBOARD_FAB2(SCH_1):PAGE75
  U2D1 CH81 VSS<461> SKX_EXT_B_BGA1-IC,TBD    I17 @BASEBOARD_FAB2_LIB.BASEBOARD_FAB2(SCH_1):PAGE75
  U2D1 CH79 VSS<462> SKX_EXT_B_BGA1-IC,TBD    I17 @BASEBOARD_FAB2_LIB.BASEBOARD_FAB2(SCH_1):PAGE75
  U2D1 CH73 VSS<463> SKX_EXT_B_BGA1-IC,TBD    I17 @BASEBOARD_FAB2_LIB.BASEBOARD_FAB2(SCH_1):PAGE75
  U2D1 CH67 VSS<464> SKX_EXT_B_BGA1-IC,TBD    I17 @BASEBOARD_FAB2_LIB.BASEBOARD_FAB2(SCH_1):PAGE75
  U2D1 CH63 VSS<465> SKX_EXT_B_BGA1-IC,TBD    I17 @BASEBOARD_FAB2_LIB.BASEBOARD_FAB2(SCH_1):PAGE75
  U2D1 CH19 VSS<466> SKX_EXT_B_BGA1-IC,TBD    I17 @BASEBOARD_FAB2_LIB.BASEBOARD_FAB2(SCH_1):PAGE75
  U2D1 CH15 VSS<467> SKX_EXT_B_BGA1-IC,TBD    I17 @BASEBOARD_FAB2_LIB.BASEBOARD_FAB2(SCH_1):PAGE75
  U2D1  CH3 VSS<468> SKX_EXT_B_BGA1-IC,TBD    I17 @BASEBOARD_FAB2_LIB.BASEBOARD_FAB2(SCH_1):PAGE75
  U2D1  CH1 VSS<469> SKX_EXT_B_BGA1-IC,TBD    I17 @BASEBOARD_FAB2_LIB.BASEBOARD_FAB2(SCH_1):PAGE75
  U2D1 CG80 VSS<470> SKX_EXT_B_BGA1-IC,TBD    I17 @BASEBOARD_FAB2_LIB.BASEBOARD_FAB2(SCH_1):PAGE75
  U2D1 CG72 VSS<471> SKX_EXT_B_BGA1-IC,TBD    I17 @BASEBOARD_FAB2_LIB.BASEBOARD_FAB2(SCH_1):PAGE75
  U2D1 CG68 VSS<472> SKX_EXT_B_BGA1-IC,TBD    I17 @BASEBOARD_FAB2_LIB.BASEBOARD_FAB2(SCH_1):PAGE75
  U2D1 CG62 VSS<473> SKX_EXT_B_BGA1-IC,TBD    I17 @BASEBOARD_FAB2_LIB.BASEBOARD_FAB2(SCH_1):PAGE75
  U2D1 CG22 VSS<474> SKX_EXT_B_BGA1-IC,TBD    I17 @BASEBOARD_FAB2_LIB.BASEBOARD_FAB2(SCH_1):PAGE75
  U2D1 CG18 VSS<475> SKX_EXT_B_BGA1-IC,TBD    I17 @BASEBOARD_FAB2_LIB.BASEBOARD_FAB2(SCH_1):PAGE75
  U2D1  P51 VSS<476> SKX_EXT_B_BGA1-IC,TBD    I17 @BASEBOARD_FAB2_LIB.BASEBOARD_FAB2(SCH_1):PAGE75
  U2D1 CF83 VSS<477> SKX_EXT_B_BGA1-IC,TBD    I17 @BASEBOARD_FAB2_LIB.BASEBOARD_FAB2(SCH_1):PAGE75
  U2D1 CF77 VSS<478> SKX_EXT_B_BGA1-IC,TBD    I17 @BASEBOARD_FAB2_LIB.BASEBOARD_FAB2(SCH_1):PAGE75
  U2D1 CF71 VSS<479> SKX_EXT_B_BGA1-IC,TBD    I17 @BASEBOARD_FAB2_LIB.BASEBOARD_FAB2(SCH_1):PAGE75
  U2D1 CF69 VSS<480> SKX_EXT_B_BGA1-IC,TBD    I17 @BASEBOARD_FAB2_LIB.BASEBOARD_FAB2(SCH_1):PAGE75
  U2D1 CF63 VSS<481> SKX_EXT_B_BGA1-IC,TBD    I17 @BASEBOARD_FAB2_LIB.BASEBOARD_FAB2(SCH_1):PAGE75
  U2D1  CF9 VSS<482> SKX_EXT_B_BGA1-IC,TBD    I17 @BASEBOARD_FAB2_LIB.BASEBOARD_FAB2(SCH_1):PAGE75
  U2D1  P53 VSS<483> SKX_EXT_B_BGA1-IC,TBD    I17 @BASEBOARD_FAB2_LIB.BASEBOARD_FAB2(SCH_1):PAGE75
  U2D1 CE82 VSS<484> SKX_EXT_B_BGA1-IC,TBD    I17 @BASEBOARD_FAB2_LIB.BASEBOARD_FAB2(SCH_1):PAGE75
  U2D1 CE70 VSS<485> SKX_EXT_B_BGA1-IC,TBD    I17 @BASEBOARD_FAB2_LIB.BASEBOARD_FAB2(SCH_1):PAGE75
  U2D1 CE62 VSS<486> SKX_EXT_B_BGA1-IC,TBD    I17 @BASEBOARD_FAB2_LIB.BASEBOARD_FAB2(SCH_1):PAGE75
  U2D1 CE26 VSS<487> SKX_EXT_B_BGA1-IC,TBD    I17 @BASEBOARD_FAB2_LIB.BASEBOARD_FAB2(SCH_1):PAGE75
  U2D1 CE20 VSS<488> SKX_EXT_B_BGA1-IC,TBD    I17 @BASEBOARD_FAB2_LIB.BASEBOARD_FAB2(SCH_1):PAGE75
  U2D1 CE14 VSS<489> SKX_EXT_B_BGA1-IC,TBD    I17 @BASEBOARD_FAB2_LIB.BASEBOARD_FAB2(SCH_1):PAGE75
  U2D1 CE10 VSS<490> SKX_EXT_B_BGA1-IC,TBD    I17 @BASEBOARD_FAB2_LIB.BASEBOARD_FAB2(SCH_1):PAGE75
  U2D1 CD81 VSS<491> SKX_EXT_B_BGA1-IC,TBD    I17 @BASEBOARD_FAB2_LIB.BASEBOARD_FAB2(SCH_1):PAGE75
  U2D1 CD79 VSS<492> SKX_EXT_B_BGA1-IC,TBD    I17 @BASEBOARD_FAB2_LIB.BASEBOARD_FAB2(SCH_1):PAGE75
  U2D1 CD77 VSS<493> SKX_EXT_B_BGA1-IC,TBD    I17 @BASEBOARD_FAB2_LIB.BASEBOARD_FAB2(SCH_1):PAGE75
  U2D1 CD75 VSS<494> SKX_EXT_B_BGA1-IC,TBD    I17 @BASEBOARD_FAB2_LIB.BASEBOARD_FAB2(SCH_1):PAGE75
  U2D1 CD73 VSS<495> SKX_EXT_B_BGA1-IC,TBD    I17 @BASEBOARD_FAB2_LIB.BASEBOARD_FAB2(SCH_1):PAGE75
  U2D1 CD63 VSS<496> SKX_EXT_B_BGA1-IC,TBD    I17 @BASEBOARD_FAB2_LIB.BASEBOARD_FAB2(SCH_1):PAGE75
  U2D1 CD13 VSS<497> SKX_EXT_B_BGA1-IC,TBD    I17 @BASEBOARD_FAB2_LIB.BASEBOARD_FAB2(SCH_1):PAGE75
  U2D1  CD5 VSS<498> SKX_EXT_B_BGA1-IC,TBD    I17 @BASEBOARD_FAB2_LIB.BASEBOARD_FAB2(SCH_1):PAGE75
  U2D1 CC82 VSS<499> SKX_EXT_B_BGA1-IC,TBD    I17 @BASEBOARD_FAB2_LIB.BASEBOARD_FAB2(SCH_1):PAGE75
  U2D1 CC80 VSS<500> SKX_EXT_B_BGA1-IC,TBD    I17 @BASEBOARD_FAB2_LIB.BASEBOARD_FAB2(SCH_1):PAGE75
  U2D1 CC78 VSS<501> SKX_EXT_B_BGA1-IC,TBD    I17 @BASEBOARD_FAB2_LIB.BASEBOARD_FAB2(SCH_1):PAGE75
  U2D1 CC76 VSS<502> SKX_EXT_B_BGA1-IC,TBD    I17 @BASEBOARD_FAB2_LIB.BASEBOARD_FAB2(SCH_1):PAGE75
  U2D1 CC74 VSS<503> SKX_EXT_B_BGA1-IC,TBD    I17 @BASEBOARD_FAB2_LIB.BASEBOARD_FAB2(SCH_1):PAGE75
  U2D1 CC72 VSS<504> SKX_EXT_B_BGA1-IC,TBD    I17 @BASEBOARD_FAB2_LIB.BASEBOARD_FAB2(SCH_1):PAGE75
  U2D1 CC64 VSS<505> SKX_EXT_B_BGA1-IC,TBD    I17 @BASEBOARD_FAB2_LIB.BASEBOARD_FAB2(SCH_1):PAGE75
  U2D1 CC24 VSS<506> SKX_EXT_B_BGA1-IC,TBD    I17 @BASEBOARD_FAB2_LIB.BASEBOARD_FAB2(SCH_1):PAGE75
  U2D1 CC18 VSS<507> SKX_EXT_B_BGA1-IC,TBD    I17 @BASEBOARD_FAB2_LIB.BASEBOARD_FAB2(SCH_1):PAGE75
  U2D1 CC16 VSS<508> SKX_EXT_B_BGA1-IC,TBD    I17 @BASEBOARD_FAB2_LIB.BASEBOARD_FAB2(SCH_1):PAGE75
  U2D1  CC4 VSS<509> SKX_EXT_B_BGA1-IC,TBD    I17 @BASEBOARD_FAB2_LIB.BASEBOARD_FAB2(SCH_1):PAGE75
  U2D1 CB71 VSS<510> SKX_EXT_B_BGA1-IC,TBD    I17 @BASEBOARD_FAB2_LIB.BASEBOARD_FAB2(SCH_1):PAGE75
  U2D1 CB63 VSS<511> SKX_EXT_B_BGA1-IC,TBD    I17 @BASEBOARD_FAB2_LIB.BASEBOARD_FAB2(SCH_1):PAGE75
  U2D1 CB27 VSS<512> SKX_EXT_B_BGA1-IC,TBD    I17 @BASEBOARD_FAB2_LIB.BASEBOARD_FAB2(SCH_1):PAGE75
  U2D1  CB9 VSS<513> SKX_EXT_B_BGA1-IC,TBD    I17 @BASEBOARD_FAB2_LIB.BASEBOARD_FAB2(SCH_1):PAGE75
  U2D1  CB7 VSS<514> SKX_EXT_B_BGA1-IC,TBD    I17 @BASEBOARD_FAB2_LIB.BASEBOARD_FAB2(SCH_1):PAGE75
  U2D1 CA70 VSS<515> SKX_EXT_B_BGA1-IC,TBD    I17 @BASEBOARD_FAB2_LIB.BASEBOARD_FAB2(SCH_1):PAGE75
  U2D1 CA68 VSS<516> SKX_EXT_B_BGA1-IC,TBD    I17 @BASEBOARD_FAB2_LIB.BASEBOARD_FAB2(SCH_1):PAGE75
  U2D1 CA66 VSS<517> SKX_EXT_B_BGA1-IC,TBD    I17 @BASEBOARD_FAB2_LIB.BASEBOARD_FAB2(SCH_1):PAGE75
  U2D1 CA64 VSS<518> SKX_EXT_B_BGA1-IC,TBD    I17 @BASEBOARD_FAB2_LIB.BASEBOARD_FAB2(SCH_1):PAGE75
  U2D1 CA26 VSS<519> SKX_EXT_B_BGA1-IC,TBD    I17 @BASEBOARD_FAB2_LIB.BASEBOARD_FAB2(SCH_1):PAGE75
  U2D1 CA18 VSS<520> SKX_EXT_B_BGA1-IC,TBD    I17 @BASEBOARD_FAB2_LIB.BASEBOARD_FAB2(SCH_1):PAGE75
  U2D1 CA14 VSS<521> SKX_EXT_B_BGA1-IC,TBD    I17 @BASEBOARD_FAB2_LIB.BASEBOARD_FAB2(SCH_1):PAGE75
  U2D1 CA10 VSS<522> SKX_EXT_B_BGA1-IC,TBD    I17 @BASEBOARD_FAB2_LIB.BASEBOARD_FAB2(SCH_1):PAGE75
  U2D1  CA8 VSS<523> SKX_EXT_B_BGA1-IC,TBD    I17 @BASEBOARD_FAB2_LIB.BASEBOARD_FAB2(SCH_1):PAGE75
  U2D1  CA6 VSS<524> SKX_EXT_B_BGA1-IC,TBD    I17 @BASEBOARD_FAB2_LIB.BASEBOARD_FAB2(SCH_1):PAGE75
  U2D1  CA2 VSS<525> SKX_EXT_B_BGA1-IC,TBD    I17 @BASEBOARD_FAB2_LIB.BASEBOARD_FAB2(SCH_1):PAGE75
  U2D1 BY71 VSS<526> SKX_EXT_B_BGA1-IC,TBD    I17 @BASEBOARD_FAB2_LIB.BASEBOARD_FAB2(SCH_1):PAGE75
  U2D1 BY69 VSS<527> SKX_EXT_B_BGA1-IC,TBD    I17 @BASEBOARD_FAB2_LIB.BASEBOARD_FAB2(SCH_1):PAGE75
  U2D1 BY67 VSS<528> SKX_EXT_B_BGA1-IC,TBD    I17 @BASEBOARD_FAB2_LIB.BASEBOARD_FAB2(SCH_1):PAGE75
  U2D1 BY65 VSS<529> SKX_EXT_B_BGA1-IC,TBD    I17 @BASEBOARD_FAB2_LIB.BASEBOARD_FAB2(SCH_1):PAGE75
  U2D1 BY63 VSS<530> SKX_EXT_B_BGA1-IC,TBD    I17 @BASEBOARD_FAB2_LIB.BASEBOARD_FAB2(SCH_1):PAGE75
  U2D1 BY23 VSS<531> SKX_EXT_B_BGA1-IC,TBD    I17 @BASEBOARD_FAB2_LIB.BASEBOARD_FAB2(SCH_1):PAGE75
  U2D1 BY13 VSS<532> SKX_EXT_B_BGA1-IC,TBD    I17 @BASEBOARD_FAB2_LIB.BASEBOARD_FAB2(SCH_1):PAGE75
  U2D1 BY11 VSS<533> SKX_EXT_B_BGA1-IC,TBD    I17 @BASEBOARD_FAB2_LIB.BASEBOARD_FAB2(SCH_1):PAGE75
  U2D1 BW82 VSS<534> SKX_EXT_B_BGA1-IC,TBD    I17 @BASEBOARD_FAB2_LIB.BASEBOARD_FAB2(SCH_1):PAGE75
  U2D1 BW80 VSS<535> SKX_EXT_B_BGA1-IC,TBD    I17 @BASEBOARD_FAB2_LIB.BASEBOARD_FAB2(SCH_1):PAGE75
  U2D1 BW78 VSS<536> SKX_EXT_B_BGA1-IC,TBD    I17 @BASEBOARD_FAB2_LIB.BASEBOARD_FAB2(SCH_1):PAGE75
  U2D1 BW76 VSS<537> SKX_EXT_B_BGA1-IC,TBD    I17 @BASEBOARD_FAB2_LIB.BASEBOARD_FAB2(SCH_1):PAGE75
  U2D1 BW74 VSS<538> SKX_EXT_B_BGA1-IC,TBD    I17 @BASEBOARD_FAB2_LIB.BASEBOARD_FAB2(SCH_1):PAGE75
  U2D1 BW72 VSS<539> SKX_EXT_B_BGA1-IC,TBD    I17 @BASEBOARD_FAB2_LIB.BASEBOARD_FAB2(SCH_1):PAGE75
  U2D1 BW26 VSS<540> SKX_EXT_B_BGA1-IC,TBD    I17 @BASEBOARD_FAB2_LIB.BASEBOARD_FAB2(SCH_1):PAGE75
  U2D1 BW18 VSS<541> SKX_EXT_B_BGA1-IC,TBD    I17 @BASEBOARD_FAB2_LIB.BASEBOARD_FAB2(SCH_1):PAGE75
  U2D1 BW16 VSS<542> SKX_EXT_B_BGA1-IC,TBD    I17 @BASEBOARD_FAB2_LIB.BASEBOARD_FAB2(SCH_1):PAGE75
  U2D1 BW14 VSS<543> SKX_EXT_B_BGA1-IC,TBD    I17 @BASEBOARD_FAB2_LIB.BASEBOARD_FAB2(SCH_1):PAGE75
  U2D1 BW12 VSS<544> SKX_EXT_B_BGA1-IC,TBD    I17 @BASEBOARD_FAB2_LIB.BASEBOARD_FAB2(SCH_1):PAGE75
  U2D1  P55 VSS<545> SKX_EXT_B_BGA1-IC,TBD    I17 @BASEBOARD_FAB2_LIB.BASEBOARD_FAB2(SCH_1):PAGE75
  U2D1  BW6 VSS<546> SKX_EXT_B_BGA1-IC,TBD    I17 @BASEBOARD_FAB2_LIB.BASEBOARD_FAB2(SCH_1):PAGE75
  U2D1 BV25 VSS<547> SKX_EXT_B_BGA1-IC,TBD    I17 @BASEBOARD_FAB2_LIB.BASEBOARD_FAB2(SCH_1):PAGE75
  U2D1 BV17 VSS<548> SKX_EXT_B_BGA1-IC,TBD    I17 @BASEBOARD_FAB2_LIB.BASEBOARD_FAB2(SCH_1):PAGE75
  U2D1 BU10 VSS<549> SKX_EXT_B_BGA1-IC,TBD    I17 @BASEBOARD_FAB2_LIB.BASEBOARD_FAB2(SCH_1):PAGE75
  U2D1  BV5 VSS<550> SKX_EXT_B_BGA1-IC,TBD    I17 @BASEBOARD_FAB2_LIB.BASEBOARD_FAB2(SCH_1):PAGE75
  U2D1  BU8 VSS<551> SKX_EXT_B_BGA1-IC,TBD    I17 @BASEBOARD_FAB2_LIB.BASEBOARD_FAB2(SCH_1):PAGE75
  U2D1 BT25 VSS<552> SKX_EXT_B_BGA1-IC,TBD    I17 @BASEBOARD_FAB2_LIB.BASEBOARD_FAB2(SCH_1):PAGE75
  U2D1 BT23 VSS<553> SKX_EXT_B_BGA1-IC,TBD    I17 @BASEBOARD_FAB2_LIB.BASEBOARD_FAB2(SCH_1):PAGE75
  U2D1 BT21 VSS<554> SKX_EXT_B_BGA1-IC,TBD    I17 @BASEBOARD_FAB2_LIB.BASEBOARD_FAB2(SCH_1):PAGE75
  U2D1  BT5 VSS<555> SKX_EXT_B_BGA1-IC,TBD    I17 @BASEBOARD_FAB2_LIB.BASEBOARD_FAB2(SCH_1):PAGE75
  U2D1  BT3 VSS<556> SKX_EXT_B_BGA1-IC,TBD    I17 @BASEBOARD_FAB2_LIB.BASEBOARD_FAB2(SCH_1):PAGE75
  U2D1 BR82 VSS<557> SKX_EXT_B_BGA1-IC,TBD    I17 @BASEBOARD_FAB2_LIB.BASEBOARD_FAB2(SCH_1):PAGE75
  U2D1 BR80 VSS<558> SKX_EXT_B_BGA1-IC,TBD    I17 @BASEBOARD_FAB2_LIB.BASEBOARD_FAB2(SCH_1):PAGE75
  U2D1 BR78 VSS<559> SKX_EXT_B_BGA1-IC,TBD    I17 @BASEBOARD_FAB2_LIB.BASEBOARD_FAB2(SCH_1):PAGE75
  U2D1 BR76 VSS<560> SKX_EXT_B_BGA1-IC,TBD    I17 @BASEBOARD_FAB2_LIB.BASEBOARD_FAB2(SCH_1):PAGE75
  U2D1 BR74 VSS<561> SKX_EXT_B_BGA1-IC,TBD    I17 @BASEBOARD_FAB2_LIB.BASEBOARD_FAB2(SCH_1):PAGE75
  U2D1 BR72 VSS<562> SKX_EXT_B_BGA1-IC,TBD    I17 @BASEBOARD_FAB2_LIB.BASEBOARD_FAB2(SCH_1):PAGE75
  U2D1 BR70 VSS<563> SKX_EXT_B_BGA1-IC,TBD    I17 @BASEBOARD_FAB2_LIB.BASEBOARD_FAB2(SCH_1):PAGE75
  U2D1 BR68 VSS<564> SKX_EXT_B_BGA1-IC,TBD    I17 @BASEBOARD_FAB2_LIB.BASEBOARD_FAB2(SCH_1):PAGE75
  U2D1 BR66 VSS<565> SKX_EXT_B_BGA1-IC,TBD    I17 @BASEBOARD_FAB2_LIB.BASEBOARD_FAB2(SCH_1):PAGE75
  U2D1 BR64 VSS<566> SKX_EXT_B_BGA1-IC,TBD    I17 @BASEBOARD_FAB2_LIB.BASEBOARD_FAB2(SCH_1):PAGE75
  U2D1  P57 VSS<567> SKX_EXT_B_BGA1-IC,TBD    I17 @BASEBOARD_FAB2_LIB.BASEBOARD_FAB2(SCH_1):PAGE75
  U2D1 BR16 VSS<568> SKX_EXT_B_BGA1-IC,TBD    I17 @BASEBOARD_FAB2_LIB.BASEBOARD_FAB2(SCH_1):PAGE75
  U2D1 BR10 VSS<569> SKX_EXT_B_BGA1-IC,TBD    I17 @BASEBOARD_FAB2_LIB.BASEBOARD_FAB2(SCH_1):PAGE75
  U2D1  BR6 VSS<570> SKX_EXT_B_BGA1-IC,TBD    I17 @BASEBOARD_FAB2_LIB.BASEBOARD_FAB2(SCH_1):PAGE75
  U2D1 BP27 VSS<571> SKX_EXT_B_BGA1-IC,TBD    I17 @BASEBOARD_FAB2_LIB.BASEBOARD_FAB2(SCH_1):PAGE75
  U2D1  BP3 VSS<572> SKX_EXT_B_BGA1-IC,TBD    I17 @BASEBOARD_FAB2_LIB.BASEBOARD_FAB2(SCH_1):PAGE75
  U2D1 BN26 VSS<573> SKX_EXT_B_BGA1-IC,TBD    I17 @BASEBOARD_FAB2_LIB.BASEBOARD_FAB2(SCH_1):PAGE75
  U2D1 BN20 VSS<574> SKX_EXT_B_BGA1-IC,TBD    I17 @BASEBOARD_FAB2_LIB.BASEBOARD_FAB2(SCH_1):PAGE75
  U2D1 BN10 VSS<575> SKX_EXT_B_BGA1-IC,TBD    I17 @BASEBOARD_FAB2_LIB.BASEBOARD_FAB2(SCH_1):PAGE75
  U2D1  BN6 VSS<576> SKX_EXT_B_BGA1-IC,TBD    I17 @BASEBOARD_FAB2_LIB.BASEBOARD_FAB2(SCH_1):PAGE75
  U2D1 BM25 VSS<577> SKX_EXT_B_BGA1-IC,TBD    I17 @BASEBOARD_FAB2_LIB.BASEBOARD_FAB2(SCH_1):PAGE75
  U2D1  P59 VSS<578> SKX_EXT_B_BGA1-IC,TBD    I17 @BASEBOARD_FAB2_LIB.BASEBOARD_FAB2(SCH_1):PAGE75
  U2D1 BM15 VSS<579> SKX_EXT_B_BGA1-IC,TBD    I17 @BASEBOARD_FAB2_LIB.BASEBOARD_FAB2(SCH_1):PAGE75
  U2D1 BM13 VSS<580> SKX_EXT_B_BGA1-IC,TBD    I17 @BASEBOARD_FAB2_LIB.BASEBOARD_FAB2(SCH_1):PAGE75
  U2D1  BM9 VSS<581> SKX_EXT_B_BGA1-IC,TBD    I17 @BASEBOARD_FAB2_LIB.BASEBOARD_FAB2(SCH_1):PAGE75
  U2D1 BL82 VSS<582> SKX_EXT_B_BGA1-IC,TBD    I17 @BASEBOARD_FAB2_LIB.BASEBOARD_FAB2(SCH_1):PAGE75
  U2D1 BL80 VSS<583> SKX_EXT_B_BGA1-IC,TBD    I17 @BASEBOARD_FAB2_LIB.BASEBOARD_FAB2(SCH_1):PAGE75
  U2D1 BL78 VSS<584> SKX_EXT_B_BGA1-IC,TBD    I17 @BASEBOARD_FAB2_LIB.BASEBOARD_FAB2(SCH_1):PAGE75
  U2D1 BL76 VSS<585> SKX_EXT_B_BGA1-IC,TBD    I17 @BASEBOARD_FAB2_LIB.BASEBOARD_FAB2(SCH_1):PAGE75
  U2D1 BL74 VSS<586> SKX_EXT_B_BGA1-IC,TBD    I17 @BASEBOARD_FAB2_LIB.BASEBOARD_FAB2(SCH_1):PAGE75
  U2D1 BL72 VSS<587> SKX_EXT_B_BGA1-IC,TBD    I17 @BASEBOARD_FAB2_LIB.BASEBOARD_FAB2(SCH_1):PAGE75
  U2D1 BL70 VSS<588> SKX_EXT_B_BGA1-IC,TBD    I17 @BASEBOARD_FAB2_LIB.BASEBOARD_FAB2(SCH_1):PAGE75
  U2D1 BL68 VSS<589> SKX_EXT_B_BGA1-IC,TBD    I17 @BASEBOARD_FAB2_LIB.BASEBOARD_FAB2(SCH_1):PAGE75
  U2D1 BL66 VSS<590> SKX_EXT_B_BGA1-IC,TBD    I17 @BASEBOARD_FAB2_LIB.BASEBOARD_FAB2(SCH_1):PAGE75
  U2D1 BL64 VSS<591> SKX_EXT_B_BGA1-IC,TBD    I17 @BASEBOARD_FAB2_LIB.BASEBOARD_FAB2(SCH_1):PAGE75
  U2D1 BL24 VSS<592> SKX_EXT_B_BGA1-IC,TBD    I17 @BASEBOARD_FAB2_LIB.BASEBOARD_FAB2(SCH_1):PAGE75
  U2D1 BL22 VSS<593> SKX_EXT_B_BGA1-IC,TBD    I17 @BASEBOARD_FAB2_LIB.BASEBOARD_FAB2(SCH_1):PAGE75
  U2D1  P61 VSS<594> SKX_EXT_B_BGA1-IC,TBD    I17 @BASEBOARD_FAB2_LIB.BASEBOARD_FAB2(SCH_1):PAGE75
  U2D1 BL12 VSS<595> SKX_EXT_B_BGA1-IC,TBD    I17 @BASEBOARD_FAB2_LIB.BASEBOARD_FAB2(SCH_1):PAGE75
  U2D1 BL10 VSS<596> SKX_EXT_B_BGA1-IC,TBD    I17 @BASEBOARD_FAB2_LIB.BASEBOARD_FAB2(SCH_1):PAGE75
  U2D1  BL6 VSS<597> SKX_EXT_B_BGA1-IC,TBD    I17 @BASEBOARD_FAB2_LIB.BASEBOARD_FAB2(SCH_1):PAGE75
  U2D1 BK19 VSS<598> SKX_EXT_B_BGA1-IC,TBD    I17 @BASEBOARD_FAB2_LIB.BASEBOARD_FAB2(SCH_1):PAGE75
  U2D1 BK11 VSS<599> SKX_EXT_B_BGA1-IC,TBD    I17 @BASEBOARD_FAB2_LIB.BASEBOARD_FAB2(SCH_1):PAGE75
  U2D1  BK7 VSS<600> SKX_EXT_B_BGA1-IC,TBD    I17 @BASEBOARD_FAB2_LIB.BASEBOARD_FAB2(SCH_1):PAGE75
  U2D1  BK3 VSS<601> SKX_EXT_B_BGA1-IC,TBD    I17 @BASEBOARD_FAB2_LIB.BASEBOARD_FAB2(SCH_1):PAGE75
  U2D1  BJ6 VSS<602> SKX_EXT_B_BGA1-IC,TBD    I17 @BASEBOARD_FAB2_LIB.BASEBOARD_FAB2(SCH_1):PAGE75
  U2D1  BJ4 VSS<603> SKX_EXT_B_BGA1-IC,TBD    I17 @BASEBOARD_FAB2_LIB.BASEBOARD_FAB2(SCH_1):PAGE75
  U2D1 BH21 VSS<604> SKX_EXT_B_BGA1-IC,TBD    I17 @BASEBOARD_FAB2_LIB.BASEBOARD_FAB2(SCH_1):PAGE75
  U2D1 BH15 VSS<605> SKX_EXT_B_BGA1-IC,TBD    I17 @BASEBOARD_FAB2_LIB.BASEBOARD_FAB2(SCH_1):PAGE75
  U2D1 BH11 VSS<606> SKX_EXT_B_BGA1-IC,TBD    I17 @BASEBOARD_FAB2_LIB.BASEBOARD_FAB2(SCH_1):PAGE75
  U2D1  BH9 VSS<607> SKX_EXT_B_BGA1-IC,TBD    I17 @BASEBOARD_FAB2_LIB.BASEBOARD_FAB2(SCH_1):PAGE75
  U2D1  BH7 VSS<608> SKX_EXT_B_BGA1-IC,TBD    I17 @BASEBOARD_FAB2_LIB.BASEBOARD_FAB2(SCH_1):PAGE75
  U2D1 BG82 VSS<609> SKX_EXT_B_BGA1-IC,TBD    I17 @BASEBOARD_FAB2_LIB.BASEBOARD_FAB2(SCH_1):PAGE75
  U2D1 BG80 VSS<610> SKX_EXT_B_BGA1-IC,TBD    I17 @BASEBOARD_FAB2_LIB.BASEBOARD_FAB2(SCH_1):PAGE75
  U2D1 BG78 VSS<611> SKX_EXT_B_BGA1-IC,TBD    I17 @BASEBOARD_FAB2_LIB.BASEBOARD_FAB2(SCH_1):PAGE75
  U2D1 BG76 VSS<612> SKX_EXT_B_BGA1-IC,TBD    I17 @BASEBOARD_FAB2_LIB.BASEBOARD_FAB2(SCH_1):PAGE75
  U2D1 BG74 VSS<613> SKX_EXT_B_BGA1-IC,TBD    I17 @BASEBOARD_FAB2_LIB.BASEBOARD_FAB2(SCH_1):PAGE75
  U2D1 DA46 VSS<294> SKX_EXT_B_BGA1-IC,TBD    I18 @BASEBOARD_FAB2_LIB.BASEBOARD_FAB2(SCH_1):PAGE75
  U2D1 DA44 VSS<295> SKX_EXT_B_BGA1-IC,TBD    I18 @BASEBOARD_FAB2_LIB.BASEBOARD_FAB2(SCH_1):PAGE75
  U2D1 DA38 VSS<296> SKX_EXT_B_BGA1-IC,TBD    I18 @BASEBOARD_FAB2_LIB.BASEBOARD_FAB2(SCH_1):PAGE75
  U2D1 DA36 VSS<297> SKX_EXT_B_BGA1-IC,TBD    I18 @BASEBOARD_FAB2_LIB.BASEBOARD_FAB2(SCH_1):PAGE75
  U2D1 DA34 VSS<298> SKX_EXT_B_BGA1-IC,TBD    I18 @BASEBOARD_FAB2_LIB.BASEBOARD_FAB2(SCH_1):PAGE75
  U2D1 DA32 VSS<299> SKX_EXT_B_BGA1-IC,TBD    I18 @BASEBOARD_FAB2_LIB.BASEBOARD_FAB2(SCH_1):PAGE75
  U2D1 DA30 VSS<300> SKX_EXT_B_BGA1-IC,TBD    I18 @BASEBOARD_FAB2_LIB.BASEBOARD_FAB2(SCH_1):PAGE75
  U2D1 DA28 VSS<301> SKX_EXT_B_BGA1-IC,TBD    I18 @BASEBOARD_FAB2_LIB.BASEBOARD_FAB2(SCH_1):PAGE75
  U2D1 DA26 VSS<302> SKX_EXT_B_BGA1-IC,TBD    I18 @BASEBOARD_FAB2_LIB.BASEBOARD_FAB2(SCH_1):PAGE75
  U2D1 DA18 VSS<303> SKX_EXT_B_BGA1-IC,TBD    I18 @BASEBOARD_FAB2_LIB.BASEBOARD_FAB2(SCH_1):PAGE75
  U2D1  H53 VSS<304> SKX_EXT_B_BGA1-IC,TBD    I18 @BASEBOARD_FAB2_LIB.BASEBOARD_FAB2(SCH_1):PAGE75
  U2D1  DA6 VSS<305> SKX_EXT_B_BGA1-IC,TBD    I18 @BASEBOARD_FAB2_LIB.BASEBOARD_FAB2(SCH_1):PAGE75
  U2D1 CY85 VSS<306> SKX_EXT_B_BGA1-IC,TBD    I18 @BASEBOARD_FAB2_LIB.BASEBOARD_FAB2(SCH_1):PAGE75
  U2D1 CY83 VSS<307> SKX_EXT_B_BGA1-IC,TBD    I18 @BASEBOARD_FAB2_LIB.BASEBOARD_FAB2(SCH_1):PAGE75
  U2D1 CY77 VSS<308> SKX_EXT_B_BGA1-IC,TBD    I18 @BASEBOARD_FAB2_LIB.BASEBOARD_FAB2(SCH_1):PAGE75
  U2D1 CY75 VSS<309> SKX_EXT_B_BGA1-IC,TBD    I18 @BASEBOARD_FAB2_LIB.BASEBOARD_FAB2(SCH_1):PAGE75
  U2D1 CY69 VSS<310> SKX_EXT_B_BGA1-IC,TBD    I18 @BASEBOARD_FAB2_LIB.BASEBOARD_FAB2(SCH_1):PAGE75
  U2D1 CY65 VSS<311> SKX_EXT_B_BGA1-IC,TBD    I18 @BASEBOARD_FAB2_LIB.BASEBOARD_FAB2(SCH_1):PAGE75
  U2D1 CY61 VSS<312> SKX_EXT_B_BGA1-IC,TBD    I18 @BASEBOARD_FAB2_LIB.BASEBOARD_FAB2(SCH_1):PAGE75
  U2D1 CY59 VSS<313> SKX_EXT_B_BGA1-IC,TBD    I18 @BASEBOARD_FAB2_LIB.BASEBOARD_FAB2(SCH_1):PAGE75
  U2D1 CY51 VSS<314> SKX_EXT_B_BGA1-IC,TBD    I18 @BASEBOARD_FAB2_LIB.BASEBOARD_FAB2(SCH_1):PAGE75
  U2D1 CY45 VSS<315> SKX_EXT_B_BGA1-IC,TBD    I18 @BASEBOARD_FAB2_LIB.BASEBOARD_FAB2(SCH_1):PAGE75
  U2D1 CY41 VSS<316> SKX_EXT_B_BGA1-IC,TBD    I18 @BASEBOARD_FAB2_LIB.BASEBOARD_FAB2(SCH_1):PAGE75
  U2D1 CY21 VSS<317> SKX_EXT_B_BGA1-IC,TBD    I18 @BASEBOARD_FAB2_LIB.BASEBOARD_FAB2(SCH_1):PAGE75
  U2D1 CY15 VSS<318> SKX_EXT_B_BGA1-IC,TBD    I18 @BASEBOARD_FAB2_LIB.BASEBOARD_FAB2(SCH_1):PAGE75
  U2D1 CY13 VSS<319> SKX_EXT_B_BGA1-IC,TBD    I18 @BASEBOARD_FAB2_LIB.BASEBOARD_FAB2(SCH_1):PAGE75
  U2D1  CY9 VSS<320> SKX_EXT_B_BGA1-IC,TBD    I18 @BASEBOARD_FAB2_LIB.BASEBOARD_FAB2(SCH_1):PAGE75
  U2D1  CY1 VSS<321> SKX_EXT_B_BGA1-IC,TBD    I18 @BASEBOARD_FAB2_LIB.BASEBOARD_FAB2(SCH_1):PAGE75
  U2D1 CW82 VSS<322> SKX_EXT_B_BGA1-IC,TBD    I18 @BASEBOARD_FAB2_LIB.BASEBOARD_FAB2(SCH_1):PAGE75
  U2D1 CW78 VSS<323> SKX_EXT_B_BGA1-IC,TBD    I18 @BASEBOARD_FAB2_LIB.BASEBOARD_FAB2(SCH_1):PAGE75
  U2D1 CW74 VSS<324> SKX_EXT_B_BGA1-IC,TBD    I18 @BASEBOARD_FAB2_LIB.BASEBOARD_FAB2(SCH_1):PAGE75
  U2D1 CW68 VSS<325> SKX_EXT_B_BGA1-IC,TBD    I18 @BASEBOARD_FAB2_LIB.BASEBOARD_FAB2(SCH_1):PAGE75
  U2D1 CW66 VSS<326> SKX_EXT_B_BGA1-IC,TBD    I18 @BASEBOARD_FAB2_LIB.BASEBOARD_FAB2(SCH_1):PAGE75
  U2D1 CW64 VSS<327> SKX_EXT_B_BGA1-IC,TBD    I18 @BASEBOARD_FAB2_LIB.BASEBOARD_FAB2(SCH_1):PAGE75
  U2D1 CW54 VSS<328> SKX_EXT_B_BGA1-IC,TBD    I18 @BASEBOARD_FAB2_LIB.BASEBOARD_FAB2(SCH_1):PAGE75
  U2D1 CW52 VSS<329> SKX_EXT_B_BGA1-IC,TBD    I18 @BASEBOARD_FAB2_LIB.BASEBOARD_FAB2(SCH_1):PAGE75
  U2D1 CW42 VSS<330> SKX_EXT_B_BGA1-IC,TBD    I18 @BASEBOARD_FAB2_LIB.BASEBOARD_FAB2(SCH_1):PAGE75
  U2D1 CW40 VSS<331> SKX_EXT_B_BGA1-IC,TBD    I18 @BASEBOARD_FAB2_LIB.BASEBOARD_FAB2(SCH_1):PAGE75
  U2D1 CW38 VSS<332> SKX_EXT_B_BGA1-IC,TBD    I18 @BASEBOARD_FAB2_LIB.BASEBOARD_FAB2(SCH_1):PAGE75
  U2D1 CW32 VSS<333> SKX_EXT_B_BGA1-IC,TBD    I18 @BASEBOARD_FAB2_LIB.BASEBOARD_FAB2(SCH_1):PAGE75
  U2D1 CW26 VSS<334> SKX_EXT_B_BGA1-IC,TBD    I18 @BASEBOARD_FAB2_LIB.BASEBOARD_FAB2(SCH_1):PAGE75
  U2D1 CW12 VSS<335> SKX_EXT_B_BGA1-IC,TBD    I18 @BASEBOARD_FAB2_LIB.BASEBOARD_FAB2(SCH_1):PAGE75
  U2D1 CV83 VSS<336> SKX_EXT_B_BGA1-IC,TBD    I18 @BASEBOARD_FAB2_LIB.BASEBOARD_FAB2(SCH_1):PAGE75
  U2D1 CV81 VSS<337> SKX_EXT_B_BGA1-IC,TBD    I18 @BASEBOARD_FAB2_LIB.BASEBOARD_FAB2(SCH_1):PAGE75
  U2D1 CV79 VSS<338> SKX_EXT_B_BGA1-IC,TBD    I18 @BASEBOARD_FAB2_LIB.BASEBOARD_FAB2(SCH_1):PAGE75
  U2D1 CV73 VSS<339> SKX_EXT_B_BGA1-IC,TBD    I18 @BASEBOARD_FAB2_LIB.BASEBOARD_FAB2(SCH_1):PAGE75
  U2D1 CV67 VSS<340> SKX_EXT_B_BGA1-IC,TBD    I18 @BASEBOARD_FAB2_LIB.BASEBOARD_FAB2(SCH_1):PAGE75
  U2D1 CV63 VSS<341> SKX_EXT_B_BGA1-IC,TBD    I18 @BASEBOARD_FAB2_LIB.BASEBOARD_FAB2(SCH_1):PAGE75
  U2D1 CV55 VSS<342> SKX_EXT_B_BGA1-IC,TBD    I18 @BASEBOARD_FAB2_LIB.BASEBOARD_FAB2(SCH_1):PAGE75
  U2D1 CV53 VSS<343> SKX_EXT_B_BGA1-IC,TBD    I18 @BASEBOARD_FAB2_LIB.BASEBOARD_FAB2(SCH_1):PAGE75
  U2D1 CV41 VSS<344> SKX_EXT_B_BGA1-IC,TBD    I18 @BASEBOARD_FAB2_LIB.BASEBOARD_FAB2(SCH_1):PAGE75
  U2D1 CV39 VSS<345> SKX_EXT_B_BGA1-IC,TBD    I18 @BASEBOARD_FAB2_LIB.BASEBOARD_FAB2(SCH_1):PAGE75
  U2D1 CV37 VSS<346> SKX_EXT_B_BGA1-IC,TBD    I18 @BASEBOARD_FAB2_LIB.BASEBOARD_FAB2(SCH_1):PAGE75
  U2D1 CV33 VSS<347> SKX_EXT_B_BGA1-IC,TBD    I18 @BASEBOARD_FAB2_LIB.BASEBOARD_FAB2(SCH_1):PAGE75
  U2D1 CV31 VSS<348> SKX_EXT_B_BGA1-IC,TBD    I18 @BASEBOARD_FAB2_LIB.BASEBOARD_FAB2(SCH_1):PAGE75
  U2D1 CV27 VSS<349> SKX_EXT_B_BGA1-IC,TBD    I18 @BASEBOARD_FAB2_LIB.BASEBOARD_FAB2(SCH_1):PAGE75
  U2D1 CV25 VSS<350> SKX_EXT_B_BGA1-IC,TBD    I18 @BASEBOARD_FAB2_LIB.BASEBOARD_FAB2(SCH_1):PAGE75
  U2D1 CV17 VSS<351> SKX_EXT_B_BGA1-IC,TBD    I18 @BASEBOARD_FAB2_LIB.BASEBOARD_FAB2(SCH_1):PAGE75
  U2D1  H55 VSS<352> SKX_EXT_B_BGA1-IC,TBD    I18 @BASEBOARD_FAB2_LIB.BASEBOARD_FAB2(SCH_1):PAGE75
  U2D1  CV1 VSS<353> SKX_EXT_B_BGA1-IC,TBD    I18 @BASEBOARD_FAB2_LIB.BASEBOARD_FAB2(SCH_1):PAGE75
  U2D1 CU86 VSS<354> SKX_EXT_B_BGA1-IC,TBD    I18 @BASEBOARD_FAB2_LIB.BASEBOARD_FAB2(SCH_1):PAGE75
  U2D1 CU82 VSS<355> SKX_EXT_B_BGA1-IC,TBD    I18 @BASEBOARD_FAB2_LIB.BASEBOARD_FAB2(SCH_1):PAGE75
  U2D1 CU80 VSS<356> SKX_EXT_B_BGA1-IC,TBD    I18 @BASEBOARD_FAB2_LIB.BASEBOARD_FAB2(SCH_1):PAGE75
  U2D1 CU78 VSS<357> SKX_EXT_B_BGA1-IC,TBD    I18 @BASEBOARD_FAB2_LIB.BASEBOARD_FAB2(SCH_1):PAGE75
  U2D1 CU76 VSS<358> SKX_EXT_B_BGA1-IC,TBD    I18 @BASEBOARD_FAB2_LIB.BASEBOARD_FAB2(SCH_1):PAGE75
  U2D1 CU68 VSS<359> SKX_EXT_B_BGA1-IC,TBD    I18 @BASEBOARD_FAB2_LIB.BASEBOARD_FAB2(SCH_1):PAGE75
  U2D1 CU62 VSS<360> SKX_EXT_B_BGA1-IC,TBD    I18 @BASEBOARD_FAB2_LIB.BASEBOARD_FAB2(SCH_1):PAGE75
  U2D1 CU56 VSS<361> SKX_EXT_B_BGA1-IC,TBD    I18 @BASEBOARD_FAB2_LIB.BASEBOARD_FAB2(SCH_1):PAGE75
  U2D1 CU36 VSS<362> SKX_EXT_B_BGA1-IC,TBD    I18 @BASEBOARD_FAB2_LIB.BASEBOARD_FAB2(SCH_1):PAGE75
  U2D1 CU34 VSS<363> SKX_EXT_B_BGA1-IC,TBD    I18 @BASEBOARD_FAB2_LIB.BASEBOARD_FAB2(SCH_1):PAGE75
  U2D1 CU30 VSS<364> SKX_EXT_B_BGA1-IC,TBD    I18 @BASEBOARD_FAB2_LIB.BASEBOARD_FAB2(SCH_1):PAGE75
  U2D1 CU28 VSS<365> SKX_EXT_B_BGA1-IC,TBD    I18 @BASEBOARD_FAB2_LIB.BASEBOARD_FAB2(SCH_1):PAGE75
  U2D1 CU22 VSS<366> SKX_EXT_B_BGA1-IC,TBD    I18 @BASEBOARD_FAB2_LIB.BASEBOARD_FAB2(SCH_1):PAGE75
  U2D1  CU4 VSS<367> SKX_EXT_B_BGA1-IC,TBD    I18 @BASEBOARD_FAB2_LIB.BASEBOARD_FAB2(SCH_1):PAGE75
  U2D1 CT85 VSS<368> SKX_EXT_B_BGA1-IC,TBD    I18 @BASEBOARD_FAB2_LIB.BASEBOARD_FAB2(SCH_1):PAGE75
  U2D1 CT83 VSS<369> SKX_EXT_B_BGA1-IC,TBD    I18 @BASEBOARD_FAB2_LIB.BASEBOARD_FAB2(SCH_1):PAGE75
  U2D1 CT79 VSS<370> SKX_EXT_B_BGA1-IC,TBD    I18 @BASEBOARD_FAB2_LIB.BASEBOARD_FAB2(SCH_1):PAGE75
  U2D1 CT73 VSS<371> SKX_EXT_B_BGA1-IC,TBD    I18 @BASEBOARD_FAB2_LIB.BASEBOARD_FAB2(SCH_1):PAGE75
  U2D1 CT57 VSS<372> SKX_EXT_B_BGA1-IC,TBD    I18 @BASEBOARD_FAB2_LIB.BASEBOARD_FAB2(SCH_1):PAGE75
  U2D1 CT35 VSS<373> SKX_EXT_B_BGA1-IC,TBD    I18 @BASEBOARD_FAB2_LIB.BASEBOARD_FAB2(SCH_1):PAGE75
  U2D1 CT33 VSS<374> SKX_EXT_B_BGA1-IC,TBD    I18 @BASEBOARD_FAB2_LIB.BASEBOARD_FAB2(SCH_1):PAGE75
  U2D1 CT29 VSS<375> SKX_EXT_B_BGA1-IC,TBD    I18 @BASEBOARD_FAB2_LIB.BASEBOARD_FAB2(SCH_1):PAGE75
  U2D1 CT27 VSS<376> SKX_EXT_B_BGA1-IC,TBD    I18 @BASEBOARD_FAB2_LIB.BASEBOARD_FAB2(SCH_1):PAGE75
  U2D1 CT19 VSS<377> SKX_EXT_B_BGA1-IC,TBD    I18 @BASEBOARD_FAB2_LIB.BASEBOARD_FAB2(SCH_1):PAGE75
  U2D1 CT13 VSS<378> SKX_EXT_B_BGA1-IC,TBD    I18 @BASEBOARD_FAB2_LIB.BASEBOARD_FAB2(SCH_1):PAGE75
  U2D1  H57 VSS<379> SKX_EXT_B_BGA1-IC,TBD    I18 @BASEBOARD_FAB2_LIB.BASEBOARD_FAB2(SCH_1):PAGE75
  U2D1 CR86 VSS<380> SKX_EXT_B_BGA1-IC,TBD    I18 @BASEBOARD_FAB2_LIB.BASEBOARD_FAB2(SCH_1):PAGE75
  U2D1 CR78 VSS<381> SKX_EXT_B_BGA1-IC,TBD    I18 @BASEBOARD_FAB2_LIB.BASEBOARD_FAB2(SCH_1):PAGE75
  U2D1 CR68 VSS<382> SKX_EXT_B_BGA1-IC,TBD    I18 @BASEBOARD_FAB2_LIB.BASEBOARD_FAB2(SCH_1):PAGE75
  U2D1 CR66 VSS<383> SKX_EXT_B_BGA1-IC,TBD    I18 @BASEBOARD_FAB2_LIB.BASEBOARD_FAB2(SCH_1):PAGE75
  U2D1 CR64 VSS<384> SKX_EXT_B_BGA1-IC,TBD    I18 @BASEBOARD_FAB2_LIB.BASEBOARD_FAB2(SCH_1):PAGE75
  U2D1 CR62 VSS<385> SKX_EXT_B_BGA1-IC,TBD    I18 @BASEBOARD_FAB2_LIB.BASEBOARD_FAB2(SCH_1):PAGE75
  U2D1 CR58 VSS<386> SKX_EXT_B_BGA1-IC,TBD    I18 @BASEBOARD_FAB2_LIB.BASEBOARD_FAB2(SCH_1):PAGE75
  U2D1 CR32 VSS<387> SKX_EXT_B_BGA1-IC,TBD    I18 @BASEBOARD_FAB2_LIB.BASEBOARD_FAB2(SCH_1):PAGE75
  U2D1 CR24 VSS<388> SKX_EXT_B_BGA1-IC,TBD    I18 @BASEBOARD_FAB2_LIB.BASEBOARD_FAB2(SCH_1):PAGE75
  U2D1 CR22 VSS<389> SKX_EXT_B_BGA1-IC,TBD    I18 @BASEBOARD_FAB2_LIB.BASEBOARD_FAB2(SCH_1):PAGE75
  U2D1 CR10 VSS<390> SKX_EXT_B_BGA1-IC,TBD    I18 @BASEBOARD_FAB2_LIB.BASEBOARD_FAB2(SCH_1):PAGE75
  U2D1  CR6 VSS<391> SKX_EXT_B_BGA1-IC,TBD    I18 @BASEBOARD_FAB2_LIB.BASEBOARD_FAB2(SCH_1):PAGE75
  U2D1 CP83 VSS<392> SKX_EXT_B_BGA1-IC,TBD    I18 @BASEBOARD_FAB2_LIB.BASEBOARD_FAB2(SCH_1):PAGE75
  U2D1 CP81 VSS<393> SKX_EXT_B_BGA1-IC,TBD    I18 @BASEBOARD_FAB2_LIB.BASEBOARD_FAB2(SCH_1):PAGE75
  U2D1 CP75 VSS<394> SKX_EXT_B_BGA1-IC,TBD    I18 @BASEBOARD_FAB2_LIB.BASEBOARD_FAB2(SCH_1):PAGE75
  U2D1 CP73 VSS<395> SKX_EXT_B_BGA1-IC,TBD    I18 @BASEBOARD_FAB2_LIB.BASEBOARD_FAB2(SCH_1):PAGE75
  U2D1 CP69 VSS<396> SKX_EXT_B_BGA1-IC,TBD    I18 @BASEBOARD_FAB2_LIB.BASEBOARD_FAB2(SCH_1):PAGE75
  U2D1 CP59 VSS<397> SKX_EXT_B_BGA1-IC,TBD    I18 @BASEBOARD_FAB2_LIB.BASEBOARD_FAB2(SCH_1):PAGE75
  U2D1 CP25 VSS<398> SKX_EXT_B_BGA1-IC,TBD    I18 @BASEBOARD_FAB2_LIB.BASEBOARD_FAB2(SCH_1):PAGE75
  U2D1  H59 VSS<399> SKX_EXT_B_BGA1-IC,TBD    I18 @BASEBOARD_FAB2_LIB.BASEBOARD_FAB2(SCH_1):PAGE75
  U2D1  CP1 VSS<400> SKX_EXT_B_BGA1-IC,TBD    I18 @BASEBOARD_FAB2_LIB.BASEBOARD_FAB2(SCH_1):PAGE75
  U2D1 CN78 VSS<401> SKX_EXT_B_BGA1-IC,TBD    I18 @BASEBOARD_FAB2_LIB.BASEBOARD_FAB2(SCH_1):PAGE75
  U2D1 CN68 VSS<402> SKX_EXT_B_BGA1-IC,TBD    I18 @BASEBOARD_FAB2_LIB.BASEBOARD_FAB2(SCH_1):PAGE75
  U2D1 CN62 VSS<403> SKX_EXT_B_BGA1-IC,TBD    I18 @BASEBOARD_FAB2_LIB.BASEBOARD_FAB2(SCH_1):PAGE75
  U2D1 CN60 VSS<404> SKX_EXT_B_BGA1-IC,TBD    I18 @BASEBOARD_FAB2_LIB.BASEBOARD_FAB2(SCH_1):PAGE75
  U2D1 CN32 VSS<405> SKX_EXT_B_BGA1-IC,TBD    I18 @BASEBOARD_FAB2_LIB.BASEBOARD_FAB2(SCH_1):PAGE75
  U2D1 CN26 VSS<406> SKX_EXT_B_BGA1-IC,TBD    I18 @BASEBOARD_FAB2_LIB.BASEBOARD_FAB2(SCH_1):PAGE75
  U2D1  H61 VSS<407> SKX_EXT_B_BGA1-IC,TBD    I18 @BASEBOARD_FAB2_LIB.BASEBOARD_FAB2(SCH_1):PAGE75
  U2D1 CN12 VSS<408> SKX_EXT_B_BGA1-IC,TBD    I18 @BASEBOARD_FAB2_LIB.BASEBOARD_FAB2(SCH_1):PAGE75
  U2D1  CN2 VSS<409> SKX_EXT_B_BGA1-IC,TBD    I18 @BASEBOARD_FAB2_LIB.BASEBOARD_FAB2(SCH_1):PAGE75
  U2D1 CM85 VSS<410> SKX_EXT_B_BGA1-IC,TBD    I18 @BASEBOARD_FAB2_LIB.BASEBOARD_FAB2(SCH_1):PAGE75
  U2D1 CM83 VSS<411> SKX_EXT_B_BGA1-IC,TBD    I18 @BASEBOARD_FAB2_LIB.BASEBOARD_FAB2(SCH_1):PAGE75
  U2D1 CM77 VSS<412> SKX_EXT_B_BGA1-IC,TBD    I18 @BASEBOARD_FAB2_LIB.BASEBOARD_FAB2(SCH_1):PAGE75
  U2D1 CM73 VSS<413> SKX_EXT_B_BGA1-IC,TBD    I18 @BASEBOARD_FAB2_LIB.BASEBOARD_FAB2(SCH_1):PAGE75
  U2D1 CM67 VSS<414> SKX_EXT_B_BGA1-IC,TBD    I18 @BASEBOARD_FAB2_LIB.BASEBOARD_FAB2(SCH_1):PAGE75
  U2D1 CM63 VSS<415> SKX_EXT_B_BGA1-IC,TBD    I18 @BASEBOARD_FAB2_LIB.BASEBOARD_FAB2(SCH_1):PAGE75
  U2D1 CM61 VSS<416> SKX_EXT_B_BGA1-IC,TBD    I18 @BASEBOARD_FAB2_LIB.BASEBOARD_FAB2(SCH_1):PAGE75
  U2D1 CM31 VSS<417> SKX_EXT_B_BGA1-IC,TBD    I18 @BASEBOARD_FAB2_LIB.BASEBOARD_FAB2(SCH_1):PAGE75
  U2D1  CM5 VSS<418> SKX_EXT_B_BGA1-IC,TBD    I18 @BASEBOARD_FAB2_LIB.BASEBOARD_FAB2(SCH_1):PAGE75
  U2D1 CM29 VSS<419> SKX_EXT_B_BGA1-IC,TBD    I18 @BASEBOARD_FAB2_LIB.BASEBOARD_FAB2(SCH_1):PAGE75
  U2D1 CM19 VSS<420> SKX_EXT_B_BGA1-IC,TBD    I18 @BASEBOARD_FAB2_LIB.BASEBOARD_FAB2(SCH_1):PAGE75
  U2D1 CL80 VSS<421> SKX_EXT_B_BGA1-IC,TBD    I18 @BASEBOARD_FAB2_LIB.BASEBOARD_FAB2(SCH_1):PAGE75
  U2D1 CL78 VSS<422> SKX_EXT_B_BGA1-IC,TBD    I18 @BASEBOARD_FAB2_LIB.BASEBOARD_FAB2(SCH_1):PAGE75
  U2D1 CL76 VSS<423> SKX_EXT_B_BGA1-IC,TBD    I18 @BASEBOARD_FAB2_LIB.BASEBOARD_FAB2(SCH_1):PAGE75
  U2D1 CL74 VSS<424> SKX_EXT_B_BGA1-IC,TBD    I18 @BASEBOARD_FAB2_LIB.BASEBOARD_FAB2(SCH_1):PAGE75
  U2D1 CL66 VSS<425> SKX_EXT_B_BGA1-IC,TBD    I18 @BASEBOARD_FAB2_LIB.BASEBOARD_FAB2(SCH_1):PAGE75
  U2D1 CL64 VSS<426> SKX_EXT_B_BGA1-IC,TBD    I18 @BASEBOARD_FAB2_LIB.BASEBOARD_FAB2(SCH_1):PAGE75
  U2D1 CL62 VSS<427> SKX_EXT_B_BGA1-IC,TBD    I18 @BASEBOARD_FAB2_LIB.BASEBOARD_FAB2(SCH_1):PAGE75
  U2D1  H63 VSS<428> SKX_EXT_B_BGA1-IC,TBD    I18 @BASEBOARD_FAB2_LIB.BASEBOARD_FAB2(SCH_1):PAGE75
  U2D1  P45 VSS<429> SKX_EXT_B_BGA1-IC,TBD    I18 @BASEBOARD_FAB2_LIB.BASEBOARD_FAB2(SCH_1):PAGE75
  U2D1 CL18 VSS<430> SKX_EXT_B_BGA1-IC,TBD    I18 @BASEBOARD_FAB2_LIB.BASEBOARD_FAB2(SCH_1):PAGE75
  U2D1 CL14 VSS<431> SKX_EXT_B_BGA1-IC,TBD    I18 @BASEBOARD_FAB2_LIB.BASEBOARD_FAB2(SCH_1):PAGE75
  U2D1  CL8 VSS<432> SKX_EXT_B_BGA1-IC,TBD    I18 @BASEBOARD_FAB2_LIB.BASEBOARD_FAB2(SCH_1):PAGE75
  U2D1 CK85 VSS<433> SKX_EXT_B_BGA1-IC,TBD    I18 @BASEBOARD_FAB2_LIB.BASEBOARD_FAB2(SCH_1):PAGE75
  U2D1 CK83 VSS<434> SKX_EXT_B_BGA1-IC,TBD    I18 @BASEBOARD_FAB2_LIB.BASEBOARD_FAB2(SCH_1):PAGE75
  U2D1 CK75 VSS<435> SKX_EXT_B_BGA1-IC,TBD    I18 @BASEBOARD_FAB2_LIB.BASEBOARD_FAB2(SCH_1):PAGE75
  U2D1 CK73 VSS<436> SKX_EXT_B_BGA1-IC,TBD    I18 @BASEBOARD_FAB2_LIB.BASEBOARD_FAB2(SCH_1):PAGE75
  U2D1 CK71 VSS<437> SKX_EXT_B_BGA1-IC,TBD    I18 @BASEBOARD_FAB2_LIB.BASEBOARD_FAB2(SCH_1):PAGE75
  U2D1 CK69 VSS<438> SKX_EXT_B_BGA1-IC,TBD    I18 @BASEBOARD_FAB2_LIB.BASEBOARD_FAB2(SCH_1):PAGE75
  U2D1 CK67 VSS<439> SKX_EXT_B_BGA1-IC,TBD    I18 @BASEBOARD_FAB2_LIB.BASEBOARD_FAB2(SCH_1):PAGE75
  U2D1 CK65 VSS<440> SKX_EXT_B_BGA1-IC,TBD    I18 @BASEBOARD_FAB2_LIB.BASEBOARD_FAB2(SCH_1):PAGE75
  U2D1 CK63 VSS<441> SKX_EXT_B_BGA1-IC,TBD    I18 @BASEBOARD_FAB2_LIB.BASEBOARD_FAB2(SCH_1):PAGE75
  U2D1 CK27 VSS<442> SKX_EXT_B_BGA1-IC,TBD    I18 @BASEBOARD_FAB2_LIB.BASEBOARD_FAB2(SCH_1):PAGE75
  U2D1 CK21 VSS<443> SKX_EXT_B_BGA1-IC,TBD    I18 @BASEBOARD_FAB2_LIB.BASEBOARD_FAB2(SCH_1):PAGE75
  U2D1 CK15 VSS<444> SKX_EXT_B_BGA1-IC,TBD    I18 @BASEBOARD_FAB2_LIB.BASEBOARD_FAB2(SCH_1):PAGE75
  U2D1 CK11 VSS<445> SKX_EXT_B_BGA1-IC,TBD    I18 @BASEBOARD_FAB2_LIB.BASEBOARD_FAB2(SCH_1):PAGE75
  U2D1 CJ86 VSS<446> SKX_EXT_B_BGA1-IC,TBD    I18 @BASEBOARD_FAB2_LIB.BASEBOARD_FAB2(SCH_1):PAGE75
  U2D1 CJ84 VSS<447> SKX_EXT_B_BGA1-IC,TBD    I18 @BASEBOARD_FAB2_LIB.BASEBOARD_FAB2(SCH_1):PAGE75
  U2D1 CJ82 VSS<448> SKX_EXT_B_BGA1-IC,TBD    I18 @BASEBOARD_FAB2_LIB.BASEBOARD_FAB2(SCH_1):PAGE75
  U2D1 CJ78 VSS<449> SKX_EXT_B_BGA1-IC,TBD    I18 @BASEBOARD_FAB2_LIB.BASEBOARD_FAB2(SCH_1):PAGE75
  U2D1 CJ76 VSS<450> SKX_EXT_B_BGA1-IC,TBD    I18 @BASEBOARD_FAB2_LIB.BASEBOARD_FAB2(SCH_1):PAGE75
  U2D1 CJ74 VSS<451> SKX_EXT_B_BGA1-IC,TBD    I18 @BASEBOARD_FAB2_LIB.BASEBOARD_FAB2(SCH_1):PAGE75
  U2D1 CJ62 VSS<452> SKX_EXT_B_BGA1-IC,TBD    I18 @BASEBOARD_FAB2_LIB.BASEBOARD_FAB2(SCH_1):PAGE75
  U2D1  P47 VSS<453> SKX_EXT_B_BGA1-IC,TBD    I18 @BASEBOARD_FAB2_LIB.BASEBOARD_FAB2(SCH_1):PAGE75
  U2D1 DN72 VSS<134> SKX_EXT_B_BGA1-IC,TBD    I19 @BASEBOARD_FAB2_LIB.BASEBOARD_FAB2(SCH_1):PAGE75
  U2D1 DN68 VSS<135> SKX_EXT_B_BGA1-IC,TBD    I19 @BASEBOARD_FAB2_LIB.BASEBOARD_FAB2(SCH_1):PAGE75
  U2D1 DN38 VSS<136> SKX_EXT_B_BGA1-IC,TBD    I19 @BASEBOARD_FAB2_LIB.BASEBOARD_FAB2(SCH_1):PAGE75
  U2D1 DN32 VSS<137> SKX_EXT_B_BGA1-IC,TBD    I19 @BASEBOARD_FAB2_LIB.BASEBOARD_FAB2(SCH_1):PAGE75
  U2D1 DN26 VSS<138> SKX_EXT_B_BGA1-IC,TBD    I19 @BASEBOARD_FAB2_LIB.BASEBOARD_FAB2(SCH_1):PAGE75
  U2D1 DN22 VSS<139> SKX_EXT_B_BGA1-IC,TBD    I19 @BASEBOARD_FAB2_LIB.BASEBOARD_FAB2(SCH_1):PAGE75
  U2D1 DN12 VSS<140> SKX_EXT_B_BGA1-IC,TBD    I19 @BASEBOARD_FAB2_LIB.BASEBOARD_FAB2(SCH_1):PAGE75
  U2D1 BH17 VSS<141> SKX_EXT_B_BGA1-IC,TBD    I19 @BASEBOARD_FAB2_LIB.BASEBOARD_FAB2(SCH_1):PAGE75
  U2D1  DN2 VSS<142> SKX_EXT_B_BGA1-IC,TBD    I19 @BASEBOARD_FAB2_LIB.BASEBOARD_FAB2(SCH_1):PAGE75
  U2D1 DM83 VSS<143> SKX_EXT_B_BGA1-IC,TBD    I19 @BASEBOARD_FAB2_LIB.BASEBOARD_FAB2(SCH_1):PAGE75
  U2D1 DM77 VSS<144> SKX_EXT_B_BGA1-IC,TBD    I19 @BASEBOARD_FAB2_LIB.BASEBOARD_FAB2(SCH_1):PAGE75
  U2D1 DM73 VSS<145> SKX_EXT_B_BGA1-IC,TBD    I19 @BASEBOARD_FAB2_LIB.BASEBOARD_FAB2(SCH_1):PAGE75
  U2D1 DM65 VSS<146> SKX_EXT_B_BGA1-IC,TBD    I19 @BASEBOARD_FAB2_LIB.BASEBOARD_FAB2(SCH_1):PAGE75
  U2D1 DM39 VSS<147> SKX_EXT_B_BGA1-IC,TBD    I19 @BASEBOARD_FAB2_LIB.BASEBOARD_FAB2(SCH_1):PAGE75
  U2D1 DM37 VSS<148> SKX_EXT_B_BGA1-IC,TBD    I19 @BASEBOARD_FAB2_LIB.BASEBOARD_FAB2(SCH_1):PAGE75
  U2D1 DM33 VSS<149> SKX_EXT_B_BGA1-IC,TBD    I19 @BASEBOARD_FAB2_LIB.BASEBOARD_FAB2(SCH_1):PAGE75
  U2D1 DM31 VSS<150> SKX_EXT_B_BGA1-IC,TBD    I19 @BASEBOARD_FAB2_LIB.BASEBOARD_FAB2(SCH_1):PAGE75
  U2D1 DM27 VSS<151> SKX_EXT_B_BGA1-IC,TBD    I19 @BASEBOARD_FAB2_LIB.BASEBOARD_FAB2(SCH_1):PAGE75
  U2D1 DM25 VSS<152> SKX_EXT_B_BGA1-IC,TBD    I19 @BASEBOARD_FAB2_LIB.BASEBOARD_FAB2(SCH_1):PAGE75
  U2D1  H45 VSS<153> SKX_EXT_B_BGA1-IC,TBD    I19 @BASEBOARD_FAB2_LIB.BASEBOARD_FAB2(SCH_1):PAGE75
  U2D1 DM15 VSS<154> SKX_EXT_B_BGA1-IC,TBD    I19 @BASEBOARD_FAB2_LIB.BASEBOARD_FAB2(SCH_1):PAGE75
  U2D1 DL80 VSS<155> SKX_EXT_B_BGA1-IC,TBD    I19 @BASEBOARD_FAB2_LIB.BASEBOARD_FAB2(SCH_1):PAGE75
  U2D1 DL78 VSS<156> SKX_EXT_B_BGA1-IC,TBD    I19 @BASEBOARD_FAB2_LIB.BASEBOARD_FAB2(SCH_1):PAGE75
  U2D1 DL76 VSS<157> SKX_EXT_B_BGA1-IC,TBD    I19 @BASEBOARD_FAB2_LIB.BASEBOARD_FAB2(SCH_1):PAGE75
  U2D1 DL74 VSS<158> SKX_EXT_B_BGA1-IC,TBD    I19 @BASEBOARD_FAB2_LIB.BASEBOARD_FAB2(SCH_1):PAGE75
  U2D1 DL70 VSS<159> SKX_EXT_B_BGA1-IC,TBD    I19 @BASEBOARD_FAB2_LIB.BASEBOARD_FAB2(SCH_1):PAGE75
  U2D1 DL68 VSS<160> SKX_EXT_B_BGA1-IC,TBD    I19 @BASEBOARD_FAB2_LIB.BASEBOARD_FAB2(SCH_1):PAGE75
  U2D1 DL40 VSS<161> SKX_EXT_B_BGA1-IC,TBD    I19 @BASEBOARD_FAB2_LIB.BASEBOARD_FAB2(SCH_1):PAGE75
  U2D1 DL36 VSS<162> SKX_EXT_B_BGA1-IC,TBD    I19 @BASEBOARD_FAB2_LIB.BASEBOARD_FAB2(SCH_1):PAGE75
  U2D1 DL34 VSS<163> SKX_EXT_B_BGA1-IC,TBD    I19 @BASEBOARD_FAB2_LIB.BASEBOARD_FAB2(SCH_1):PAGE75
  U2D1 DL30 VSS<164> SKX_EXT_B_BGA1-IC,TBD    I19 @BASEBOARD_FAB2_LIB.BASEBOARD_FAB2(SCH_1):PAGE75
  U2D1 DL28 VSS<165> SKX_EXT_B_BGA1-IC,TBD    I19 @BASEBOARD_FAB2_LIB.BASEBOARD_FAB2(SCH_1):PAGE75
  U2D1 DL24 VSS<166> SKX_EXT_B_BGA1-IC,TBD    I19 @BASEBOARD_FAB2_LIB.BASEBOARD_FAB2(SCH_1):PAGE75
  U2D1 DL22 VSS<167> SKX_EXT_B_BGA1-IC,TBD    I19 @BASEBOARD_FAB2_LIB.BASEBOARD_FAB2(SCH_1):PAGE75
  U2D1  DL4 VSS<168> SKX_EXT_B_BGA1-IC,TBD    I19 @BASEBOARD_FAB2_LIB.BASEBOARD_FAB2(SCH_1):PAGE75
  U2D1 DL18 VSS<169> SKX_EXT_B_BGA1-IC,TBD    I19 @BASEBOARD_FAB2_LIB.BASEBOARD_FAB2(SCH_1):PAGE75
  U2D1 DL16 VSS<170> SKX_EXT_B_BGA1-IC,TBD    I19 @BASEBOARD_FAB2_LIB.BASEBOARD_FAB2(SCH_1):PAGE75
  U2D1 DK85 VSS<171> SKX_EXT_B_BGA1-IC,TBD    I19 @BASEBOARD_FAB2_LIB.BASEBOARD_FAB2(SCH_1):PAGE75
  U2D1 DK83 VSS<172> SKX_EXT_B_BGA1-IC,TBD    I19 @BASEBOARD_FAB2_LIB.BASEBOARD_FAB2(SCH_1):PAGE75
  U2D1 DK77 VSS<173> SKX_EXT_B_BGA1-IC,TBD    I19 @BASEBOARD_FAB2_LIB.BASEBOARD_FAB2(SCH_1):PAGE75
  U2D1 DK75 VSS<174> SKX_EXT_B_BGA1-IC,TBD    I19 @BASEBOARD_FAB2_LIB.BASEBOARD_FAB2(SCH_1):PAGE75
  U2D1 DK73 VSS<175> SKX_EXT_B_BGA1-IC,TBD    I19 @BASEBOARD_FAB2_LIB.BASEBOARD_FAB2(SCH_1):PAGE75
  U2D1 DK41 VSS<176> SKX_EXT_B_BGA1-IC,TBD    I19 @BASEBOARD_FAB2_LIB.BASEBOARD_FAB2(SCH_1):PAGE75
  U2D1 DK39 VSS<177> SKX_EXT_B_BGA1-IC,TBD    I19 @BASEBOARD_FAB2_LIB.BASEBOARD_FAB2(SCH_1):PAGE75
  U2D1 DK35 VSS<178> SKX_EXT_B_BGA1-IC,TBD    I19 @BASEBOARD_FAB2_LIB.BASEBOARD_FAB2(SCH_1):PAGE75
  U2D1 DK29 VSS<179> SKX_EXT_B_BGA1-IC,TBD    I19 @BASEBOARD_FAB2_LIB.BASEBOARD_FAB2(SCH_1):PAGE75
  U2D1 DK23 VSS<180> SKX_EXT_B_BGA1-IC,TBD    I19 @BASEBOARD_FAB2_LIB.BASEBOARD_FAB2(SCH_1):PAGE75
  U2D1  DK7 VSS<181> SKX_EXT_B_BGA1-IC,TBD    I19 @BASEBOARD_FAB2_LIB.BASEBOARD_FAB2(SCH_1):PAGE75
  U2D1 DJ84 VSS<182> SKX_EXT_B_BGA1-IC,TBD    I19 @BASEBOARD_FAB2_LIB.BASEBOARD_FAB2(SCH_1):PAGE75
  U2D1 DJ82 VSS<183> SKX_EXT_B_BGA1-IC,TBD    I19 @BASEBOARD_FAB2_LIB.BASEBOARD_FAB2(SCH_1):PAGE75
  U2D1 DJ78 VSS<184> SKX_EXT_B_BGA1-IC,TBD    I19 @BASEBOARD_FAB2_LIB.BASEBOARD_FAB2(SCH_1):PAGE75
  U2D1 DJ74 VSS<185> SKX_EXT_B_BGA1-IC,TBD    I19 @BASEBOARD_FAB2_LIB.BASEBOARD_FAB2(SCH_1):PAGE75
  U2D1 DJ68 VSS<186> SKX_EXT_B_BGA1-IC,TBD    I19 @BASEBOARD_FAB2_LIB.BASEBOARD_FAB2(SCH_1):PAGE75
  U2D1 DJ42 VSS<187> SKX_EXT_B_BGA1-IC,TBD    I19 @BASEBOARD_FAB2_LIB.BASEBOARD_FAB2(SCH_1):PAGE75
  U2D1 DJ38 VSS<188> SKX_EXT_B_BGA1-IC,TBD    I19 @BASEBOARD_FAB2_LIB.BASEBOARD_FAB2(SCH_1):PAGE75
  U2D1 DJ22 VSS<189> SKX_EXT_B_BGA1-IC,TBD    I19 @BASEBOARD_FAB2_LIB.BASEBOARD_FAB2(SCH_1):PAGE75
  U2D1  H47 VSS<190> SKX_EXT_B_BGA1-IC,TBD    I19 @BASEBOARD_FAB2_LIB.BASEBOARD_FAB2(SCH_1):PAGE75
  U2D1 DJ10 VSS<191> SKX_EXT_B_BGA1-IC,TBD    I19 @BASEBOARD_FAB2_LIB.BASEBOARD_FAB2(SCH_1):PAGE75
  U2D1  DJ2 VSS<192> SKX_EXT_B_BGA1-IC,TBD    I19 @BASEBOARD_FAB2_LIB.BASEBOARD_FAB2(SCH_1):PAGE75
  U2D1 DH83 VSS<193> SKX_EXT_B_BGA1-IC,TBD    I19 @BASEBOARD_FAB2_LIB.BASEBOARD_FAB2(SCH_1):PAGE75
  U2D1 DH81 VSS<194> SKX_EXT_B_BGA1-IC,TBD    I19 @BASEBOARD_FAB2_LIB.BASEBOARD_FAB2(SCH_1):PAGE75
  U2D1 DH79 VSS<195> SKX_EXT_B_BGA1-IC,TBD    I19 @BASEBOARD_FAB2_LIB.BASEBOARD_FAB2(SCH_1):PAGE75
  U2D1 DH73 VSS<196> SKX_EXT_B_BGA1-IC,TBD    I19 @BASEBOARD_FAB2_LIB.BASEBOARD_FAB2(SCH_1):PAGE75
  U2D1 DH71 VSS<197> SKX_EXT_B_BGA1-IC,TBD    I19 @BASEBOARD_FAB2_LIB.BASEBOARD_FAB2(SCH_1):PAGE75
  U2D1 DH67 VSS<198> SKX_EXT_B_BGA1-IC,TBD    I19 @BASEBOARD_FAB2_LIB.BASEBOARD_FAB2(SCH_1):PAGE75
  U2D1 DH41 VSS<199> SKX_EXT_B_BGA1-IC,TBD    I19 @BASEBOARD_FAB2_LIB.BASEBOARD_FAB2(SCH_1):PAGE75
  U2D1 DH37 VSS<200> SKX_EXT_B_BGA1-IC,TBD    I19 @BASEBOARD_FAB2_LIB.BASEBOARD_FAB2(SCH_1):PAGE75
  U2D1 DH35 VSS<201> SKX_EXT_B_BGA1-IC,TBD    I19 @BASEBOARD_FAB2_LIB.BASEBOARD_FAB2(SCH_1):PAGE75
  U2D1 DH33 VSS<202> SKX_EXT_B_BGA1-IC,TBD    I19 @BASEBOARD_FAB2_LIB.BASEBOARD_FAB2(SCH_1):PAGE75
  U2D1 DH31 VSS<203> SKX_EXT_B_BGA1-IC,TBD    I19 @BASEBOARD_FAB2_LIB.BASEBOARD_FAB2(SCH_1):PAGE75
  U2D1 DH29 VSS<204> SKX_EXT_B_BGA1-IC,TBD    I19 @BASEBOARD_FAB2_LIB.BASEBOARD_FAB2(SCH_1):PAGE75
  U2D1 DH27 VSS<205> SKX_EXT_B_BGA1-IC,TBD    I19 @BASEBOARD_FAB2_LIB.BASEBOARD_FAB2(SCH_1):PAGE75
  U2D1 DH25 VSS<206> SKX_EXT_B_BGA1-IC,TBD    I19 @BASEBOARD_FAB2_LIB.BASEBOARD_FAB2(SCH_1):PAGE75
  U2D1 DH23 VSS<207> SKX_EXT_B_BGA1-IC,TBD    I19 @BASEBOARD_FAB2_LIB.BASEBOARD_FAB2(SCH_1):PAGE75
  U2D1 DH15 VSS<208> SKX_EXT_B_BGA1-IC,TBD    I19 @BASEBOARD_FAB2_LIB.BASEBOARD_FAB2(SCH_1):PAGE75
  U2D1 DH13 VSS<209> SKX_EXT_B_BGA1-IC,TBD    I19 @BASEBOARD_FAB2_LIB.BASEBOARD_FAB2(SCH_1):PAGE75
  U2D1 DG82 VSS<210> SKX_EXT_B_BGA1-IC,TBD    I19 @BASEBOARD_FAB2_LIB.BASEBOARD_FAB2(SCH_1):PAGE75
  U2D1 DG80 VSS<211> SKX_EXT_B_BGA1-IC,TBD    I19 @BASEBOARD_FAB2_LIB.BASEBOARD_FAB2(SCH_1):PAGE75
  U2D1 DG78 VSS<212> SKX_EXT_B_BGA1-IC,TBD    I19 @BASEBOARD_FAB2_LIB.BASEBOARD_FAB2(SCH_1):PAGE75
  U2D1 DG76 VSS<213> SKX_EXT_B_BGA1-IC,TBD    I19 @BASEBOARD_FAB2_LIB.BASEBOARD_FAB2(SCH_1):PAGE75
  U2D1 DG68 VSS<214> SKX_EXT_B_BGA1-IC,TBD    I19 @BASEBOARD_FAB2_LIB.BASEBOARD_FAB2(SCH_1):PAGE75
  U2D1 DG66 VSS<215> SKX_EXT_B_BGA1-IC,TBD    I19 @BASEBOARD_FAB2_LIB.BASEBOARD_FAB2(SCH_1):PAGE75
  U2D1 DG24 VSS<216> SKX_EXT_B_BGA1-IC,TBD    I19 @BASEBOARD_FAB2_LIB.BASEBOARD_FAB2(SCH_1):PAGE75
  U2D1 DG16 VSS<217> SKX_EXT_B_BGA1-IC,TBD    I19 @BASEBOARD_FAB2_LIB.BASEBOARD_FAB2(SCH_1):PAGE75
  U2D1 DG14 VSS<218> SKX_EXT_B_BGA1-IC,TBD    I19 @BASEBOARD_FAB2_LIB.BASEBOARD_FAB2(SCH_1):PAGE75
  U2D1  H49 VSS<219> SKX_EXT_B_BGA1-IC,TBD    I19 @BASEBOARD_FAB2_LIB.BASEBOARD_FAB2(SCH_1):PAGE75
  U2D1  DG2 VSS<220> SKX_EXT_B_BGA1-IC,TBD    I19 @BASEBOARD_FAB2_LIB.BASEBOARD_FAB2(SCH_1):PAGE75
  U2D1 DF85 VSS<221> SKX_EXT_B_BGA1-IC,TBD    I19 @BASEBOARD_FAB2_LIB.BASEBOARD_FAB2(SCH_1):PAGE75
  U2D1 DF83 VSS<222> SKX_EXT_B_BGA1-IC,TBD    I19 @BASEBOARD_FAB2_LIB.BASEBOARD_FAB2(SCH_1):PAGE75
  U2D1 DF79 VSS<223> SKX_EXT_B_BGA1-IC,TBD    I19 @BASEBOARD_FAB2_LIB.BASEBOARD_FAB2(SCH_1):PAGE75
  U2D1 DF73 VSS<224> SKX_EXT_B_BGA1-IC,TBD    I19 @BASEBOARD_FAB2_LIB.BASEBOARD_FAB2(SCH_1):PAGE75
  U2D1 DF69 VSS<225> SKX_EXT_B_BGA1-IC,TBD    I19 @BASEBOARD_FAB2_LIB.BASEBOARD_FAB2(SCH_1):PAGE75
  U2D1 DF65 VSS<226> SKX_EXT_B_BGA1-IC,TBD    I19 @BASEBOARD_FAB2_LIB.BASEBOARD_FAB2(SCH_1):PAGE75
  U2D1 DF41 VSS<227> SKX_EXT_B_BGA1-IC,TBD    I19 @BASEBOARD_FAB2_LIB.BASEBOARD_FAB2(SCH_1):PAGE75
  U2D1 DF39 VSS<228> SKX_EXT_B_BGA1-IC,TBD    I19 @BASEBOARD_FAB2_LIB.BASEBOARD_FAB2(SCH_1):PAGE75
  U2D1 DF37 VSS<229> SKX_EXT_B_BGA1-IC,TBD    I19 @BASEBOARD_FAB2_LIB.BASEBOARD_FAB2(SCH_1):PAGE75
  U2D1 DF35 VSS<230> SKX_EXT_B_BGA1-IC,TBD    I19 @BASEBOARD_FAB2_LIB.BASEBOARD_FAB2(SCH_1):PAGE75
  U2D1 DF29 VSS<231> SKX_EXT_B_BGA1-IC,TBD    I19 @BASEBOARD_FAB2_LIB.BASEBOARD_FAB2(SCH_1):PAGE75
  U2D1 DF19 VSS<232> SKX_EXT_B_BGA1-IC,TBD    I19 @BASEBOARD_FAB2_LIB.BASEBOARD_FAB2(SCH_1):PAGE75
  U2D1  H51 VSS<233> SKX_EXT_B_BGA1-IC,TBD    I19 @BASEBOARD_FAB2_LIB.BASEBOARD_FAB2(SCH_1):PAGE75
  U2D1  DF7 VSS<234> SKX_EXT_B_BGA1-IC,TBD    I19 @BASEBOARD_FAB2_LIB.BASEBOARD_FAB2(SCH_1):PAGE75
  U2D1  DF5 VSS<235> SKX_EXT_B_BGA1-IC,TBD    I19 @BASEBOARD_FAB2_LIB.BASEBOARD_FAB2(SCH_1):PAGE75
  U2D1 DE78 VSS<236> SKX_EXT_B_BGA1-IC,TBD    I19 @BASEBOARD_FAB2_LIB.BASEBOARD_FAB2(SCH_1):PAGE75
  U2D1 DE72 VSS<237> SKX_EXT_B_BGA1-IC,TBD    I19 @BASEBOARD_FAB2_LIB.BASEBOARD_FAB2(SCH_1):PAGE75
  U2D1 DE70 VSS<238> SKX_EXT_B_BGA1-IC,TBD    I19 @BASEBOARD_FAB2_LIB.BASEBOARD_FAB2(SCH_1):PAGE75
  U2D1 DE64 VSS<239> SKX_EXT_B_BGA1-IC,TBD    I19 @BASEBOARD_FAB2_LIB.BASEBOARD_FAB2(SCH_1):PAGE75
  U2D1 DE36 VSS<240> SKX_EXT_B_BGA1-IC,TBD    I19 @BASEBOARD_FAB2_LIB.BASEBOARD_FAB2(SCH_1):PAGE75
  U2D1 DE34 VSS<241> SKX_EXT_B_BGA1-IC,TBD    I19 @BASEBOARD_FAB2_LIB.BASEBOARD_FAB2(SCH_1):PAGE75
  U2D1 DE30 VSS<242> SKX_EXT_B_BGA1-IC,TBD    I19 @BASEBOARD_FAB2_LIB.BASEBOARD_FAB2(SCH_1):PAGE75
  U2D1 DE28 VSS<243> SKX_EXT_B_BGA1-IC,TBD    I19 @BASEBOARD_FAB2_LIB.BASEBOARD_FAB2(SCH_1):PAGE75
  U2D1 DE24 VSS<244> SKX_EXT_B_BGA1-IC,TBD    I19 @BASEBOARD_FAB2_LIB.BASEBOARD_FAB2(SCH_1):PAGE75
  U2D1 DE20 VSS<245> SKX_EXT_B_BGA1-IC,TBD    I19 @BASEBOARD_FAB2_LIB.BASEBOARD_FAB2(SCH_1):PAGE75
  U2D1 DE18 VSS<246> SKX_EXT_B_BGA1-IC,TBD    I19 @BASEBOARD_FAB2_LIB.BASEBOARD_FAB2(SCH_1):PAGE75
  U2D1  DE8 VSS<247> SKX_EXT_B_BGA1-IC,TBD    I19 @BASEBOARD_FAB2_LIB.BASEBOARD_FAB2(SCH_1):PAGE75
  U2D1  DE6 VSS<248> SKX_EXT_B_BGA1-IC,TBD    I19 @BASEBOARD_FAB2_LIB.BASEBOARD_FAB2(SCH_1):PAGE75
  U2D1 DD83 VSS<249> SKX_EXT_B_BGA1-IC,TBD    I19 @BASEBOARD_FAB2_LIB.BASEBOARD_FAB2(SCH_1):PAGE75
  U2D1 DD81 VSS<250> SKX_EXT_B_BGA1-IC,TBD    I19 @BASEBOARD_FAB2_LIB.BASEBOARD_FAB2(SCH_1):PAGE75
  U2D1 DD75 VSS<251> SKX_EXT_B_BGA1-IC,TBD    I19 @BASEBOARD_FAB2_LIB.BASEBOARD_FAB2(SCH_1):PAGE75
  U2D1 DD73 VSS<252> SKX_EXT_B_BGA1-IC,TBD    I19 @BASEBOARD_FAB2_LIB.BASEBOARD_FAB2(SCH_1):PAGE75
  U2D1 DD71 VSS<253> SKX_EXT_B_BGA1-IC,TBD    I19 @BASEBOARD_FAB2_LIB.BASEBOARD_FAB2(SCH_1):PAGE75
  U2D1 DD37 VSS<254> SKX_EXT_B_BGA1-IC,TBD    I19 @BASEBOARD_FAB2_LIB.BASEBOARD_FAB2(SCH_1):PAGE75
  U2D1 DD33 VSS<255> SKX_EXT_B_BGA1-IC,TBD    I19 @BASEBOARD_FAB2_LIB.BASEBOARD_FAB2(SCH_1):PAGE75
  U2D1 DD31 VSS<256> SKX_EXT_B_BGA1-IC,TBD    I19 @BASEBOARD_FAB2_LIB.BASEBOARD_FAB2(SCH_1):PAGE75
  U2D1 DD27 VSS<257> SKX_EXT_B_BGA1-IC,TBD    I19 @BASEBOARD_FAB2_LIB.BASEBOARD_FAB2(SCH_1):PAGE75
  U2D1 DD23 VSS<258> SKX_EXT_B_BGA1-IC,TBD    I19 @BASEBOARD_FAB2_LIB.BASEBOARD_FAB2(SCH_1):PAGE75
  U2D1 DD11 VSS<259> SKX_EXT_B_BGA1-IC,TBD    I19 @BASEBOARD_FAB2_LIB.BASEBOARD_FAB2(SCH_1):PAGE75
  U2D1 DC86 VSS<260> SKX_EXT_B_BGA1-IC,TBD    I19 @BASEBOARD_FAB2_LIB.BASEBOARD_FAB2(SCH_1):PAGE75
  U2D1 DC84 VSS<261> SKX_EXT_B_BGA1-IC,TBD    I19 @BASEBOARD_FAB2_LIB.BASEBOARD_FAB2(SCH_1):PAGE75
  U2D1 DC78 VSS<262> SKX_EXT_B_BGA1-IC,TBD    I19 @BASEBOARD_FAB2_LIB.BASEBOARD_FAB2(SCH_1):PAGE75
  U2D1 DC70 VSS<263> SKX_EXT_B_BGA1-IC,TBD    I19 @BASEBOARD_FAB2_LIB.BASEBOARD_FAB2(SCH_1):PAGE75
  U2D1 DC68 VSS<264> SKX_EXT_B_BGA1-IC,TBD    I19 @BASEBOARD_FAB2_LIB.BASEBOARD_FAB2(SCH_1):PAGE75
  U2D1 DC66 VSS<265> SKX_EXT_B_BGA1-IC,TBD    I19 @BASEBOARD_FAB2_LIB.BASEBOARD_FAB2(SCH_1):PAGE75
  U2D1 DC64 VSS<266> SKX_EXT_B_BGA1-IC,TBD    I19 @BASEBOARD_FAB2_LIB.BASEBOARD_FAB2(SCH_1):PAGE75
  U2D1 DC42 VSS<267> SKX_EXT_B_BGA1-IC,TBD    I19 @BASEBOARD_FAB2_LIB.BASEBOARD_FAB2(SCH_1):PAGE75
  U2D1 DC38 VSS<268> SKX_EXT_B_BGA1-IC,TBD    I19 @BASEBOARD_FAB2_LIB.BASEBOARD_FAB2(SCH_1):PAGE75
  U2D1 DC32 VSS<269> SKX_EXT_B_BGA1-IC,TBD    I19 @BASEBOARD_FAB2_LIB.BASEBOARD_FAB2(SCH_1):PAGE75
  U2D1 DC26 VSS<270> SKX_EXT_B_BGA1-IC,TBD    I19 @BASEBOARD_FAB2_LIB.BASEBOARD_FAB2(SCH_1):PAGE75
  U2D1 DC24 VSS<271> SKX_EXT_B_BGA1-IC,TBD    I19 @BASEBOARD_FAB2_LIB.BASEBOARD_FAB2(SCH_1):PAGE75
  U2D1 DC14 VSS<272> SKX_EXT_B_BGA1-IC,TBD    I19 @BASEBOARD_FAB2_LIB.BASEBOARD_FAB2(SCH_1):PAGE75
  U2D1 DB85 VSS<273> SKX_EXT_B_BGA1-IC,TBD    I19 @BASEBOARD_FAB2_LIB.BASEBOARD_FAB2(SCH_1):PAGE75
  U2D1 DB83 VSS<274> SKX_EXT_B_BGA1-IC,TBD    I19 @BASEBOARD_FAB2_LIB.BASEBOARD_FAB2(SCH_1):PAGE75
  U2D1 DB77 VSS<275> SKX_EXT_B_BGA1-IC,TBD    I19 @BASEBOARD_FAB2_LIB.BASEBOARD_FAB2(SCH_1):PAGE75
  U2D1 DB73 VSS<276> SKX_EXT_B_BGA1-IC,TBD    I19 @BASEBOARD_FAB2_LIB.BASEBOARD_FAB2(SCH_1):PAGE75
  U2D1 DB49 VSS<277> SKX_EXT_B_BGA1-IC,TBD    I19 @BASEBOARD_FAB2_LIB.BASEBOARD_FAB2(SCH_1):PAGE75
  U2D1 DB47 VSS<278> SKX_EXT_B_BGA1-IC,TBD    I19 @BASEBOARD_FAB2_LIB.BASEBOARD_FAB2(SCH_1):PAGE75
  U2D1 DB41 VSS<279> SKX_EXT_B_BGA1-IC,TBD    I19 @BASEBOARD_FAB2_LIB.BASEBOARD_FAB2(SCH_1):PAGE75
  U2D1 DB39 VSS<280> SKX_EXT_B_BGA1-IC,TBD    I19 @BASEBOARD_FAB2_LIB.BASEBOARD_FAB2(SCH_1):PAGE75
  U2D1 DB25 VSS<281> SKX_EXT_B_BGA1-IC,TBD    I19 @BASEBOARD_FAB2_LIB.BASEBOARD_FAB2(SCH_1):PAGE75
  U2D1 DB23 VSS<282> SKX_EXT_B_BGA1-IC,TBD    I19 @BASEBOARD_FAB2_LIB.BASEBOARD_FAB2(SCH_1):PAGE75
  U2D1 DB17 VSS<283> SKX_EXT_B_BGA1-IC,TBD    I19 @BASEBOARD_FAB2_LIB.BASEBOARD_FAB2(SCH_1):PAGE75
  U2D1 DB13 VSS<284> SKX_EXT_B_BGA1-IC,TBD    I19 @BASEBOARD_FAB2_LIB.BASEBOARD_FAB2(SCH_1):PAGE75
  U2D1  DB3 VSS<285> SKX_EXT_B_BGA1-IC,TBD    I19 @BASEBOARD_FAB2_LIB.BASEBOARD_FAB2(SCH_1):PAGE75
  U2D1 DA80 VSS<286> SKX_EXT_B_BGA1-IC,TBD    I19 @BASEBOARD_FAB2_LIB.BASEBOARD_FAB2(SCH_1):PAGE75
  U2D1 DA78 VSS<287> SKX_EXT_B_BGA1-IC,TBD    I19 @BASEBOARD_FAB2_LIB.BASEBOARD_FAB2(SCH_1):PAGE75
  U2D1 DA76 VSS<288> SKX_EXT_B_BGA1-IC,TBD    I19 @BASEBOARD_FAB2_LIB.BASEBOARD_FAB2(SCH_1):PAGE75
  U2D1 DA74 VSS<289> SKX_EXT_B_BGA1-IC,TBD    I19 @BASEBOARD_FAB2_LIB.BASEBOARD_FAB2(SCH_1):PAGE75
  U2D1 DA70 VSS<290> SKX_EXT_B_BGA1-IC,TBD    I19 @BASEBOARD_FAB2_LIB.BASEBOARD_FAB2(SCH_1):PAGE75
  U2D1 DA64 VSS<291> SKX_EXT_B_BGA1-IC,TBD    I19 @BASEBOARD_FAB2_LIB.BASEBOARD_FAB2(SCH_1):PAGE75
  U2D1 DA50 VSS<292> SKX_EXT_B_BGA1-IC,TBD    I19 @BASEBOARD_FAB2_LIB.BASEBOARD_FAB2(SCH_1):PAGE75
  U2D1 DA48 VSS<293> SKX_EXT_B_BGA1-IC,TBD    I19 @BASEBOARD_FAB2_LIB.BASEBOARD_FAB2(SCH_1):PAGE75
  U2D1 EF79 VSS<0> SKX_EXT_B_BGA1-IC,TBD    I20 @BASEBOARD_FAB2_LIB.BASEBOARD_FAB2(SCH_1):PAGE75
  U2D1 EF75 VSS<1> SKX_EXT_B_BGA1-IC,TBD    I20 @BASEBOARD_FAB2_LIB.BASEBOARD_FAB2(SCH_1):PAGE75
  U2D1 EF71 VSS<2> SKX_EXT_B_BGA1-IC,TBD    I20 @BASEBOARD_FAB2_LIB.BASEBOARD_FAB2(SCH_1):PAGE75
  U2D1 EE78 VSS<3> SKX_EXT_B_BGA1-IC,TBD    I20 @BASEBOARD_FAB2_LIB.BASEBOARD_FAB2(SCH_1):PAGE75
  U2D1 EE76 VSS<4> SKX_EXT_B_BGA1-IC,TBD    I20 @BASEBOARD_FAB2_LIB.BASEBOARD_FAB2(SCH_1):PAGE75
  U2D1 EE70 VSS<5> SKX_EXT_B_BGA1-IC,TBD    I20 @BASEBOARD_FAB2_LIB.BASEBOARD_FAB2(SCH_1):PAGE75
  U2D1 EE36 VSS<6> SKX_EXT_B_BGA1-IC,TBD    I20 @BASEBOARD_FAB2_LIB.BASEBOARD_FAB2(SCH_1):PAGE75
  U2D1 EE34 VSS<7> SKX_EXT_B_BGA1-IC,TBD    I20 @BASEBOARD_FAB2_LIB.BASEBOARD_FAB2(SCH_1):PAGE75
  U2D1 EE30 VSS<8> SKX_EXT_B_BGA1-IC,TBD    I20 @BASEBOARD_FAB2_LIB.BASEBOARD_FAB2(SCH_1):PAGE75
  U2D1 EE28 VSS<9> SKX_EXT_B_BGA1-IC,TBD    I20 @BASEBOARD_FAB2_LIB.BASEBOARD_FAB2(SCH_1):PAGE75
  U2D1 EE24 VSS<10> SKX_EXT_B_BGA1-IC,TBD    I20 @BASEBOARD_FAB2_LIB.BASEBOARD_FAB2(SCH_1):PAGE75
  U2D1 ED77 VSS<11> SKX_EXT_B_BGA1-IC,TBD    I20 @BASEBOARD_FAB2_LIB.BASEBOARD_FAB2(SCH_1):PAGE75
  U2D1 ED35 VSS<12> SKX_EXT_B_BGA1-IC,TBD    I20 @BASEBOARD_FAB2_LIB.BASEBOARD_FAB2(SCH_1):PAGE75
  U2D1 ED29 VSS<13> SKX_EXT_B_BGA1-IC,TBD    I20 @BASEBOARD_FAB2_LIB.BASEBOARD_FAB2(SCH_1):PAGE75
  U2D1 ED23 VSS<14> SKX_EXT_B_BGA1-IC,TBD    I20 @BASEBOARD_FAB2_LIB.BASEBOARD_FAB2(SCH_1):PAGE75
  U2D1 ED15 VSS<15> SKX_EXT_B_BGA1-IC,TBD    I20 @BASEBOARD_FAB2_LIB.BASEBOARD_FAB2(SCH_1):PAGE75
  U2D1 ED11 VSS<16> SKX_EXT_B_BGA1-IC,TBD    I20 @BASEBOARD_FAB2_LIB.BASEBOARD_FAB2(SCH_1):PAGE75
  U2D1 EC76 VSS<17> SKX_EXT_B_BGA1-IC,TBD    I20 @BASEBOARD_FAB2_LIB.BASEBOARD_FAB2(SCH_1):PAGE75
  U2D1 EC74 VSS<18> SKX_EXT_B_BGA1-IC,TBD    I20 @BASEBOARD_FAB2_LIB.BASEBOARD_FAB2(SCH_1):PAGE75
  U2D1 EC72 VSS<19> SKX_EXT_B_BGA1-IC,TBD    I20 @BASEBOARD_FAB2_LIB.BASEBOARD_FAB2(SCH_1):PAGE75
  U2D1 EC70 VSS<20> SKX_EXT_B_BGA1-IC,TBD    I20 @BASEBOARD_FAB2_LIB.BASEBOARD_FAB2(SCH_1):PAGE75
  U2D1 EC10 VSS<21> SKX_EXT_B_BGA1-IC,TBD    I20 @BASEBOARD_FAB2_LIB.BASEBOARD_FAB2(SCH_1):PAGE75
  U2D1 EB69 VSS<22> SKX_EXT_B_BGA1-IC,TBD    I20 @BASEBOARD_FAB2_LIB.BASEBOARD_FAB2(SCH_1):PAGE75
  U2D1 EB65 VSS<23> SKX_EXT_B_BGA1-IC,TBD    I20 @BASEBOARD_FAB2_LIB.BASEBOARD_FAB2(SCH_1):PAGE75
  U2D1 EB41 VSS<24> SKX_EXT_B_BGA1-IC,TBD    I20 @BASEBOARD_FAB2_LIB.BASEBOARD_FAB2(SCH_1):PAGE75
  U2D1 EB39 VSS<25> SKX_EXT_B_BGA1-IC,TBD    I20 @BASEBOARD_FAB2_LIB.BASEBOARD_FAB2(SCH_1):PAGE75
  U2D1 EB37 VSS<26> SKX_EXT_B_BGA1-IC,TBD    I20 @BASEBOARD_FAB2_LIB.BASEBOARD_FAB2(SCH_1):PAGE75
  U2D1 EB35 VSS<27> SKX_EXT_B_BGA1-IC,TBD    I20 @BASEBOARD_FAB2_LIB.BASEBOARD_FAB2(SCH_1):PAGE75
  U2D1 EB33 VSS<28> SKX_EXT_B_BGA1-IC,TBD    I20 @BASEBOARD_FAB2_LIB.BASEBOARD_FAB2(SCH_1):PAGE75
  U2D1 EB31 VSS<29> SKX_EXT_B_BGA1-IC,TBD    I20 @BASEBOARD_FAB2_LIB.BASEBOARD_FAB2(SCH_1):PAGE75
  U2D1 EB29 VSS<30> SKX_EXT_B_BGA1-IC,TBD    I20 @BASEBOARD_FAB2_LIB.BASEBOARD_FAB2(SCH_1):PAGE75
  U2D1 EB27 VSS<31> SKX_EXT_B_BGA1-IC,TBD    I20 @BASEBOARD_FAB2_LIB.BASEBOARD_FAB2(SCH_1):PAGE75
  U2D1 EB25 VSS<32> SKX_EXT_B_BGA1-IC,TBD    I20 @BASEBOARD_FAB2_LIB.BASEBOARD_FAB2(SCH_1):PAGE75
  U2D1 EB23 VSS<33> SKX_EXT_B_BGA1-IC,TBD    I20 @BASEBOARD_FAB2_LIB.BASEBOARD_FAB2(SCH_1):PAGE75
  U2D1 BR18 VSS<34> SKX_EXT_B_BGA1-IC,TBD    I20 @BASEBOARD_FAB2_LIB.BASEBOARD_FAB2(SCH_1):PAGE75
  U2D1 EB13 VSS<35> SKX_EXT_B_BGA1-IC,TBD    I20 @BASEBOARD_FAB2_LIB.BASEBOARD_FAB2(SCH_1):PAGE75
  U2D1 EA82 VSS<36> SKX_EXT_B_BGA1-IC,TBD    I20 @BASEBOARD_FAB2_LIB.BASEBOARD_FAB2(SCH_1):PAGE75
  U2D1 EA80 VSS<37> SKX_EXT_B_BGA1-IC,TBD    I20 @BASEBOARD_FAB2_LIB.BASEBOARD_FAB2(SCH_1):PAGE75
  U2D1 EA78 VSS<38> SKX_EXT_B_BGA1-IC,TBD    I20 @BASEBOARD_FAB2_LIB.BASEBOARD_FAB2(SCH_1):PAGE75
  U2D1 EA76 VSS<39> SKX_EXT_B_BGA1-IC,TBD    I20 @BASEBOARD_FAB2_LIB.BASEBOARD_FAB2(SCH_1):PAGE75
  U2D1 EA70 VSS<40> SKX_EXT_B_BGA1-IC,TBD    I20 @BASEBOARD_FAB2_LIB.BASEBOARD_FAB2(SCH_1):PAGE75
  U2D1 EA64 VSS<41> SKX_EXT_B_BGA1-IC,TBD    I20 @BASEBOARD_FAB2_LIB.BASEBOARD_FAB2(SCH_1):PAGE75
  U2D1 EA42 VSS<42> SKX_EXT_B_BGA1-IC,TBD    I20 @BASEBOARD_FAB2_LIB.BASEBOARD_FAB2(SCH_1):PAGE75
  U2D1 EA22 VSS<43> SKX_EXT_B_BGA1-IC,TBD    I20 @BASEBOARD_FAB2_LIB.BASEBOARD_FAB2(SCH_1):PAGE75
  U2D1 EA20 VSS<44> SKX_EXT_B_BGA1-IC,TBD    I20 @BASEBOARD_FAB2_LIB.BASEBOARD_FAB2(SCH_1):PAGE75
  U2D1 EA16 VSS<45> SKX_EXT_B_BGA1-IC,TBD    I20 @BASEBOARD_FAB2_LIB.BASEBOARD_FAB2(SCH_1):PAGE75
  U2D1  J16 VSS<46> SKX_EXT_B_BGA1-IC,TBD    I20 @BASEBOARD_FAB2_LIB.BASEBOARD_FAB2(SCH_1):PAGE75
  U2D1  EA6 VSS<47> SKX_EXT_B_BGA1-IC,TBD    I20 @BASEBOARD_FAB2_LIB.BASEBOARD_FAB2(SCH_1):PAGE75
  U2D1 DY75 VSS<48> SKX_EXT_B_BGA1-IC,TBD    I20 @BASEBOARD_FAB2_LIB.BASEBOARD_FAB2(SCH_1):PAGE75
  U2D1 DY71 VSS<49> SKX_EXT_B_BGA1-IC,TBD    I20 @BASEBOARD_FAB2_LIB.BASEBOARD_FAB2(SCH_1):PAGE75
  U2D1 DY41 VSS<50> SKX_EXT_B_BGA1-IC,TBD    I20 @BASEBOARD_FAB2_LIB.BASEBOARD_FAB2(SCH_1):PAGE75
  U2D1 DY35 VSS<51> SKX_EXT_B_BGA1-IC,TBD    I20 @BASEBOARD_FAB2_LIB.BASEBOARD_FAB2(SCH_1):PAGE75
  U2D1 DY29 VSS<52> SKX_EXT_B_BGA1-IC,TBD    I20 @BASEBOARD_FAB2_LIB.BASEBOARD_FAB2(SCH_1):PAGE75
  U2D1 DY23 VSS<53> SKX_EXT_B_BGA1-IC,TBD    I20 @BASEBOARD_FAB2_LIB.BASEBOARD_FAB2(SCH_1):PAGE75
  U2D1 DY19 VSS<54> SKX_EXT_B_BGA1-IC,TBD    I20 @BASEBOARD_FAB2_LIB.BASEBOARD_FAB2(SCH_1):PAGE75
  U2D1  DY5 VSS<55> SKX_EXT_B_BGA1-IC,TBD    I20 @BASEBOARD_FAB2_LIB.BASEBOARD_FAB2(SCH_1):PAGE75
  U2D1 DW84 VSS<56> SKX_EXT_B_BGA1-IC,TBD    I20 @BASEBOARD_FAB2_LIB.BASEBOARD_FAB2(SCH_1):PAGE75
  U2D1 DW82 VSS<57> SKX_EXT_B_BGA1-IC,TBD    I20 @BASEBOARD_FAB2_LIB.BASEBOARD_FAB2(SCH_1):PAGE75
  U2D1  DW8 VSS<58> SKX_EXT_B_BGA1-IC,TBD    I20 @BASEBOARD_FAB2_LIB.BASEBOARD_FAB2(SCH_1):PAGE75
  U2D1 DW76 VSS<59> SKX_EXT_B_BGA1-IC,TBD    I20 @BASEBOARD_FAB2_LIB.BASEBOARD_FAB2(SCH_1):PAGE75
  U2D1 DW74 VSS<60> SKX_EXT_B_BGA1-IC,TBD    I20 @BASEBOARD_FAB2_LIB.BASEBOARD_FAB2(SCH_1):PAGE75
  U2D1 DW72 VSS<61> SKX_EXT_B_BGA1-IC,TBD    I20 @BASEBOARD_FAB2_LIB.BASEBOARD_FAB2(SCH_1):PAGE75
  U2D1 DW70 VSS<62> SKX_EXT_B_BGA1-IC,TBD    I20 @BASEBOARD_FAB2_LIB.BASEBOARD_FAB2(SCH_1):PAGE75
  U2D1 DW68 VSS<63> SKX_EXT_B_BGA1-IC,TBD    I20 @BASEBOARD_FAB2_LIB.BASEBOARD_FAB2(SCH_1):PAGE75
  U2D1 DW66 VSS<64> SKX_EXT_B_BGA1-IC,TBD    I20 @BASEBOARD_FAB2_LIB.BASEBOARD_FAB2(SCH_1):PAGE75
  U2D1 DW64 VSS<65> SKX_EXT_B_BGA1-IC,TBD    I20 @BASEBOARD_FAB2_LIB.BASEBOARD_FAB2(SCH_1):PAGE75
  U2D1 DW40 VSS<66> SKX_EXT_B_BGA1-IC,TBD    I20 @BASEBOARD_FAB2_LIB.BASEBOARD_FAB2(SCH_1):PAGE75
  U2D1 DW36 VSS<67> SKX_EXT_B_BGA1-IC,TBD    I20 @BASEBOARD_FAB2_LIB.BASEBOARD_FAB2(SCH_1):PAGE75
  U2D1 DW34 VSS<68> SKX_EXT_B_BGA1-IC,TBD    I20 @BASEBOARD_FAB2_LIB.BASEBOARD_FAB2(SCH_1):PAGE75
  U2D1 DW30 VSS<69> SKX_EXT_B_BGA1-IC,TBD    I20 @BASEBOARD_FAB2_LIB.BASEBOARD_FAB2(SCH_1):PAGE75
  U2D1 DW28 VSS<70> SKX_EXT_B_BGA1-IC,TBD    I20 @BASEBOARD_FAB2_LIB.BASEBOARD_FAB2(SCH_1):PAGE75
  U2D1 DW24 VSS<71> SKX_EXT_B_BGA1-IC,TBD    I20 @BASEBOARD_FAB2_LIB.BASEBOARD_FAB2(SCH_1):PAGE75
  U2D1 DW20 VSS<72> SKX_EXT_B_BGA1-IC,TBD    I20 @BASEBOARD_FAB2_LIB.BASEBOARD_FAB2(SCH_1):PAGE75
  U2D1 DW12 VSS<73> SKX_EXT_B_BGA1-IC,TBD    I20 @BASEBOARD_FAB2_LIB.BASEBOARD_FAB2(SCH_1):PAGE75
  U2D1 DV81 VSS<74> SKX_EXT_B_BGA1-IC,TBD    I20 @BASEBOARD_FAB2_LIB.BASEBOARD_FAB2(SCH_1):PAGE75
  U2D1 DV77 VSS<75> SKX_EXT_B_BGA1-IC,TBD    I20 @BASEBOARD_FAB2_LIB.BASEBOARD_FAB2(SCH_1):PAGE75
  U2D1 DV73 VSS<76> SKX_EXT_B_BGA1-IC,TBD    I20 @BASEBOARD_FAB2_LIB.BASEBOARD_FAB2(SCH_1):PAGE75
  U2D1 DV39 VSS<77> SKX_EXT_B_BGA1-IC,TBD    I20 @BASEBOARD_FAB2_LIB.BASEBOARD_FAB2(SCH_1):PAGE75
  U2D1 DV37 VSS<78> SKX_EXT_B_BGA1-IC,TBD    I20 @BASEBOARD_FAB2_LIB.BASEBOARD_FAB2(SCH_1):PAGE75
  U2D1 DV33 VSS<79> SKX_EXT_B_BGA1-IC,TBD    I20 @BASEBOARD_FAB2_LIB.BASEBOARD_FAB2(SCH_1):PAGE75
  U2D1 DV31 VSS<80> SKX_EXT_B_BGA1-IC,TBD    I20 @BASEBOARD_FAB2_LIB.BASEBOARD_FAB2(SCH_1):PAGE75
  U2D1 DV27 VSS<81> SKX_EXT_B_BGA1-IC,TBD    I20 @BASEBOARD_FAB2_LIB.BASEBOARD_FAB2(SCH_1):PAGE75
  U2D1 DV25 VSS<82> SKX_EXT_B_BGA1-IC,TBD    I20 @BASEBOARD_FAB2_LIB.BASEBOARD_FAB2(SCH_1):PAGE75
  U2D1 DV21 VSS<83> SKX_EXT_B_BGA1-IC,TBD    I20 @BASEBOARD_FAB2_LIB.BASEBOARD_FAB2(SCH_1):PAGE75
  U2D1 DU84 VSS<84> SKX_EXT_B_BGA1-IC,TBD    I20 @BASEBOARD_FAB2_LIB.BASEBOARD_FAB2(SCH_1):PAGE75
  U2D1 DU82 VSS<85> SKX_EXT_B_BGA1-IC,TBD    I20 @BASEBOARD_FAB2_LIB.BASEBOARD_FAB2(SCH_1):PAGE75
  U2D1 DU80 VSS<86> SKX_EXT_B_BGA1-IC,TBD    I20 @BASEBOARD_FAB2_LIB.BASEBOARD_FAB2(SCH_1):PAGE75
  U2D1 DU78 VSS<87> SKX_EXT_B_BGA1-IC,TBD    I20 @BASEBOARD_FAB2_LIB.BASEBOARD_FAB2(SCH_1):PAGE75
  U2D1 DU72 VSS<88> SKX_EXT_B_BGA1-IC,TBD    I20 @BASEBOARD_FAB2_LIB.BASEBOARD_FAB2(SCH_1):PAGE75
  U2D1 DU70 VSS<89> SKX_EXT_B_BGA1-IC,TBD    I20 @BASEBOARD_FAB2_LIB.BASEBOARD_FAB2(SCH_1):PAGE75
  U2D1 DU38 VSS<90> SKX_EXT_B_BGA1-IC,TBD    I20 @BASEBOARD_FAB2_LIB.BASEBOARD_FAB2(SCH_1):PAGE75
  U2D1 DU32 VSS<91> SKX_EXT_B_BGA1-IC,TBD    I20 @BASEBOARD_FAB2_LIB.BASEBOARD_FAB2(SCH_1):PAGE75
  U2D1 DU26 VSS<92> SKX_EXT_B_BGA1-IC,TBD    I20 @BASEBOARD_FAB2_LIB.BASEBOARD_FAB2(SCH_1):PAGE75
  U2D1 DU22 VSS<93> SKX_EXT_B_BGA1-IC,TBD    I20 @BASEBOARD_FAB2_LIB.BASEBOARD_FAB2(SCH_1):PAGE75
  U2D1 CN14 VSS<94> SKX_EXT_B_BGA1-IC,TBD    I20 @BASEBOARD_FAB2_LIB.BASEBOARD_FAB2(SCH_1):PAGE75
  U2D1 DU14 VSS<95> SKX_EXT_B_BGA1-IC,TBD    I20 @BASEBOARD_FAB2_LIB.BASEBOARD_FAB2(SCH_1):PAGE75
  U2D1 DU10 VSS<96> SKX_EXT_B_BGA1-IC,TBD    I20 @BASEBOARD_FAB2_LIB.BASEBOARD_FAB2(SCH_1):PAGE75
  U2D1 DT85 VSS<97> SKX_EXT_B_BGA1-IC,TBD    I20 @BASEBOARD_FAB2_LIB.BASEBOARD_FAB2(SCH_1):PAGE75
  U2D1 DT83 VSS<98> SKX_EXT_B_BGA1-IC,TBD    I20 @BASEBOARD_FAB2_LIB.BASEBOARD_FAB2(SCH_1):PAGE75
  U2D1 DT79 VSS<99> SKX_EXT_B_BGA1-IC,TBD    I20 @BASEBOARD_FAB2_LIB.BASEBOARD_FAB2(SCH_1):PAGE75
  U2D1 DT69 VSS<100> SKX_EXT_B_BGA1-IC,TBD    I20 @BASEBOARD_FAB2_LIB.BASEBOARD_FAB2(SCH_1):PAGE75
  U2D1 DT65 VSS<101> SKX_EXT_B_BGA1-IC,TBD    I20 @BASEBOARD_FAB2_LIB.BASEBOARD_FAB2(SCH_1):PAGE75
  U2D1 DH21 VSS<102> SKX_EXT_B_BGA1-IC,TBD    I20 @BASEBOARD_FAB2_LIB.BASEBOARD_FAB2(SCH_1):PAGE75
  U2D1 DT17 VSS<103> SKX_EXT_B_BGA1-IC,TBD    I20 @BASEBOARD_FAB2_LIB.BASEBOARD_FAB2(SCH_1):PAGE75
  U2D1  DT3 VSS<104> SKX_EXT_B_BGA1-IC,TBD    I20 @BASEBOARD_FAB2_LIB.BASEBOARD_FAB2(SCH_1):PAGE75
  U2D1 DR78 VSS<105> SKX_EXT_B_BGA1-IC,TBD    I20 @BASEBOARD_FAB2_LIB.BASEBOARD_FAB2(SCH_1):PAGE75
  U2D1 DR76 VSS<106> SKX_EXT_B_BGA1-IC,TBD    I20 @BASEBOARD_FAB2_LIB.BASEBOARD_FAB2(SCH_1):PAGE75
  U2D1 DR74 VSS<107> SKX_EXT_B_BGA1-IC,TBD    I20 @BASEBOARD_FAB2_LIB.BASEBOARD_FAB2(SCH_1):PAGE75
  U2D1 DR72 VSS<108> SKX_EXT_B_BGA1-IC,TBD    I20 @BASEBOARD_FAB2_LIB.BASEBOARD_FAB2(SCH_1):PAGE75
  U2D1 DR70 VSS<109> SKX_EXT_B_BGA1-IC,TBD    I20 @BASEBOARD_FAB2_LIB.BASEBOARD_FAB2(SCH_1):PAGE75
  U2D1 DR68 VSS<110> SKX_EXT_B_BGA1-IC,TBD    I20 @BASEBOARD_FAB2_LIB.BASEBOARD_FAB2(SCH_1):PAGE75
  U2D1 DR66 VSS<111> SKX_EXT_B_BGA1-IC,TBD    I20 @BASEBOARD_FAB2_LIB.BASEBOARD_FAB2(SCH_1):PAGE75
  U2D1 DR42 VSS<112> SKX_EXT_B_BGA1-IC,TBD    I20 @BASEBOARD_FAB2_LIB.BASEBOARD_FAB2(SCH_1):PAGE75
  U2D1 DR40 VSS<113> SKX_EXT_B_BGA1-IC,TBD    I20 @BASEBOARD_FAB2_LIB.BASEBOARD_FAB2(SCH_1):PAGE75
  U2D1 DR38 VSS<114> SKX_EXT_B_BGA1-IC,TBD    I20 @BASEBOARD_FAB2_LIB.BASEBOARD_FAB2(SCH_1):PAGE75
  U2D1 DR36 VSS<115> SKX_EXT_B_BGA1-IC,TBD    I20 @BASEBOARD_FAB2_LIB.BASEBOARD_FAB2(SCH_1):PAGE75
  U2D1 DR34 VSS<116> SKX_EXT_B_BGA1-IC,TBD    I20 @BASEBOARD_FAB2_LIB.BASEBOARD_FAB2(SCH_1):PAGE75
  U2D1 DR32 VSS<117> SKX_EXT_B_BGA1-IC,TBD    I20 @BASEBOARD_FAB2_LIB.BASEBOARD_FAB2(SCH_1):PAGE75
  U2D1 DR30 VSS<118> SKX_EXT_B_BGA1-IC,TBD    I20 @BASEBOARD_FAB2_LIB.BASEBOARD_FAB2(SCH_1):PAGE75
  U2D1 DR28 VSS<119> SKX_EXT_B_BGA1-IC,TBD    I20 @BASEBOARD_FAB2_LIB.BASEBOARD_FAB2(SCH_1):PAGE75
  U2D1 DR26 VSS<120> SKX_EXT_B_BGA1-IC,TBD    I20 @BASEBOARD_FAB2_LIB.BASEBOARD_FAB2(SCH_1):PAGE75
  U2D1 DR24 VSS<121> SKX_EXT_B_BGA1-IC,TBD    I20 @BASEBOARD_FAB2_LIB.BASEBOARD_FAB2(SCH_1):PAGE75
  U2D1 DR22 VSS<122> SKX_EXT_B_BGA1-IC,TBD    I20 @BASEBOARD_FAB2_LIB.BASEBOARD_FAB2(SCH_1):PAGE75
  U2D1 DR20 VSS<123> SKX_EXT_B_BGA1-IC,TBD    I20 @BASEBOARD_FAB2_LIB.BASEBOARD_FAB2(SCH_1):PAGE75
  U2D1 CL22 VSS<124> SKX_EXT_B_BGA1-IC,TBD    I20 @BASEBOARD_FAB2_LIB.BASEBOARD_FAB2(SCH_1):PAGE75
  U2D1 CA20 VSS<125> SKX_EXT_B_BGA1-IC,TBD    I20 @BASEBOARD_FAB2_LIB.BASEBOARD_FAB2(SCH_1):PAGE75
  U2D1  DR6 VSS<126> SKX_EXT_B_BGA1-IC,TBD    I20 @BASEBOARD_FAB2_LIB.BASEBOARD_FAB2(SCH_1):PAGE75
  U2D1 BR26 VSS<127> SKX_EXT_B_BGA1-IC,TBD    I20 @BASEBOARD_FAB2_LIB.BASEBOARD_FAB2(SCH_1):PAGE75
  U2D1 DP83 VSS<128> SKX_EXT_B_BGA1-IC,TBD    I20 @BASEBOARD_FAB2_LIB.BASEBOARD_FAB2(SCH_1):PAGE75
  U2D1 DP81 VSS<129> SKX_EXT_B_BGA1-IC,TBD    I20 @BASEBOARD_FAB2_LIB.BASEBOARD_FAB2(SCH_1):PAGE75
  U2D1 DP71 VSS<130> SKX_EXT_B_BGA1-IC,TBD    I20 @BASEBOARD_FAB2_LIB.BASEBOARD_FAB2(SCH_1):PAGE75
  U2D1 DP69 VSS<131> SKX_EXT_B_BGA1-IC,TBD    I20 @BASEBOARD_FAB2_LIB.BASEBOARD_FAB2(SCH_1):PAGE75
  U2D1 DP67 VSS<132> SKX_EXT_B_BGA1-IC,TBD    I20 @BASEBOARD_FAB2_LIB.BASEBOARD_FAB2(SCH_1):PAGE75
  U2D1 DN78 VSS<133> SKX_EXT_B_BGA1-IC,TBD    I20 @BASEBOARD_FAB2_LIB.BASEBOARD_FAB2(SCH_1):PAGE75
 C3D21    2      B CAP_A_0603V-22.0UF,4V,20%,X6S,A     I1 @BASEBOARD_FAB2_LIB.BASEBOARD_FAB2(SCH_1):PAGE76
  C3D5    2      B CAP_A_0603V-22.0UF,4V,20%,X6S,A     I3 @BASEBOARD_FAB2_LIB.BASEBOARD_FAB2(SCH_1):PAGE76
 C3D12    2      B CAP_A_0603V-22.0UF,4V,20%,X6S,A     I4 @BASEBOARD_FAB2_LIB.BASEBOARD_FAB2(SCH_1):PAGE76
  C3D4    2      B CAP_A_0603V-22.0UF,4V,20%,X6S,A     I5 @BASEBOARD_FAB2_LIB.BASEBOARD_FAB2(SCH_1):PAGE76
 C3D11    2      B CAP_A_0603V-22.0UF,4V,20%,X6S,A     I7 @BASEBOARD_FAB2_LIB.BASEBOARD_FAB2(SCH_1):PAGE76
 C3D13    2      B CAP_A_0603V-22.0UF,4V,20%,X6S,A     I8 @BASEBOARD_FAB2_LIB.BASEBOARD_FAB2(SCH_1):PAGE76
 C2D40    2      B CAP_A_0603V-22.0UF,4V,20%,X6S,A    I10 @BASEBOARD_FAB2_LIB.BASEBOARD_FAB2(SCH_1):PAGE76
  C3D9    2      B CAP_A_0603V-22.0UF,4V,20%,X6S,A    I15 @BASEBOARD_FAB2_LIB.BASEBOARD_FAB2(SCH_1):PAGE76
  C3D8    2      B CAP_A_0603V-22.0UF,4V,20%,X6S,A    I18 @BASEBOARD_FAB2_LIB.BASEBOARD_FAB2(SCH_1):PAGE76
 C7P17    2      B CAP_0805-47UF,4V,20%,X6S,C9533A    I29 @BASEBOARD_FAB2_LIB.BASEBOARD_FAB2(SCH_1):PAGE76
  C2D8    2      B CAP_0603LF-10UF,4V,20%,X6S,E15A    I33 @BASEBOARD_FAB2_LIB.BASEBOARD_FAB2(SCH_1):PAGE76
 C2D10    2      B CAP_0603LF-10UF,4V,20%,X6S,E15A    I37 @BASEBOARD_FAB2_LIB.BASEBOARD_FAB2(SCH_1):PAGE76
 C2D11    2      B CAP_0603LF-10UF,4V,20%,X6S,E15A    I42 @BASEBOARD_FAB2_LIB.BASEBOARD_FAB2(SCH_1):PAGE76
  C2D9    2      B CAP_0603LF-10UF,4V,20%,X6S,E15A    I43 @BASEBOARD_FAB2_LIB.BASEBOARD_FAB2(SCH_1):PAGE76
 C7P18    2      B CAP_0805-47UF,4V,20%,X6S,C9533A    I51 @BASEBOARD_FAB2_LIB.BASEBOARD_FAB2(SCH_1):PAGE76
  C7P3    2      B CAP_0805-47UF,4V,20%,X6S,C9533A    I52 @BASEBOARD_FAB2_LIB.BASEBOARD_FAB2(SCH_1):PAGE76
 C2D12    2      B CAP_A_0603V-22.0UF,4V,20%,X6S,A    I59 @BASEBOARD_FAB2_LIB.BASEBOARD_FAB2(SCH_1):PAGE76
 C2D22    2      B CAP_A_0603V-22.0UF,4V,20%,X6S,A    I61 @BASEBOARD_FAB2_LIB.BASEBOARD_FAB2(SCH_1):PAGE76
 C2D31    2      B CAP_A_0603V-22.0UF,4V,20%,X6S,A    I63 @BASEBOARD_FAB2_LIB.BASEBOARD_FAB2(SCH_1):PAGE76
 C2D21    2      B CAP_A_0603V-22.0UF,4V,20%,X6S,A    I65 @BASEBOARD_FAB2_LIB.BASEBOARD_FAB2(SCH_1):PAGE76
 C2D27    2      B CAP_A_0603V-22.0UF,4V,20%,X6S,A    I66 @BASEBOARD_FAB2_LIB.BASEBOARD_FAB2(SCH_1):PAGE76
  C3D2    2      B CAP_A_0603V-22.0UF,4V,20%,X6S,A    I69 @BASEBOARD_FAB2_LIB.BASEBOARD_FAB2(SCH_1):PAGE76
 C2D36    2      B CAP_A_0603V-22.0UF,4V,20%,X6S,A    I70 @BASEBOARD_FAB2_LIB.BASEBOARD_FAB2(SCH_1):PAGE76
 C2D13    2      B CAP_A_0603V-22.0UF,4V,20%,X6S,A    I73 @BASEBOARD_FAB2_LIB.BASEBOARD_FAB2(SCH_1):PAGE76
 C2D19    2      B CAP_A_0603V-22.0UF,4V,20%,X6S,A    I75 @BASEBOARD_FAB2_LIB.BASEBOARD_FAB2(SCH_1):PAGE76
 C2D14    2      B CAP_A_0603V-22.0UF,4V,20%,X6S,A    I76 @BASEBOARD_FAB2_LIB.BASEBOARD_FAB2(SCH_1):PAGE76
 C2D20    2      B CAP_A_0603V-22.0UF,4V,20%,X6S,A    I79 @BASEBOARD_FAB2_LIB.BASEBOARD_FAB2(SCH_1):PAGE76
 C2D24    2      B CAP_A_0603V-22.0UF,4V,20%,X6S,A    I80 @BASEBOARD_FAB2_LIB.BASEBOARD_FAB2(SCH_1):PAGE76
 C2D25    2      B CAP_A_0603V-22.0UF,4V,20%,X6S,A    I82 @BASEBOARD_FAB2_LIB.BASEBOARD_FAB2(SCH_1):PAGE76
 C2D30    2      B CAP_A_0603V-22.0UF,4V,20%,X6S,A    I83 @BASEBOARD_FAB2_LIB.BASEBOARD_FAB2(SCH_1):PAGE76
 C2D33    2      B CAP_A_0603V-22.0UF,4V,20%,X6S,A    I85 @BASEBOARD_FAB2_LIB.BASEBOARD_FAB2(SCH_1):PAGE76
 C8P20    2      B CAP_0805-47UF,4V,20%,X6S,C9533A    I89 @BASEBOARD_FAB2_LIB.BASEBOARD_FAB2(SCH_1):PAGE76
 C2D32    2      B CAP_A_0603V-22.0UF,4V,20%,X6S,A    I90 @BASEBOARD_FAB2_LIB.BASEBOARD_FAB2(SCH_1):PAGE76
 C8P18    2      B CAP_0805-47UF,4V,20%,X6S,C9533A    I92 @BASEBOARD_FAB2_LIB.BASEBOARD_FAB2(SCH_1):PAGE76
 C8P19    2      B CAP_0805-47UF,4V,20%,X6S,C9533A   I103 @BASEBOARD_FAB2_LIB.BASEBOARD_FAB2(SCH_1):PAGE76
 C8P12    2      B CAP_0805-47UF,4V,20%,X6S,C9533A   I107 @BASEBOARD_FAB2_LIB.BASEBOARD_FAB2(SCH_1):PAGE76
 C2D26    2      B CAP_A_0603V-22.0UF,4V,20%,X6S,A   I108 @BASEBOARD_FAB2_LIB.BASEBOARD_FAB2(SCH_1):PAGE76
 C2D23    2      B CAP_A_0603V-22.0UF,4V,20%,X6S,A   I112 @BASEBOARD_FAB2_LIB.BASEBOARD_FAB2(SCH_1):PAGE76
 C2D17    2      B CAP_A_0603V-22.0UF,4V,20%,X6S,A   I114 @BASEBOARD_FAB2_LIB.BASEBOARD_FAB2(SCH_1):PAGE76
 C8P26    2      B CAP_0805-47UF,4V,20%,X6S,C9533A   I118 @BASEBOARD_FAB2_LIB.BASEBOARD_FAB2(SCH_1):PAGE76
 C2D37    2      B CAP_A_0603V-22.0UF,4V,20%,X6S,A   I119 @BASEBOARD_FAB2_LIB.BASEBOARD_FAB2(SCH_1):PAGE76
 C2D34    2      B CAP_A_0603V-22.0UF,4V,20%,X6S,A   I122 @BASEBOARD_FAB2_LIB.BASEBOARD_FAB2(SCH_1):PAGE76
 C2D16    2      B CAP_A_0603V-22.0UF,4V,20%,X6S,A   I124 @BASEBOARD_FAB2_LIB.BASEBOARD_FAB2(SCH_1):PAGE76
 C8P29    2      B CAP_0805-47UF,4V,20%,X6S,C9533A   I125 @BASEBOARD_FAB2_LIB.BASEBOARD_FAB2(SCH_1):PAGE76
 C8P10    2      B CAP_0805-47UF,4V,20%,X6S,C9533A   I127 @BASEBOARD_FAB2_LIB.BASEBOARD_FAB2(SCH_1):PAGE76
 C8P16    2      B CAP_0805-47UF,4V,20%,X6S,C9533A   I129 @BASEBOARD_FAB2_LIB.BASEBOARD_FAB2(SCH_1):PAGE76
 C8P13    2      B CAP_0805-47UF,4V,20%,X6S,C9533A   I132 @BASEBOARD_FAB2_LIB.BASEBOARD_FAB2(SCH_1):PAGE76
 C8P28    2      B CAP_0805-47UF,4V,20%,X6S,C9533A   I137 @BASEBOARD_FAB2_LIB.BASEBOARD_FAB2(SCH_1):PAGE76
 C8P11    2      B CAP_0805-47UF,4V,20%,X6S,C9533A   I139 @BASEBOARD_FAB2_LIB.BASEBOARD_FAB2(SCH_1):PAGE76
 C2D15    2      B CAP_A_0603V-22.0UF,4V,20%,X6S,A   I159 @BASEBOARD_FAB2_LIB.BASEBOARD_FAB2(SCH_1):PAGE76
 C2D38    2      B CAP_A_0603V-22.0UF,4V,20%,X6S,A   I160 @BASEBOARD_FAB2_LIB.BASEBOARD_FAB2(SCH_1):PAGE76
 C2D35    2      B CAP_A_0603V-22.0UF,4V,20%,X6S,A   I161 @BASEBOARD_FAB2_LIB.BASEBOARD_FAB2(SCH_1):PAGE76
  C3D7    2      B CAP_A_0603V-22.0UF,4V,20%,X6S,A   I164 @BASEBOARD_FAB2_LIB.BASEBOARD_FAB2(SCH_1):PAGE76
 C2D39    2      B CAP_A_0603V-22.0UF,4V,20%,X6S,A   I165 @BASEBOARD_FAB2_LIB.BASEBOARD_FAB2(SCH_1):PAGE76
 C3D17    2      B CAP_A_0603V-22.0UF,4V,20%,X6S,A   I166 @BASEBOARD_FAB2_LIB.BASEBOARD_FAB2(SCH_1):PAGE76
 C3D18    2      B CAP_A_0603V-22.0UF,4V,20%,X6S,A   I169 @BASEBOARD_FAB2_LIB.BASEBOARD_FAB2(SCH_1):PAGE76
  C3D6    2      B CAP_A_0603V-22.0UF,4V,20%,X6S,A   I170 @BASEBOARD_FAB2_LIB.BASEBOARD_FAB2(SCH_1):PAGE76
 C3D14    2      B CAP_A_0603V-22.0UF,4V,20%,X6S,A   I171 @BASEBOARD_FAB2_LIB.BASEBOARD_FAB2(SCH_1):PAGE76
 C3D23    2      B CAP_A_0603V-22.0UF,4V,20%,X6S,A   I172 @BASEBOARD_FAB2_LIB.BASEBOARD_FAB2(SCH_1):PAGE76
 C3D15    2      B CAP_A_0603V-22.0UF,4V,20%,X6S,A   I174 @BASEBOARD_FAB2_LIB.BASEBOARD_FAB2(SCH_1):PAGE76
 C3D24    2      B CAP_A_0603V-22.0UF,4V,20%,X6S,A   I175 @BASEBOARD_FAB2_LIB.BASEBOARD_FAB2(SCH_1):PAGE76
 C3D16    2      B CAP_A_0603V-22.0UF,4V,20%,X6S,A   I176 @BASEBOARD_FAB2_LIB.BASEBOARD_FAB2(SCH_1):PAGE76
 C7P12    2      B CAP_A_0603V-22.0UF,4V,20%,X6S,A   I179 @BASEBOARD_FAB2_LIB.BASEBOARD_FAB2(SCH_1):PAGE76
 C3D10    2      B CAP_A_0603V-22.0UF,4V,20%,X6S,A   I196 @BASEBOARD_FAB2_LIB.BASEBOARD_FAB2(SCH_1):PAGE76
 C2D18    2      B CAP_A_0603V-22.0UF,4V,20%,X6S,A   I197 @BASEBOARD_FAB2_LIB.BASEBOARD_FAB2(SCH_1):PAGE76
 C2D28    2      B CAP_A_0603V-22.0UF,4V,20%,X6S,A   I198 @BASEBOARD_FAB2_LIB.BASEBOARD_FAB2(SCH_1):PAGE76
 C2D29    2      B CAP_A_0603V-22.0UF,4V,20%,X6S,A   I199 @BASEBOARD_FAB2_LIB.BASEBOARD_FAB2(SCH_1):PAGE76
 C7P16    2      B CAP_A_0603V-22.0UF,4V,20%,X6S,A   I206 @BASEBOARD_FAB2_LIB.BASEBOARD_FAB2(SCH_1):PAGE76
 C3D20    2      B CAP_A_0603V-22.0UF,4V,20%,X6S,A   I207 @BASEBOARD_FAB2_LIB.BASEBOARD_FAB2(SCH_1):PAGE76
 C3D19    2      B CAP_A_0603V-22.0UF,4V,20%,X6S,A   I208 @BASEBOARD_FAB2_LIB.BASEBOARD_FAB2(SCH_1):PAGE76
 C7P19    2      B CAP_0805-47UF,4V,20%,X6S,C9533A   I215 @BASEBOARD_FAB2_LIB.BASEBOARD_FAB2(SCH_1):PAGE76
 C8P24    2      B CAP_0805-47UF,4V,20%,X6S,C9533A   I217 @BASEBOARD_FAB2_LIB.BASEBOARD_FAB2(SCH_1):PAGE76
  J1G1  283 VSS<0> SCONN288_H44441004_PIP-SCONN,HA    I43 @BASEBOARD_FAB2_LIB.BASEBOARD_FAB2(SCH_1):PAGE77
  J1G1  281 VSS<1> SCONN288_H44441004_PIP-SCONN,HA    I43 @BASEBOARD_FAB2_LIB.BASEBOARD_FAB2(SCH_1):PAGE77
  J1G1  279 VSS<2> SCONN288_H44441004_PIP-SCONN,HA    I43 @BASEBOARD_FAB2_LIB.BASEBOARD_FAB2(SCH_1):PAGE77
  J1G1  276 VSS<3> SCONN288_H44441004_PIP-SCONN,HA    I43 @BASEBOARD_FAB2_LIB.BASEBOARD_FAB2(SCH_1):PAGE77
  J1G1  274 VSS<4> SCONN288_H44441004_PIP-SCONN,HA    I43 @BASEBOARD_FAB2_LIB.BASEBOARD_FAB2(SCH_1):PAGE77
  J1G1  272 VSS<5> SCONN288_H44441004_PIP-SCONN,HA    I43 @BASEBOARD_FAB2_LIB.BASEBOARD_FAB2(SCH_1):PAGE77
  J1G1  270 VSS<6> SCONN288_H44441004_PIP-SCONN,HA    I43 @BASEBOARD_FAB2_LIB.BASEBOARD_FAB2(SCH_1):PAGE77
  J1G1  268 VSS<7> SCONN288_H44441004_PIP-SCONN,HA    I43 @BASEBOARD_FAB2_LIB.BASEBOARD_FAB2(SCH_1):PAGE77
  J1G1  265 VSS<8> SCONN288_H44441004_PIP-SCONN,HA    I43 @BASEBOARD_FAB2_LIB.BASEBOARD_FAB2(SCH_1):PAGE77
  J1G1  263 VSS<9> SCONN288_H44441004_PIP-SCONN,HA    I43 @BASEBOARD_FAB2_LIB.BASEBOARD_FAB2(SCH_1):PAGE77
  J1G1  261 VSS<10> SCONN288_H44441004_PIP-SCONN,HA    I43 @BASEBOARD_FAB2_LIB.BASEBOARD_FAB2(SCH_1):PAGE77
  J1G1  259 VSS<11> SCONN288_H44441004_PIP-SCONN,HA    I43 @BASEBOARD_FAB2_LIB.BASEBOARD_FAB2(SCH_1):PAGE77
  J1G1  257 VSS<12> SCONN288_H44441004_PIP-SCONN,HA    I43 @BASEBOARD_FAB2_LIB.BASEBOARD_FAB2(SCH_1):PAGE77
  J1G1  254 VSS<13> SCONN288_H44441004_PIP-SCONN,HA    I43 @BASEBOARD_FAB2_LIB.BASEBOARD_FAB2(SCH_1):PAGE77
  J1G1  252 VSS<14> SCONN288_H44441004_PIP-SCONN,HA    I43 @BASEBOARD_FAB2_LIB.BASEBOARD_FAB2(SCH_1):PAGE77
  J1G1  250 VSS<15> SCONN288_H44441004_PIP-SCONN,HA    I43 @BASEBOARD_FAB2_LIB.BASEBOARD_FAB2(SCH_1):PAGE77
  J1G1  248 VSS<16> SCONN288_H44441004_PIP-SCONN,HA    I43 @BASEBOARD_FAB2_LIB.BASEBOARD_FAB2(SCH_1):PAGE77
  J1G1  246 VSS<17> SCONN288_H44441004_PIP-SCONN,HA    I43 @BASEBOARD_FAB2_LIB.BASEBOARD_FAB2(SCH_1):PAGE77
  J1G1  243 VSS<18> SCONN288_H44441004_PIP-SCONN,HA    I43 @BASEBOARD_FAB2_LIB.BASEBOARD_FAB2(SCH_1):PAGE77
  J1G1  241 VSS<19> SCONN288_H44441004_PIP-SCONN,HA    I43 @BASEBOARD_FAB2_LIB.BASEBOARD_FAB2(SCH_1):PAGE77
  J1G1  239 VSS<20> SCONN288_H44441004_PIP-SCONN,HA    I43 @BASEBOARD_FAB2_LIB.BASEBOARD_FAB2(SCH_1):PAGE77
  J1G1  202 VSS<21> SCONN288_H44441004_PIP-SCONN,HA    I43 @BASEBOARD_FAB2_LIB.BASEBOARD_FAB2(SCH_1):PAGE77
  J1G1  200 VSS<22> SCONN288_H44441004_PIP-SCONN,HA    I43 @BASEBOARD_FAB2_LIB.BASEBOARD_FAB2(SCH_1):PAGE77
  J1G1  198 VSS<23> SCONN288_H44441004_PIP-SCONN,HA    I43 @BASEBOARD_FAB2_LIB.BASEBOARD_FAB2(SCH_1):PAGE77
  J1G1  195 VSS<24> SCONN288_H44441004_PIP-SCONN,HA    I43 @BASEBOARD_FAB2_LIB.BASEBOARD_FAB2(SCH_1):PAGE77
  J1G1  193 VSS<25> SCONN288_H44441004_PIP-SCONN,HA    I43 @BASEBOARD_FAB2_LIB.BASEBOARD_FAB2(SCH_1):PAGE77
  J1G1  191 VSS<26> SCONN288_H44441004_PIP-SCONN,HA    I43 @BASEBOARD_FAB2_LIB.BASEBOARD_FAB2(SCH_1):PAGE77
  J1G1  189 VSS<27> SCONN288_H44441004_PIP-SCONN,HA    I43 @BASEBOARD_FAB2_LIB.BASEBOARD_FAB2(SCH_1):PAGE77
  J1G1  187 VSS<28> SCONN288_H44441004_PIP-SCONN,HA    I43 @BASEBOARD_FAB2_LIB.BASEBOARD_FAB2(SCH_1):PAGE77
  J1G1  184 VSS<29> SCONN288_H44441004_PIP-SCONN,HA    I43 @BASEBOARD_FAB2_LIB.BASEBOARD_FAB2(SCH_1):PAGE77
  J1G1  182 VSS<30> SCONN288_H44441004_PIP-SCONN,HA    I43 @BASEBOARD_FAB2_LIB.BASEBOARD_FAB2(SCH_1):PAGE77
  J1G1  180 VSS<31> SCONN288_H44441004_PIP-SCONN,HA    I43 @BASEBOARD_FAB2_LIB.BASEBOARD_FAB2(SCH_1):PAGE77
  J1G1  178 VSS<32> SCONN288_H44441004_PIP-SCONN,HA    I43 @BASEBOARD_FAB2_LIB.BASEBOARD_FAB2(SCH_1):PAGE77
  J1G1  176 VSS<33> SCONN288_H44441004_PIP-SCONN,HA    I43 @BASEBOARD_FAB2_LIB.BASEBOARD_FAB2(SCH_1):PAGE77
  J1G1  173 VSS<34> SCONN288_H44441004_PIP-SCONN,HA    I43 @BASEBOARD_FAB2_LIB.BASEBOARD_FAB2(SCH_1):PAGE77
  J1G1  171 VSS<35> SCONN288_H44441004_PIP-SCONN,HA    I43 @BASEBOARD_FAB2_LIB.BASEBOARD_FAB2(SCH_1):PAGE77
  J1G1  169 VSS<36> SCONN288_H44441004_PIP-SCONN,HA    I43 @BASEBOARD_FAB2_LIB.BASEBOARD_FAB2(SCH_1):PAGE77
  J1G1  167 VSS<37> SCONN288_H44441004_PIP-SCONN,HA    I43 @BASEBOARD_FAB2_LIB.BASEBOARD_FAB2(SCH_1):PAGE77
  J1G1  165 VSS<38> SCONN288_H44441004_PIP-SCONN,HA    I43 @BASEBOARD_FAB2_LIB.BASEBOARD_FAB2(SCH_1):PAGE77
  J1G1  162 VSS<39> SCONN288_H44441004_PIP-SCONN,HA    I43 @BASEBOARD_FAB2_LIB.BASEBOARD_FAB2(SCH_1):PAGE77
  J1G1  160 VSS<40> SCONN288_H44441004_PIP-SCONN,HA    I43 @BASEBOARD_FAB2_LIB.BASEBOARD_FAB2(SCH_1):PAGE77
  J1G1  158 VSS<41> SCONN288_H44441004_PIP-SCONN,HA    I43 @BASEBOARD_FAB2_LIB.BASEBOARD_FAB2(SCH_1):PAGE77
  J1G1  156 VSS<42> SCONN288_H44441004_PIP-SCONN,HA    I43 @BASEBOARD_FAB2_LIB.BASEBOARD_FAB2(SCH_1):PAGE77
  J1G1  154 VSS<43> SCONN288_H44441004_PIP-SCONN,HA    I43 @BASEBOARD_FAB2_LIB.BASEBOARD_FAB2(SCH_1):PAGE77
  J1G1  151 VSS<44> SCONN288_H44441004_PIP-SCONN,HA    I43 @BASEBOARD_FAB2_LIB.BASEBOARD_FAB2(SCH_1):PAGE77
  J1G1  149 VSS<45> SCONN288_H44441004_PIP-SCONN,HA    I43 @BASEBOARD_FAB2_LIB.BASEBOARD_FAB2(SCH_1):PAGE77
  J1G1  147 VSS<46> SCONN288_H44441004_PIP-SCONN,HA    I43 @BASEBOARD_FAB2_LIB.BASEBOARD_FAB2(SCH_1):PAGE77
  J1G1  138 VSS<47> SCONN288_H44441004_PIP-SCONN,HA    I43 @BASEBOARD_FAB2_LIB.BASEBOARD_FAB2(SCH_1):PAGE77
  J1G1  136 VSS<48> SCONN288_H44441004_PIP-SCONN,HA    I43 @BASEBOARD_FAB2_LIB.BASEBOARD_FAB2(SCH_1):PAGE77
  J1G1  134 VSS<49> SCONN288_H44441004_PIP-SCONN,HA    I43 @BASEBOARD_FAB2_LIB.BASEBOARD_FAB2(SCH_1):PAGE77
  J1G1  131 VSS<50> SCONN288_H44441004_PIP-SCONN,HA    I43 @BASEBOARD_FAB2_LIB.BASEBOARD_FAB2(SCH_1):PAGE77
  J1G1  129 VSS<51> SCONN288_H44441004_PIP-SCONN,HA    I43 @BASEBOARD_FAB2_LIB.BASEBOARD_FAB2(SCH_1):PAGE77
  J1G1  127 VSS<52> SCONN288_H44441004_PIP-SCONN,HA    I43 @BASEBOARD_FAB2_LIB.BASEBOARD_FAB2(SCH_1):PAGE77
  J1G1  125 VSS<53> SCONN288_H44441004_PIP-SCONN,HA    I43 @BASEBOARD_FAB2_LIB.BASEBOARD_FAB2(SCH_1):PAGE77
  J1G1  123 VSS<54> SCONN288_H44441004_PIP-SCONN,HA    I43 @BASEBOARD_FAB2_LIB.BASEBOARD_FAB2(SCH_1):PAGE77
  J1G1  120 VSS<55> SCONN288_H44441004_PIP-SCONN,HA    I43 @BASEBOARD_FAB2_LIB.BASEBOARD_FAB2(SCH_1):PAGE77
  J1G1  118 VSS<56> SCONN288_H44441004_PIP-SCONN,HA    I43 @BASEBOARD_FAB2_LIB.BASEBOARD_FAB2(SCH_1):PAGE77
  J1G1  116 VSS<57> SCONN288_H44441004_PIP-SCONN,HA    I43 @BASEBOARD_FAB2_LIB.BASEBOARD_FAB2(SCH_1):PAGE77
  J1G1  114 VSS<58> SCONN288_H44441004_PIP-SCONN,HA    I43 @BASEBOARD_FAB2_LIB.BASEBOARD_FAB2(SCH_1):PAGE77
  J1G1  112 VSS<59> SCONN288_H44441004_PIP-SCONN,HA    I43 @BASEBOARD_FAB2_LIB.BASEBOARD_FAB2(SCH_1):PAGE77
  J1G1  109 VSS<60> SCONN288_H44441004_PIP-SCONN,HA    I43 @BASEBOARD_FAB2_LIB.BASEBOARD_FAB2(SCH_1):PAGE77
  J1G1  107 VSS<61> SCONN288_H44441004_PIP-SCONN,HA    I43 @BASEBOARD_FAB2_LIB.BASEBOARD_FAB2(SCH_1):PAGE77
  J1G1  105 VSS<62> SCONN288_H44441004_PIP-SCONN,HA    I43 @BASEBOARD_FAB2_LIB.BASEBOARD_FAB2(SCH_1):PAGE77
  J1G1  103 VSS<63> SCONN288_H44441004_PIP-SCONN,HA    I43 @BASEBOARD_FAB2_LIB.BASEBOARD_FAB2(SCH_1):PAGE77
  J1G1  101 VSS<64> SCONN288_H44441004_PIP-SCONN,HA    I43 @BASEBOARD_FAB2_LIB.BASEBOARD_FAB2(SCH_1):PAGE77
  J1G1   98 VSS<65> SCONN288_H44441004_PIP-SCONN,HA    I43 @BASEBOARD_FAB2_LIB.BASEBOARD_FAB2(SCH_1):PAGE77
  J1G1   96 VSS<66> SCONN288_H44441004_PIP-SCONN,HA    I43 @BASEBOARD_FAB2_LIB.BASEBOARD_FAB2(SCH_1):PAGE77
  J1G1   94 VSS<67> SCONN288_H44441004_PIP-SCONN,HA    I43 @BASEBOARD_FAB2_LIB.BASEBOARD_FAB2(SCH_1):PAGE77
  J1G1   57 VSS<68> SCONN288_H44441004_PIP-SCONN,HA    I43 @BASEBOARD_FAB2_LIB.BASEBOARD_FAB2(SCH_1):PAGE77
  J1G1   55 VSS<69> SCONN288_H44441004_PIP-SCONN,HA    I43 @BASEBOARD_FAB2_LIB.BASEBOARD_FAB2(SCH_1):PAGE77
  J1G1   53 VSS<70> SCONN288_H44441004_PIP-SCONN,HA    I43 @BASEBOARD_FAB2_LIB.BASEBOARD_FAB2(SCH_1):PAGE77
  J1G1   50 VSS<71> SCONN288_H44441004_PIP-SCONN,HA    I43 @BASEBOARD_FAB2_LIB.BASEBOARD_FAB2(SCH_1):PAGE77
  J1G1   48 VSS<72> SCONN288_H44441004_PIP-SCONN,HA    I43 @BASEBOARD_FAB2_LIB.BASEBOARD_FAB2(SCH_1):PAGE77
  J1G1   46 VSS<73> SCONN288_H44441004_PIP-SCONN,HA    I43 @BASEBOARD_FAB2_LIB.BASEBOARD_FAB2(SCH_1):PAGE77
  J1G1   44 VSS<74> SCONN288_H44441004_PIP-SCONN,HA    I43 @BASEBOARD_FAB2_LIB.BASEBOARD_FAB2(SCH_1):PAGE77
  J1G1   42 VSS<75> SCONN288_H44441004_PIP-SCONN,HA    I43 @BASEBOARD_FAB2_LIB.BASEBOARD_FAB2(SCH_1):PAGE77
  J1G1   39 VSS<76> SCONN288_H44441004_PIP-SCONN,HA    I43 @BASEBOARD_FAB2_LIB.BASEBOARD_FAB2(SCH_1):PAGE77
  J1G1   37 VSS<77> SCONN288_H44441004_PIP-SCONN,HA    I43 @BASEBOARD_FAB2_LIB.BASEBOARD_FAB2(SCH_1):PAGE77
  J1G1   35 VSS<78> SCONN288_H44441004_PIP-SCONN,HA    I43 @BASEBOARD_FAB2_LIB.BASEBOARD_FAB2(SCH_1):PAGE77
  J1G1   33 VSS<79> SCONN288_H44441004_PIP-SCONN,HA    I43 @BASEBOARD_FAB2_LIB.BASEBOARD_FAB2(SCH_1):PAGE77
  J1G1   31 VSS<80> SCONN288_H44441004_PIP-SCONN,HA    I43 @BASEBOARD_FAB2_LIB.BASEBOARD_FAB2(SCH_1):PAGE77
  J1G1   28 VSS<81> SCONN288_H44441004_PIP-SCONN,HA    I43 @BASEBOARD_FAB2_LIB.BASEBOARD_FAB2(SCH_1):PAGE77
  J1G1   26 VSS<82> SCONN288_H44441004_PIP-SCONN,HA    I43 @BASEBOARD_FAB2_LIB.BASEBOARD_FAB2(SCH_1):PAGE77
  J1G1   24 VSS<83> SCONN288_H44441004_PIP-SCONN,HA    I43 @BASEBOARD_FAB2_LIB.BASEBOARD_FAB2(SCH_1):PAGE77
  J1G1   22 VSS<84> SCONN288_H44441004_PIP-SCONN,HA    I43 @BASEBOARD_FAB2_LIB.BASEBOARD_FAB2(SCH_1):PAGE77
  J1G1   20 VSS<85> SCONN288_H44441004_PIP-SCONN,HA    I43 @BASEBOARD_FAB2_LIB.BASEBOARD_FAB2(SCH_1):PAGE77
  J1G1   17 VSS<86> SCONN288_H44441004_PIP-SCONN,HA    I43 @BASEBOARD_FAB2_LIB.BASEBOARD_FAB2(SCH_1):PAGE77
  J1G1   15 VSS<87> SCONN288_H44441004_PIP-SCONN,HA    I43 @BASEBOARD_FAB2_LIB.BASEBOARD_FAB2(SCH_1):PAGE77
  J1G1   13 VSS<88> SCONN288_H44441004_PIP-SCONN,HA    I43 @BASEBOARD_FAB2_LIB.BASEBOARD_FAB2(SCH_1):PAGE77
  J1G1   11 VSS<89> SCONN288_H44441004_PIP-SCONN,HA    I43 @BASEBOARD_FAB2_LIB.BASEBOARD_FAB2(SCH_1):PAGE77
  J1G1    9 VSS<90> SCONN288_H44441004_PIP-SCONN,HA    I43 @BASEBOARD_FAB2_LIB.BASEBOARD_FAB2(SCH_1):PAGE77
  J1G1    6 VSS<91> SCONN288_H44441004_PIP-SCONN,HA    I43 @BASEBOARD_FAB2_LIB.BASEBOARD_FAB2(SCH_1):PAGE77
  J1G1    4 VSS<92> SCONN288_H44441004_PIP-SCONN,HA    I43 @BASEBOARD_FAB2_LIB.BASEBOARD_FAB2(SCH_1):PAGE77
  J1G1    2 VSS<93> SCONN288_H44441004_PIP-SCONN,HA    I43 @BASEBOARD_FAB2_LIB.BASEBOARD_FAB2(SCH_1):PAGE77
  J1G1  139  SA<0> SCONN288_H44441004_PIP-SCONN,HA   I111 @BASEBOARD_FAB2_LIB.BASEBOARD_FAB2(SCH_1):PAGE77
  J1G1  140  SA<1> SCONN288_H44441004_PIP-SCONN,HA   I111 @BASEBOARD_FAB2_LIB.BASEBOARD_FAB2(SCH_1):PAGE77
  J1G1  238  SA<2> SCONN288_H44441004_PIP-SCONN,HA   I111 @BASEBOARD_FAB2_LIB.BASEBOARD_FAB2(SCH_1):PAGE77
 C1F22    2      B CAP_A_0402V-0.01UF,25V,10%,X7RA   I181 @BASEBOARD_FAB2_LIB.BASEBOARD_FAB2(SCH_1):PAGE77
  C9T7    2      B CAP_A_0402V-0.01UF,25V,10%,X7RA     I2 @BASEBOARD_FAB2_LIB.BASEBOARD_FAB2(SCH_1):PAGE78
  J9T1  140  SA<1> SCONN288_H44441003_PIP-SCONN,HA    I13 @BASEBOARD_FAB2_LIB.BASEBOARD_FAB2(SCH_1):PAGE78
  J9T1  238  SA<2> SCONN288_H44441003_PIP-SCONN,HA    I13 @BASEBOARD_FAB2_LIB.BASEBOARD_FAB2(SCH_1):PAGE78
  J9T1  283 VSS<0> SCONN288_H44441003_PIP-SCONN,HA   I144 @BASEBOARD_FAB2_LIB.BASEBOARD_FAB2(SCH_1):PAGE78
  J9T1  281 VSS<1> SCONN288_H44441003_PIP-SCONN,HA   I144 @BASEBOARD_FAB2_LIB.BASEBOARD_FAB2(SCH_1):PAGE78
  J9T1  279 VSS<2> SCONN288_H44441003_PIP-SCONN,HA   I144 @BASEBOARD_FAB2_LIB.BASEBOARD_FAB2(SCH_1):PAGE78
  J9T1  276 VSS<3> SCONN288_H44441003_PIP-SCONN,HA   I144 @BASEBOARD_FAB2_LIB.BASEBOARD_FAB2(SCH_1):PAGE78
  J9T1  274 VSS<4> SCONN288_H44441003_PIP-SCONN,HA   I144 @BASEBOARD_FAB2_LIB.BASEBOARD_FAB2(SCH_1):PAGE78
  J9T1  272 VSS<5> SCONN288_H44441003_PIP-SCONN,HA   I144 @BASEBOARD_FAB2_LIB.BASEBOARD_FAB2(SCH_1):PAGE78
  J9T1  270 VSS<6> SCONN288_H44441003_PIP-SCONN,HA   I144 @BASEBOARD_FAB2_LIB.BASEBOARD_FAB2(SCH_1):PAGE78
  J9T1  268 VSS<7> SCONN288_H44441003_PIP-SCONN,HA   I144 @BASEBOARD_FAB2_LIB.BASEBOARD_FAB2(SCH_1):PAGE78
  J9T1  265 VSS<8> SCONN288_H44441003_PIP-SCONN,HA   I144 @BASEBOARD_FAB2_LIB.BASEBOARD_FAB2(SCH_1):PAGE78
  J9T1  263 VSS<9> SCONN288_H44441003_PIP-SCONN,HA   I144 @BASEBOARD_FAB2_LIB.BASEBOARD_FAB2(SCH_1):PAGE78
  J9T1  261 VSS<10> SCONN288_H44441003_PIP-SCONN,HA   I144 @BASEBOARD_FAB2_LIB.BASEBOARD_FAB2(SCH_1):PAGE78
  J9T1  259 VSS<11> SCONN288_H44441003_PIP-SCONN,HA   I144 @BASEBOARD_FAB2_LIB.BASEBOARD_FAB2(SCH_1):PAGE78
  J9T1  257 VSS<12> SCONN288_H44441003_PIP-SCONN,HA   I144 @BASEBOARD_FAB2_LIB.BASEBOARD_FAB2(SCH_1):PAGE78
  J9T1  254 VSS<13> SCONN288_H44441003_PIP-SCONN,HA   I144 @BASEBOARD_FAB2_LIB.BASEBOARD_FAB2(SCH_1):PAGE78
  J9T1  252 VSS<14> SCONN288_H44441003_PIP-SCONN,HA   I144 @BASEBOARD_FAB2_LIB.BASEBOARD_FAB2(SCH_1):PAGE78
  J9T1  250 VSS<15> SCONN288_H44441003_PIP-SCONN,HA   I144 @BASEBOARD_FAB2_LIB.BASEBOARD_FAB2(SCH_1):PAGE78
  J9T1  248 VSS<16> SCONN288_H44441003_PIP-SCONN,HA   I144 @BASEBOARD_FAB2_LIB.BASEBOARD_FAB2(SCH_1):PAGE78
  J9T1  246 VSS<17> SCONN288_H44441003_PIP-SCONN,HA   I144 @BASEBOARD_FAB2_LIB.BASEBOARD_FAB2(SCH_1):PAGE78
  J9T1  243 VSS<18> SCONN288_H44441003_PIP-SCONN,HA   I144 @BASEBOARD_FAB2_LIB.BASEBOARD_FAB2(SCH_1):PAGE78
  J9T1  241 VSS<19> SCONN288_H44441003_PIP-SCONN,HA   I144 @BASEBOARD_FAB2_LIB.BASEBOARD_FAB2(SCH_1):PAGE78
  J9T1  239 VSS<20> SCONN288_H44441003_PIP-SCONN,HA   I144 @BASEBOARD_FAB2_LIB.BASEBOARD_FAB2(SCH_1):PAGE78
  J9T1  202 VSS<21> SCONN288_H44441003_PIP-SCONN,HA   I144 @BASEBOARD_FAB2_LIB.BASEBOARD_FAB2(SCH_1):PAGE78
  J9T1  200 VSS<22> SCONN288_H44441003_PIP-SCONN,HA   I144 @BASEBOARD_FAB2_LIB.BASEBOARD_FAB2(SCH_1):PAGE78
  J9T1  198 VSS<23> SCONN288_H44441003_PIP-SCONN,HA   I144 @BASEBOARD_FAB2_LIB.BASEBOARD_FAB2(SCH_1):PAGE78
  J9T1  195 VSS<24> SCONN288_H44441003_PIP-SCONN,HA   I144 @BASEBOARD_FAB2_LIB.BASEBOARD_FAB2(SCH_1):PAGE78
  J9T1  193 VSS<25> SCONN288_H44441003_PIP-SCONN,HA   I144 @BASEBOARD_FAB2_LIB.BASEBOARD_FAB2(SCH_1):PAGE78
  J9T1  191 VSS<26> SCONN288_H44441003_PIP-SCONN,HA   I144 @BASEBOARD_FAB2_LIB.BASEBOARD_FAB2(SCH_1):PAGE78
  J9T1  189 VSS<27> SCONN288_H44441003_PIP-SCONN,HA   I144 @BASEBOARD_FAB2_LIB.BASEBOARD_FAB2(SCH_1):PAGE78
  J9T1  187 VSS<28> SCONN288_H44441003_PIP-SCONN,HA   I144 @BASEBOARD_FAB2_LIB.BASEBOARD_FAB2(SCH_1):PAGE78
  J9T1  184 VSS<29> SCONN288_H44441003_PIP-SCONN,HA   I144 @BASEBOARD_FAB2_LIB.BASEBOARD_FAB2(SCH_1):PAGE78
  J9T1  182 VSS<30> SCONN288_H44441003_PIP-SCONN,HA   I144 @BASEBOARD_FAB2_LIB.BASEBOARD_FAB2(SCH_1):PAGE78
  J9T1  180 VSS<31> SCONN288_H44441003_PIP-SCONN,HA   I144 @BASEBOARD_FAB2_LIB.BASEBOARD_FAB2(SCH_1):PAGE78
  J9T1  178 VSS<32> SCONN288_H44441003_PIP-SCONN,HA   I144 @BASEBOARD_FAB2_LIB.BASEBOARD_FAB2(SCH_1):PAGE78
  J9T1  176 VSS<33> SCONN288_H44441003_PIP-SCONN,HA   I144 @BASEBOARD_FAB2_LIB.BASEBOARD_FAB2(SCH_1):PAGE78
  J9T1  173 VSS<34> SCONN288_H44441003_PIP-SCONN,HA   I144 @BASEBOARD_FAB2_LIB.BASEBOARD_FAB2(SCH_1):PAGE78
  J9T1  171 VSS<35> SCONN288_H44441003_PIP-SCONN,HA   I144 @BASEBOARD_FAB2_LIB.BASEBOARD_FAB2(SCH_1):PAGE78
  J9T1  169 VSS<36> SCONN288_H44441003_PIP-SCONN,HA   I144 @BASEBOARD_FAB2_LIB.BASEBOARD_FAB2(SCH_1):PAGE78
  J9T1  167 VSS<37> SCONN288_H44441003_PIP-SCONN,HA   I144 @BASEBOARD_FAB2_LIB.BASEBOARD_FAB2(SCH_1):PAGE78
  J9T1  165 VSS<38> SCONN288_H44441003_PIP-SCONN,HA   I144 @BASEBOARD_FAB2_LIB.BASEBOARD_FAB2(SCH_1):PAGE78
  J9T1  162 VSS<39> SCONN288_H44441003_PIP-SCONN,HA   I144 @BASEBOARD_FAB2_LIB.BASEBOARD_FAB2(SCH_1):PAGE78
  J9T1  160 VSS<40> SCONN288_H44441003_PIP-SCONN,HA   I144 @BASEBOARD_FAB2_LIB.BASEBOARD_FAB2(SCH_1):PAGE78
  J9T1  158 VSS<41> SCONN288_H44441003_PIP-SCONN,HA   I144 @BASEBOARD_FAB2_LIB.BASEBOARD_FAB2(SCH_1):PAGE78
  J9T1  156 VSS<42> SCONN288_H44441003_PIP-SCONN,HA   I144 @BASEBOARD_FAB2_LIB.BASEBOARD_FAB2(SCH_1):PAGE78
  J9T1  154 VSS<43> SCONN288_H44441003_PIP-SCONN,HA   I144 @BASEBOARD_FAB2_LIB.BASEBOARD_FAB2(SCH_1):PAGE78
  J9T1  151 VSS<44> SCONN288_H44441003_PIP-SCONN,HA   I144 @BASEBOARD_FAB2_LIB.BASEBOARD_FAB2(SCH_1):PAGE78
  J9T1  149 VSS<45> SCONN288_H44441003_PIP-SCONN,HA   I144 @BASEBOARD_FAB2_LIB.BASEBOARD_FAB2(SCH_1):PAGE78
  J9T1  147 VSS<46> SCONN288_H44441003_PIP-SCONN,HA   I144 @BASEBOARD_FAB2_LIB.BASEBOARD_FAB2(SCH_1):PAGE78
  J9T1  138 VSS<47> SCONN288_H44441003_PIP-SCONN,HA   I144 @BASEBOARD_FAB2_LIB.BASEBOARD_FAB2(SCH_1):PAGE78
  J9T1  136 VSS<48> SCONN288_H44441003_PIP-SCONN,HA   I144 @BASEBOARD_FAB2_LIB.BASEBOARD_FAB2(SCH_1):PAGE78
  J9T1  134 VSS<49> SCONN288_H44441003_PIP-SCONN,HA   I144 @BASEBOARD_FAB2_LIB.BASEBOARD_FAB2(SCH_1):PAGE78
  J9T1  131 VSS<50> SCONN288_H44441003_PIP-SCONN,HA   I144 @BASEBOARD_FAB2_LIB.BASEBOARD_FAB2(SCH_1):PAGE78
  J9T1  129 VSS<51> SCONN288_H44441003_PIP-SCONN,HA   I144 @BASEBOARD_FAB2_LIB.BASEBOARD_FAB2(SCH_1):PAGE78
  J9T1  127 VSS<52> SCONN288_H44441003_PIP-SCONN,HA   I144 @BASEBOARD_FAB2_LIB.BASEBOARD_FAB2(SCH_1):PAGE78
  J9T1  125 VSS<53> SCONN288_H44441003_PIP-SCONN,HA   I144 @BASEBOARD_FAB2_LIB.BASEBOARD_FAB2(SCH_1):PAGE78
  J9T1  123 VSS<54> SCONN288_H44441003_PIP-SCONN,HA   I144 @BASEBOARD_FAB2_LIB.BASEBOARD_FAB2(SCH_1):PAGE78
  J9T1  120 VSS<55> SCONN288_H44441003_PIP-SCONN,HA   I144 @BASEBOARD_FAB2_LIB.BASEBOARD_FAB2(SCH_1):PAGE78
  J9T1  118 VSS<56> SCONN288_H44441003_PIP-SCONN,HA   I144 @BASEBOARD_FAB2_LIB.BASEBOARD_FAB2(SCH_1):PAGE78
  J9T1  116 VSS<57> SCONN288_H44441003_PIP-SCONN,HA   I144 @BASEBOARD_FAB2_LIB.BASEBOARD_FAB2(SCH_1):PAGE78
  J9T1  114 VSS<58> SCONN288_H44441003_PIP-SCONN,HA   I144 @BASEBOARD_FAB2_LIB.BASEBOARD_FAB2(SCH_1):PAGE78
  J9T1  112 VSS<59> SCONN288_H44441003_PIP-SCONN,HA   I144 @BASEBOARD_FAB2_LIB.BASEBOARD_FAB2(SCH_1):PAGE78
  J9T1  109 VSS<60> SCONN288_H44441003_PIP-SCONN,HA   I144 @BASEBOARD_FAB2_LIB.BASEBOARD_FAB2(SCH_1):PAGE78
  J9T1  107 VSS<61> SCONN288_H44441003_PIP-SCONN,HA   I144 @BASEBOARD_FAB2_LIB.BASEBOARD_FAB2(SCH_1):PAGE78
  J9T1  105 VSS<62> SCONN288_H44441003_PIP-SCONN,HA   I144 @BASEBOARD_FAB2_LIB.BASEBOARD_FAB2(SCH_1):PAGE78
  J9T1  103 VSS<63> SCONN288_H44441003_PIP-SCONN,HA   I144 @BASEBOARD_FAB2_LIB.BASEBOARD_FAB2(SCH_1):PAGE78
  J9T1  101 VSS<64> SCONN288_H44441003_PIP-SCONN,HA   I144 @BASEBOARD_FAB2_LIB.BASEBOARD_FAB2(SCH_1):PAGE78
  J9T1   98 VSS<65> SCONN288_H44441003_PIP-SCONN,HA   I144 @BASEBOARD_FAB2_LIB.BASEBOARD_FAB2(SCH_1):PAGE78
  J9T1   96 VSS<66> SCONN288_H44441003_PIP-SCONN,HA   I144 @BASEBOARD_FAB2_LIB.BASEBOARD_FAB2(SCH_1):PAGE78
  J9T1   94 VSS<67> SCONN288_H44441003_PIP-SCONN,HA   I144 @BASEBOARD_FAB2_LIB.BASEBOARD_FAB2(SCH_1):PAGE78
  J9T1   57 VSS<68> SCONN288_H44441003_PIP-SCONN,HA   I144 @BASEBOARD_FAB2_LIB.BASEBOARD_FAB2(SCH_1):PAGE78
  J9T1   55 VSS<69> SCONN288_H44441003_PIP-SCONN,HA   I144 @BASEBOARD_FAB2_LIB.BASEBOARD_FAB2(SCH_1):PAGE78
  J9T1   53 VSS<70> SCONN288_H44441003_PIP-SCONN,HA   I144 @BASEBOARD_FAB2_LIB.BASEBOARD_FAB2(SCH_1):PAGE78
  J9T1   50 VSS<71> SCONN288_H44441003_PIP-SCONN,HA   I144 @BASEBOARD_FAB2_LIB.BASEBOARD_FAB2(SCH_1):PAGE78
  J9T1   48 VSS<72> SCONN288_H44441003_PIP-SCONN,HA   I144 @BASEBOARD_FAB2_LIB.BASEBOARD_FAB2(SCH_1):PAGE78
  J9T1   46 VSS<73> SCONN288_H44441003_PIP-SCONN,HA   I144 @BASEBOARD_FAB2_LIB.BASEBOARD_FAB2(SCH_1):PAGE78
  J9T1   44 VSS<74> SCONN288_H44441003_PIP-SCONN,HA   I144 @BASEBOARD_FAB2_LIB.BASEBOARD_FAB2(SCH_1):PAGE78
  J9T1   42 VSS<75> SCONN288_H44441003_PIP-SCONN,HA   I144 @BASEBOARD_FAB2_LIB.BASEBOARD_FAB2(SCH_1):PAGE78
  J9T1   39 VSS<76> SCONN288_H44441003_PIP-SCONN,HA   I144 @BASEBOARD_FAB2_LIB.BASEBOARD_FAB2(SCH_1):PAGE78
  J9T1   37 VSS<77> SCONN288_H44441003_PIP-SCONN,HA   I144 @BASEBOARD_FAB2_LIB.BASEBOARD_FAB2(SCH_1):PAGE78
  J9T1   35 VSS<78> SCONN288_H44441003_PIP-SCONN,HA   I144 @BASEBOARD_FAB2_LIB.BASEBOARD_FAB2(SCH_1):PAGE78
  J9T1   33 VSS<79> SCONN288_H44441003_PIP-SCONN,HA   I144 @BASEBOARD_FAB2_LIB.BASEBOARD_FAB2(SCH_1):PAGE78
  J9T1   31 VSS<80> SCONN288_H44441003_PIP-SCONN,HA   I144 @BASEBOARD_FAB2_LIB.BASEBOARD_FAB2(SCH_1):PAGE78
  J9T1   28 VSS<81> SCONN288_H44441003_PIP-SCONN,HA   I144 @BASEBOARD_FAB2_LIB.BASEBOARD_FAB2(SCH_1):PAGE78
  J9T1   26 VSS<82> SCONN288_H44441003_PIP-SCONN,HA   I144 @BASEBOARD_FAB2_LIB.BASEBOARD_FAB2(SCH_1):PAGE78
  J9T1   24 VSS<83> SCONN288_H44441003_PIP-SCONN,HA   I144 @BASEBOARD_FAB2_LIB.BASEBOARD_FAB2(SCH_1):PAGE78
  J9T1   22 VSS<84> SCONN288_H44441003_PIP-SCONN,HA   I144 @BASEBOARD_FAB2_LIB.BASEBOARD_FAB2(SCH_1):PAGE78
  J9T1   20 VSS<85> SCONN288_H44441003_PIP-SCONN,HA   I144 @BASEBOARD_FAB2_LIB.BASEBOARD_FAB2(SCH_1):PAGE78
  J9T1   17 VSS<86> SCONN288_H44441003_PIP-SCONN,HA   I144 @BASEBOARD_FAB2_LIB.BASEBOARD_FAB2(SCH_1):PAGE78
  J9T1   15 VSS<87> SCONN288_H44441003_PIP-SCONN,HA   I144 @BASEBOARD_FAB2_LIB.BASEBOARD_FAB2(SCH_1):PAGE78
  J9T1   13 VSS<88> SCONN288_H44441003_PIP-SCONN,HA   I144 @BASEBOARD_FAB2_LIB.BASEBOARD_FAB2(SCH_1):PAGE78
  J9T1   11 VSS<89> SCONN288_H44441003_PIP-SCONN,HA   I144 @BASEBOARD_FAB2_LIB.BASEBOARD_FAB2(SCH_1):PAGE78
  J9T1    9 VSS<90> SCONN288_H44441003_PIP-SCONN,HA   I144 @BASEBOARD_FAB2_LIB.BASEBOARD_FAB2(SCH_1):PAGE78
  J9T1    6 VSS<91> SCONN288_H44441003_PIP-SCONN,HA   I144 @BASEBOARD_FAB2_LIB.BASEBOARD_FAB2(SCH_1):PAGE78
  J9T1    4 VSS<92> SCONN288_H44441003_PIP-SCONN,HA   I144 @BASEBOARD_FAB2_LIB.BASEBOARD_FAB2(SCH_1):PAGE78
  J9T1    2 VSS<93> SCONN288_H44441003_PIP-SCONN,HA   I144 @BASEBOARD_FAB2_LIB.BASEBOARD_FAB2(SCH_1):PAGE78
  J1G2  283 VSS<0> SCONN288_H44441004_PIP-SCONN,HA    I43 @BASEBOARD_FAB2_LIB.BASEBOARD_FAB2(SCH_1):PAGE79
  J1G2  281 VSS<1> SCONN288_H44441004_PIP-SCONN,HA    I43 @BASEBOARD_FAB2_LIB.BASEBOARD_FAB2(SCH_1):PAGE79
  J1G2  279 VSS<2> SCONN288_H44441004_PIP-SCONN,HA    I43 @BASEBOARD_FAB2_LIB.BASEBOARD_FAB2(SCH_1):PAGE79
  J1G2  276 VSS<3> SCONN288_H44441004_PIP-SCONN,HA    I43 @BASEBOARD_FAB2_LIB.BASEBOARD_FAB2(SCH_1):PAGE79
  J1G2  274 VSS<4> SCONN288_H44441004_PIP-SCONN,HA    I43 @BASEBOARD_FAB2_LIB.BASEBOARD_FAB2(SCH_1):PAGE79
  J1G2  272 VSS<5> SCONN288_H44441004_PIP-SCONN,HA    I43 @BASEBOARD_FAB2_LIB.BASEBOARD_FAB2(SCH_1):PAGE79
  J1G2  270 VSS<6> SCONN288_H44441004_PIP-SCONN,HA    I43 @BASEBOARD_FAB2_LIB.BASEBOARD_FAB2(SCH_1):PAGE79
  J1G2  268 VSS<7> SCONN288_H44441004_PIP-SCONN,HA    I43 @BASEBOARD_FAB2_LIB.BASEBOARD_FAB2(SCH_1):PAGE79
  J1G2  265 VSS<8> SCONN288_H44441004_PIP-SCONN,HA    I43 @BASEBOARD_FAB2_LIB.BASEBOARD_FAB2(SCH_1):PAGE79
  J1G2  263 VSS<9> SCONN288_H44441004_PIP-SCONN,HA    I43 @BASEBOARD_FAB2_LIB.BASEBOARD_FAB2(SCH_1):PAGE79
  J1G2  261 VSS<10> SCONN288_H44441004_PIP-SCONN,HA    I43 @BASEBOARD_FAB2_LIB.BASEBOARD_FAB2(SCH_1):PAGE79
  J1G2  259 VSS<11> SCONN288_H44441004_PIP-SCONN,HA    I43 @BASEBOARD_FAB2_LIB.BASEBOARD_FAB2(SCH_1):PAGE79
  J1G2  257 VSS<12> SCONN288_H44441004_PIP-SCONN,HA    I43 @BASEBOARD_FAB2_LIB.BASEBOARD_FAB2(SCH_1):PAGE79
  J1G2  254 VSS<13> SCONN288_H44441004_PIP-SCONN,HA    I43 @BASEBOARD_FAB2_LIB.BASEBOARD_FAB2(SCH_1):PAGE79
  J1G2  252 VSS<14> SCONN288_H44441004_PIP-SCONN,HA    I43 @BASEBOARD_FAB2_LIB.BASEBOARD_FAB2(SCH_1):PAGE79
  J1G2  250 VSS<15> SCONN288_H44441004_PIP-SCONN,HA    I43 @BASEBOARD_FAB2_LIB.BASEBOARD_FAB2(SCH_1):PAGE79
  J1G2  248 VSS<16> SCONN288_H44441004_PIP-SCONN,HA    I43 @BASEBOARD_FAB2_LIB.BASEBOARD_FAB2(SCH_1):PAGE79
  J1G2  246 VSS<17> SCONN288_H44441004_PIP-SCONN,HA    I43 @BASEBOARD_FAB2_LIB.BASEBOARD_FAB2(SCH_1):PAGE79
  J1G2  243 VSS<18> SCONN288_H44441004_PIP-SCONN,HA    I43 @BASEBOARD_FAB2_LIB.BASEBOARD_FAB2(SCH_1):PAGE79
  J1G2  241 VSS<19> SCONN288_H44441004_PIP-SCONN,HA    I43 @BASEBOARD_FAB2_LIB.BASEBOARD_FAB2(SCH_1):PAGE79
  J1G2  239 VSS<20> SCONN288_H44441004_PIP-SCONN,HA    I43 @BASEBOARD_FAB2_LIB.BASEBOARD_FAB2(SCH_1):PAGE79
  J1G2  202 VSS<21> SCONN288_H44441004_PIP-SCONN,HA    I43 @BASEBOARD_FAB2_LIB.BASEBOARD_FAB2(SCH_1):PAGE79
  J1G2  200 VSS<22> SCONN288_H44441004_PIP-SCONN,HA    I43 @BASEBOARD_FAB2_LIB.BASEBOARD_FAB2(SCH_1):PAGE79
  J1G2  198 VSS<23> SCONN288_H44441004_PIP-SCONN,HA    I43 @BASEBOARD_FAB2_LIB.BASEBOARD_FAB2(SCH_1):PAGE79
  J1G2  195 VSS<24> SCONN288_H44441004_PIP-SCONN,HA    I43 @BASEBOARD_FAB2_LIB.BASEBOARD_FAB2(SCH_1):PAGE79
  J1G2  193 VSS<25> SCONN288_H44441004_PIP-SCONN,HA    I43 @BASEBOARD_FAB2_LIB.BASEBOARD_FAB2(SCH_1):PAGE79
  J1G2  191 VSS<26> SCONN288_H44441004_PIP-SCONN,HA    I43 @BASEBOARD_FAB2_LIB.BASEBOARD_FAB2(SCH_1):PAGE79
  J1G2  189 VSS<27> SCONN288_H44441004_PIP-SCONN,HA    I43 @BASEBOARD_FAB2_LIB.BASEBOARD_FAB2(SCH_1):PAGE79
  J1G2  187 VSS<28> SCONN288_H44441004_PIP-SCONN,HA    I43 @BASEBOARD_FAB2_LIB.BASEBOARD_FAB2(SCH_1):PAGE79
  J1G2  184 VSS<29> SCONN288_H44441004_PIP-SCONN,HA    I43 @BASEBOARD_FAB2_LIB.BASEBOARD_FAB2(SCH_1):PAGE79
  J1G2  182 VSS<30> SCONN288_H44441004_PIP-SCONN,HA    I43 @BASEBOARD_FAB2_LIB.BASEBOARD_FAB2(SCH_1):PAGE79
  J1G2  180 VSS<31> SCONN288_H44441004_PIP-SCONN,HA    I43 @BASEBOARD_FAB2_LIB.BASEBOARD_FAB2(SCH_1):PAGE79
  J1G2  178 VSS<32> SCONN288_H44441004_PIP-SCONN,HA    I43 @BASEBOARD_FAB2_LIB.BASEBOARD_FAB2(SCH_1):PAGE79
  J1G2  176 VSS<33> SCONN288_H44441004_PIP-SCONN,HA    I43 @BASEBOARD_FAB2_LIB.BASEBOARD_FAB2(SCH_1):PAGE79
  J1G2  173 VSS<34> SCONN288_H44441004_PIP-SCONN,HA    I43 @BASEBOARD_FAB2_LIB.BASEBOARD_FAB2(SCH_1):PAGE79
  J1G2  171 VSS<35> SCONN288_H44441004_PIP-SCONN,HA    I43 @BASEBOARD_FAB2_LIB.BASEBOARD_FAB2(SCH_1):PAGE79
  J1G2  169 VSS<36> SCONN288_H44441004_PIP-SCONN,HA    I43 @BASEBOARD_FAB2_LIB.BASEBOARD_FAB2(SCH_1):PAGE79
  J1G2  167 VSS<37> SCONN288_H44441004_PIP-SCONN,HA    I43 @BASEBOARD_FAB2_LIB.BASEBOARD_FAB2(SCH_1):PAGE79
  J1G2  165 VSS<38> SCONN288_H44441004_PIP-SCONN,HA    I43 @BASEBOARD_FAB2_LIB.BASEBOARD_FAB2(SCH_1):PAGE79
  J1G2  162 VSS<39> SCONN288_H44441004_PIP-SCONN,HA    I43 @BASEBOARD_FAB2_LIB.BASEBOARD_FAB2(SCH_1):PAGE79
  J1G2  160 VSS<40> SCONN288_H44441004_PIP-SCONN,HA    I43 @BASEBOARD_FAB2_LIB.BASEBOARD_FAB2(SCH_1):PAGE79
  J1G2  158 VSS<41> SCONN288_H44441004_PIP-SCONN,HA    I43 @BASEBOARD_FAB2_LIB.BASEBOARD_FAB2(SCH_1):PAGE79
  J1G2  156 VSS<42> SCONN288_H44441004_PIP-SCONN,HA    I43 @BASEBOARD_FAB2_LIB.BASEBOARD_FAB2(SCH_1):PAGE79
  J1G2  154 VSS<43> SCONN288_H44441004_PIP-SCONN,HA    I43 @BASEBOARD_FAB2_LIB.BASEBOARD_FAB2(SCH_1):PAGE79
  J1G2  151 VSS<44> SCONN288_H44441004_PIP-SCONN,HA    I43 @BASEBOARD_FAB2_LIB.BASEBOARD_FAB2(SCH_1):PAGE79
  J1G2  149 VSS<45> SCONN288_H44441004_PIP-SCONN,HA    I43 @BASEBOARD_FAB2_LIB.BASEBOARD_FAB2(SCH_1):PAGE79
  J1G2  147 VSS<46> SCONN288_H44441004_PIP-SCONN,HA    I43 @BASEBOARD_FAB2_LIB.BASEBOARD_FAB2(SCH_1):PAGE79
  J1G2  138 VSS<47> SCONN288_H44441004_PIP-SCONN,HA    I43 @BASEBOARD_FAB2_LIB.BASEBOARD_FAB2(SCH_1):PAGE79
  J1G2  136 VSS<48> SCONN288_H44441004_PIP-SCONN,HA    I43 @BASEBOARD_FAB2_LIB.BASEBOARD_FAB2(SCH_1):PAGE79
  J1G2  134 VSS<49> SCONN288_H44441004_PIP-SCONN,HA    I43 @BASEBOARD_FAB2_LIB.BASEBOARD_FAB2(SCH_1):PAGE79
  J1G2  131 VSS<50> SCONN288_H44441004_PIP-SCONN,HA    I43 @BASEBOARD_FAB2_LIB.BASEBOARD_FAB2(SCH_1):PAGE79
  J1G2  129 VSS<51> SCONN288_H44441004_PIP-SCONN,HA    I43 @BASEBOARD_FAB2_LIB.BASEBOARD_FAB2(SCH_1):PAGE79
  J1G2  127 VSS<52> SCONN288_H44441004_PIP-SCONN,HA    I43 @BASEBOARD_FAB2_LIB.BASEBOARD_FAB2(SCH_1):PAGE79
  J1G2  125 VSS<53> SCONN288_H44441004_PIP-SCONN,HA    I43 @BASEBOARD_FAB2_LIB.BASEBOARD_FAB2(SCH_1):PAGE79
  J1G2  123 VSS<54> SCONN288_H44441004_PIP-SCONN,HA    I43 @BASEBOARD_FAB2_LIB.BASEBOARD_FAB2(SCH_1):PAGE79
  J1G2  120 VSS<55> SCONN288_H44441004_PIP-SCONN,HA    I43 @BASEBOARD_FAB2_LIB.BASEBOARD_FAB2(SCH_1):PAGE79
  J1G2  118 VSS<56> SCONN288_H44441004_PIP-SCONN,HA    I43 @BASEBOARD_FAB2_LIB.BASEBOARD_FAB2(SCH_1):PAGE79
  J1G2  116 VSS<57> SCONN288_H44441004_PIP-SCONN,HA    I43 @BASEBOARD_FAB2_LIB.BASEBOARD_FAB2(SCH_1):PAGE79
  J1G2  114 VSS<58> SCONN288_H44441004_PIP-SCONN,HA    I43 @BASEBOARD_FAB2_LIB.BASEBOARD_FAB2(SCH_1):PAGE79
  J1G2  112 VSS<59> SCONN288_H44441004_PIP-SCONN,HA    I43 @BASEBOARD_FAB2_LIB.BASEBOARD_FAB2(SCH_1):PAGE79
  J1G2  109 VSS<60> SCONN288_H44441004_PIP-SCONN,HA    I43 @BASEBOARD_FAB2_LIB.BASEBOARD_FAB2(SCH_1):PAGE79
  J1G2  107 VSS<61> SCONN288_H44441004_PIP-SCONN,HA    I43 @BASEBOARD_FAB2_LIB.BASEBOARD_FAB2(SCH_1):PAGE79
  J1G2  105 VSS<62> SCONN288_H44441004_PIP-SCONN,HA    I43 @BASEBOARD_FAB2_LIB.BASEBOARD_FAB2(SCH_1):PAGE79
  J1G2  103 VSS<63> SCONN288_H44441004_PIP-SCONN,HA    I43 @BASEBOARD_FAB2_LIB.BASEBOARD_FAB2(SCH_1):PAGE79
  J1G2  101 VSS<64> SCONN288_H44441004_PIP-SCONN,HA    I43 @BASEBOARD_FAB2_LIB.BASEBOARD_FAB2(SCH_1):PAGE79
  J1G2   98 VSS<65> SCONN288_H44441004_PIP-SCONN,HA    I43 @BASEBOARD_FAB2_LIB.BASEBOARD_FAB2(SCH_1):PAGE79
  J1G2   96 VSS<66> SCONN288_H44441004_PIP-SCONN,HA    I43 @BASEBOARD_FAB2_LIB.BASEBOARD_FAB2(SCH_1):PAGE79
  J1G2   94 VSS<67> SCONN288_H44441004_PIP-SCONN,HA    I43 @BASEBOARD_FAB2_LIB.BASEBOARD_FAB2(SCH_1):PAGE79
  J1G2   57 VSS<68> SCONN288_H44441004_PIP-SCONN,HA    I43 @BASEBOARD_FAB2_LIB.BASEBOARD_FAB2(SCH_1):PAGE79
  J1G2   55 VSS<69> SCONN288_H44441004_PIP-SCONN,HA    I43 @BASEBOARD_FAB2_LIB.BASEBOARD_FAB2(SCH_1):PAGE79
  J1G2   53 VSS<70> SCONN288_H44441004_PIP-SCONN,HA    I43 @BASEBOARD_FAB2_LIB.BASEBOARD_FAB2(SCH_1):PAGE79
  J1G2   50 VSS<71> SCONN288_H44441004_PIP-SCONN,HA    I43 @BASEBOARD_FAB2_LIB.BASEBOARD_FAB2(SCH_1):PAGE79
  J1G2   48 VSS<72> SCONN288_H44441004_PIP-SCONN,HA    I43 @BASEBOARD_FAB2_LIB.BASEBOARD_FAB2(SCH_1):PAGE79
  J1G2   46 VSS<73> SCONN288_H44441004_PIP-SCONN,HA    I43 @BASEBOARD_FAB2_LIB.BASEBOARD_FAB2(SCH_1):PAGE79
  J1G2   44 VSS<74> SCONN288_H44441004_PIP-SCONN,HA    I43 @BASEBOARD_FAB2_LIB.BASEBOARD_FAB2(SCH_1):PAGE79
  J1G2   42 VSS<75> SCONN288_H44441004_PIP-SCONN,HA    I43 @BASEBOARD_FAB2_LIB.BASEBOARD_FAB2(SCH_1):PAGE79
  J1G2   39 VSS<76> SCONN288_H44441004_PIP-SCONN,HA    I43 @BASEBOARD_FAB2_LIB.BASEBOARD_FAB2(SCH_1):PAGE79
  J1G2   37 VSS<77> SCONN288_H44441004_PIP-SCONN,HA    I43 @BASEBOARD_FAB2_LIB.BASEBOARD_FAB2(SCH_1):PAGE79
  J1G2   35 VSS<78> SCONN288_H44441004_PIP-SCONN,HA    I43 @BASEBOARD_FAB2_LIB.BASEBOARD_FAB2(SCH_1):PAGE79
  J1G2   33 VSS<79> SCONN288_H44441004_PIP-SCONN,HA    I43 @BASEBOARD_FAB2_LIB.BASEBOARD_FAB2(SCH_1):PAGE79
  J1G2   31 VSS<80> SCONN288_H44441004_PIP-SCONN,HA    I43 @BASEBOARD_FAB2_LIB.BASEBOARD_FAB2(SCH_1):PAGE79
  J1G2   28 VSS<81> SCONN288_H44441004_PIP-SCONN,HA    I43 @BASEBOARD_FAB2_LIB.BASEBOARD_FAB2(SCH_1):PAGE79
  J1G2   26 VSS<82> SCONN288_H44441004_PIP-SCONN,HA    I43 @BASEBOARD_FAB2_LIB.BASEBOARD_FAB2(SCH_1):PAGE79
  J1G2   24 VSS<83> SCONN288_H44441004_PIP-SCONN,HA    I43 @BASEBOARD_FAB2_LIB.BASEBOARD_FAB2(SCH_1):PAGE79
  J1G2   22 VSS<84> SCONN288_H44441004_PIP-SCONN,HA    I43 @BASEBOARD_FAB2_LIB.BASEBOARD_FAB2(SCH_1):PAGE79
  J1G2   20 VSS<85> SCONN288_H44441004_PIP-SCONN,HA    I43 @BASEBOARD_FAB2_LIB.BASEBOARD_FAB2(SCH_1):PAGE79
  J1G2   17 VSS<86> SCONN288_H44441004_PIP-SCONN,HA    I43 @BASEBOARD_FAB2_LIB.BASEBOARD_FAB2(SCH_1):PAGE79
  J1G2   15 VSS<87> SCONN288_H44441004_PIP-SCONN,HA    I43 @BASEBOARD_FAB2_LIB.BASEBOARD_FAB2(SCH_1):PAGE79
  J1G2   13 VSS<88> SCONN288_H44441004_PIP-SCONN,HA    I43 @BASEBOARD_FAB2_LIB.BASEBOARD_FAB2(SCH_1):PAGE79
  J1G2   11 VSS<89> SCONN288_H44441004_PIP-SCONN,HA    I43 @BASEBOARD_FAB2_LIB.BASEBOARD_FAB2(SCH_1):PAGE79
  J1G2    9 VSS<90> SCONN288_H44441004_PIP-SCONN,HA    I43 @BASEBOARD_FAB2_LIB.BASEBOARD_FAB2(SCH_1):PAGE79
  J1G2    6 VSS<91> SCONN288_H44441004_PIP-SCONN,HA    I43 @BASEBOARD_FAB2_LIB.BASEBOARD_FAB2(SCH_1):PAGE79
  J1G2    4 VSS<92> SCONN288_H44441004_PIP-SCONN,HA    I43 @BASEBOARD_FAB2_LIB.BASEBOARD_FAB2(SCH_1):PAGE79
  J1G2    2 VSS<93> SCONN288_H44441004_PIP-SCONN,HA    I43 @BASEBOARD_FAB2_LIB.BASEBOARD_FAB2(SCH_1):PAGE79
  J1G2  139  SA<0> SCONN288_H44441004_PIP-SCONN,HA   I111 @BASEBOARD_FAB2_LIB.BASEBOARD_FAB2(SCH_1):PAGE79
  J1G2  238  SA<2> SCONN288_H44441004_PIP-SCONN,HA   I111 @BASEBOARD_FAB2_LIB.BASEBOARD_FAB2(SCH_1):PAGE79
  C9U7    2      B CAP_A_0402V-0.01UF,25V,10%,X7RA   I178 @BASEBOARD_FAB2_LIB.BASEBOARD_FAB2(SCH_1):PAGE79
 C1G10    2      B CAP_A_0402V-0.01UF,25V,10%,X7RA     I3 @BASEBOARD_FAB2_LIB.BASEBOARD_FAB2(SCH_1):PAGE80
  J9U1  238  SA<2> SCONN288_H44441003_PIP-SCONN,HA    I24 @BASEBOARD_FAB2_LIB.BASEBOARD_FAB2(SCH_1):PAGE80
  J9U1  283 VSS<0> SCONN288_H44441003_PIP-SCONN,HA   I138 @BASEBOARD_FAB2_LIB.BASEBOARD_FAB2(SCH_1):PAGE80
  J9U1  281 VSS<1> SCONN288_H44441003_PIP-SCONN,HA   I138 @BASEBOARD_FAB2_LIB.BASEBOARD_FAB2(SCH_1):PAGE80
  J9U1  279 VSS<2> SCONN288_H44441003_PIP-SCONN,HA   I138 @BASEBOARD_FAB2_LIB.BASEBOARD_FAB2(SCH_1):PAGE80
  J9U1  276 VSS<3> SCONN288_H44441003_PIP-SCONN,HA   I138 @BASEBOARD_FAB2_LIB.BASEBOARD_FAB2(SCH_1):PAGE80
  J9U1  274 VSS<4> SCONN288_H44441003_PIP-SCONN,HA   I138 @BASEBOARD_FAB2_LIB.BASEBOARD_FAB2(SCH_1):PAGE80
  J9U1  272 VSS<5> SCONN288_H44441003_PIP-SCONN,HA   I138 @BASEBOARD_FAB2_LIB.BASEBOARD_FAB2(SCH_1):PAGE80
  J9U1  270 VSS<6> SCONN288_H44441003_PIP-SCONN,HA   I138 @BASEBOARD_FAB2_LIB.BASEBOARD_FAB2(SCH_1):PAGE80
  J9U1  268 VSS<7> SCONN288_H44441003_PIP-SCONN,HA   I138 @BASEBOARD_FAB2_LIB.BASEBOARD_FAB2(SCH_1):PAGE80
  J9U1  265 VSS<8> SCONN288_H44441003_PIP-SCONN,HA   I138 @BASEBOARD_FAB2_LIB.BASEBOARD_FAB2(SCH_1):PAGE80
  J9U1  263 VSS<9> SCONN288_H44441003_PIP-SCONN,HA   I138 @BASEBOARD_FAB2_LIB.BASEBOARD_FAB2(SCH_1):PAGE80
  J9U1  261 VSS<10> SCONN288_H44441003_PIP-SCONN,HA   I138 @BASEBOARD_FAB2_LIB.BASEBOARD_FAB2(SCH_1):PAGE80
  J9U1  259 VSS<11> SCONN288_H44441003_PIP-SCONN,HA   I138 @BASEBOARD_FAB2_LIB.BASEBOARD_FAB2(SCH_1):PAGE80
  J9U1  257 VSS<12> SCONN288_H44441003_PIP-SCONN,HA   I138 @BASEBOARD_FAB2_LIB.BASEBOARD_FAB2(SCH_1):PAGE80
  J9U1  254 VSS<13> SCONN288_H44441003_PIP-SCONN,HA   I138 @BASEBOARD_FAB2_LIB.BASEBOARD_FAB2(SCH_1):PAGE80
  J9U1  252 VSS<14> SCONN288_H44441003_PIP-SCONN,HA   I138 @BASEBOARD_FAB2_LIB.BASEBOARD_FAB2(SCH_1):PAGE80
  J9U1  250 VSS<15> SCONN288_H44441003_PIP-SCONN,HA   I138 @BASEBOARD_FAB2_LIB.BASEBOARD_FAB2(SCH_1):PAGE80
  J9U1  248 VSS<16> SCONN288_H44441003_PIP-SCONN,HA   I138 @BASEBOARD_FAB2_LIB.BASEBOARD_FAB2(SCH_1):PAGE80
  J9U1  246 VSS<17> SCONN288_H44441003_PIP-SCONN,HA   I138 @BASEBOARD_FAB2_LIB.BASEBOARD_FAB2(SCH_1):PAGE80
  J9U1  243 VSS<18> SCONN288_H44441003_PIP-SCONN,HA   I138 @BASEBOARD_FAB2_LIB.BASEBOARD_FAB2(SCH_1):PAGE80
  J9U1  241 VSS<19> SCONN288_H44441003_PIP-SCONN,HA   I138 @BASEBOARD_FAB2_LIB.BASEBOARD_FAB2(SCH_1):PAGE80
  J9U1  239 VSS<20> SCONN288_H44441003_PIP-SCONN,HA   I138 @BASEBOARD_FAB2_LIB.BASEBOARD_FAB2(SCH_1):PAGE80
  J9U1  202 VSS<21> SCONN288_H44441003_PIP-SCONN,HA   I138 @BASEBOARD_FAB2_LIB.BASEBOARD_FAB2(SCH_1):PAGE80
  J9U1  200 VSS<22> SCONN288_H44441003_PIP-SCONN,HA   I138 @BASEBOARD_FAB2_LIB.BASEBOARD_FAB2(SCH_1):PAGE80
  J9U1  198 VSS<23> SCONN288_H44441003_PIP-SCONN,HA   I138 @BASEBOARD_FAB2_LIB.BASEBOARD_FAB2(SCH_1):PAGE80
  J9U1  195 VSS<24> SCONN288_H44441003_PIP-SCONN,HA   I138 @BASEBOARD_FAB2_LIB.BASEBOARD_FAB2(SCH_1):PAGE80
  J9U1  193 VSS<25> SCONN288_H44441003_PIP-SCONN,HA   I138 @BASEBOARD_FAB2_LIB.BASEBOARD_FAB2(SCH_1):PAGE80
  J9U1  191 VSS<26> SCONN288_H44441003_PIP-SCONN,HA   I138 @BASEBOARD_FAB2_LIB.BASEBOARD_FAB2(SCH_1):PAGE80
  J9U1  189 VSS<27> SCONN288_H44441003_PIP-SCONN,HA   I138 @BASEBOARD_FAB2_LIB.BASEBOARD_FAB2(SCH_1):PAGE80
  J9U1  187 VSS<28> SCONN288_H44441003_PIP-SCONN,HA   I138 @BASEBOARD_FAB2_LIB.BASEBOARD_FAB2(SCH_1):PAGE80
  J9U1  184 VSS<29> SCONN288_H44441003_PIP-SCONN,HA   I138 @BASEBOARD_FAB2_LIB.BASEBOARD_FAB2(SCH_1):PAGE80
  J9U1  182 VSS<30> SCONN288_H44441003_PIP-SCONN,HA   I138 @BASEBOARD_FAB2_LIB.BASEBOARD_FAB2(SCH_1):PAGE80
  J9U1  180 VSS<31> SCONN288_H44441003_PIP-SCONN,HA   I138 @BASEBOARD_FAB2_LIB.BASEBOARD_FAB2(SCH_1):PAGE80
  J9U1  178 VSS<32> SCONN288_H44441003_PIP-SCONN,HA   I138 @BASEBOARD_FAB2_LIB.BASEBOARD_FAB2(SCH_1):PAGE80
  J9U1  176 VSS<33> SCONN288_H44441003_PIP-SCONN,HA   I138 @BASEBOARD_FAB2_LIB.BASEBOARD_FAB2(SCH_1):PAGE80
  J9U1  173 VSS<34> SCONN288_H44441003_PIP-SCONN,HA   I138 @BASEBOARD_FAB2_LIB.BASEBOARD_FAB2(SCH_1):PAGE80
  J9U1  171 VSS<35> SCONN288_H44441003_PIP-SCONN,HA   I138 @BASEBOARD_FAB2_LIB.BASEBOARD_FAB2(SCH_1):PAGE80
  J9U1  169 VSS<36> SCONN288_H44441003_PIP-SCONN,HA   I138 @BASEBOARD_FAB2_LIB.BASEBOARD_FAB2(SCH_1):PAGE80
  J9U1  167 VSS<37> SCONN288_H44441003_PIP-SCONN,HA   I138 @BASEBOARD_FAB2_LIB.BASEBOARD_FAB2(SCH_1):PAGE80
  J9U1  165 VSS<38> SCONN288_H44441003_PIP-SCONN,HA   I138 @BASEBOARD_FAB2_LIB.BASEBOARD_FAB2(SCH_1):PAGE80
  J9U1  162 VSS<39> SCONN288_H44441003_PIP-SCONN,HA   I138 @BASEBOARD_FAB2_LIB.BASEBOARD_FAB2(SCH_1):PAGE80
  J9U1  160 VSS<40> SCONN288_H44441003_PIP-SCONN,HA   I138 @BASEBOARD_FAB2_LIB.BASEBOARD_FAB2(SCH_1):PAGE80
  J9U1  158 VSS<41> SCONN288_H44441003_PIP-SCONN,HA   I138 @BASEBOARD_FAB2_LIB.BASEBOARD_FAB2(SCH_1):PAGE80
  J9U1  156 VSS<42> SCONN288_H44441003_PIP-SCONN,HA   I138 @BASEBOARD_FAB2_LIB.BASEBOARD_FAB2(SCH_1):PAGE80
  J9U1  154 VSS<43> SCONN288_H44441003_PIP-SCONN,HA   I138 @BASEBOARD_FAB2_LIB.BASEBOARD_FAB2(SCH_1):PAGE80
  J9U1  151 VSS<44> SCONN288_H44441003_PIP-SCONN,HA   I138 @BASEBOARD_FAB2_LIB.BASEBOARD_FAB2(SCH_1):PAGE80
  J9U1  149 VSS<45> SCONN288_H44441003_PIP-SCONN,HA   I138 @BASEBOARD_FAB2_LIB.BASEBOARD_FAB2(SCH_1):PAGE80
  J9U1  147 VSS<46> SCONN288_H44441003_PIP-SCONN,HA   I138 @BASEBOARD_FAB2_LIB.BASEBOARD_FAB2(SCH_1):PAGE80
  J9U1  138 VSS<47> SCONN288_H44441003_PIP-SCONN,HA   I138 @BASEBOARD_FAB2_LIB.BASEBOARD_FAB2(SCH_1):PAGE80
  J9U1  136 VSS<48> SCONN288_H44441003_PIP-SCONN,HA   I138 @BASEBOARD_FAB2_LIB.BASEBOARD_FAB2(SCH_1):PAGE80
  J9U1  134 VSS<49> SCONN288_H44441003_PIP-SCONN,HA   I138 @BASEBOARD_FAB2_LIB.BASEBOARD_FAB2(SCH_1):PAGE80
  J9U1  131 VSS<50> SCONN288_H44441003_PIP-SCONN,HA   I138 @BASEBOARD_FAB2_LIB.BASEBOARD_FAB2(SCH_1):PAGE80
  J9U1  129 VSS<51> SCONN288_H44441003_PIP-SCONN,HA   I138 @BASEBOARD_FAB2_LIB.BASEBOARD_FAB2(SCH_1):PAGE80
  J9U1  127 VSS<52> SCONN288_H44441003_PIP-SCONN,HA   I138 @BASEBOARD_FAB2_LIB.BASEBOARD_FAB2(SCH_1):PAGE80
  J9U1  125 VSS<53> SCONN288_H44441003_PIP-SCONN,HA   I138 @BASEBOARD_FAB2_LIB.BASEBOARD_FAB2(SCH_1):PAGE80
  J9U1  123 VSS<54> SCONN288_H44441003_PIP-SCONN,HA   I138 @BASEBOARD_FAB2_LIB.BASEBOARD_FAB2(SCH_1):PAGE80
  J9U1  120 VSS<55> SCONN288_H44441003_PIP-SCONN,HA   I138 @BASEBOARD_FAB2_LIB.BASEBOARD_FAB2(SCH_1):PAGE80
  J9U1  118 VSS<56> SCONN288_H44441003_PIP-SCONN,HA   I138 @BASEBOARD_FAB2_LIB.BASEBOARD_FAB2(SCH_1):PAGE80
  J9U1  116 VSS<57> SCONN288_H44441003_PIP-SCONN,HA   I138 @BASEBOARD_FAB2_LIB.BASEBOARD_FAB2(SCH_1):PAGE80
  J9U1  114 VSS<58> SCONN288_H44441003_PIP-SCONN,HA   I138 @BASEBOARD_FAB2_LIB.BASEBOARD_FAB2(SCH_1):PAGE80
  J9U1  112 VSS<59> SCONN288_H44441003_PIP-SCONN,HA   I138 @BASEBOARD_FAB2_LIB.BASEBOARD_FAB2(SCH_1):PAGE80
  J9U1  109 VSS<60> SCONN288_H44441003_PIP-SCONN,HA   I138 @BASEBOARD_FAB2_LIB.BASEBOARD_FAB2(SCH_1):PAGE80
  J9U1  107 VSS<61> SCONN288_H44441003_PIP-SCONN,HA   I138 @BASEBOARD_FAB2_LIB.BASEBOARD_FAB2(SCH_1):PAGE80
  J9U1  105 VSS<62> SCONN288_H44441003_PIP-SCONN,HA   I138 @BASEBOARD_FAB2_LIB.BASEBOARD_FAB2(SCH_1):PAGE80
  J9U1  103 VSS<63> SCONN288_H44441003_PIP-SCONN,HA   I138 @BASEBOARD_FAB2_LIB.BASEBOARD_FAB2(SCH_1):PAGE80
  J9U1  101 VSS<64> SCONN288_H44441003_PIP-SCONN,HA   I138 @BASEBOARD_FAB2_LIB.BASEBOARD_FAB2(SCH_1):PAGE80
  J9U1   98 VSS<65> SCONN288_H44441003_PIP-SCONN,HA   I138 @BASEBOARD_FAB2_LIB.BASEBOARD_FAB2(SCH_1):PAGE80
  J9U1   96 VSS<66> SCONN288_H44441003_PIP-SCONN,HA   I138 @BASEBOARD_FAB2_LIB.BASEBOARD_FAB2(SCH_1):PAGE80
  J9U1   94 VSS<67> SCONN288_H44441003_PIP-SCONN,HA   I138 @BASEBOARD_FAB2_LIB.BASEBOARD_FAB2(SCH_1):PAGE80
  J9U1   57 VSS<68> SCONN288_H44441003_PIP-SCONN,HA   I138 @BASEBOARD_FAB2_LIB.BASEBOARD_FAB2(SCH_1):PAGE80
  J9U1   55 VSS<69> SCONN288_H44441003_PIP-SCONN,HA   I138 @BASEBOARD_FAB2_LIB.BASEBOARD_FAB2(SCH_1):PAGE80
  J9U1   53 VSS<70> SCONN288_H44441003_PIP-SCONN,HA   I138 @BASEBOARD_FAB2_LIB.BASEBOARD_FAB2(SCH_1):PAGE80
  J9U1   50 VSS<71> SCONN288_H44441003_PIP-SCONN,HA   I138 @BASEBOARD_FAB2_LIB.BASEBOARD_FAB2(SCH_1):PAGE80
  J9U1   48 VSS<72> SCONN288_H44441003_PIP-SCONN,HA   I138 @BASEBOARD_FAB2_LIB.BASEBOARD_FAB2(SCH_1):PAGE80
  J9U1   46 VSS<73> SCONN288_H44441003_PIP-SCONN,HA   I138 @BASEBOARD_FAB2_LIB.BASEBOARD_FAB2(SCH_1):PAGE80
  J9U1   44 VSS<74> SCONN288_H44441003_PIP-SCONN,HA   I138 @BASEBOARD_FAB2_LIB.BASEBOARD_FAB2(SCH_1):PAGE80
  J9U1   42 VSS<75> SCONN288_H44441003_PIP-SCONN,HA   I138 @BASEBOARD_FAB2_LIB.BASEBOARD_FAB2(SCH_1):PAGE80
  J9U1   39 VSS<76> SCONN288_H44441003_PIP-SCONN,HA   I138 @BASEBOARD_FAB2_LIB.BASEBOARD_FAB2(SCH_1):PAGE80
  J9U1   37 VSS<77> SCONN288_H44441003_PIP-SCONN,HA   I138 @BASEBOARD_FAB2_LIB.BASEBOARD_FAB2(SCH_1):PAGE80
  J9U1   35 VSS<78> SCONN288_H44441003_PIP-SCONN,HA   I138 @BASEBOARD_FAB2_LIB.BASEBOARD_FAB2(SCH_1):PAGE80
  J9U1   33 VSS<79> SCONN288_H44441003_PIP-SCONN,HA   I138 @BASEBOARD_FAB2_LIB.BASEBOARD_FAB2(SCH_1):PAGE80
  J9U1   31 VSS<80> SCONN288_H44441003_PIP-SCONN,HA   I138 @BASEBOARD_FAB2_LIB.BASEBOARD_FAB2(SCH_1):PAGE80
  J9U1   28 VSS<81> SCONN288_H44441003_PIP-SCONN,HA   I138 @BASEBOARD_FAB2_LIB.BASEBOARD_FAB2(SCH_1):PAGE80
  J9U1   26 VSS<82> SCONN288_H44441003_PIP-SCONN,HA   I138 @BASEBOARD_FAB2_LIB.BASEBOARD_FAB2(SCH_1):PAGE80
  J9U1   24 VSS<83> SCONN288_H44441003_PIP-SCONN,HA   I138 @BASEBOARD_FAB2_LIB.BASEBOARD_FAB2(SCH_1):PAGE80
  J9U1   22 VSS<84> SCONN288_H44441003_PIP-SCONN,HA   I138 @BASEBOARD_FAB2_LIB.BASEBOARD_FAB2(SCH_1):PAGE80
  J9U1   20 VSS<85> SCONN288_H44441003_PIP-SCONN,HA   I138 @BASEBOARD_FAB2_LIB.BASEBOARD_FAB2(SCH_1):PAGE80
  J9U1   17 VSS<86> SCONN288_H44441003_PIP-SCONN,HA   I138 @BASEBOARD_FAB2_LIB.BASEBOARD_FAB2(SCH_1):PAGE80
  J9U1   15 VSS<87> SCONN288_H44441003_PIP-SCONN,HA   I138 @BASEBOARD_FAB2_LIB.BASEBOARD_FAB2(SCH_1):PAGE80
  J9U1   13 VSS<88> SCONN288_H44441003_PIP-SCONN,HA   I138 @BASEBOARD_FAB2_LIB.BASEBOARD_FAB2(SCH_1):PAGE80
  J9U1   11 VSS<89> SCONN288_H44441003_PIP-SCONN,HA   I138 @BASEBOARD_FAB2_LIB.BASEBOARD_FAB2(SCH_1):PAGE80
  J9U1    9 VSS<90> SCONN288_H44441003_PIP-SCONN,HA   I138 @BASEBOARD_FAB2_LIB.BASEBOARD_FAB2(SCH_1):PAGE80
  J9U1    6 VSS<91> SCONN288_H44441003_PIP-SCONN,HA   I138 @BASEBOARD_FAB2_LIB.BASEBOARD_FAB2(SCH_1):PAGE80
  J9U1    4 VSS<92> SCONN288_H44441003_PIP-SCONN,HA   I138 @BASEBOARD_FAB2_LIB.BASEBOARD_FAB2(SCH_1):PAGE80
  J9U1    2 VSS<93> SCONN288_H44441003_PIP-SCONN,HA   I138 @BASEBOARD_FAB2_LIB.BASEBOARD_FAB2(SCH_1):PAGE80
 C9U10    2      B CAP_A_0402V-0.01UF,25V,10%,X7RA   I178 @BASEBOARD_FAB2_LIB.BASEBOARD_FAB2(SCH_1):PAGE81
  J1G3  283 VSS<0> SCONN288_H44441004_PIP-SCONN,HA   I185 @BASEBOARD_FAB2_LIB.BASEBOARD_FAB2(SCH_1):PAGE81
  J1G3  281 VSS<1> SCONN288_H44441004_PIP-SCONN,HA   I185 @BASEBOARD_FAB2_LIB.BASEBOARD_FAB2(SCH_1):PAGE81
  J1G3  279 VSS<2> SCONN288_H44441004_PIP-SCONN,HA   I185 @BASEBOARD_FAB2_LIB.BASEBOARD_FAB2(SCH_1):PAGE81
  J1G3  276 VSS<3> SCONN288_H44441004_PIP-SCONN,HA   I185 @BASEBOARD_FAB2_LIB.BASEBOARD_FAB2(SCH_1):PAGE81
  J1G3  274 VSS<4> SCONN288_H44441004_PIP-SCONN,HA   I185 @BASEBOARD_FAB2_LIB.BASEBOARD_FAB2(SCH_1):PAGE81
  J1G3  272 VSS<5> SCONN288_H44441004_PIP-SCONN,HA   I185 @BASEBOARD_FAB2_LIB.BASEBOARD_FAB2(SCH_1):PAGE81
  J1G3  270 VSS<6> SCONN288_H44441004_PIP-SCONN,HA   I185 @BASEBOARD_FAB2_LIB.BASEBOARD_FAB2(SCH_1):PAGE81
  J1G3  268 VSS<7> SCONN288_H44441004_PIP-SCONN,HA   I185 @BASEBOARD_FAB2_LIB.BASEBOARD_FAB2(SCH_1):PAGE81
  J1G3  265 VSS<8> SCONN288_H44441004_PIP-SCONN,HA   I185 @BASEBOARD_FAB2_LIB.BASEBOARD_FAB2(SCH_1):PAGE81
  J1G3  263 VSS<9> SCONN288_H44441004_PIP-SCONN,HA   I185 @BASEBOARD_FAB2_LIB.BASEBOARD_FAB2(SCH_1):PAGE81
  J1G3  261 VSS<10> SCONN288_H44441004_PIP-SCONN,HA   I185 @BASEBOARD_FAB2_LIB.BASEBOARD_FAB2(SCH_1):PAGE81
  J1G3  259 VSS<11> SCONN288_H44441004_PIP-SCONN,HA   I185 @BASEBOARD_FAB2_LIB.BASEBOARD_FAB2(SCH_1):PAGE81
  J1G3  257 VSS<12> SCONN288_H44441004_PIP-SCONN,HA   I185 @BASEBOARD_FAB2_LIB.BASEBOARD_FAB2(SCH_1):PAGE81
  J1G3  254 VSS<13> SCONN288_H44441004_PIP-SCONN,HA   I185 @BASEBOARD_FAB2_LIB.BASEBOARD_FAB2(SCH_1):PAGE81
  J1G3  252 VSS<14> SCONN288_H44441004_PIP-SCONN,HA   I185 @BASEBOARD_FAB2_LIB.BASEBOARD_FAB2(SCH_1):PAGE81
  J1G3  250 VSS<15> SCONN288_H44441004_PIP-SCONN,HA   I185 @BASEBOARD_FAB2_LIB.BASEBOARD_FAB2(SCH_1):PAGE81
  J1G3  248 VSS<16> SCONN288_H44441004_PIP-SCONN,HA   I185 @BASEBOARD_FAB2_LIB.BASEBOARD_FAB2(SCH_1):PAGE81
  J1G3  246 VSS<17> SCONN288_H44441004_PIP-SCONN,HA   I185 @BASEBOARD_FAB2_LIB.BASEBOARD_FAB2(SCH_1):PAGE81
  J1G3  243 VSS<18> SCONN288_H44441004_PIP-SCONN,HA   I185 @BASEBOARD_FAB2_LIB.BASEBOARD_FAB2(SCH_1):PAGE81
  J1G3  241 VSS<19> SCONN288_H44441004_PIP-SCONN,HA   I185 @BASEBOARD_FAB2_LIB.BASEBOARD_FAB2(SCH_1):PAGE81
  J1G3  239 VSS<20> SCONN288_H44441004_PIP-SCONN,HA   I185 @BASEBOARD_FAB2_LIB.BASEBOARD_FAB2(SCH_1):PAGE81
  J1G3  202 VSS<21> SCONN288_H44441004_PIP-SCONN,HA   I185 @BASEBOARD_FAB2_LIB.BASEBOARD_FAB2(SCH_1):PAGE81
  J1G3  200 VSS<22> SCONN288_H44441004_PIP-SCONN,HA   I185 @BASEBOARD_FAB2_LIB.BASEBOARD_FAB2(SCH_1):PAGE81
  J1G3  198 VSS<23> SCONN288_H44441004_PIP-SCONN,HA   I185 @BASEBOARD_FAB2_LIB.BASEBOARD_FAB2(SCH_1):PAGE81
  J1G3  195 VSS<24> SCONN288_H44441004_PIP-SCONN,HA   I185 @BASEBOARD_FAB2_LIB.BASEBOARD_FAB2(SCH_1):PAGE81
  J1G3  193 VSS<25> SCONN288_H44441004_PIP-SCONN,HA   I185 @BASEBOARD_FAB2_LIB.BASEBOARD_FAB2(SCH_1):PAGE81
  J1G3  191 VSS<26> SCONN288_H44441004_PIP-SCONN,HA   I185 @BASEBOARD_FAB2_LIB.BASEBOARD_FAB2(SCH_1):PAGE81
  J1G3  189 VSS<27> SCONN288_H44441004_PIP-SCONN,HA   I185 @BASEBOARD_FAB2_LIB.BASEBOARD_FAB2(SCH_1):PAGE81
  J1G3  187 VSS<28> SCONN288_H44441004_PIP-SCONN,HA   I185 @BASEBOARD_FAB2_LIB.BASEBOARD_FAB2(SCH_1):PAGE81
  J1G3  184 VSS<29> SCONN288_H44441004_PIP-SCONN,HA   I185 @BASEBOARD_FAB2_LIB.BASEBOARD_FAB2(SCH_1):PAGE81
  J1G3  182 VSS<30> SCONN288_H44441004_PIP-SCONN,HA   I185 @BASEBOARD_FAB2_LIB.BASEBOARD_FAB2(SCH_1):PAGE81
  J1G3  180 VSS<31> SCONN288_H44441004_PIP-SCONN,HA   I185 @BASEBOARD_FAB2_LIB.BASEBOARD_FAB2(SCH_1):PAGE81
  J1G3  178 VSS<32> SCONN288_H44441004_PIP-SCONN,HA   I185 @BASEBOARD_FAB2_LIB.BASEBOARD_FAB2(SCH_1):PAGE81
  J1G3  176 VSS<33> SCONN288_H44441004_PIP-SCONN,HA   I185 @BASEBOARD_FAB2_LIB.BASEBOARD_FAB2(SCH_1):PAGE81
  J1G3  173 VSS<34> SCONN288_H44441004_PIP-SCONN,HA   I185 @BASEBOARD_FAB2_LIB.BASEBOARD_FAB2(SCH_1):PAGE81
  J1G3  171 VSS<35> SCONN288_H44441004_PIP-SCONN,HA   I185 @BASEBOARD_FAB2_LIB.BASEBOARD_FAB2(SCH_1):PAGE81
  J1G3  169 VSS<36> SCONN288_H44441004_PIP-SCONN,HA   I185 @BASEBOARD_FAB2_LIB.BASEBOARD_FAB2(SCH_1):PAGE81
  J1G3  167 VSS<37> SCONN288_H44441004_PIP-SCONN,HA   I185 @BASEBOARD_FAB2_LIB.BASEBOARD_FAB2(SCH_1):PAGE81
  J1G3  165 VSS<38> SCONN288_H44441004_PIP-SCONN,HA   I185 @BASEBOARD_FAB2_LIB.BASEBOARD_FAB2(SCH_1):PAGE81
  J1G3  162 VSS<39> SCONN288_H44441004_PIP-SCONN,HA   I185 @BASEBOARD_FAB2_LIB.BASEBOARD_FAB2(SCH_1):PAGE81
  J1G3  160 VSS<40> SCONN288_H44441004_PIP-SCONN,HA   I185 @BASEBOARD_FAB2_LIB.BASEBOARD_FAB2(SCH_1):PAGE81
  J1G3  158 VSS<41> SCONN288_H44441004_PIP-SCONN,HA   I185 @BASEBOARD_FAB2_LIB.BASEBOARD_FAB2(SCH_1):PAGE81
  J1G3  156 VSS<42> SCONN288_H44441004_PIP-SCONN,HA   I185 @BASEBOARD_FAB2_LIB.BASEBOARD_FAB2(SCH_1):PAGE81
  J1G3  154 VSS<43> SCONN288_H44441004_PIP-SCONN,HA   I185 @BASEBOARD_FAB2_LIB.BASEBOARD_FAB2(SCH_1):PAGE81
  J1G3  151 VSS<44> SCONN288_H44441004_PIP-SCONN,HA   I185 @BASEBOARD_FAB2_LIB.BASEBOARD_FAB2(SCH_1):PAGE81
  J1G3  149 VSS<45> SCONN288_H44441004_PIP-SCONN,HA   I185 @BASEBOARD_FAB2_LIB.BASEBOARD_FAB2(SCH_1):PAGE81
  J1G3  147 VSS<46> SCONN288_H44441004_PIP-SCONN,HA   I185 @BASEBOARD_FAB2_LIB.BASEBOARD_FAB2(SCH_1):PAGE81
  J1G3  138 VSS<47> SCONN288_H44441004_PIP-SCONN,HA   I185 @BASEBOARD_FAB2_LIB.BASEBOARD_FAB2(SCH_1):PAGE81
  J1G3  136 VSS<48> SCONN288_H44441004_PIP-SCONN,HA   I185 @BASEBOARD_FAB2_LIB.BASEBOARD_FAB2(SCH_1):PAGE81
  J1G3  134 VSS<49> SCONN288_H44441004_PIP-SCONN,HA   I185 @BASEBOARD_FAB2_LIB.BASEBOARD_FAB2(SCH_1):PAGE81
  J1G3  131 VSS<50> SCONN288_H44441004_PIP-SCONN,HA   I185 @BASEBOARD_FAB2_LIB.BASEBOARD_FAB2(SCH_1):PAGE81
  J1G3  129 VSS<51> SCONN288_H44441004_PIP-SCONN,HA   I185 @BASEBOARD_FAB2_LIB.BASEBOARD_FAB2(SCH_1):PAGE81
  J1G3  127 VSS<52> SCONN288_H44441004_PIP-SCONN,HA   I185 @BASEBOARD_FAB2_LIB.BASEBOARD_FAB2(SCH_1):PAGE81
  J1G3  125 VSS<53> SCONN288_H44441004_PIP-SCONN,HA   I185 @BASEBOARD_FAB2_LIB.BASEBOARD_FAB2(SCH_1):PAGE81
  J1G3  123 VSS<54> SCONN288_H44441004_PIP-SCONN,HA   I185 @BASEBOARD_FAB2_LIB.BASEBOARD_FAB2(SCH_1):PAGE81
  J1G3  120 VSS<55> SCONN288_H44441004_PIP-SCONN,HA   I185 @BASEBOARD_FAB2_LIB.BASEBOARD_FAB2(SCH_1):PAGE81
  J1G3  118 VSS<56> SCONN288_H44441004_PIP-SCONN,HA   I185 @BASEBOARD_FAB2_LIB.BASEBOARD_FAB2(SCH_1):PAGE81
  J1G3  116 VSS<57> SCONN288_H44441004_PIP-SCONN,HA   I185 @BASEBOARD_FAB2_LIB.BASEBOARD_FAB2(SCH_1):PAGE81
  J1G3  114 VSS<58> SCONN288_H44441004_PIP-SCONN,HA   I185 @BASEBOARD_FAB2_LIB.BASEBOARD_FAB2(SCH_1):PAGE81
  J1G3  112 VSS<59> SCONN288_H44441004_PIP-SCONN,HA   I185 @BASEBOARD_FAB2_LIB.BASEBOARD_FAB2(SCH_1):PAGE81
  J1G3  109 VSS<60> SCONN288_H44441004_PIP-SCONN,HA   I185 @BASEBOARD_FAB2_LIB.BASEBOARD_FAB2(SCH_1):PAGE81
  J1G3  107 VSS<61> SCONN288_H44441004_PIP-SCONN,HA   I185 @BASEBOARD_FAB2_LIB.BASEBOARD_FAB2(SCH_1):PAGE81
  J1G3  105 VSS<62> SCONN288_H44441004_PIP-SCONN,HA   I185 @BASEBOARD_FAB2_LIB.BASEBOARD_FAB2(SCH_1):PAGE81
  J1G3  103 VSS<63> SCONN288_H44441004_PIP-SCONN,HA   I185 @BASEBOARD_FAB2_LIB.BASEBOARD_FAB2(SCH_1):PAGE81
  J1G3  101 VSS<64> SCONN288_H44441004_PIP-SCONN,HA   I185 @BASEBOARD_FAB2_LIB.BASEBOARD_FAB2(SCH_1):PAGE81
  J1G3   98 VSS<65> SCONN288_H44441004_PIP-SCONN,HA   I185 @BASEBOARD_FAB2_LIB.BASEBOARD_FAB2(SCH_1):PAGE81
  J1G3   96 VSS<66> SCONN288_H44441004_PIP-SCONN,HA   I185 @BASEBOARD_FAB2_LIB.BASEBOARD_FAB2(SCH_1):PAGE81
  J1G3   94 VSS<67> SCONN288_H44441004_PIP-SCONN,HA   I185 @BASEBOARD_FAB2_LIB.BASEBOARD_FAB2(SCH_1):PAGE81
  J1G3   57 VSS<68> SCONN288_H44441004_PIP-SCONN,HA   I185 @BASEBOARD_FAB2_LIB.BASEBOARD_FAB2(SCH_1):PAGE81
  J1G3   55 VSS<69> SCONN288_H44441004_PIP-SCONN,HA   I185 @BASEBOARD_FAB2_LIB.BASEBOARD_FAB2(SCH_1):PAGE81
  J1G3   53 VSS<70> SCONN288_H44441004_PIP-SCONN,HA   I185 @BASEBOARD_FAB2_LIB.BASEBOARD_FAB2(SCH_1):PAGE81
  J1G3   50 VSS<71> SCONN288_H44441004_PIP-SCONN,HA   I185 @BASEBOARD_FAB2_LIB.BASEBOARD_FAB2(SCH_1):PAGE81
  J1G3   48 VSS<72> SCONN288_H44441004_PIP-SCONN,HA   I185 @BASEBOARD_FAB2_LIB.BASEBOARD_FAB2(SCH_1):PAGE81
  J1G3   46 VSS<73> SCONN288_H44441004_PIP-SCONN,HA   I185 @BASEBOARD_FAB2_LIB.BASEBOARD_FAB2(SCH_1):PAGE81
  J1G3   44 VSS<74> SCONN288_H44441004_PIP-SCONN,HA   I185 @BASEBOARD_FAB2_LIB.BASEBOARD_FAB2(SCH_1):PAGE81
  J1G3   42 VSS<75> SCONN288_H44441004_PIP-SCONN,HA   I185 @BASEBOARD_FAB2_LIB.BASEBOARD_FAB2(SCH_1):PAGE81
  J1G3   39 VSS<76> SCONN288_H44441004_PIP-SCONN,HA   I185 @BASEBOARD_FAB2_LIB.BASEBOARD_FAB2(SCH_1):PAGE81
  J1G3   37 VSS<77> SCONN288_H44441004_PIP-SCONN,HA   I185 @BASEBOARD_FAB2_LIB.BASEBOARD_FAB2(SCH_1):PAGE81
  J1G3   35 VSS<78> SCONN288_H44441004_PIP-SCONN,HA   I185 @BASEBOARD_FAB2_LIB.BASEBOARD_FAB2(SCH_1):PAGE81
  J1G3   33 VSS<79> SCONN288_H44441004_PIP-SCONN,HA   I185 @BASEBOARD_FAB2_LIB.BASEBOARD_FAB2(SCH_1):PAGE81
  J1G3   31 VSS<80> SCONN288_H44441004_PIP-SCONN,HA   I185 @BASEBOARD_FAB2_LIB.BASEBOARD_FAB2(SCH_1):PAGE81
  J1G3   28 VSS<81> SCONN288_H44441004_PIP-SCONN,HA   I185 @BASEBOARD_FAB2_LIB.BASEBOARD_FAB2(SCH_1):PAGE81
  J1G3   26 VSS<82> SCONN288_H44441004_PIP-SCONN,HA   I185 @BASEBOARD_FAB2_LIB.BASEBOARD_FAB2(SCH_1):PAGE81
  J1G3   24 VSS<83> SCONN288_H44441004_PIP-SCONN,HA   I185 @BASEBOARD_FAB2_LIB.BASEBOARD_FAB2(SCH_1):PAGE81
  J1G3   22 VSS<84> SCONN288_H44441004_PIP-SCONN,HA   I185 @BASEBOARD_FAB2_LIB.BASEBOARD_FAB2(SCH_1):PAGE81
  J1G3   20 VSS<85> SCONN288_H44441004_PIP-SCONN,HA   I185 @BASEBOARD_FAB2_LIB.BASEBOARD_FAB2(SCH_1):PAGE81
  J1G3   17 VSS<86> SCONN288_H44441004_PIP-SCONN,HA   I185 @BASEBOARD_FAB2_LIB.BASEBOARD_FAB2(SCH_1):PAGE81
  J1G3   15 VSS<87> SCONN288_H44441004_PIP-SCONN,HA   I185 @BASEBOARD_FAB2_LIB.BASEBOARD_FAB2(SCH_1):PAGE81
  J1G3   13 VSS<88> SCONN288_H44441004_PIP-SCONN,HA   I185 @BASEBOARD_FAB2_LIB.BASEBOARD_FAB2(SCH_1):PAGE81
  J1G3   11 VSS<89> SCONN288_H44441004_PIP-SCONN,HA   I185 @BASEBOARD_FAB2_LIB.BASEBOARD_FAB2(SCH_1):PAGE81
  J1G3    9 VSS<90> SCONN288_H44441004_PIP-SCONN,HA   I185 @BASEBOARD_FAB2_LIB.BASEBOARD_FAB2(SCH_1):PAGE81
  J1G3    6 VSS<91> SCONN288_H44441004_PIP-SCONN,HA   I185 @BASEBOARD_FAB2_LIB.BASEBOARD_FAB2(SCH_1):PAGE81
  J1G3    4 VSS<92> SCONN288_H44441004_PIP-SCONN,HA   I185 @BASEBOARD_FAB2_LIB.BASEBOARD_FAB2(SCH_1):PAGE81
  J1G3    2 VSS<93> SCONN288_H44441004_PIP-SCONN,HA   I185 @BASEBOARD_FAB2_LIB.BASEBOARD_FAB2(SCH_1):PAGE81
  J1G3  139  SA<0> SCONN288_H44441004_PIP-SCONN,HA   I186 @BASEBOARD_FAB2_LIB.BASEBOARD_FAB2(SCH_1):PAGE81
  J1G3  140  SA<1> SCONN288_H44441004_PIP-SCONN,HA   I186 @BASEBOARD_FAB2_LIB.BASEBOARD_FAB2(SCH_1):PAGE81
 C1G19    2      B CAP_A_0402V-0.01UF,25V,10%,X7RA   I180 @BASEBOARD_FAB2_LIB.BASEBOARD_FAB2(SCH_1):PAGE82
  J9U2  140  SA<1> SCONN288_H44441003_PIP-SCONN,HA   I187 @BASEBOARD_FAB2_LIB.BASEBOARD_FAB2(SCH_1):PAGE82
  J9U2  283 VSS<0> SCONN288_H44441003_PIP-SCONN,HA   I188 @BASEBOARD_FAB2_LIB.BASEBOARD_FAB2(SCH_1):PAGE82
  J9U2  281 VSS<1> SCONN288_H44441003_PIP-SCONN,HA   I188 @BASEBOARD_FAB2_LIB.BASEBOARD_FAB2(SCH_1):PAGE82
  J9U2  279 VSS<2> SCONN288_H44441003_PIP-SCONN,HA   I188 @BASEBOARD_FAB2_LIB.BASEBOARD_FAB2(SCH_1):PAGE82
  J9U2  276 VSS<3> SCONN288_H44441003_PIP-SCONN,HA   I188 @BASEBOARD_FAB2_LIB.BASEBOARD_FAB2(SCH_1):PAGE82
  J9U2  274 VSS<4> SCONN288_H44441003_PIP-SCONN,HA   I188 @BASEBOARD_FAB2_LIB.BASEBOARD_FAB2(SCH_1):PAGE82
  J9U2  272 VSS<5> SCONN288_H44441003_PIP-SCONN,HA   I188 @BASEBOARD_FAB2_LIB.BASEBOARD_FAB2(SCH_1):PAGE82
  J9U2  270 VSS<6> SCONN288_H44441003_PIP-SCONN,HA   I188 @BASEBOARD_FAB2_LIB.BASEBOARD_FAB2(SCH_1):PAGE82
  J9U2  268 VSS<7> SCONN288_H44441003_PIP-SCONN,HA   I188 @BASEBOARD_FAB2_LIB.BASEBOARD_FAB2(SCH_1):PAGE82
  J9U2  265 VSS<8> SCONN288_H44441003_PIP-SCONN,HA   I188 @BASEBOARD_FAB2_LIB.BASEBOARD_FAB2(SCH_1):PAGE82
  J9U2  263 VSS<9> SCONN288_H44441003_PIP-SCONN,HA   I188 @BASEBOARD_FAB2_LIB.BASEBOARD_FAB2(SCH_1):PAGE82
  J9U2  261 VSS<10> SCONN288_H44441003_PIP-SCONN,HA   I188 @BASEBOARD_FAB2_LIB.BASEBOARD_FAB2(SCH_1):PAGE82
  J9U2  259 VSS<11> SCONN288_H44441003_PIP-SCONN,HA   I188 @BASEBOARD_FAB2_LIB.BASEBOARD_FAB2(SCH_1):PAGE82
  J9U2  257 VSS<12> SCONN288_H44441003_PIP-SCONN,HA   I188 @BASEBOARD_FAB2_LIB.BASEBOARD_FAB2(SCH_1):PAGE82
  J9U2  254 VSS<13> SCONN288_H44441003_PIP-SCONN,HA   I188 @BASEBOARD_FAB2_LIB.BASEBOARD_FAB2(SCH_1):PAGE82
  J9U2  252 VSS<14> SCONN288_H44441003_PIP-SCONN,HA   I188 @BASEBOARD_FAB2_LIB.BASEBOARD_FAB2(SCH_1):PAGE82
  J9U2  250 VSS<15> SCONN288_H44441003_PIP-SCONN,HA   I188 @BASEBOARD_FAB2_LIB.BASEBOARD_FAB2(SCH_1):PAGE82
  J9U2  248 VSS<16> SCONN288_H44441003_PIP-SCONN,HA   I188 @BASEBOARD_FAB2_LIB.BASEBOARD_FAB2(SCH_1):PAGE82
  J9U2  246 VSS<17> SCONN288_H44441003_PIP-SCONN,HA   I188 @BASEBOARD_FAB2_LIB.BASEBOARD_FAB2(SCH_1):PAGE82
  J9U2  243 VSS<18> SCONN288_H44441003_PIP-SCONN,HA   I188 @BASEBOARD_FAB2_LIB.BASEBOARD_FAB2(SCH_1):PAGE82
  J9U2  241 VSS<19> SCONN288_H44441003_PIP-SCONN,HA   I188 @BASEBOARD_FAB2_LIB.BASEBOARD_FAB2(SCH_1):PAGE82
  J9U2  239 VSS<20> SCONN288_H44441003_PIP-SCONN,HA   I188 @BASEBOARD_FAB2_LIB.BASEBOARD_FAB2(SCH_1):PAGE82
  J9U2  202 VSS<21> SCONN288_H44441003_PIP-SCONN,HA   I188 @BASEBOARD_FAB2_LIB.BASEBOARD_FAB2(SCH_1):PAGE82
  J9U2  200 VSS<22> SCONN288_H44441003_PIP-SCONN,HA   I188 @BASEBOARD_FAB2_LIB.BASEBOARD_FAB2(SCH_1):PAGE82
  J9U2  198 VSS<23> SCONN288_H44441003_PIP-SCONN,HA   I188 @BASEBOARD_FAB2_LIB.BASEBOARD_FAB2(SCH_1):PAGE82
  J9U2  195 VSS<24> SCONN288_H44441003_PIP-SCONN,HA   I188 @BASEBOARD_FAB2_LIB.BASEBOARD_FAB2(SCH_1):PAGE82
  J9U2  193 VSS<25> SCONN288_H44441003_PIP-SCONN,HA   I188 @BASEBOARD_FAB2_LIB.BASEBOARD_FAB2(SCH_1):PAGE82
  J9U2  191 VSS<26> SCONN288_H44441003_PIP-SCONN,HA   I188 @BASEBOARD_FAB2_LIB.BASEBOARD_FAB2(SCH_1):PAGE82
  J9U2  189 VSS<27> SCONN288_H44441003_PIP-SCONN,HA   I188 @BASEBOARD_FAB2_LIB.BASEBOARD_FAB2(SCH_1):PAGE82
  J9U2  187 VSS<28> SCONN288_H44441003_PIP-SCONN,HA   I188 @BASEBOARD_FAB2_LIB.BASEBOARD_FAB2(SCH_1):PAGE82
  J9U2  184 VSS<29> SCONN288_H44441003_PIP-SCONN,HA   I188 @BASEBOARD_FAB2_LIB.BASEBOARD_FAB2(SCH_1):PAGE82
  J9U2  182 VSS<30> SCONN288_H44441003_PIP-SCONN,HA   I188 @BASEBOARD_FAB2_LIB.BASEBOARD_FAB2(SCH_1):PAGE82
  J9U2  180 VSS<31> SCONN288_H44441003_PIP-SCONN,HA   I188 @BASEBOARD_FAB2_LIB.BASEBOARD_FAB2(SCH_1):PAGE82
  J9U2  178 VSS<32> SCONN288_H44441003_PIP-SCONN,HA   I188 @BASEBOARD_FAB2_LIB.BASEBOARD_FAB2(SCH_1):PAGE82
  J9U2  176 VSS<33> SCONN288_H44441003_PIP-SCONN,HA   I188 @BASEBOARD_FAB2_LIB.BASEBOARD_FAB2(SCH_1):PAGE82
  J9U2  173 VSS<34> SCONN288_H44441003_PIP-SCONN,HA   I188 @BASEBOARD_FAB2_LIB.BASEBOARD_FAB2(SCH_1):PAGE82
  J9U2  171 VSS<35> SCONN288_H44441003_PIP-SCONN,HA   I188 @BASEBOARD_FAB2_LIB.BASEBOARD_FAB2(SCH_1):PAGE82
  J9U2  169 VSS<36> SCONN288_H44441003_PIP-SCONN,HA   I188 @BASEBOARD_FAB2_LIB.BASEBOARD_FAB2(SCH_1):PAGE82
  J9U2  167 VSS<37> SCONN288_H44441003_PIP-SCONN,HA   I188 @BASEBOARD_FAB2_LIB.BASEBOARD_FAB2(SCH_1):PAGE82
  J9U2  165 VSS<38> SCONN288_H44441003_PIP-SCONN,HA   I188 @BASEBOARD_FAB2_LIB.BASEBOARD_FAB2(SCH_1):PAGE82
  J9U2  162 VSS<39> SCONN288_H44441003_PIP-SCONN,HA   I188 @BASEBOARD_FAB2_LIB.BASEBOARD_FAB2(SCH_1):PAGE82
  J9U2  160 VSS<40> SCONN288_H44441003_PIP-SCONN,HA   I188 @BASEBOARD_FAB2_LIB.BASEBOARD_FAB2(SCH_1):PAGE82
  J9U2  158 VSS<41> SCONN288_H44441003_PIP-SCONN,HA   I188 @BASEBOARD_FAB2_LIB.BASEBOARD_FAB2(SCH_1):PAGE82
  J9U2  156 VSS<42> SCONN288_H44441003_PIP-SCONN,HA   I188 @BASEBOARD_FAB2_LIB.BASEBOARD_FAB2(SCH_1):PAGE82
  J9U2  154 VSS<43> SCONN288_H44441003_PIP-SCONN,HA   I188 @BASEBOARD_FAB2_LIB.BASEBOARD_FAB2(SCH_1):PAGE82
  J9U2  151 VSS<44> SCONN288_H44441003_PIP-SCONN,HA   I188 @BASEBOARD_FAB2_LIB.BASEBOARD_FAB2(SCH_1):PAGE82
  J9U2  149 VSS<45> SCONN288_H44441003_PIP-SCONN,HA   I188 @BASEBOARD_FAB2_LIB.BASEBOARD_FAB2(SCH_1):PAGE82
  J9U2  147 VSS<46> SCONN288_H44441003_PIP-SCONN,HA   I188 @BASEBOARD_FAB2_LIB.BASEBOARD_FAB2(SCH_1):PAGE82
  J9U2  138 VSS<47> SCONN288_H44441003_PIP-SCONN,HA   I188 @BASEBOARD_FAB2_LIB.BASEBOARD_FAB2(SCH_1):PAGE82
  J9U2  136 VSS<48> SCONN288_H44441003_PIP-SCONN,HA   I188 @BASEBOARD_FAB2_LIB.BASEBOARD_FAB2(SCH_1):PAGE82
  J9U2  134 VSS<49> SCONN288_H44441003_PIP-SCONN,HA   I188 @BASEBOARD_FAB2_LIB.BASEBOARD_FAB2(SCH_1):PAGE82
  J9U2  131 VSS<50> SCONN288_H44441003_PIP-SCONN,HA   I188 @BASEBOARD_FAB2_LIB.BASEBOARD_FAB2(SCH_1):PAGE82
  J9U2  129 VSS<51> SCONN288_H44441003_PIP-SCONN,HA   I188 @BASEBOARD_FAB2_LIB.BASEBOARD_FAB2(SCH_1):PAGE82
  J9U2  127 VSS<52> SCONN288_H44441003_PIP-SCONN,HA   I188 @BASEBOARD_FAB2_LIB.BASEBOARD_FAB2(SCH_1):PAGE82
  J9U2  125 VSS<53> SCONN288_H44441003_PIP-SCONN,HA   I188 @BASEBOARD_FAB2_LIB.BASEBOARD_FAB2(SCH_1):PAGE82
  J9U2  123 VSS<54> SCONN288_H44441003_PIP-SCONN,HA   I188 @BASEBOARD_FAB2_LIB.BASEBOARD_FAB2(SCH_1):PAGE82
  J9U2  120 VSS<55> SCONN288_H44441003_PIP-SCONN,HA   I188 @BASEBOARD_FAB2_LIB.BASEBOARD_FAB2(SCH_1):PAGE82
  J9U2  118 VSS<56> SCONN288_H44441003_PIP-SCONN,HA   I188 @BASEBOARD_FAB2_LIB.BASEBOARD_FAB2(SCH_1):PAGE82
  J9U2  116 VSS<57> SCONN288_H44441003_PIP-SCONN,HA   I188 @BASEBOARD_FAB2_LIB.BASEBOARD_FAB2(SCH_1):PAGE82
  J9U2  114 VSS<58> SCONN288_H44441003_PIP-SCONN,HA   I188 @BASEBOARD_FAB2_LIB.BASEBOARD_FAB2(SCH_1):PAGE82
  J9U2  112 VSS<59> SCONN288_H44441003_PIP-SCONN,HA   I188 @BASEBOARD_FAB2_LIB.BASEBOARD_FAB2(SCH_1):PAGE82
  J9U2  109 VSS<60> SCONN288_H44441003_PIP-SCONN,HA   I188 @BASEBOARD_FAB2_LIB.BASEBOARD_FAB2(SCH_1):PAGE82
  J9U2  107 VSS<61> SCONN288_H44441003_PIP-SCONN,HA   I188 @BASEBOARD_FAB2_LIB.BASEBOARD_FAB2(SCH_1):PAGE82
  J9U2  105 VSS<62> SCONN288_H44441003_PIP-SCONN,HA   I188 @BASEBOARD_FAB2_LIB.BASEBOARD_FAB2(SCH_1):PAGE82
  J9U2  103 VSS<63> SCONN288_H44441003_PIP-SCONN,HA   I188 @BASEBOARD_FAB2_LIB.BASEBOARD_FAB2(SCH_1):PAGE82
  J9U2  101 VSS<64> SCONN288_H44441003_PIP-SCONN,HA   I188 @BASEBOARD_FAB2_LIB.BASEBOARD_FAB2(SCH_1):PAGE82
  J9U2   98 VSS<65> SCONN288_H44441003_PIP-SCONN,HA   I188 @BASEBOARD_FAB2_LIB.BASEBOARD_FAB2(SCH_1):PAGE82
  J9U2   96 VSS<66> SCONN288_H44441003_PIP-SCONN,HA   I188 @BASEBOARD_FAB2_LIB.BASEBOARD_FAB2(SCH_1):PAGE82
  J9U2   94 VSS<67> SCONN288_H44441003_PIP-SCONN,HA   I188 @BASEBOARD_FAB2_LIB.BASEBOARD_FAB2(SCH_1):PAGE82
  J9U2   57 VSS<68> SCONN288_H44441003_PIP-SCONN,HA   I188 @BASEBOARD_FAB2_LIB.BASEBOARD_FAB2(SCH_1):PAGE82
  J9U2   55 VSS<69> SCONN288_H44441003_PIP-SCONN,HA   I188 @BASEBOARD_FAB2_LIB.BASEBOARD_FAB2(SCH_1):PAGE82
  J9U2   53 VSS<70> SCONN288_H44441003_PIP-SCONN,HA   I188 @BASEBOARD_FAB2_LIB.BASEBOARD_FAB2(SCH_1):PAGE82
  J9U2   50 VSS<71> SCONN288_H44441003_PIP-SCONN,HA   I188 @BASEBOARD_FAB2_LIB.BASEBOARD_FAB2(SCH_1):PAGE82
  J9U2   48 VSS<72> SCONN288_H44441003_PIP-SCONN,HA   I188 @BASEBOARD_FAB2_LIB.BASEBOARD_FAB2(SCH_1):PAGE82
  J9U2   46 VSS<73> SCONN288_H44441003_PIP-SCONN,HA   I188 @BASEBOARD_FAB2_LIB.BASEBOARD_FAB2(SCH_1):PAGE82
  J9U2   44 VSS<74> SCONN288_H44441003_PIP-SCONN,HA   I188 @BASEBOARD_FAB2_LIB.BASEBOARD_FAB2(SCH_1):PAGE82
  J9U2   42 VSS<75> SCONN288_H44441003_PIP-SCONN,HA   I188 @BASEBOARD_FAB2_LIB.BASEBOARD_FAB2(SCH_1):PAGE82
  J9U2   39 VSS<76> SCONN288_H44441003_PIP-SCONN,HA   I188 @BASEBOARD_FAB2_LIB.BASEBOARD_FAB2(SCH_1):PAGE82
  J9U2   37 VSS<77> SCONN288_H44441003_PIP-SCONN,HA   I188 @BASEBOARD_FAB2_LIB.BASEBOARD_FAB2(SCH_1):PAGE82
  J9U2   35 VSS<78> SCONN288_H44441003_PIP-SCONN,HA   I188 @BASEBOARD_FAB2_LIB.BASEBOARD_FAB2(SCH_1):PAGE82
  J9U2   33 VSS<79> SCONN288_H44441003_PIP-SCONN,HA   I188 @BASEBOARD_FAB2_LIB.BASEBOARD_FAB2(SCH_1):PAGE82
  J9U2   31 VSS<80> SCONN288_H44441003_PIP-SCONN,HA   I188 @BASEBOARD_FAB2_LIB.BASEBOARD_FAB2(SCH_1):PAGE82
  J9U2   28 VSS<81> SCONN288_H44441003_PIP-SCONN,HA   I188 @BASEBOARD_FAB2_LIB.BASEBOARD_FAB2(SCH_1):PAGE82
  J9U2   26 VSS<82> SCONN288_H44441003_PIP-SCONN,HA   I188 @BASEBOARD_FAB2_LIB.BASEBOARD_FAB2(SCH_1):PAGE82
  J9U2   24 VSS<83> SCONN288_H44441003_PIP-SCONN,HA   I188 @BASEBOARD_FAB2_LIB.BASEBOARD_FAB2(SCH_1):PAGE82
  J9U2   22 VSS<84> SCONN288_H44441003_PIP-SCONN,HA   I188 @BASEBOARD_FAB2_LIB.BASEBOARD_FAB2(SCH_1):PAGE82
  J9U2   20 VSS<85> SCONN288_H44441003_PIP-SCONN,HA   I188 @BASEBOARD_FAB2_LIB.BASEBOARD_FAB2(SCH_1):PAGE82
  J9U2   17 VSS<86> SCONN288_H44441003_PIP-SCONN,HA   I188 @BASEBOARD_FAB2_LIB.BASEBOARD_FAB2(SCH_1):PAGE82
  J9U2   15 VSS<87> SCONN288_H44441003_PIP-SCONN,HA   I188 @BASEBOARD_FAB2_LIB.BASEBOARD_FAB2(SCH_1):PAGE82
  J9U2   13 VSS<88> SCONN288_H44441003_PIP-SCONN,HA   I188 @BASEBOARD_FAB2_LIB.BASEBOARD_FAB2(SCH_1):PAGE82
  J9U2   11 VSS<89> SCONN288_H44441003_PIP-SCONN,HA   I188 @BASEBOARD_FAB2_LIB.BASEBOARD_FAB2(SCH_1):PAGE82
  J9U2    9 VSS<90> SCONN288_H44441003_PIP-SCONN,HA   I188 @BASEBOARD_FAB2_LIB.BASEBOARD_FAB2(SCH_1):PAGE82
  J9U2    6 VSS<91> SCONN288_H44441003_PIP-SCONN,HA   I188 @BASEBOARD_FAB2_LIB.BASEBOARD_FAB2(SCH_1):PAGE82
  J9U2    4 VSS<92> SCONN288_H44441003_PIP-SCONN,HA   I188 @BASEBOARD_FAB2_LIB.BASEBOARD_FAB2(SCH_1):PAGE82
  J9U2    2 VSS<93> SCONN288_H44441003_PIP-SCONN,HA   I188 @BASEBOARD_FAB2_LIB.BASEBOARD_FAB2(SCH_1):PAGE82
  J1B1  283 VSS<0> SCONN288_H44441004_PIP-SCONN,HA    I43 @BASEBOARD_FAB2_LIB.BASEBOARD_FAB2(SCH_1):PAGE83
  J1B1  281 VSS<1> SCONN288_H44441004_PIP-SCONN,HA    I43 @BASEBOARD_FAB2_LIB.BASEBOARD_FAB2(SCH_1):PAGE83
  J1B1  279 VSS<2> SCONN288_H44441004_PIP-SCONN,HA    I43 @BASEBOARD_FAB2_LIB.BASEBOARD_FAB2(SCH_1):PAGE83
  J1B1  276 VSS<3> SCONN288_H44441004_PIP-SCONN,HA    I43 @BASEBOARD_FAB2_LIB.BASEBOARD_FAB2(SCH_1):PAGE83
  J1B1  274 VSS<4> SCONN288_H44441004_PIP-SCONN,HA    I43 @BASEBOARD_FAB2_LIB.BASEBOARD_FAB2(SCH_1):PAGE83
  J1B1  272 VSS<5> SCONN288_H44441004_PIP-SCONN,HA    I43 @BASEBOARD_FAB2_LIB.BASEBOARD_FAB2(SCH_1):PAGE83
  J1B1  270 VSS<6> SCONN288_H44441004_PIP-SCONN,HA    I43 @BASEBOARD_FAB2_LIB.BASEBOARD_FAB2(SCH_1):PAGE83
  J1B1  268 VSS<7> SCONN288_H44441004_PIP-SCONN,HA    I43 @BASEBOARD_FAB2_LIB.BASEBOARD_FAB2(SCH_1):PAGE83
  J1B1  265 VSS<8> SCONN288_H44441004_PIP-SCONN,HA    I43 @BASEBOARD_FAB2_LIB.BASEBOARD_FAB2(SCH_1):PAGE83
  J1B1  263 VSS<9> SCONN288_H44441004_PIP-SCONN,HA    I43 @BASEBOARD_FAB2_LIB.BASEBOARD_FAB2(SCH_1):PAGE83
  J1B1  261 VSS<10> SCONN288_H44441004_PIP-SCONN,HA    I43 @BASEBOARD_FAB2_LIB.BASEBOARD_FAB2(SCH_1):PAGE83
  J1B1  259 VSS<11> SCONN288_H44441004_PIP-SCONN,HA    I43 @BASEBOARD_FAB2_LIB.BASEBOARD_FAB2(SCH_1):PAGE83
  J1B1  257 VSS<12> SCONN288_H44441004_PIP-SCONN,HA    I43 @BASEBOARD_FAB2_LIB.BASEBOARD_FAB2(SCH_1):PAGE83
  J1B1  254 VSS<13> SCONN288_H44441004_PIP-SCONN,HA    I43 @BASEBOARD_FAB2_LIB.BASEBOARD_FAB2(SCH_1):PAGE83
  J1B1  252 VSS<14> SCONN288_H44441004_PIP-SCONN,HA    I43 @BASEBOARD_FAB2_LIB.BASEBOARD_FAB2(SCH_1):PAGE83
  J1B1  250 VSS<15> SCONN288_H44441004_PIP-SCONN,HA    I43 @BASEBOARD_FAB2_LIB.BASEBOARD_FAB2(SCH_1):PAGE83
  J1B1  248 VSS<16> SCONN288_H44441004_PIP-SCONN,HA    I43 @BASEBOARD_FAB2_LIB.BASEBOARD_FAB2(SCH_1):PAGE83
  J1B1  246 VSS<17> SCONN288_H44441004_PIP-SCONN,HA    I43 @BASEBOARD_FAB2_LIB.BASEBOARD_FAB2(SCH_1):PAGE83
  J1B1  243 VSS<18> SCONN288_H44441004_PIP-SCONN,HA    I43 @BASEBOARD_FAB2_LIB.BASEBOARD_FAB2(SCH_1):PAGE83
  J1B1  241 VSS<19> SCONN288_H44441004_PIP-SCONN,HA    I43 @BASEBOARD_FAB2_LIB.BASEBOARD_FAB2(SCH_1):PAGE83
  J1B1  239 VSS<20> SCONN288_H44441004_PIP-SCONN,HA    I43 @BASEBOARD_FAB2_LIB.BASEBOARD_FAB2(SCH_1):PAGE83
  J1B1  202 VSS<21> SCONN288_H44441004_PIP-SCONN,HA    I43 @BASEBOARD_FAB2_LIB.BASEBOARD_FAB2(SCH_1):PAGE83
  J1B1  200 VSS<22> SCONN288_H44441004_PIP-SCONN,HA    I43 @BASEBOARD_FAB2_LIB.BASEBOARD_FAB2(SCH_1):PAGE83
  J1B1  198 VSS<23> SCONN288_H44441004_PIP-SCONN,HA    I43 @BASEBOARD_FAB2_LIB.BASEBOARD_FAB2(SCH_1):PAGE83
  J1B1  195 VSS<24> SCONN288_H44441004_PIP-SCONN,HA    I43 @BASEBOARD_FAB2_LIB.BASEBOARD_FAB2(SCH_1):PAGE83
  J1B1  193 VSS<25> SCONN288_H44441004_PIP-SCONN,HA    I43 @BASEBOARD_FAB2_LIB.BASEBOARD_FAB2(SCH_1):PAGE83
  J1B1  191 VSS<26> SCONN288_H44441004_PIP-SCONN,HA    I43 @BASEBOARD_FAB2_LIB.BASEBOARD_FAB2(SCH_1):PAGE83
  J1B1  189 VSS<27> SCONN288_H44441004_PIP-SCONN,HA    I43 @BASEBOARD_FAB2_LIB.BASEBOARD_FAB2(SCH_1):PAGE83
  J1B1  187 VSS<28> SCONN288_H44441004_PIP-SCONN,HA    I43 @BASEBOARD_FAB2_LIB.BASEBOARD_FAB2(SCH_1):PAGE83
  J1B1  184 VSS<29> SCONN288_H44441004_PIP-SCONN,HA    I43 @BASEBOARD_FAB2_LIB.BASEBOARD_FAB2(SCH_1):PAGE83
  J1B1  182 VSS<30> SCONN288_H44441004_PIP-SCONN,HA    I43 @BASEBOARD_FAB2_LIB.BASEBOARD_FAB2(SCH_1):PAGE83
  J1B1  180 VSS<31> SCONN288_H44441004_PIP-SCONN,HA    I43 @BASEBOARD_FAB2_LIB.BASEBOARD_FAB2(SCH_1):PAGE83
  J1B1  178 VSS<32> SCONN288_H44441004_PIP-SCONN,HA    I43 @BASEBOARD_FAB2_LIB.BASEBOARD_FAB2(SCH_1):PAGE83
  J1B1  176 VSS<33> SCONN288_H44441004_PIP-SCONN,HA    I43 @BASEBOARD_FAB2_LIB.BASEBOARD_FAB2(SCH_1):PAGE83
  J1B1  173 VSS<34> SCONN288_H44441004_PIP-SCONN,HA    I43 @BASEBOARD_FAB2_LIB.BASEBOARD_FAB2(SCH_1):PAGE83
  J1B1  171 VSS<35> SCONN288_H44441004_PIP-SCONN,HA    I43 @BASEBOARD_FAB2_LIB.BASEBOARD_FAB2(SCH_1):PAGE83
  J1B1  169 VSS<36> SCONN288_H44441004_PIP-SCONN,HA    I43 @BASEBOARD_FAB2_LIB.BASEBOARD_FAB2(SCH_1):PAGE83
  J1B1  167 VSS<37> SCONN288_H44441004_PIP-SCONN,HA    I43 @BASEBOARD_FAB2_LIB.BASEBOARD_FAB2(SCH_1):PAGE83
  J1B1  165 VSS<38> SCONN288_H44441004_PIP-SCONN,HA    I43 @BASEBOARD_FAB2_LIB.BASEBOARD_FAB2(SCH_1):PAGE83
  J1B1  162 VSS<39> SCONN288_H44441004_PIP-SCONN,HA    I43 @BASEBOARD_FAB2_LIB.BASEBOARD_FAB2(SCH_1):PAGE83
  J1B1  160 VSS<40> SCONN288_H44441004_PIP-SCONN,HA    I43 @BASEBOARD_FAB2_LIB.BASEBOARD_FAB2(SCH_1):PAGE83
  J1B1  158 VSS<41> SCONN288_H44441004_PIP-SCONN,HA    I43 @BASEBOARD_FAB2_LIB.BASEBOARD_FAB2(SCH_1):PAGE83
  J1B1  156 VSS<42> SCONN288_H44441004_PIP-SCONN,HA    I43 @BASEBOARD_FAB2_LIB.BASEBOARD_FAB2(SCH_1):PAGE83
  J1B1  154 VSS<43> SCONN288_H44441004_PIP-SCONN,HA    I43 @BASEBOARD_FAB2_LIB.BASEBOARD_FAB2(SCH_1):PAGE83
  J1B1  151 VSS<44> SCONN288_H44441004_PIP-SCONN,HA    I43 @BASEBOARD_FAB2_LIB.BASEBOARD_FAB2(SCH_1):PAGE83
  J1B1  149 VSS<45> SCONN288_H44441004_PIP-SCONN,HA    I43 @BASEBOARD_FAB2_LIB.BASEBOARD_FAB2(SCH_1):PAGE83
  J1B1  147 VSS<46> SCONN288_H44441004_PIP-SCONN,HA    I43 @BASEBOARD_FAB2_LIB.BASEBOARD_FAB2(SCH_1):PAGE83
  J1B1  138 VSS<47> SCONN288_H44441004_PIP-SCONN,HA    I43 @BASEBOARD_FAB2_LIB.BASEBOARD_FAB2(SCH_1):PAGE83
  J1B1  136 VSS<48> SCONN288_H44441004_PIP-SCONN,HA    I43 @BASEBOARD_FAB2_LIB.BASEBOARD_FAB2(SCH_1):PAGE83
  J1B1  134 VSS<49> SCONN288_H44441004_PIP-SCONN,HA    I43 @BASEBOARD_FAB2_LIB.BASEBOARD_FAB2(SCH_1):PAGE83
  J1B1  131 VSS<50> SCONN288_H44441004_PIP-SCONN,HA    I43 @BASEBOARD_FAB2_LIB.BASEBOARD_FAB2(SCH_1):PAGE83
  J1B1  129 VSS<51> SCONN288_H44441004_PIP-SCONN,HA    I43 @BASEBOARD_FAB2_LIB.BASEBOARD_FAB2(SCH_1):PAGE83
  J1B1  127 VSS<52> SCONN288_H44441004_PIP-SCONN,HA    I43 @BASEBOARD_FAB2_LIB.BASEBOARD_FAB2(SCH_1):PAGE83
  J1B1  125 VSS<53> SCONN288_H44441004_PIP-SCONN,HA    I43 @BASEBOARD_FAB2_LIB.BASEBOARD_FAB2(SCH_1):PAGE83
  J1B1  123 VSS<54> SCONN288_H44441004_PIP-SCONN,HA    I43 @BASEBOARD_FAB2_LIB.BASEBOARD_FAB2(SCH_1):PAGE83
  J1B1  120 VSS<55> SCONN288_H44441004_PIP-SCONN,HA    I43 @BASEBOARD_FAB2_LIB.BASEBOARD_FAB2(SCH_1):PAGE83
  J1B1  118 VSS<56> SCONN288_H44441004_PIP-SCONN,HA    I43 @BASEBOARD_FAB2_LIB.BASEBOARD_FAB2(SCH_1):PAGE83
  J1B1  116 VSS<57> SCONN288_H44441004_PIP-SCONN,HA    I43 @BASEBOARD_FAB2_LIB.BASEBOARD_FAB2(SCH_1):PAGE83
  J1B1  114 VSS<58> SCONN288_H44441004_PIP-SCONN,HA    I43 @BASEBOARD_FAB2_LIB.BASEBOARD_FAB2(SCH_1):PAGE83
  J1B1  112 VSS<59> SCONN288_H44441004_PIP-SCONN,HA    I43 @BASEBOARD_FAB2_LIB.BASEBOARD_FAB2(SCH_1):PAGE83
  J1B1  109 VSS<60> SCONN288_H44441004_PIP-SCONN,HA    I43 @BASEBOARD_FAB2_LIB.BASEBOARD_FAB2(SCH_1):PAGE83
  J1B1  107 VSS<61> SCONN288_H44441004_PIP-SCONN,HA    I43 @BASEBOARD_FAB2_LIB.BASEBOARD_FAB2(SCH_1):PAGE83
  J1B1  105 VSS<62> SCONN288_H44441004_PIP-SCONN,HA    I43 @BASEBOARD_FAB2_LIB.BASEBOARD_FAB2(SCH_1):PAGE83
  J1B1  103 VSS<63> SCONN288_H44441004_PIP-SCONN,HA    I43 @BASEBOARD_FAB2_LIB.BASEBOARD_FAB2(SCH_1):PAGE83
  J1B1  101 VSS<64> SCONN288_H44441004_PIP-SCONN,HA    I43 @BASEBOARD_FAB2_LIB.BASEBOARD_FAB2(SCH_1):PAGE83
  J1B1   98 VSS<65> SCONN288_H44441004_PIP-SCONN,HA    I43 @BASEBOARD_FAB2_LIB.BASEBOARD_FAB2(SCH_1):PAGE83
  J1B1   96 VSS<66> SCONN288_H44441004_PIP-SCONN,HA    I43 @BASEBOARD_FAB2_LIB.BASEBOARD_FAB2(SCH_1):PAGE83
  J1B1   94 VSS<67> SCONN288_H44441004_PIP-SCONN,HA    I43 @BASEBOARD_FAB2_LIB.BASEBOARD_FAB2(SCH_1):PAGE83
  J1B1   57 VSS<68> SCONN288_H44441004_PIP-SCONN,HA    I43 @BASEBOARD_FAB2_LIB.BASEBOARD_FAB2(SCH_1):PAGE83
  J1B1   55 VSS<69> SCONN288_H44441004_PIP-SCONN,HA    I43 @BASEBOARD_FAB2_LIB.BASEBOARD_FAB2(SCH_1):PAGE83
  J1B1   53 VSS<70> SCONN288_H44441004_PIP-SCONN,HA    I43 @BASEBOARD_FAB2_LIB.BASEBOARD_FAB2(SCH_1):PAGE83
  J1B1   50 VSS<71> SCONN288_H44441004_PIP-SCONN,HA    I43 @BASEBOARD_FAB2_LIB.BASEBOARD_FAB2(SCH_1):PAGE83
  J1B1   48 VSS<72> SCONN288_H44441004_PIP-SCONN,HA    I43 @BASEBOARD_FAB2_LIB.BASEBOARD_FAB2(SCH_1):PAGE83
  J1B1   46 VSS<73> SCONN288_H44441004_PIP-SCONN,HA    I43 @BASEBOARD_FAB2_LIB.BASEBOARD_FAB2(SCH_1):PAGE83
  J1B1   44 VSS<74> SCONN288_H44441004_PIP-SCONN,HA    I43 @BASEBOARD_FAB2_LIB.BASEBOARD_FAB2(SCH_1):PAGE83
  J1B1   42 VSS<75> SCONN288_H44441004_PIP-SCONN,HA    I43 @BASEBOARD_FAB2_LIB.BASEBOARD_FAB2(SCH_1):PAGE83
  J1B1   39 VSS<76> SCONN288_H44441004_PIP-SCONN,HA    I43 @BASEBOARD_FAB2_LIB.BASEBOARD_FAB2(SCH_1):PAGE83
  J1B1   37 VSS<77> SCONN288_H44441004_PIP-SCONN,HA    I43 @BASEBOARD_FAB2_LIB.BASEBOARD_FAB2(SCH_1):PAGE83
  J1B1   35 VSS<78> SCONN288_H44441004_PIP-SCONN,HA    I43 @BASEBOARD_FAB2_LIB.BASEBOARD_FAB2(SCH_1):PAGE83
  J1B1   33 VSS<79> SCONN288_H44441004_PIP-SCONN,HA    I43 @BASEBOARD_FAB2_LIB.BASEBOARD_FAB2(SCH_1):PAGE83
  J1B1   31 VSS<80> SCONN288_H44441004_PIP-SCONN,HA    I43 @BASEBOARD_FAB2_LIB.BASEBOARD_FAB2(SCH_1):PAGE83
  J1B1   28 VSS<81> SCONN288_H44441004_PIP-SCONN,HA    I43 @BASEBOARD_FAB2_LIB.BASEBOARD_FAB2(SCH_1):PAGE83
  J1B1   26 VSS<82> SCONN288_H44441004_PIP-SCONN,HA    I43 @BASEBOARD_FAB2_LIB.BASEBOARD_FAB2(SCH_1):PAGE83
  J1B1   24 VSS<83> SCONN288_H44441004_PIP-SCONN,HA    I43 @BASEBOARD_FAB2_LIB.BASEBOARD_FAB2(SCH_1):PAGE83
  J1B1   22 VSS<84> SCONN288_H44441004_PIP-SCONN,HA    I43 @BASEBOARD_FAB2_LIB.BASEBOARD_FAB2(SCH_1):PAGE83
  J1B1   20 VSS<85> SCONN288_H44441004_PIP-SCONN,HA    I43 @BASEBOARD_FAB2_LIB.BASEBOARD_FAB2(SCH_1):PAGE83
  J1B1   17 VSS<86> SCONN288_H44441004_PIP-SCONN,HA    I43 @BASEBOARD_FAB2_LIB.BASEBOARD_FAB2(SCH_1):PAGE83
  J1B1   15 VSS<87> SCONN288_H44441004_PIP-SCONN,HA    I43 @BASEBOARD_FAB2_LIB.BASEBOARD_FAB2(SCH_1):PAGE83
  J1B1   13 VSS<88> SCONN288_H44441004_PIP-SCONN,HA    I43 @BASEBOARD_FAB2_LIB.BASEBOARD_FAB2(SCH_1):PAGE83
  J1B1   11 VSS<89> SCONN288_H44441004_PIP-SCONN,HA    I43 @BASEBOARD_FAB2_LIB.BASEBOARD_FAB2(SCH_1):PAGE83
  J1B1    9 VSS<90> SCONN288_H44441004_PIP-SCONN,HA    I43 @BASEBOARD_FAB2_LIB.BASEBOARD_FAB2(SCH_1):PAGE83
  J1B1    6 VSS<91> SCONN288_H44441004_PIP-SCONN,HA    I43 @BASEBOARD_FAB2_LIB.BASEBOARD_FAB2(SCH_1):PAGE83
  J1B1    4 VSS<92> SCONN288_H44441004_PIP-SCONN,HA    I43 @BASEBOARD_FAB2_LIB.BASEBOARD_FAB2(SCH_1):PAGE83
  J1B1    2 VSS<93> SCONN288_H44441004_PIP-SCONN,HA    I43 @BASEBOARD_FAB2_LIB.BASEBOARD_FAB2(SCH_1):PAGE83
  J1B1  139  SA<0> SCONN288_H44441004_PIP-SCONN,HA   I111 @BASEBOARD_FAB2_LIB.BASEBOARD_FAB2(SCH_1):PAGE83
  J1B1  140  SA<1> SCONN288_H44441004_PIP-SCONN,HA   I111 @BASEBOARD_FAB2_LIB.BASEBOARD_FAB2(SCH_1):PAGE83
  J1B1  238  SA<2> SCONN288_H44441004_PIP-SCONN,HA   I111 @BASEBOARD_FAB2_LIB.BASEBOARD_FAB2(SCH_1):PAGE83
  C1B9    2      B CAP_A_0402V-0.01UF,25V,10%,X7RA   I176 @BASEBOARD_FAB2_LIB.BASEBOARD_FAB2(SCH_1):PAGE83
  C9M1    2      B CAP_A_0402V-0.01UF,25V,10%,X7RA     I4 @BASEBOARD_FAB2_LIB.BASEBOARD_FAB2(SCH_1):PAGE84
  J9M1  140  SA<1> SCONN288_H44441003_PIP-SCONN,HA    I14 @BASEBOARD_FAB2_LIB.BASEBOARD_FAB2(SCH_1):PAGE84
  J9M1  238  SA<2> SCONN288_H44441003_PIP-SCONN,HA    I14 @BASEBOARD_FAB2_LIB.BASEBOARD_FAB2(SCH_1):PAGE84
  J9M1  283 VSS<0> SCONN288_H44441003_PIP-SCONN,HA   I138 @BASEBOARD_FAB2_LIB.BASEBOARD_FAB2(SCH_1):PAGE84
  J9M1  281 VSS<1> SCONN288_H44441003_PIP-SCONN,HA   I138 @BASEBOARD_FAB2_LIB.BASEBOARD_FAB2(SCH_1):PAGE84
  J9M1  279 VSS<2> SCONN288_H44441003_PIP-SCONN,HA   I138 @BASEBOARD_FAB2_LIB.BASEBOARD_FAB2(SCH_1):PAGE84
  J9M1  276 VSS<3> SCONN288_H44441003_PIP-SCONN,HA   I138 @BASEBOARD_FAB2_LIB.BASEBOARD_FAB2(SCH_1):PAGE84
  J9M1  274 VSS<4> SCONN288_H44441003_PIP-SCONN,HA   I138 @BASEBOARD_FAB2_LIB.BASEBOARD_FAB2(SCH_1):PAGE84
  J9M1  272 VSS<5> SCONN288_H44441003_PIP-SCONN,HA   I138 @BASEBOARD_FAB2_LIB.BASEBOARD_FAB2(SCH_1):PAGE84
  J9M1  270 VSS<6> SCONN288_H44441003_PIP-SCONN,HA   I138 @BASEBOARD_FAB2_LIB.BASEBOARD_FAB2(SCH_1):PAGE84
  J9M1  268 VSS<7> SCONN288_H44441003_PIP-SCONN,HA   I138 @BASEBOARD_FAB2_LIB.BASEBOARD_FAB2(SCH_1):PAGE84
  J9M1  265 VSS<8> SCONN288_H44441003_PIP-SCONN,HA   I138 @BASEBOARD_FAB2_LIB.BASEBOARD_FAB2(SCH_1):PAGE84
  J9M1  263 VSS<9> SCONN288_H44441003_PIP-SCONN,HA   I138 @BASEBOARD_FAB2_LIB.BASEBOARD_FAB2(SCH_1):PAGE84
  J9M1  261 VSS<10> SCONN288_H44441003_PIP-SCONN,HA   I138 @BASEBOARD_FAB2_LIB.BASEBOARD_FAB2(SCH_1):PAGE84
  J9M1  259 VSS<11> SCONN288_H44441003_PIP-SCONN,HA   I138 @BASEBOARD_FAB2_LIB.BASEBOARD_FAB2(SCH_1):PAGE84
  J9M1  257 VSS<12> SCONN288_H44441003_PIP-SCONN,HA   I138 @BASEBOARD_FAB2_LIB.BASEBOARD_FAB2(SCH_1):PAGE84
  J9M1  254 VSS<13> SCONN288_H44441003_PIP-SCONN,HA   I138 @BASEBOARD_FAB2_LIB.BASEBOARD_FAB2(SCH_1):PAGE84
  J9M1  252 VSS<14> SCONN288_H44441003_PIP-SCONN,HA   I138 @BASEBOARD_FAB2_LIB.BASEBOARD_FAB2(SCH_1):PAGE84
  J9M1  250 VSS<15> SCONN288_H44441003_PIP-SCONN,HA   I138 @BASEBOARD_FAB2_LIB.BASEBOARD_FAB2(SCH_1):PAGE84
  J9M1  248 VSS<16> SCONN288_H44441003_PIP-SCONN,HA   I138 @BASEBOARD_FAB2_LIB.BASEBOARD_FAB2(SCH_1):PAGE84
  J9M1  246 VSS<17> SCONN288_H44441003_PIP-SCONN,HA   I138 @BASEBOARD_FAB2_LIB.BASEBOARD_FAB2(SCH_1):PAGE84
  J9M1  243 VSS<18> SCONN288_H44441003_PIP-SCONN,HA   I138 @BASEBOARD_FAB2_LIB.BASEBOARD_FAB2(SCH_1):PAGE84
  J9M1  241 VSS<19> SCONN288_H44441003_PIP-SCONN,HA   I138 @BASEBOARD_FAB2_LIB.BASEBOARD_FAB2(SCH_1):PAGE84
  J9M1  239 VSS<20> SCONN288_H44441003_PIP-SCONN,HA   I138 @BASEBOARD_FAB2_LIB.BASEBOARD_FAB2(SCH_1):PAGE84
  J9M1  202 VSS<21> SCONN288_H44441003_PIP-SCONN,HA   I138 @BASEBOARD_FAB2_LIB.BASEBOARD_FAB2(SCH_1):PAGE84
  J9M1  200 VSS<22> SCONN288_H44441003_PIP-SCONN,HA   I138 @BASEBOARD_FAB2_LIB.BASEBOARD_FAB2(SCH_1):PAGE84
  J9M1  198 VSS<23> SCONN288_H44441003_PIP-SCONN,HA   I138 @BASEBOARD_FAB2_LIB.BASEBOARD_FAB2(SCH_1):PAGE84
  J9M1  195 VSS<24> SCONN288_H44441003_PIP-SCONN,HA   I138 @BASEBOARD_FAB2_LIB.BASEBOARD_FAB2(SCH_1):PAGE84
  J9M1  193 VSS<25> SCONN288_H44441003_PIP-SCONN,HA   I138 @BASEBOARD_FAB2_LIB.BASEBOARD_FAB2(SCH_1):PAGE84
  J9M1  191 VSS<26> SCONN288_H44441003_PIP-SCONN,HA   I138 @BASEBOARD_FAB2_LIB.BASEBOARD_FAB2(SCH_1):PAGE84
  J9M1  189 VSS<27> SCONN288_H44441003_PIP-SCONN,HA   I138 @BASEBOARD_FAB2_LIB.BASEBOARD_FAB2(SCH_1):PAGE84
  J9M1  187 VSS<28> SCONN288_H44441003_PIP-SCONN,HA   I138 @BASEBOARD_FAB2_LIB.BASEBOARD_FAB2(SCH_1):PAGE84
  J9M1  184 VSS<29> SCONN288_H44441003_PIP-SCONN,HA   I138 @BASEBOARD_FAB2_LIB.BASEBOARD_FAB2(SCH_1):PAGE84
  J9M1  182 VSS<30> SCONN288_H44441003_PIP-SCONN,HA   I138 @BASEBOARD_FAB2_LIB.BASEBOARD_FAB2(SCH_1):PAGE84
  J9M1  180 VSS<31> SCONN288_H44441003_PIP-SCONN,HA   I138 @BASEBOARD_FAB2_LIB.BASEBOARD_FAB2(SCH_1):PAGE84
  J9M1  178 VSS<32> SCONN288_H44441003_PIP-SCONN,HA   I138 @BASEBOARD_FAB2_LIB.BASEBOARD_FAB2(SCH_1):PAGE84
  J9M1  176 VSS<33> SCONN288_H44441003_PIP-SCONN,HA   I138 @BASEBOARD_FAB2_LIB.BASEBOARD_FAB2(SCH_1):PAGE84
  J9M1  173 VSS<34> SCONN288_H44441003_PIP-SCONN,HA   I138 @BASEBOARD_FAB2_LIB.BASEBOARD_FAB2(SCH_1):PAGE84
  J9M1  171 VSS<35> SCONN288_H44441003_PIP-SCONN,HA   I138 @BASEBOARD_FAB2_LIB.BASEBOARD_FAB2(SCH_1):PAGE84
  J9M1  169 VSS<36> SCONN288_H44441003_PIP-SCONN,HA   I138 @BASEBOARD_FAB2_LIB.BASEBOARD_FAB2(SCH_1):PAGE84
  J9M1  167 VSS<37> SCONN288_H44441003_PIP-SCONN,HA   I138 @BASEBOARD_FAB2_LIB.BASEBOARD_FAB2(SCH_1):PAGE84
  J9M1  165 VSS<38> SCONN288_H44441003_PIP-SCONN,HA   I138 @BASEBOARD_FAB2_LIB.BASEBOARD_FAB2(SCH_1):PAGE84
  J9M1  162 VSS<39> SCONN288_H44441003_PIP-SCONN,HA   I138 @BASEBOARD_FAB2_LIB.BASEBOARD_FAB2(SCH_1):PAGE84
  J9M1  160 VSS<40> SCONN288_H44441003_PIP-SCONN,HA   I138 @BASEBOARD_FAB2_LIB.BASEBOARD_FAB2(SCH_1):PAGE84
  J9M1  158 VSS<41> SCONN288_H44441003_PIP-SCONN,HA   I138 @BASEBOARD_FAB2_LIB.BASEBOARD_FAB2(SCH_1):PAGE84
  J9M1  156 VSS<42> SCONN288_H44441003_PIP-SCONN,HA   I138 @BASEBOARD_FAB2_LIB.BASEBOARD_FAB2(SCH_1):PAGE84
  J9M1  154 VSS<43> SCONN288_H44441003_PIP-SCONN,HA   I138 @BASEBOARD_FAB2_LIB.BASEBOARD_FAB2(SCH_1):PAGE84
  J9M1  151 VSS<44> SCONN288_H44441003_PIP-SCONN,HA   I138 @BASEBOARD_FAB2_LIB.BASEBOARD_FAB2(SCH_1):PAGE84
  J9M1  149 VSS<45> SCONN288_H44441003_PIP-SCONN,HA   I138 @BASEBOARD_FAB2_LIB.BASEBOARD_FAB2(SCH_1):PAGE84
  J9M1  147 VSS<46> SCONN288_H44441003_PIP-SCONN,HA   I138 @BASEBOARD_FAB2_LIB.BASEBOARD_FAB2(SCH_1):PAGE84
  J9M1  138 VSS<47> SCONN288_H44441003_PIP-SCONN,HA   I138 @BASEBOARD_FAB2_LIB.BASEBOARD_FAB2(SCH_1):PAGE84
  J9M1  136 VSS<48> SCONN288_H44441003_PIP-SCONN,HA   I138 @BASEBOARD_FAB2_LIB.BASEBOARD_FAB2(SCH_1):PAGE84
  J9M1  134 VSS<49> SCONN288_H44441003_PIP-SCONN,HA   I138 @BASEBOARD_FAB2_LIB.BASEBOARD_FAB2(SCH_1):PAGE84
  J9M1  131 VSS<50> SCONN288_H44441003_PIP-SCONN,HA   I138 @BASEBOARD_FAB2_LIB.BASEBOARD_FAB2(SCH_1):PAGE84
  J9M1  129 VSS<51> SCONN288_H44441003_PIP-SCONN,HA   I138 @BASEBOARD_FAB2_LIB.BASEBOARD_FAB2(SCH_1):PAGE84
  J9M1  127 VSS<52> SCONN288_H44441003_PIP-SCONN,HA   I138 @BASEBOARD_FAB2_LIB.BASEBOARD_FAB2(SCH_1):PAGE84
  J9M1  125 VSS<53> SCONN288_H44441003_PIP-SCONN,HA   I138 @BASEBOARD_FAB2_LIB.BASEBOARD_FAB2(SCH_1):PAGE84
  J9M1  123 VSS<54> SCONN288_H44441003_PIP-SCONN,HA   I138 @BASEBOARD_FAB2_LIB.BASEBOARD_FAB2(SCH_1):PAGE84
  J9M1  120 VSS<55> SCONN288_H44441003_PIP-SCONN,HA   I138 @BASEBOARD_FAB2_LIB.BASEBOARD_FAB2(SCH_1):PAGE84
  J9M1  118 VSS<56> SCONN288_H44441003_PIP-SCONN,HA   I138 @BASEBOARD_FAB2_LIB.BASEBOARD_FAB2(SCH_1):PAGE84
  J9M1  116 VSS<57> SCONN288_H44441003_PIP-SCONN,HA   I138 @BASEBOARD_FAB2_LIB.BASEBOARD_FAB2(SCH_1):PAGE84
  J9M1  114 VSS<58> SCONN288_H44441003_PIP-SCONN,HA   I138 @BASEBOARD_FAB2_LIB.BASEBOARD_FAB2(SCH_1):PAGE84
  J9M1  112 VSS<59> SCONN288_H44441003_PIP-SCONN,HA   I138 @BASEBOARD_FAB2_LIB.BASEBOARD_FAB2(SCH_1):PAGE84
  J9M1  109 VSS<60> SCONN288_H44441003_PIP-SCONN,HA   I138 @BASEBOARD_FAB2_LIB.BASEBOARD_FAB2(SCH_1):PAGE84
  J9M1  107 VSS<61> SCONN288_H44441003_PIP-SCONN,HA   I138 @BASEBOARD_FAB2_LIB.BASEBOARD_FAB2(SCH_1):PAGE84
  J9M1  105 VSS<62> SCONN288_H44441003_PIP-SCONN,HA   I138 @BASEBOARD_FAB2_LIB.BASEBOARD_FAB2(SCH_1):PAGE84
  J9M1  103 VSS<63> SCONN288_H44441003_PIP-SCONN,HA   I138 @BASEBOARD_FAB2_LIB.BASEBOARD_FAB2(SCH_1):PAGE84
  J9M1  101 VSS<64> SCONN288_H44441003_PIP-SCONN,HA   I138 @BASEBOARD_FAB2_LIB.BASEBOARD_FAB2(SCH_1):PAGE84
  J9M1   98 VSS<65> SCONN288_H44441003_PIP-SCONN,HA   I138 @BASEBOARD_FAB2_LIB.BASEBOARD_FAB2(SCH_1):PAGE84
  J9M1   96 VSS<66> SCONN288_H44441003_PIP-SCONN,HA   I138 @BASEBOARD_FAB2_LIB.BASEBOARD_FAB2(SCH_1):PAGE84
  J9M1   94 VSS<67> SCONN288_H44441003_PIP-SCONN,HA   I138 @BASEBOARD_FAB2_LIB.BASEBOARD_FAB2(SCH_1):PAGE84
  J9M1   57 VSS<68> SCONN288_H44441003_PIP-SCONN,HA   I138 @BASEBOARD_FAB2_LIB.BASEBOARD_FAB2(SCH_1):PAGE84
  J9M1   55 VSS<69> SCONN288_H44441003_PIP-SCONN,HA   I138 @BASEBOARD_FAB2_LIB.BASEBOARD_FAB2(SCH_1):PAGE84
  J9M1   53 VSS<70> SCONN288_H44441003_PIP-SCONN,HA   I138 @BASEBOARD_FAB2_LIB.BASEBOARD_FAB2(SCH_1):PAGE84
  J9M1   50 VSS<71> SCONN288_H44441003_PIP-SCONN,HA   I138 @BASEBOARD_FAB2_LIB.BASEBOARD_FAB2(SCH_1):PAGE84
  J9M1   48 VSS<72> SCONN288_H44441003_PIP-SCONN,HA   I138 @BASEBOARD_FAB2_LIB.BASEBOARD_FAB2(SCH_1):PAGE84
  J9M1   46 VSS<73> SCONN288_H44441003_PIP-SCONN,HA   I138 @BASEBOARD_FAB2_LIB.BASEBOARD_FAB2(SCH_1):PAGE84
  J9M1   44 VSS<74> SCONN288_H44441003_PIP-SCONN,HA   I138 @BASEBOARD_FAB2_LIB.BASEBOARD_FAB2(SCH_1):PAGE84
  J9M1   42 VSS<75> SCONN288_H44441003_PIP-SCONN,HA   I138 @BASEBOARD_FAB2_LIB.BASEBOARD_FAB2(SCH_1):PAGE84
  J9M1   39 VSS<76> SCONN288_H44441003_PIP-SCONN,HA   I138 @BASEBOARD_FAB2_LIB.BASEBOARD_FAB2(SCH_1):PAGE84
  J9M1   37 VSS<77> SCONN288_H44441003_PIP-SCONN,HA   I138 @BASEBOARD_FAB2_LIB.BASEBOARD_FAB2(SCH_1):PAGE84
  J9M1   35 VSS<78> SCONN288_H44441003_PIP-SCONN,HA   I138 @BASEBOARD_FAB2_LIB.BASEBOARD_FAB2(SCH_1):PAGE84
  J9M1   33 VSS<79> SCONN288_H44441003_PIP-SCONN,HA   I138 @BASEBOARD_FAB2_LIB.BASEBOARD_FAB2(SCH_1):PAGE84
  J9M1   31 VSS<80> SCONN288_H44441003_PIP-SCONN,HA   I138 @BASEBOARD_FAB2_LIB.BASEBOARD_FAB2(SCH_1):PAGE84
  J9M1   28 VSS<81> SCONN288_H44441003_PIP-SCONN,HA   I138 @BASEBOARD_FAB2_LIB.BASEBOARD_FAB2(SCH_1):PAGE84
  J9M1   26 VSS<82> SCONN288_H44441003_PIP-SCONN,HA   I138 @BASEBOARD_FAB2_LIB.BASEBOARD_FAB2(SCH_1):PAGE84
  J9M1   24 VSS<83> SCONN288_H44441003_PIP-SCONN,HA   I138 @BASEBOARD_FAB2_LIB.BASEBOARD_FAB2(SCH_1):PAGE84
  J9M1   22 VSS<84> SCONN288_H44441003_PIP-SCONN,HA   I138 @BASEBOARD_FAB2_LIB.BASEBOARD_FAB2(SCH_1):PAGE84
  J9M1   20 VSS<85> SCONN288_H44441003_PIP-SCONN,HA   I138 @BASEBOARD_FAB2_LIB.BASEBOARD_FAB2(SCH_1):PAGE84
  J9M1   17 VSS<86> SCONN288_H44441003_PIP-SCONN,HA   I138 @BASEBOARD_FAB2_LIB.BASEBOARD_FAB2(SCH_1):PAGE84
  J9M1   15 VSS<87> SCONN288_H44441003_PIP-SCONN,HA   I138 @BASEBOARD_FAB2_LIB.BASEBOARD_FAB2(SCH_1):PAGE84
  J9M1   13 VSS<88> SCONN288_H44441003_PIP-SCONN,HA   I138 @BASEBOARD_FAB2_LIB.BASEBOARD_FAB2(SCH_1):PAGE84
  J9M1   11 VSS<89> SCONN288_H44441003_PIP-SCONN,HA   I138 @BASEBOARD_FAB2_LIB.BASEBOARD_FAB2(SCH_1):PAGE84
  J9M1    9 VSS<90> SCONN288_H44441003_PIP-SCONN,HA   I138 @BASEBOARD_FAB2_LIB.BASEBOARD_FAB2(SCH_1):PAGE84
  J9M1    6 VSS<91> SCONN288_H44441003_PIP-SCONN,HA   I138 @BASEBOARD_FAB2_LIB.BASEBOARD_FAB2(SCH_1):PAGE84
  J9M1    4 VSS<92> SCONN288_H44441003_PIP-SCONN,HA   I138 @BASEBOARD_FAB2_LIB.BASEBOARD_FAB2(SCH_1):PAGE84
  J9M1    2 VSS<93> SCONN288_H44441003_PIP-SCONN,HA   I138 @BASEBOARD_FAB2_LIB.BASEBOARD_FAB2(SCH_1):PAGE84
  J1A2  283 VSS<0> SCONN288_H44441004_PIP-SCONN,HA    I43 @BASEBOARD_FAB2_LIB.BASEBOARD_FAB2(SCH_1):PAGE85
  J1A2  281 VSS<1> SCONN288_H44441004_PIP-SCONN,HA    I43 @BASEBOARD_FAB2_LIB.BASEBOARD_FAB2(SCH_1):PAGE85
  J1A2  279 VSS<2> SCONN288_H44441004_PIP-SCONN,HA    I43 @BASEBOARD_FAB2_LIB.BASEBOARD_FAB2(SCH_1):PAGE85
  J1A2  276 VSS<3> SCONN288_H44441004_PIP-SCONN,HA    I43 @BASEBOARD_FAB2_LIB.BASEBOARD_FAB2(SCH_1):PAGE85
  J1A2  274 VSS<4> SCONN288_H44441004_PIP-SCONN,HA    I43 @BASEBOARD_FAB2_LIB.BASEBOARD_FAB2(SCH_1):PAGE85
  J1A2  272 VSS<5> SCONN288_H44441004_PIP-SCONN,HA    I43 @BASEBOARD_FAB2_LIB.BASEBOARD_FAB2(SCH_1):PAGE85
  J1A2  270 VSS<6> SCONN288_H44441004_PIP-SCONN,HA    I43 @BASEBOARD_FAB2_LIB.BASEBOARD_FAB2(SCH_1):PAGE85
  J1A2  268 VSS<7> SCONN288_H44441004_PIP-SCONN,HA    I43 @BASEBOARD_FAB2_LIB.BASEBOARD_FAB2(SCH_1):PAGE85
  J1A2  265 VSS<8> SCONN288_H44441004_PIP-SCONN,HA    I43 @BASEBOARD_FAB2_LIB.BASEBOARD_FAB2(SCH_1):PAGE85
  J1A2  263 VSS<9> SCONN288_H44441004_PIP-SCONN,HA    I43 @BASEBOARD_FAB2_LIB.BASEBOARD_FAB2(SCH_1):PAGE85
  J1A2  261 VSS<10> SCONN288_H44441004_PIP-SCONN,HA    I43 @BASEBOARD_FAB2_LIB.BASEBOARD_FAB2(SCH_1):PAGE85
  J1A2  259 VSS<11> SCONN288_H44441004_PIP-SCONN,HA    I43 @BASEBOARD_FAB2_LIB.BASEBOARD_FAB2(SCH_1):PAGE85
  J1A2  257 VSS<12> SCONN288_H44441004_PIP-SCONN,HA    I43 @BASEBOARD_FAB2_LIB.BASEBOARD_FAB2(SCH_1):PAGE85
  J1A2  254 VSS<13> SCONN288_H44441004_PIP-SCONN,HA    I43 @BASEBOARD_FAB2_LIB.BASEBOARD_FAB2(SCH_1):PAGE85
  J1A2  252 VSS<14> SCONN288_H44441004_PIP-SCONN,HA    I43 @BASEBOARD_FAB2_LIB.BASEBOARD_FAB2(SCH_1):PAGE85
  J1A2  250 VSS<15> SCONN288_H44441004_PIP-SCONN,HA    I43 @BASEBOARD_FAB2_LIB.BASEBOARD_FAB2(SCH_1):PAGE85
  J1A2  248 VSS<16> SCONN288_H44441004_PIP-SCONN,HA    I43 @BASEBOARD_FAB2_LIB.BASEBOARD_FAB2(SCH_1):PAGE85
  J1A2  246 VSS<17> SCONN288_H44441004_PIP-SCONN,HA    I43 @BASEBOARD_FAB2_LIB.BASEBOARD_FAB2(SCH_1):PAGE85
  J1A2  243 VSS<18> SCONN288_H44441004_PIP-SCONN,HA    I43 @BASEBOARD_FAB2_LIB.BASEBOARD_FAB2(SCH_1):PAGE85
  J1A2  241 VSS<19> SCONN288_H44441004_PIP-SCONN,HA    I43 @BASEBOARD_FAB2_LIB.BASEBOARD_FAB2(SCH_1):PAGE85
  J1A2  239 VSS<20> SCONN288_H44441004_PIP-SCONN,HA    I43 @BASEBOARD_FAB2_LIB.BASEBOARD_FAB2(SCH_1):PAGE85
  J1A2  202 VSS<21> SCONN288_H44441004_PIP-SCONN,HA    I43 @BASEBOARD_FAB2_LIB.BASEBOARD_FAB2(SCH_1):PAGE85
  J1A2  200 VSS<22> SCONN288_H44441004_PIP-SCONN,HA    I43 @BASEBOARD_FAB2_LIB.BASEBOARD_FAB2(SCH_1):PAGE85
  J1A2  198 VSS<23> SCONN288_H44441004_PIP-SCONN,HA    I43 @BASEBOARD_FAB2_LIB.BASEBOARD_FAB2(SCH_1):PAGE85
  J1A2  195 VSS<24> SCONN288_H44441004_PIP-SCONN,HA    I43 @BASEBOARD_FAB2_LIB.BASEBOARD_FAB2(SCH_1):PAGE85
  J1A2  193 VSS<25> SCONN288_H44441004_PIP-SCONN,HA    I43 @BASEBOARD_FAB2_LIB.BASEBOARD_FAB2(SCH_1):PAGE85
  J1A2  191 VSS<26> SCONN288_H44441004_PIP-SCONN,HA    I43 @BASEBOARD_FAB2_LIB.BASEBOARD_FAB2(SCH_1):PAGE85
  J1A2  189 VSS<27> SCONN288_H44441004_PIP-SCONN,HA    I43 @BASEBOARD_FAB2_LIB.BASEBOARD_FAB2(SCH_1):PAGE85
  J1A2  187 VSS<28> SCONN288_H44441004_PIP-SCONN,HA    I43 @BASEBOARD_FAB2_LIB.BASEBOARD_FAB2(SCH_1):PAGE85
  J1A2  184 VSS<29> SCONN288_H44441004_PIP-SCONN,HA    I43 @BASEBOARD_FAB2_LIB.BASEBOARD_FAB2(SCH_1):PAGE85
  J1A2  182 VSS<30> SCONN288_H44441004_PIP-SCONN,HA    I43 @BASEBOARD_FAB2_LIB.BASEBOARD_FAB2(SCH_1):PAGE85
  J1A2  180 VSS<31> SCONN288_H44441004_PIP-SCONN,HA    I43 @BASEBOARD_FAB2_LIB.BASEBOARD_FAB2(SCH_1):PAGE85
  J1A2  178 VSS<32> SCONN288_H44441004_PIP-SCONN,HA    I43 @BASEBOARD_FAB2_LIB.BASEBOARD_FAB2(SCH_1):PAGE85
  J1A2  176 VSS<33> SCONN288_H44441004_PIP-SCONN,HA    I43 @BASEBOARD_FAB2_LIB.BASEBOARD_FAB2(SCH_1):PAGE85
  J1A2  173 VSS<34> SCONN288_H44441004_PIP-SCONN,HA    I43 @BASEBOARD_FAB2_LIB.BASEBOARD_FAB2(SCH_1):PAGE85
  J1A2  171 VSS<35> SCONN288_H44441004_PIP-SCONN,HA    I43 @BASEBOARD_FAB2_LIB.BASEBOARD_FAB2(SCH_1):PAGE85
  J1A2  169 VSS<36> SCONN288_H44441004_PIP-SCONN,HA    I43 @BASEBOARD_FAB2_LIB.BASEBOARD_FAB2(SCH_1):PAGE85
  J1A2  167 VSS<37> SCONN288_H44441004_PIP-SCONN,HA    I43 @BASEBOARD_FAB2_LIB.BASEBOARD_FAB2(SCH_1):PAGE85
  J1A2  165 VSS<38> SCONN288_H44441004_PIP-SCONN,HA    I43 @BASEBOARD_FAB2_LIB.BASEBOARD_FAB2(SCH_1):PAGE85
  J1A2  162 VSS<39> SCONN288_H44441004_PIP-SCONN,HA    I43 @BASEBOARD_FAB2_LIB.BASEBOARD_FAB2(SCH_1):PAGE85
  J1A2  160 VSS<40> SCONN288_H44441004_PIP-SCONN,HA    I43 @BASEBOARD_FAB2_LIB.BASEBOARD_FAB2(SCH_1):PAGE85
  J1A2  158 VSS<41> SCONN288_H44441004_PIP-SCONN,HA    I43 @BASEBOARD_FAB2_LIB.BASEBOARD_FAB2(SCH_1):PAGE85
  J1A2  156 VSS<42> SCONN288_H44441004_PIP-SCONN,HA    I43 @BASEBOARD_FAB2_LIB.BASEBOARD_FAB2(SCH_1):PAGE85
  J1A2  154 VSS<43> SCONN288_H44441004_PIP-SCONN,HA    I43 @BASEBOARD_FAB2_LIB.BASEBOARD_FAB2(SCH_1):PAGE85
  J1A2  151 VSS<44> SCONN288_H44441004_PIP-SCONN,HA    I43 @BASEBOARD_FAB2_LIB.BASEBOARD_FAB2(SCH_1):PAGE85
  J1A2  149 VSS<45> SCONN288_H44441004_PIP-SCONN,HA    I43 @BASEBOARD_FAB2_LIB.BASEBOARD_FAB2(SCH_1):PAGE85
  J1A2  147 VSS<46> SCONN288_H44441004_PIP-SCONN,HA    I43 @BASEBOARD_FAB2_LIB.BASEBOARD_FAB2(SCH_1):PAGE85
  J1A2  138 VSS<47> SCONN288_H44441004_PIP-SCONN,HA    I43 @BASEBOARD_FAB2_LIB.BASEBOARD_FAB2(SCH_1):PAGE85
  J1A2  136 VSS<48> SCONN288_H44441004_PIP-SCONN,HA    I43 @BASEBOARD_FAB2_LIB.BASEBOARD_FAB2(SCH_1):PAGE85
  J1A2  134 VSS<49> SCONN288_H44441004_PIP-SCONN,HA    I43 @BASEBOARD_FAB2_LIB.BASEBOARD_FAB2(SCH_1):PAGE85
  J1A2  131 VSS<50> SCONN288_H44441004_PIP-SCONN,HA    I43 @BASEBOARD_FAB2_LIB.BASEBOARD_FAB2(SCH_1):PAGE85
  J1A2  129 VSS<51> SCONN288_H44441004_PIP-SCONN,HA    I43 @BASEBOARD_FAB2_LIB.BASEBOARD_FAB2(SCH_1):PAGE85
  J1A2  127 VSS<52> SCONN288_H44441004_PIP-SCONN,HA    I43 @BASEBOARD_FAB2_LIB.BASEBOARD_FAB2(SCH_1):PAGE85
  J1A2  125 VSS<53> SCONN288_H44441004_PIP-SCONN,HA    I43 @BASEBOARD_FAB2_LIB.BASEBOARD_FAB2(SCH_1):PAGE85
  J1A2  123 VSS<54> SCONN288_H44441004_PIP-SCONN,HA    I43 @BASEBOARD_FAB2_LIB.BASEBOARD_FAB2(SCH_1):PAGE85
  J1A2  120 VSS<55> SCONN288_H44441004_PIP-SCONN,HA    I43 @BASEBOARD_FAB2_LIB.BASEBOARD_FAB2(SCH_1):PAGE85
  J1A2  118 VSS<56> SCONN288_H44441004_PIP-SCONN,HA    I43 @BASEBOARD_FAB2_LIB.BASEBOARD_FAB2(SCH_1):PAGE85
  J1A2  116 VSS<57> SCONN288_H44441004_PIP-SCONN,HA    I43 @BASEBOARD_FAB2_LIB.BASEBOARD_FAB2(SCH_1):PAGE85
  J1A2  114 VSS<58> SCONN288_H44441004_PIP-SCONN,HA    I43 @BASEBOARD_FAB2_LIB.BASEBOARD_FAB2(SCH_1):PAGE85
  J1A2  112 VSS<59> SCONN288_H44441004_PIP-SCONN,HA    I43 @BASEBOARD_FAB2_LIB.BASEBOARD_FAB2(SCH_1):PAGE85
  J1A2  109 VSS<60> SCONN288_H44441004_PIP-SCONN,HA    I43 @BASEBOARD_FAB2_LIB.BASEBOARD_FAB2(SCH_1):PAGE85
  J1A2  107 VSS<61> SCONN288_H44441004_PIP-SCONN,HA    I43 @BASEBOARD_FAB2_LIB.BASEBOARD_FAB2(SCH_1):PAGE85
  J1A2  105 VSS<62> SCONN288_H44441004_PIP-SCONN,HA    I43 @BASEBOARD_FAB2_LIB.BASEBOARD_FAB2(SCH_1):PAGE85
  J1A2  103 VSS<63> SCONN288_H44441004_PIP-SCONN,HA    I43 @BASEBOARD_FAB2_LIB.BASEBOARD_FAB2(SCH_1):PAGE85
  J1A2  101 VSS<64> SCONN288_H44441004_PIP-SCONN,HA    I43 @BASEBOARD_FAB2_LIB.BASEBOARD_FAB2(SCH_1):PAGE85
  J1A2   98 VSS<65> SCONN288_H44441004_PIP-SCONN,HA    I43 @BASEBOARD_FAB2_LIB.BASEBOARD_FAB2(SCH_1):PAGE85
  J1A2   96 VSS<66> SCONN288_H44441004_PIP-SCONN,HA    I43 @BASEBOARD_FAB2_LIB.BASEBOARD_FAB2(SCH_1):PAGE85
  J1A2   94 VSS<67> SCONN288_H44441004_PIP-SCONN,HA    I43 @BASEBOARD_FAB2_LIB.BASEBOARD_FAB2(SCH_1):PAGE85
  J1A2   57 VSS<68> SCONN288_H44441004_PIP-SCONN,HA    I43 @BASEBOARD_FAB2_LIB.BASEBOARD_FAB2(SCH_1):PAGE85
  J1A2   55 VSS<69> SCONN288_H44441004_PIP-SCONN,HA    I43 @BASEBOARD_FAB2_LIB.BASEBOARD_FAB2(SCH_1):PAGE85
  J1A2   53 VSS<70> SCONN288_H44441004_PIP-SCONN,HA    I43 @BASEBOARD_FAB2_LIB.BASEBOARD_FAB2(SCH_1):PAGE85
  J1A2   50 VSS<71> SCONN288_H44441004_PIP-SCONN,HA    I43 @BASEBOARD_FAB2_LIB.BASEBOARD_FAB2(SCH_1):PAGE85
  J1A2   48 VSS<72> SCONN288_H44441004_PIP-SCONN,HA    I43 @BASEBOARD_FAB2_LIB.BASEBOARD_FAB2(SCH_1):PAGE85
  J1A2   46 VSS<73> SCONN288_H44441004_PIP-SCONN,HA    I43 @BASEBOARD_FAB2_LIB.BASEBOARD_FAB2(SCH_1):PAGE85
  J1A2   44 VSS<74> SCONN288_H44441004_PIP-SCONN,HA    I43 @BASEBOARD_FAB2_LIB.BASEBOARD_FAB2(SCH_1):PAGE85
  J1A2   42 VSS<75> SCONN288_H44441004_PIP-SCONN,HA    I43 @BASEBOARD_FAB2_LIB.BASEBOARD_FAB2(SCH_1):PAGE85
  J1A2   39 VSS<76> SCONN288_H44441004_PIP-SCONN,HA    I43 @BASEBOARD_FAB2_LIB.BASEBOARD_FAB2(SCH_1):PAGE85
  J1A2   37 VSS<77> SCONN288_H44441004_PIP-SCONN,HA    I43 @BASEBOARD_FAB2_LIB.BASEBOARD_FAB2(SCH_1):PAGE85
  J1A2   35 VSS<78> SCONN288_H44441004_PIP-SCONN,HA    I43 @BASEBOARD_FAB2_LIB.BASEBOARD_FAB2(SCH_1):PAGE85
  J1A2   33 VSS<79> SCONN288_H44441004_PIP-SCONN,HA    I43 @BASEBOARD_FAB2_LIB.BASEBOARD_FAB2(SCH_1):PAGE85
  J1A2   31 VSS<80> SCONN288_H44441004_PIP-SCONN,HA    I43 @BASEBOARD_FAB2_LIB.BASEBOARD_FAB2(SCH_1):PAGE85
  J1A2   28 VSS<81> SCONN288_H44441004_PIP-SCONN,HA    I43 @BASEBOARD_FAB2_LIB.BASEBOARD_FAB2(SCH_1):PAGE85
  J1A2   26 VSS<82> SCONN288_H44441004_PIP-SCONN,HA    I43 @BASEBOARD_FAB2_LIB.BASEBOARD_FAB2(SCH_1):PAGE85
  J1A2   24 VSS<83> SCONN288_H44441004_PIP-SCONN,HA    I43 @BASEBOARD_FAB2_LIB.BASEBOARD_FAB2(SCH_1):PAGE85
  J1A2   22 VSS<84> SCONN288_H44441004_PIP-SCONN,HA    I43 @BASEBOARD_FAB2_LIB.BASEBOARD_FAB2(SCH_1):PAGE85
  J1A2   20 VSS<85> SCONN288_H44441004_PIP-SCONN,HA    I43 @BASEBOARD_FAB2_LIB.BASEBOARD_FAB2(SCH_1):PAGE85
  J1A2   17 VSS<86> SCONN288_H44441004_PIP-SCONN,HA    I43 @BASEBOARD_FAB2_LIB.BASEBOARD_FAB2(SCH_1):PAGE85
  J1A2   15 VSS<87> SCONN288_H44441004_PIP-SCONN,HA    I43 @BASEBOARD_FAB2_LIB.BASEBOARD_FAB2(SCH_1):PAGE85
  J1A2   13 VSS<88> SCONN288_H44441004_PIP-SCONN,HA    I43 @BASEBOARD_FAB2_LIB.BASEBOARD_FAB2(SCH_1):PAGE85
  J1A2   11 VSS<89> SCONN288_H44441004_PIP-SCONN,HA    I43 @BASEBOARD_FAB2_LIB.BASEBOARD_FAB2(SCH_1):PAGE85
  J1A2    9 VSS<90> SCONN288_H44441004_PIP-SCONN,HA    I43 @BASEBOARD_FAB2_LIB.BASEBOARD_FAB2(SCH_1):PAGE85
  J1A2    6 VSS<91> SCONN288_H44441004_PIP-SCONN,HA    I43 @BASEBOARD_FAB2_LIB.BASEBOARD_FAB2(SCH_1):PAGE85
  J1A2    4 VSS<92> SCONN288_H44441004_PIP-SCONN,HA    I43 @BASEBOARD_FAB2_LIB.BASEBOARD_FAB2(SCH_1):PAGE85
  J1A2    2 VSS<93> SCONN288_H44441004_PIP-SCONN,HA    I43 @BASEBOARD_FAB2_LIB.BASEBOARD_FAB2(SCH_1):PAGE85
  J1A2  139  SA<0> SCONN288_H44441004_PIP-SCONN,HA   I111 @BASEBOARD_FAB2_LIB.BASEBOARD_FAB2(SCH_1):PAGE85
  J1A2  238  SA<2> SCONN288_H44441004_PIP-SCONN,HA   I111 @BASEBOARD_FAB2_LIB.BASEBOARD_FAB2(SCH_1):PAGE85
  C9L7    2      B CAP_A_0402V-0.01UF,25V,10%,X7RA   I181 @BASEBOARD_FAB2_LIB.BASEBOARD_FAB2(SCH_1):PAGE85
  J9L2  238  SA<2> SCONN288_H44441003_PIP-SCONN,HA    I12 @BASEBOARD_FAB2_LIB.BASEBOARD_FAB2(SCH_1):PAGE86
  J9L2  283 VSS<0> SCONN288_H44441003_PIP-SCONN,HA   I138 @BASEBOARD_FAB2_LIB.BASEBOARD_FAB2(SCH_1):PAGE86
  J9L2  281 VSS<1> SCONN288_H44441003_PIP-SCONN,HA   I138 @BASEBOARD_FAB2_LIB.BASEBOARD_FAB2(SCH_1):PAGE86
  J9L2  279 VSS<2> SCONN288_H44441003_PIP-SCONN,HA   I138 @BASEBOARD_FAB2_LIB.BASEBOARD_FAB2(SCH_1):PAGE86
  J9L2  276 VSS<3> SCONN288_H44441003_PIP-SCONN,HA   I138 @BASEBOARD_FAB2_LIB.BASEBOARD_FAB2(SCH_1):PAGE86
  J9L2  274 VSS<4> SCONN288_H44441003_PIP-SCONN,HA   I138 @BASEBOARD_FAB2_LIB.BASEBOARD_FAB2(SCH_1):PAGE86
  J9L2  272 VSS<5> SCONN288_H44441003_PIP-SCONN,HA   I138 @BASEBOARD_FAB2_LIB.BASEBOARD_FAB2(SCH_1):PAGE86
  J9L2  270 VSS<6> SCONN288_H44441003_PIP-SCONN,HA   I138 @BASEBOARD_FAB2_LIB.BASEBOARD_FAB2(SCH_1):PAGE86
  J9L2  268 VSS<7> SCONN288_H44441003_PIP-SCONN,HA   I138 @BASEBOARD_FAB2_LIB.BASEBOARD_FAB2(SCH_1):PAGE86
  J9L2  265 VSS<8> SCONN288_H44441003_PIP-SCONN,HA   I138 @BASEBOARD_FAB2_LIB.BASEBOARD_FAB2(SCH_1):PAGE86
  J9L2  263 VSS<9> SCONN288_H44441003_PIP-SCONN,HA   I138 @BASEBOARD_FAB2_LIB.BASEBOARD_FAB2(SCH_1):PAGE86
  J9L2  261 VSS<10> SCONN288_H44441003_PIP-SCONN,HA   I138 @BASEBOARD_FAB2_LIB.BASEBOARD_FAB2(SCH_1):PAGE86
  J9L2  259 VSS<11> SCONN288_H44441003_PIP-SCONN,HA   I138 @BASEBOARD_FAB2_LIB.BASEBOARD_FAB2(SCH_1):PAGE86
  J9L2  257 VSS<12> SCONN288_H44441003_PIP-SCONN,HA   I138 @BASEBOARD_FAB2_LIB.BASEBOARD_FAB2(SCH_1):PAGE86
  J9L2  254 VSS<13> SCONN288_H44441003_PIP-SCONN,HA   I138 @BASEBOARD_FAB2_LIB.BASEBOARD_FAB2(SCH_1):PAGE86
  J9L2  252 VSS<14> SCONN288_H44441003_PIP-SCONN,HA   I138 @BASEBOARD_FAB2_LIB.BASEBOARD_FAB2(SCH_1):PAGE86
  J9L2  250 VSS<15> SCONN288_H44441003_PIP-SCONN,HA   I138 @BASEBOARD_FAB2_LIB.BASEBOARD_FAB2(SCH_1):PAGE86
  J9L2  248 VSS<16> SCONN288_H44441003_PIP-SCONN,HA   I138 @BASEBOARD_FAB2_LIB.BASEBOARD_FAB2(SCH_1):PAGE86
  J9L2  246 VSS<17> SCONN288_H44441003_PIP-SCONN,HA   I138 @BASEBOARD_FAB2_LIB.BASEBOARD_FAB2(SCH_1):PAGE86
  J9L2  243 VSS<18> SCONN288_H44441003_PIP-SCONN,HA   I138 @BASEBOARD_FAB2_LIB.BASEBOARD_FAB2(SCH_1):PAGE86
  J9L2  241 VSS<19> SCONN288_H44441003_PIP-SCONN,HA   I138 @BASEBOARD_FAB2_LIB.BASEBOARD_FAB2(SCH_1):PAGE86
  J9L2  239 VSS<20> SCONN288_H44441003_PIP-SCONN,HA   I138 @BASEBOARD_FAB2_LIB.BASEBOARD_FAB2(SCH_1):PAGE86
  J9L2  202 VSS<21> SCONN288_H44441003_PIP-SCONN,HA   I138 @BASEBOARD_FAB2_LIB.BASEBOARD_FAB2(SCH_1):PAGE86
  J9L2  200 VSS<22> SCONN288_H44441003_PIP-SCONN,HA   I138 @BASEBOARD_FAB2_LIB.BASEBOARD_FAB2(SCH_1):PAGE86
  J9L2  198 VSS<23> SCONN288_H44441003_PIP-SCONN,HA   I138 @BASEBOARD_FAB2_LIB.BASEBOARD_FAB2(SCH_1):PAGE86
  J9L2  195 VSS<24> SCONN288_H44441003_PIP-SCONN,HA   I138 @BASEBOARD_FAB2_LIB.BASEBOARD_FAB2(SCH_1):PAGE86
  J9L2  193 VSS<25> SCONN288_H44441003_PIP-SCONN,HA   I138 @BASEBOARD_FAB2_LIB.BASEBOARD_FAB2(SCH_1):PAGE86
  J9L2  191 VSS<26> SCONN288_H44441003_PIP-SCONN,HA   I138 @BASEBOARD_FAB2_LIB.BASEBOARD_FAB2(SCH_1):PAGE86
  J9L2  189 VSS<27> SCONN288_H44441003_PIP-SCONN,HA   I138 @BASEBOARD_FAB2_LIB.BASEBOARD_FAB2(SCH_1):PAGE86
  J9L2  187 VSS<28> SCONN288_H44441003_PIP-SCONN,HA   I138 @BASEBOARD_FAB2_LIB.BASEBOARD_FAB2(SCH_1):PAGE86
  J9L2  184 VSS<29> SCONN288_H44441003_PIP-SCONN,HA   I138 @BASEBOARD_FAB2_LIB.BASEBOARD_FAB2(SCH_1):PAGE86
  J9L2  182 VSS<30> SCONN288_H44441003_PIP-SCONN,HA   I138 @BASEBOARD_FAB2_LIB.BASEBOARD_FAB2(SCH_1):PAGE86
  J9L2  180 VSS<31> SCONN288_H44441003_PIP-SCONN,HA   I138 @BASEBOARD_FAB2_LIB.BASEBOARD_FAB2(SCH_1):PAGE86
  J9L2  178 VSS<32> SCONN288_H44441003_PIP-SCONN,HA   I138 @BASEBOARD_FAB2_LIB.BASEBOARD_FAB2(SCH_1):PAGE86
  J9L2  176 VSS<33> SCONN288_H44441003_PIP-SCONN,HA   I138 @BASEBOARD_FAB2_LIB.BASEBOARD_FAB2(SCH_1):PAGE86
  J9L2  173 VSS<34> SCONN288_H44441003_PIP-SCONN,HA   I138 @BASEBOARD_FAB2_LIB.BASEBOARD_FAB2(SCH_1):PAGE86
  J9L2  171 VSS<35> SCONN288_H44441003_PIP-SCONN,HA   I138 @BASEBOARD_FAB2_LIB.BASEBOARD_FAB2(SCH_1):PAGE86
  J9L2  169 VSS<36> SCONN288_H44441003_PIP-SCONN,HA   I138 @BASEBOARD_FAB2_LIB.BASEBOARD_FAB2(SCH_1):PAGE86
  J9L2  167 VSS<37> SCONN288_H44441003_PIP-SCONN,HA   I138 @BASEBOARD_FAB2_LIB.BASEBOARD_FAB2(SCH_1):PAGE86
  J9L2  165 VSS<38> SCONN288_H44441003_PIP-SCONN,HA   I138 @BASEBOARD_FAB2_LIB.BASEBOARD_FAB2(SCH_1):PAGE86
  J9L2  162 VSS<39> SCONN288_H44441003_PIP-SCONN,HA   I138 @BASEBOARD_FAB2_LIB.BASEBOARD_FAB2(SCH_1):PAGE86
  J9L2  160 VSS<40> SCONN288_H44441003_PIP-SCONN,HA   I138 @BASEBOARD_FAB2_LIB.BASEBOARD_FAB2(SCH_1):PAGE86
  J9L2  158 VSS<41> SCONN288_H44441003_PIP-SCONN,HA   I138 @BASEBOARD_FAB2_LIB.BASEBOARD_FAB2(SCH_1):PAGE86
  J9L2  156 VSS<42> SCONN288_H44441003_PIP-SCONN,HA   I138 @BASEBOARD_FAB2_LIB.BASEBOARD_FAB2(SCH_1):PAGE86
  J9L2  154 VSS<43> SCONN288_H44441003_PIP-SCONN,HA   I138 @BASEBOARD_FAB2_LIB.BASEBOARD_FAB2(SCH_1):PAGE86
  J9L2  151 VSS<44> SCONN288_H44441003_PIP-SCONN,HA   I138 @BASEBOARD_FAB2_LIB.BASEBOARD_FAB2(SCH_1):PAGE86
  J9L2  149 VSS<45> SCONN288_H44441003_PIP-SCONN,HA   I138 @BASEBOARD_FAB2_LIB.BASEBOARD_FAB2(SCH_1):PAGE86
  J9L2  147 VSS<46> SCONN288_H44441003_PIP-SCONN,HA   I138 @BASEBOARD_FAB2_LIB.BASEBOARD_FAB2(SCH_1):PAGE86
  J9L2  138 VSS<47> SCONN288_H44441003_PIP-SCONN,HA   I138 @BASEBOARD_FAB2_LIB.BASEBOARD_FAB2(SCH_1):PAGE86
  J9L2  136 VSS<48> SCONN288_H44441003_PIP-SCONN,HA   I138 @BASEBOARD_FAB2_LIB.BASEBOARD_FAB2(SCH_1):PAGE86
  J9L2  134 VSS<49> SCONN288_H44441003_PIP-SCONN,HA   I138 @BASEBOARD_FAB2_LIB.BASEBOARD_FAB2(SCH_1):PAGE86
  J9L2  131 VSS<50> SCONN288_H44441003_PIP-SCONN,HA   I138 @BASEBOARD_FAB2_LIB.BASEBOARD_FAB2(SCH_1):PAGE86
  J9L2  129 VSS<51> SCONN288_H44441003_PIP-SCONN,HA   I138 @BASEBOARD_FAB2_LIB.BASEBOARD_FAB2(SCH_1):PAGE86
  J9L2  127 VSS<52> SCONN288_H44441003_PIP-SCONN,HA   I138 @BASEBOARD_FAB2_LIB.BASEBOARD_FAB2(SCH_1):PAGE86
  J9L2  125 VSS<53> SCONN288_H44441003_PIP-SCONN,HA   I138 @BASEBOARD_FAB2_LIB.BASEBOARD_FAB2(SCH_1):PAGE86
  J9L2  123 VSS<54> SCONN288_H44441003_PIP-SCONN,HA   I138 @BASEBOARD_FAB2_LIB.BASEBOARD_FAB2(SCH_1):PAGE86
  J9L2  120 VSS<55> SCONN288_H44441003_PIP-SCONN,HA   I138 @BASEBOARD_FAB2_LIB.BASEBOARD_FAB2(SCH_1):PAGE86
  J9L2  118 VSS<56> SCONN288_H44441003_PIP-SCONN,HA   I138 @BASEBOARD_FAB2_LIB.BASEBOARD_FAB2(SCH_1):PAGE86
  J9L2  116 VSS<57> SCONN288_H44441003_PIP-SCONN,HA   I138 @BASEBOARD_FAB2_LIB.BASEBOARD_FAB2(SCH_1):PAGE86
  J9L2  114 VSS<58> SCONN288_H44441003_PIP-SCONN,HA   I138 @BASEBOARD_FAB2_LIB.BASEBOARD_FAB2(SCH_1):PAGE86
  J9L2  112 VSS<59> SCONN288_H44441003_PIP-SCONN,HA   I138 @BASEBOARD_FAB2_LIB.BASEBOARD_FAB2(SCH_1):PAGE86
  J9L2  109 VSS<60> SCONN288_H44441003_PIP-SCONN,HA   I138 @BASEBOARD_FAB2_LIB.BASEBOARD_FAB2(SCH_1):PAGE86
  J9L2  107 VSS<61> SCONN288_H44441003_PIP-SCONN,HA   I138 @BASEBOARD_FAB2_LIB.BASEBOARD_FAB2(SCH_1):PAGE86
  J9L2  105 VSS<62> SCONN288_H44441003_PIP-SCONN,HA   I138 @BASEBOARD_FAB2_LIB.BASEBOARD_FAB2(SCH_1):PAGE86
  J9L2  103 VSS<63> SCONN288_H44441003_PIP-SCONN,HA   I138 @BASEBOARD_FAB2_LIB.BASEBOARD_FAB2(SCH_1):PAGE86
  J9L2  101 VSS<64> SCONN288_H44441003_PIP-SCONN,HA   I138 @BASEBOARD_FAB2_LIB.BASEBOARD_FAB2(SCH_1):PAGE86
  J9L2   98 VSS<65> SCONN288_H44441003_PIP-SCONN,HA   I138 @BASEBOARD_FAB2_LIB.BASEBOARD_FAB2(SCH_1):PAGE86
  J9L2   96 VSS<66> SCONN288_H44441003_PIP-SCONN,HA   I138 @BASEBOARD_FAB2_LIB.BASEBOARD_FAB2(SCH_1):PAGE86
  J9L2   94 VSS<67> SCONN288_H44441003_PIP-SCONN,HA   I138 @BASEBOARD_FAB2_LIB.BASEBOARD_FAB2(SCH_1):PAGE86
  J9L2   57 VSS<68> SCONN288_H44441003_PIP-SCONN,HA   I138 @BASEBOARD_FAB2_LIB.BASEBOARD_FAB2(SCH_1):PAGE86
  J9L2   55 VSS<69> SCONN288_H44441003_PIP-SCONN,HA   I138 @BASEBOARD_FAB2_LIB.BASEBOARD_FAB2(SCH_1):PAGE86
  J9L2   53 VSS<70> SCONN288_H44441003_PIP-SCONN,HA   I138 @BASEBOARD_FAB2_LIB.BASEBOARD_FAB2(SCH_1):PAGE86
  J9L2   50 VSS<71> SCONN288_H44441003_PIP-SCONN,HA   I138 @BASEBOARD_FAB2_LIB.BASEBOARD_FAB2(SCH_1):PAGE86
  J9L2   48 VSS<72> SCONN288_H44441003_PIP-SCONN,HA   I138 @BASEBOARD_FAB2_LIB.BASEBOARD_FAB2(SCH_1):PAGE86
  J9L2   46 VSS<73> SCONN288_H44441003_PIP-SCONN,HA   I138 @BASEBOARD_FAB2_LIB.BASEBOARD_FAB2(SCH_1):PAGE86
  J9L2   44 VSS<74> SCONN288_H44441003_PIP-SCONN,HA   I138 @BASEBOARD_FAB2_LIB.BASEBOARD_FAB2(SCH_1):PAGE86
  J9L2   42 VSS<75> SCONN288_H44441003_PIP-SCONN,HA   I138 @BASEBOARD_FAB2_LIB.BASEBOARD_FAB2(SCH_1):PAGE86
  J9L2   39 VSS<76> SCONN288_H44441003_PIP-SCONN,HA   I138 @BASEBOARD_FAB2_LIB.BASEBOARD_FAB2(SCH_1):PAGE86
  J9L2   37 VSS<77> SCONN288_H44441003_PIP-SCONN,HA   I138 @BASEBOARD_FAB2_LIB.BASEBOARD_FAB2(SCH_1):PAGE86
  J9L2   35 VSS<78> SCONN288_H44441003_PIP-SCONN,HA   I138 @BASEBOARD_FAB2_LIB.BASEBOARD_FAB2(SCH_1):PAGE86
  J9L2   33 VSS<79> SCONN288_H44441003_PIP-SCONN,HA   I138 @BASEBOARD_FAB2_LIB.BASEBOARD_FAB2(SCH_1):PAGE86
  J9L2   31 VSS<80> SCONN288_H44441003_PIP-SCONN,HA   I138 @BASEBOARD_FAB2_LIB.BASEBOARD_FAB2(SCH_1):PAGE86
  J9L2   28 VSS<81> SCONN288_H44441003_PIP-SCONN,HA   I138 @BASEBOARD_FAB2_LIB.BASEBOARD_FAB2(SCH_1):PAGE86
  J9L2   26 VSS<82> SCONN288_H44441003_PIP-SCONN,HA   I138 @BASEBOARD_FAB2_LIB.BASEBOARD_FAB2(SCH_1):PAGE86
  J9L2   24 VSS<83> SCONN288_H44441003_PIP-SCONN,HA   I138 @BASEBOARD_FAB2_LIB.BASEBOARD_FAB2(SCH_1):PAGE86
  J9L2   22 VSS<84> SCONN288_H44441003_PIP-SCONN,HA   I138 @BASEBOARD_FAB2_LIB.BASEBOARD_FAB2(SCH_1):PAGE86
  J9L2   20 VSS<85> SCONN288_H44441003_PIP-SCONN,HA   I138 @BASEBOARD_FAB2_LIB.BASEBOARD_FAB2(SCH_1):PAGE86
  J9L2   17 VSS<86> SCONN288_H44441003_PIP-SCONN,HA   I138 @BASEBOARD_FAB2_LIB.BASEBOARD_FAB2(SCH_1):PAGE86
  J9L2   15 VSS<87> SCONN288_H44441003_PIP-SCONN,HA   I138 @BASEBOARD_FAB2_LIB.BASEBOARD_FAB2(SCH_1):PAGE86
  J9L2   13 VSS<88> SCONN288_H44441003_PIP-SCONN,HA   I138 @BASEBOARD_FAB2_LIB.BASEBOARD_FAB2(SCH_1):PAGE86
  J9L2   11 VSS<89> SCONN288_H44441003_PIP-SCONN,HA   I138 @BASEBOARD_FAB2_LIB.BASEBOARD_FAB2(SCH_1):PAGE86
  J9L2    9 VSS<90> SCONN288_H44441003_PIP-SCONN,HA   I138 @BASEBOARD_FAB2_LIB.BASEBOARD_FAB2(SCH_1):PAGE86
  J9L2    6 VSS<91> SCONN288_H44441003_PIP-SCONN,HA   I138 @BASEBOARD_FAB2_LIB.BASEBOARD_FAB2(SCH_1):PAGE86
  J9L2    4 VSS<92> SCONN288_H44441003_PIP-SCONN,HA   I138 @BASEBOARD_FAB2_LIB.BASEBOARD_FAB2(SCH_1):PAGE86
  J9L2    2 VSS<93> SCONN288_H44441003_PIP-SCONN,HA   I138 @BASEBOARD_FAB2_LIB.BASEBOARD_FAB2(SCH_1):PAGE86
 C1A17    2      B CAP_A_0402V-0.01UF,25V,10%,X7RA   I182 @BASEBOARD_FAB2_LIB.BASEBOARD_FAB2(SCH_1):PAGE86
  C1A5    2      B CAP_A_0402V-0.01UF,25V,10%,X7RA   I178 @BASEBOARD_FAB2_LIB.BASEBOARD_FAB2(SCH_1):PAGE87
  J1A1  283 VSS<0> SCONN288_H44441004_PIP-SCONN,HA   I185 @BASEBOARD_FAB2_LIB.BASEBOARD_FAB2(SCH_1):PAGE87
  J1A1  281 VSS<1> SCONN288_H44441004_PIP-SCONN,HA   I185 @BASEBOARD_FAB2_LIB.BASEBOARD_FAB2(SCH_1):PAGE87
  J1A1  279 VSS<2> SCONN288_H44441004_PIP-SCONN,HA   I185 @BASEBOARD_FAB2_LIB.BASEBOARD_FAB2(SCH_1):PAGE87
  J1A1  276 VSS<3> SCONN288_H44441004_PIP-SCONN,HA   I185 @BASEBOARD_FAB2_LIB.BASEBOARD_FAB2(SCH_1):PAGE87
  J1A1  274 VSS<4> SCONN288_H44441004_PIP-SCONN,HA   I185 @BASEBOARD_FAB2_LIB.BASEBOARD_FAB2(SCH_1):PAGE87
  J1A1  272 VSS<5> SCONN288_H44441004_PIP-SCONN,HA   I185 @BASEBOARD_FAB2_LIB.BASEBOARD_FAB2(SCH_1):PAGE87
  J1A1  270 VSS<6> SCONN288_H44441004_PIP-SCONN,HA   I185 @BASEBOARD_FAB2_LIB.BASEBOARD_FAB2(SCH_1):PAGE87
  J1A1  268 VSS<7> SCONN288_H44441004_PIP-SCONN,HA   I185 @BASEBOARD_FAB2_LIB.BASEBOARD_FAB2(SCH_1):PAGE87
  J1A1  265 VSS<8> SCONN288_H44441004_PIP-SCONN,HA   I185 @BASEBOARD_FAB2_LIB.BASEBOARD_FAB2(SCH_1):PAGE87
  J1A1  263 VSS<9> SCONN288_H44441004_PIP-SCONN,HA   I185 @BASEBOARD_FAB2_LIB.BASEBOARD_FAB2(SCH_1):PAGE87
  J1A1  261 VSS<10> SCONN288_H44441004_PIP-SCONN,HA   I185 @BASEBOARD_FAB2_LIB.BASEBOARD_FAB2(SCH_1):PAGE87
  J1A1  259 VSS<11> SCONN288_H44441004_PIP-SCONN,HA   I185 @BASEBOARD_FAB2_LIB.BASEBOARD_FAB2(SCH_1):PAGE87
  J1A1  257 VSS<12> SCONN288_H44441004_PIP-SCONN,HA   I185 @BASEBOARD_FAB2_LIB.BASEBOARD_FAB2(SCH_1):PAGE87
  J1A1  254 VSS<13> SCONN288_H44441004_PIP-SCONN,HA   I185 @BASEBOARD_FAB2_LIB.BASEBOARD_FAB2(SCH_1):PAGE87
  J1A1  252 VSS<14> SCONN288_H44441004_PIP-SCONN,HA   I185 @BASEBOARD_FAB2_LIB.BASEBOARD_FAB2(SCH_1):PAGE87
  J1A1  250 VSS<15> SCONN288_H44441004_PIP-SCONN,HA   I185 @BASEBOARD_FAB2_LIB.BASEBOARD_FAB2(SCH_1):PAGE87
  J1A1  248 VSS<16> SCONN288_H44441004_PIP-SCONN,HA   I185 @BASEBOARD_FAB2_LIB.BASEBOARD_FAB2(SCH_1):PAGE87
  J1A1  246 VSS<17> SCONN288_H44441004_PIP-SCONN,HA   I185 @BASEBOARD_FAB2_LIB.BASEBOARD_FAB2(SCH_1):PAGE87
  J1A1  243 VSS<18> SCONN288_H44441004_PIP-SCONN,HA   I185 @BASEBOARD_FAB2_LIB.BASEBOARD_FAB2(SCH_1):PAGE87
  J1A1  241 VSS<19> SCONN288_H44441004_PIP-SCONN,HA   I185 @BASEBOARD_FAB2_LIB.BASEBOARD_FAB2(SCH_1):PAGE87
  J1A1  239 VSS<20> SCONN288_H44441004_PIP-SCONN,HA   I185 @BASEBOARD_FAB2_LIB.BASEBOARD_FAB2(SCH_1):PAGE87
  J1A1  202 VSS<21> SCONN288_H44441004_PIP-SCONN,HA   I185 @BASEBOARD_FAB2_LIB.BASEBOARD_FAB2(SCH_1):PAGE87
  J1A1  200 VSS<22> SCONN288_H44441004_PIP-SCONN,HA   I185 @BASEBOARD_FAB2_LIB.BASEBOARD_FAB2(SCH_1):PAGE87
  J1A1  198 VSS<23> SCONN288_H44441004_PIP-SCONN,HA   I185 @BASEBOARD_FAB2_LIB.BASEBOARD_FAB2(SCH_1):PAGE87
  J1A1  195 VSS<24> SCONN288_H44441004_PIP-SCONN,HA   I185 @BASEBOARD_FAB2_LIB.BASEBOARD_FAB2(SCH_1):PAGE87
  J1A1  193 VSS<25> SCONN288_H44441004_PIP-SCONN,HA   I185 @BASEBOARD_FAB2_LIB.BASEBOARD_FAB2(SCH_1):PAGE87
  J1A1  191 VSS<26> SCONN288_H44441004_PIP-SCONN,HA   I185 @BASEBOARD_FAB2_LIB.BASEBOARD_FAB2(SCH_1):PAGE87
  J1A1  189 VSS<27> SCONN288_H44441004_PIP-SCONN,HA   I185 @BASEBOARD_FAB2_LIB.BASEBOARD_FAB2(SCH_1):PAGE87
  J1A1  187 VSS<28> SCONN288_H44441004_PIP-SCONN,HA   I185 @BASEBOARD_FAB2_LIB.BASEBOARD_FAB2(SCH_1):PAGE87
  J1A1  184 VSS<29> SCONN288_H44441004_PIP-SCONN,HA   I185 @BASEBOARD_FAB2_LIB.BASEBOARD_FAB2(SCH_1):PAGE87
  J1A1  182 VSS<30> SCONN288_H44441004_PIP-SCONN,HA   I185 @BASEBOARD_FAB2_LIB.BASEBOARD_FAB2(SCH_1):PAGE87
  J1A1  180 VSS<31> SCONN288_H44441004_PIP-SCONN,HA   I185 @BASEBOARD_FAB2_LIB.BASEBOARD_FAB2(SCH_1):PAGE87
  J1A1  178 VSS<32> SCONN288_H44441004_PIP-SCONN,HA   I185 @BASEBOARD_FAB2_LIB.BASEBOARD_FAB2(SCH_1):PAGE87
  J1A1  176 VSS<33> SCONN288_H44441004_PIP-SCONN,HA   I185 @BASEBOARD_FAB2_LIB.BASEBOARD_FAB2(SCH_1):PAGE87
  J1A1  173 VSS<34> SCONN288_H44441004_PIP-SCONN,HA   I185 @BASEBOARD_FAB2_LIB.BASEBOARD_FAB2(SCH_1):PAGE87
  J1A1  171 VSS<35> SCONN288_H44441004_PIP-SCONN,HA   I185 @BASEBOARD_FAB2_LIB.BASEBOARD_FAB2(SCH_1):PAGE87
  J1A1  169 VSS<36> SCONN288_H44441004_PIP-SCONN,HA   I185 @BASEBOARD_FAB2_LIB.BASEBOARD_FAB2(SCH_1):PAGE87
  J1A1  167 VSS<37> SCONN288_H44441004_PIP-SCONN,HA   I185 @BASEBOARD_FAB2_LIB.BASEBOARD_FAB2(SCH_1):PAGE87
  J1A1  165 VSS<38> SCONN288_H44441004_PIP-SCONN,HA   I185 @BASEBOARD_FAB2_LIB.BASEBOARD_FAB2(SCH_1):PAGE87
  J1A1  162 VSS<39> SCONN288_H44441004_PIP-SCONN,HA   I185 @BASEBOARD_FAB2_LIB.BASEBOARD_FAB2(SCH_1):PAGE87
  J1A1  160 VSS<40> SCONN288_H44441004_PIP-SCONN,HA   I185 @BASEBOARD_FAB2_LIB.BASEBOARD_FAB2(SCH_1):PAGE87
  J1A1  158 VSS<41> SCONN288_H44441004_PIP-SCONN,HA   I185 @BASEBOARD_FAB2_LIB.BASEBOARD_FAB2(SCH_1):PAGE87
  J1A1  156 VSS<42> SCONN288_H44441004_PIP-SCONN,HA   I185 @BASEBOARD_FAB2_LIB.BASEBOARD_FAB2(SCH_1):PAGE87
  J1A1  154 VSS<43> SCONN288_H44441004_PIP-SCONN,HA   I185 @BASEBOARD_FAB2_LIB.BASEBOARD_FAB2(SCH_1):PAGE87
  J1A1  151 VSS<44> SCONN288_H44441004_PIP-SCONN,HA   I185 @BASEBOARD_FAB2_LIB.BASEBOARD_FAB2(SCH_1):PAGE87
  J1A1  149 VSS<45> SCONN288_H44441004_PIP-SCONN,HA   I185 @BASEBOARD_FAB2_LIB.BASEBOARD_FAB2(SCH_1):PAGE87
  J1A1  147 VSS<46> SCONN288_H44441004_PIP-SCONN,HA   I185 @BASEBOARD_FAB2_LIB.BASEBOARD_FAB2(SCH_1):PAGE87
  J1A1  138 VSS<47> SCONN288_H44441004_PIP-SCONN,HA   I185 @BASEBOARD_FAB2_LIB.BASEBOARD_FAB2(SCH_1):PAGE87
  J1A1  136 VSS<48> SCONN288_H44441004_PIP-SCONN,HA   I185 @BASEBOARD_FAB2_LIB.BASEBOARD_FAB2(SCH_1):PAGE87
  J1A1  134 VSS<49> SCONN288_H44441004_PIP-SCONN,HA   I185 @BASEBOARD_FAB2_LIB.BASEBOARD_FAB2(SCH_1):PAGE87
  J1A1  131 VSS<50> SCONN288_H44441004_PIP-SCONN,HA   I185 @BASEBOARD_FAB2_LIB.BASEBOARD_FAB2(SCH_1):PAGE87
  J1A1  129 VSS<51> SCONN288_H44441004_PIP-SCONN,HA   I185 @BASEBOARD_FAB2_LIB.BASEBOARD_FAB2(SCH_1):PAGE87
  J1A1  127 VSS<52> SCONN288_H44441004_PIP-SCONN,HA   I185 @BASEBOARD_FAB2_LIB.BASEBOARD_FAB2(SCH_1):PAGE87
  J1A1  125 VSS<53> SCONN288_H44441004_PIP-SCONN,HA   I185 @BASEBOARD_FAB2_LIB.BASEBOARD_FAB2(SCH_1):PAGE87
  J1A1  123 VSS<54> SCONN288_H44441004_PIP-SCONN,HA   I185 @BASEBOARD_FAB2_LIB.BASEBOARD_FAB2(SCH_1):PAGE87
  J1A1  120 VSS<55> SCONN288_H44441004_PIP-SCONN,HA   I185 @BASEBOARD_FAB2_LIB.BASEBOARD_FAB2(SCH_1):PAGE87
  J1A1  118 VSS<56> SCONN288_H44441004_PIP-SCONN,HA   I185 @BASEBOARD_FAB2_LIB.BASEBOARD_FAB2(SCH_1):PAGE87
  J1A1  116 VSS<57> SCONN288_H44441004_PIP-SCONN,HA   I185 @BASEBOARD_FAB2_LIB.BASEBOARD_FAB2(SCH_1):PAGE87
  J1A1  114 VSS<58> SCONN288_H44441004_PIP-SCONN,HA   I185 @BASEBOARD_FAB2_LIB.BASEBOARD_FAB2(SCH_1):PAGE87
  J1A1  112 VSS<59> SCONN288_H44441004_PIP-SCONN,HA   I185 @BASEBOARD_FAB2_LIB.BASEBOARD_FAB2(SCH_1):PAGE87
  J1A1  109 VSS<60> SCONN288_H44441004_PIP-SCONN,HA   I185 @BASEBOARD_FAB2_LIB.BASEBOARD_FAB2(SCH_1):PAGE87
  J1A1  107 VSS<61> SCONN288_H44441004_PIP-SCONN,HA   I185 @BASEBOARD_FAB2_LIB.BASEBOARD_FAB2(SCH_1):PAGE87
  J1A1  105 VSS<62> SCONN288_H44441004_PIP-SCONN,HA   I185 @BASEBOARD_FAB2_LIB.BASEBOARD_FAB2(SCH_1):PAGE87
  J1A1  103 VSS<63> SCONN288_H44441004_PIP-SCONN,HA   I185 @BASEBOARD_FAB2_LIB.BASEBOARD_FAB2(SCH_1):PAGE87
  J1A1  101 VSS<64> SCONN288_H44441004_PIP-SCONN,HA   I185 @BASEBOARD_FAB2_LIB.BASEBOARD_FAB2(SCH_1):PAGE87
  J1A1   98 VSS<65> SCONN288_H44441004_PIP-SCONN,HA   I185 @BASEBOARD_FAB2_LIB.BASEBOARD_FAB2(SCH_1):PAGE87
  J1A1   96 VSS<66> SCONN288_H44441004_PIP-SCONN,HA   I185 @BASEBOARD_FAB2_LIB.BASEBOARD_FAB2(SCH_1):PAGE87
  J1A1   94 VSS<67> SCONN288_H44441004_PIP-SCONN,HA   I185 @BASEBOARD_FAB2_LIB.BASEBOARD_FAB2(SCH_1):PAGE87
  J1A1   57 VSS<68> SCONN288_H44441004_PIP-SCONN,HA   I185 @BASEBOARD_FAB2_LIB.BASEBOARD_FAB2(SCH_1):PAGE87
  J1A1   55 VSS<69> SCONN288_H44441004_PIP-SCONN,HA   I185 @BASEBOARD_FAB2_LIB.BASEBOARD_FAB2(SCH_1):PAGE87
  J1A1   53 VSS<70> SCONN288_H44441004_PIP-SCONN,HA   I185 @BASEBOARD_FAB2_LIB.BASEBOARD_FAB2(SCH_1):PAGE87
  J1A1   50 VSS<71> SCONN288_H44441004_PIP-SCONN,HA   I185 @BASEBOARD_FAB2_LIB.BASEBOARD_FAB2(SCH_1):PAGE87
  J1A1   48 VSS<72> SCONN288_H44441004_PIP-SCONN,HA   I185 @BASEBOARD_FAB2_LIB.BASEBOARD_FAB2(SCH_1):PAGE87
  J1A1   46 VSS<73> SCONN288_H44441004_PIP-SCONN,HA   I185 @BASEBOARD_FAB2_LIB.BASEBOARD_FAB2(SCH_1):PAGE87
  J1A1   44 VSS<74> SCONN288_H44441004_PIP-SCONN,HA   I185 @BASEBOARD_FAB2_LIB.BASEBOARD_FAB2(SCH_1):PAGE87
  J1A1   42 VSS<75> SCONN288_H44441004_PIP-SCONN,HA   I185 @BASEBOARD_FAB2_LIB.BASEBOARD_FAB2(SCH_1):PAGE87
  J1A1   39 VSS<76> SCONN288_H44441004_PIP-SCONN,HA   I185 @BASEBOARD_FAB2_LIB.BASEBOARD_FAB2(SCH_1):PAGE87
  J1A1   37 VSS<77> SCONN288_H44441004_PIP-SCONN,HA   I185 @BASEBOARD_FAB2_LIB.BASEBOARD_FAB2(SCH_1):PAGE87
  J1A1   35 VSS<78> SCONN288_H44441004_PIP-SCONN,HA   I185 @BASEBOARD_FAB2_LIB.BASEBOARD_FAB2(SCH_1):PAGE87
  J1A1   33 VSS<79> SCONN288_H44441004_PIP-SCONN,HA   I185 @BASEBOARD_FAB2_LIB.BASEBOARD_FAB2(SCH_1):PAGE87
  J1A1   31 VSS<80> SCONN288_H44441004_PIP-SCONN,HA   I185 @BASEBOARD_FAB2_LIB.BASEBOARD_FAB2(SCH_1):PAGE87
  J1A1   28 VSS<81> SCONN288_H44441004_PIP-SCONN,HA   I185 @BASEBOARD_FAB2_LIB.BASEBOARD_FAB2(SCH_1):PAGE87
  J1A1   26 VSS<82> SCONN288_H44441004_PIP-SCONN,HA   I185 @BASEBOARD_FAB2_LIB.BASEBOARD_FAB2(SCH_1):PAGE87
  J1A1   24 VSS<83> SCONN288_H44441004_PIP-SCONN,HA   I185 @BASEBOARD_FAB2_LIB.BASEBOARD_FAB2(SCH_1):PAGE87
  J1A1   22 VSS<84> SCONN288_H44441004_PIP-SCONN,HA   I185 @BASEBOARD_FAB2_LIB.BASEBOARD_FAB2(SCH_1):PAGE87
  J1A1   20 VSS<85> SCONN288_H44441004_PIP-SCONN,HA   I185 @BASEBOARD_FAB2_LIB.BASEBOARD_FAB2(SCH_1):PAGE87
  J1A1   17 VSS<86> SCONN288_H44441004_PIP-SCONN,HA   I185 @BASEBOARD_FAB2_LIB.BASEBOARD_FAB2(SCH_1):PAGE87
  J1A1   15 VSS<87> SCONN288_H44441004_PIP-SCONN,HA   I185 @BASEBOARD_FAB2_LIB.BASEBOARD_FAB2(SCH_1):PAGE87
  J1A1   13 VSS<88> SCONN288_H44441004_PIP-SCONN,HA   I185 @BASEBOARD_FAB2_LIB.BASEBOARD_FAB2(SCH_1):PAGE87
  J1A1   11 VSS<89> SCONN288_H44441004_PIP-SCONN,HA   I185 @BASEBOARD_FAB2_LIB.BASEBOARD_FAB2(SCH_1):PAGE87
  J1A1    9 VSS<90> SCONN288_H44441004_PIP-SCONN,HA   I185 @BASEBOARD_FAB2_LIB.BASEBOARD_FAB2(SCH_1):PAGE87
  J1A1    6 VSS<91> SCONN288_H44441004_PIP-SCONN,HA   I185 @BASEBOARD_FAB2_LIB.BASEBOARD_FAB2(SCH_1):PAGE87
  J1A1    4 VSS<92> SCONN288_H44441004_PIP-SCONN,HA   I185 @BASEBOARD_FAB2_LIB.BASEBOARD_FAB2(SCH_1):PAGE87
  J1A1    2 VSS<93> SCONN288_H44441004_PIP-SCONN,HA   I185 @BASEBOARD_FAB2_LIB.BASEBOARD_FAB2(SCH_1):PAGE87
  J1A1  139  SA<0> SCONN288_H44441004_PIP-SCONN,HA   I186 @BASEBOARD_FAB2_LIB.BASEBOARD_FAB2(SCH_1):PAGE87
  J1A1  140  SA<1> SCONN288_H44441004_PIP-SCONN,HA   I186 @BASEBOARD_FAB2_LIB.BASEBOARD_FAB2(SCH_1):PAGE87
  J9L1  283 VSS<0> SCONN288_H44441003_PIP-SCONN,HA    I25 @BASEBOARD_FAB2_LIB.BASEBOARD_FAB2(SCH_1):PAGE88
  J9L1  281 VSS<1> SCONN288_H44441003_PIP-SCONN,HA    I25 @BASEBOARD_FAB2_LIB.BASEBOARD_FAB2(SCH_1):PAGE88
  J9L1  279 VSS<2> SCONN288_H44441003_PIP-SCONN,HA    I25 @BASEBOARD_FAB2_LIB.BASEBOARD_FAB2(SCH_1):PAGE88
  J9L1  276 VSS<3> SCONN288_H44441003_PIP-SCONN,HA    I25 @BASEBOARD_FAB2_LIB.BASEBOARD_FAB2(SCH_1):PAGE88
  J9L1  274 VSS<4> SCONN288_H44441003_PIP-SCONN,HA    I25 @BASEBOARD_FAB2_LIB.BASEBOARD_FAB2(SCH_1):PAGE88
  J9L1  272 VSS<5> SCONN288_H44441003_PIP-SCONN,HA    I25 @BASEBOARD_FAB2_LIB.BASEBOARD_FAB2(SCH_1):PAGE88
  J9L1  270 VSS<6> SCONN288_H44441003_PIP-SCONN,HA    I25 @BASEBOARD_FAB2_LIB.BASEBOARD_FAB2(SCH_1):PAGE88
  J9L1  268 VSS<7> SCONN288_H44441003_PIP-SCONN,HA    I25 @BASEBOARD_FAB2_LIB.BASEBOARD_FAB2(SCH_1):PAGE88
  J9L1  265 VSS<8> SCONN288_H44441003_PIP-SCONN,HA    I25 @BASEBOARD_FAB2_LIB.BASEBOARD_FAB2(SCH_1):PAGE88
  J9L1  263 VSS<9> SCONN288_H44441003_PIP-SCONN,HA    I25 @BASEBOARD_FAB2_LIB.BASEBOARD_FAB2(SCH_1):PAGE88
  J9L1  261 VSS<10> SCONN288_H44441003_PIP-SCONN,HA    I25 @BASEBOARD_FAB2_LIB.BASEBOARD_FAB2(SCH_1):PAGE88
  J9L1  259 VSS<11> SCONN288_H44441003_PIP-SCONN,HA    I25 @BASEBOARD_FAB2_LIB.BASEBOARD_FAB2(SCH_1):PAGE88
  J9L1  257 VSS<12> SCONN288_H44441003_PIP-SCONN,HA    I25 @BASEBOARD_FAB2_LIB.BASEBOARD_FAB2(SCH_1):PAGE88
  J9L1  254 VSS<13> SCONN288_H44441003_PIP-SCONN,HA    I25 @BASEBOARD_FAB2_LIB.BASEBOARD_FAB2(SCH_1):PAGE88
  J9L1  252 VSS<14> SCONN288_H44441003_PIP-SCONN,HA    I25 @BASEBOARD_FAB2_LIB.BASEBOARD_FAB2(SCH_1):PAGE88
  J9L1  250 VSS<15> SCONN288_H44441003_PIP-SCONN,HA    I25 @BASEBOARD_FAB2_LIB.BASEBOARD_FAB2(SCH_1):PAGE88
  J9L1  248 VSS<16> SCONN288_H44441003_PIP-SCONN,HA    I25 @BASEBOARD_FAB2_LIB.BASEBOARD_FAB2(SCH_1):PAGE88
  J9L1  246 VSS<17> SCONN288_H44441003_PIP-SCONN,HA    I25 @BASEBOARD_FAB2_LIB.BASEBOARD_FAB2(SCH_1):PAGE88
  J9L1  243 VSS<18> SCONN288_H44441003_PIP-SCONN,HA    I25 @BASEBOARD_FAB2_LIB.BASEBOARD_FAB2(SCH_1):PAGE88
  J9L1  241 VSS<19> SCONN288_H44441003_PIP-SCONN,HA    I25 @BASEBOARD_FAB2_LIB.BASEBOARD_FAB2(SCH_1):PAGE88
  J9L1  239 VSS<20> SCONN288_H44441003_PIP-SCONN,HA    I25 @BASEBOARD_FAB2_LIB.BASEBOARD_FAB2(SCH_1):PAGE88
  J9L1  202 VSS<21> SCONN288_H44441003_PIP-SCONN,HA    I25 @BASEBOARD_FAB2_LIB.BASEBOARD_FAB2(SCH_1):PAGE88
  J9L1  200 VSS<22> SCONN288_H44441003_PIP-SCONN,HA    I25 @BASEBOARD_FAB2_LIB.BASEBOARD_FAB2(SCH_1):PAGE88
  J9L1  198 VSS<23> SCONN288_H44441003_PIP-SCONN,HA    I25 @BASEBOARD_FAB2_LIB.BASEBOARD_FAB2(SCH_1):PAGE88
  J9L1  195 VSS<24> SCONN288_H44441003_PIP-SCONN,HA    I25 @BASEBOARD_FAB2_LIB.BASEBOARD_FAB2(SCH_1):PAGE88
  J9L1  193 VSS<25> SCONN288_H44441003_PIP-SCONN,HA    I25 @BASEBOARD_FAB2_LIB.BASEBOARD_FAB2(SCH_1):PAGE88
  J9L1  191 VSS<26> SCONN288_H44441003_PIP-SCONN,HA    I25 @BASEBOARD_FAB2_LIB.BASEBOARD_FAB2(SCH_1):PAGE88
  J9L1  189 VSS<27> SCONN288_H44441003_PIP-SCONN,HA    I25 @BASEBOARD_FAB2_LIB.BASEBOARD_FAB2(SCH_1):PAGE88
  J9L1  187 VSS<28> SCONN288_H44441003_PIP-SCONN,HA    I25 @BASEBOARD_FAB2_LIB.BASEBOARD_FAB2(SCH_1):PAGE88
  J9L1  184 VSS<29> SCONN288_H44441003_PIP-SCONN,HA    I25 @BASEBOARD_FAB2_LIB.BASEBOARD_FAB2(SCH_1):PAGE88
  J9L1  182 VSS<30> SCONN288_H44441003_PIP-SCONN,HA    I25 @BASEBOARD_FAB2_LIB.BASEBOARD_FAB2(SCH_1):PAGE88
  J9L1  180 VSS<31> SCONN288_H44441003_PIP-SCONN,HA    I25 @BASEBOARD_FAB2_LIB.BASEBOARD_FAB2(SCH_1):PAGE88
  J9L1  178 VSS<32> SCONN288_H44441003_PIP-SCONN,HA    I25 @BASEBOARD_FAB2_LIB.BASEBOARD_FAB2(SCH_1):PAGE88
  J9L1  176 VSS<33> SCONN288_H44441003_PIP-SCONN,HA    I25 @BASEBOARD_FAB2_LIB.BASEBOARD_FAB2(SCH_1):PAGE88
  J9L1  173 VSS<34> SCONN288_H44441003_PIP-SCONN,HA    I25 @BASEBOARD_FAB2_LIB.BASEBOARD_FAB2(SCH_1):PAGE88
  J9L1  171 VSS<35> SCONN288_H44441003_PIP-SCONN,HA    I25 @BASEBOARD_FAB2_LIB.BASEBOARD_FAB2(SCH_1):PAGE88
  J9L1  169 VSS<36> SCONN288_H44441003_PIP-SCONN,HA    I25 @BASEBOARD_FAB2_LIB.BASEBOARD_FAB2(SCH_1):PAGE88
  J9L1  167 VSS<37> SCONN288_H44441003_PIP-SCONN,HA    I25 @BASEBOARD_FAB2_LIB.BASEBOARD_FAB2(SCH_1):PAGE88
  J9L1  165 VSS<38> SCONN288_H44441003_PIP-SCONN,HA    I25 @BASEBOARD_FAB2_LIB.BASEBOARD_FAB2(SCH_1):PAGE88
  J9L1  162 VSS<39> SCONN288_H44441003_PIP-SCONN,HA    I25 @BASEBOARD_FAB2_LIB.BASEBOARD_FAB2(SCH_1):PAGE88
  J9L1  160 VSS<40> SCONN288_H44441003_PIP-SCONN,HA    I25 @BASEBOARD_FAB2_LIB.BASEBOARD_FAB2(SCH_1):PAGE88
  J9L1  158 VSS<41> SCONN288_H44441003_PIP-SCONN,HA    I25 @BASEBOARD_FAB2_LIB.BASEBOARD_FAB2(SCH_1):PAGE88
  J9L1  156 VSS<42> SCONN288_H44441003_PIP-SCONN,HA    I25 @BASEBOARD_FAB2_LIB.BASEBOARD_FAB2(SCH_1):PAGE88
  J9L1  154 VSS<43> SCONN288_H44441003_PIP-SCONN,HA    I25 @BASEBOARD_FAB2_LIB.BASEBOARD_FAB2(SCH_1):PAGE88
  J9L1  151 VSS<44> SCONN288_H44441003_PIP-SCONN,HA    I25 @BASEBOARD_FAB2_LIB.BASEBOARD_FAB2(SCH_1):PAGE88
  J9L1  149 VSS<45> SCONN288_H44441003_PIP-SCONN,HA    I25 @BASEBOARD_FAB2_LIB.BASEBOARD_FAB2(SCH_1):PAGE88
  J9L1  147 VSS<46> SCONN288_H44441003_PIP-SCONN,HA    I25 @BASEBOARD_FAB2_LIB.BASEBOARD_FAB2(SCH_1):PAGE88
  J9L1  138 VSS<47> SCONN288_H44441003_PIP-SCONN,HA    I25 @BASEBOARD_FAB2_LIB.BASEBOARD_FAB2(SCH_1):PAGE88
  J9L1  136 VSS<48> SCONN288_H44441003_PIP-SCONN,HA    I25 @BASEBOARD_FAB2_LIB.BASEBOARD_FAB2(SCH_1):PAGE88
  J9L1  134 VSS<49> SCONN288_H44441003_PIP-SCONN,HA    I25 @BASEBOARD_FAB2_LIB.BASEBOARD_FAB2(SCH_1):PAGE88
  J9L1  131 VSS<50> SCONN288_H44441003_PIP-SCONN,HA    I25 @BASEBOARD_FAB2_LIB.BASEBOARD_FAB2(SCH_1):PAGE88
  J9L1  129 VSS<51> SCONN288_H44441003_PIP-SCONN,HA    I25 @BASEBOARD_FAB2_LIB.BASEBOARD_FAB2(SCH_1):PAGE88
  J9L1  127 VSS<52> SCONN288_H44441003_PIP-SCONN,HA    I25 @BASEBOARD_FAB2_LIB.BASEBOARD_FAB2(SCH_1):PAGE88
  J9L1  125 VSS<53> SCONN288_H44441003_PIP-SCONN,HA    I25 @BASEBOARD_FAB2_LIB.BASEBOARD_FAB2(SCH_1):PAGE88
  J9L1  123 VSS<54> SCONN288_H44441003_PIP-SCONN,HA    I25 @BASEBOARD_FAB2_LIB.BASEBOARD_FAB2(SCH_1):PAGE88
  J9L1  120 VSS<55> SCONN288_H44441003_PIP-SCONN,HA    I25 @BASEBOARD_FAB2_LIB.BASEBOARD_FAB2(SCH_1):PAGE88
  J9L1  118 VSS<56> SCONN288_H44441003_PIP-SCONN,HA    I25 @BASEBOARD_FAB2_LIB.BASEBOARD_FAB2(SCH_1):PAGE88
  J9L1  116 VSS<57> SCONN288_H44441003_PIP-SCONN,HA    I25 @BASEBOARD_FAB2_LIB.BASEBOARD_FAB2(SCH_1):PAGE88
  J9L1  114 VSS<58> SCONN288_H44441003_PIP-SCONN,HA    I25 @BASEBOARD_FAB2_LIB.BASEBOARD_FAB2(SCH_1):PAGE88
  J9L1  112 VSS<59> SCONN288_H44441003_PIP-SCONN,HA    I25 @BASEBOARD_FAB2_LIB.BASEBOARD_FAB2(SCH_1):PAGE88
  J9L1  109 VSS<60> SCONN288_H44441003_PIP-SCONN,HA    I25 @BASEBOARD_FAB2_LIB.BASEBOARD_FAB2(SCH_1):PAGE88
  J9L1  107 VSS<61> SCONN288_H44441003_PIP-SCONN,HA    I25 @BASEBOARD_FAB2_LIB.BASEBOARD_FAB2(SCH_1):PAGE88
  J9L1  105 VSS<62> SCONN288_H44441003_PIP-SCONN,HA    I25 @BASEBOARD_FAB2_LIB.BASEBOARD_FAB2(SCH_1):PAGE88
  J9L1  103 VSS<63> SCONN288_H44441003_PIP-SCONN,HA    I25 @BASEBOARD_FAB2_LIB.BASEBOARD_FAB2(SCH_1):PAGE88
  J9L1  101 VSS<64> SCONN288_H44441003_PIP-SCONN,HA    I25 @BASEBOARD_FAB2_LIB.BASEBOARD_FAB2(SCH_1):PAGE88
  J9L1   98 VSS<65> SCONN288_H44441003_PIP-SCONN,HA    I25 @BASEBOARD_FAB2_LIB.BASEBOARD_FAB2(SCH_1):PAGE88
  J9L1   96 VSS<66> SCONN288_H44441003_PIP-SCONN,HA    I25 @BASEBOARD_FAB2_LIB.BASEBOARD_FAB2(SCH_1):PAGE88
  J9L1   94 VSS<67> SCONN288_H44441003_PIP-SCONN,HA    I25 @BASEBOARD_FAB2_LIB.BASEBOARD_FAB2(SCH_1):PAGE88
  J9L1   57 VSS<68> SCONN288_H44441003_PIP-SCONN,HA    I25 @BASEBOARD_FAB2_LIB.BASEBOARD_FAB2(SCH_1):PAGE88
  J9L1   55 VSS<69> SCONN288_H44441003_PIP-SCONN,HA    I25 @BASEBOARD_FAB2_LIB.BASEBOARD_FAB2(SCH_1):PAGE88
  J9L1   53 VSS<70> SCONN288_H44441003_PIP-SCONN,HA    I25 @BASEBOARD_FAB2_LIB.BASEBOARD_FAB2(SCH_1):PAGE88
  J9L1   50 VSS<71> SCONN288_H44441003_PIP-SCONN,HA    I25 @BASEBOARD_FAB2_LIB.BASEBOARD_FAB2(SCH_1):PAGE88
  J9L1   48 VSS<72> SCONN288_H44441003_PIP-SCONN,HA    I25 @BASEBOARD_FAB2_LIB.BASEBOARD_FAB2(SCH_1):PAGE88
  J9L1   46 VSS<73> SCONN288_H44441003_PIP-SCONN,HA    I25 @BASEBOARD_FAB2_LIB.BASEBOARD_FAB2(SCH_1):PAGE88
  J9L1   44 VSS<74> SCONN288_H44441003_PIP-SCONN,HA    I25 @BASEBOARD_FAB2_LIB.BASEBOARD_FAB2(SCH_1):PAGE88
  J9L1   42 VSS<75> SCONN288_H44441003_PIP-SCONN,HA    I25 @BASEBOARD_FAB2_LIB.BASEBOARD_FAB2(SCH_1):PAGE88
  J9L1   39 VSS<76> SCONN288_H44441003_PIP-SCONN,HA    I25 @BASEBOARD_FAB2_LIB.BASEBOARD_FAB2(SCH_1):PAGE88
  J9L1   37 VSS<77> SCONN288_H44441003_PIP-SCONN,HA    I25 @BASEBOARD_FAB2_LIB.BASEBOARD_FAB2(SCH_1):PAGE88
  J9L1   35 VSS<78> SCONN288_H44441003_PIP-SCONN,HA    I25 @BASEBOARD_FAB2_LIB.BASEBOARD_FAB2(SCH_1):PAGE88
  J9L1   33 VSS<79> SCONN288_H44441003_PIP-SCONN,HA    I25 @BASEBOARD_FAB2_LIB.BASEBOARD_FAB2(SCH_1):PAGE88
  J9L1   31 VSS<80> SCONN288_H44441003_PIP-SCONN,HA    I25 @BASEBOARD_FAB2_LIB.BASEBOARD_FAB2(SCH_1):PAGE88
  J9L1   28 VSS<81> SCONN288_H44441003_PIP-SCONN,HA    I25 @BASEBOARD_FAB2_LIB.BASEBOARD_FAB2(SCH_1):PAGE88
  J9L1   26 VSS<82> SCONN288_H44441003_PIP-SCONN,HA    I25 @BASEBOARD_FAB2_LIB.BASEBOARD_FAB2(SCH_1):PAGE88
  J9L1   24 VSS<83> SCONN288_H44441003_PIP-SCONN,HA    I25 @BASEBOARD_FAB2_LIB.BASEBOARD_FAB2(SCH_1):PAGE88
  J9L1   22 VSS<84> SCONN288_H44441003_PIP-SCONN,HA    I25 @BASEBOARD_FAB2_LIB.BASEBOARD_FAB2(SCH_1):PAGE88
  J9L1   20 VSS<85> SCONN288_H44441003_PIP-SCONN,HA    I25 @BASEBOARD_FAB2_LIB.BASEBOARD_FAB2(SCH_1):PAGE88
  J9L1   17 VSS<86> SCONN288_H44441003_PIP-SCONN,HA    I25 @BASEBOARD_FAB2_LIB.BASEBOARD_FAB2(SCH_1):PAGE88
  J9L1   15 VSS<87> SCONN288_H44441003_PIP-SCONN,HA    I25 @BASEBOARD_FAB2_LIB.BASEBOARD_FAB2(SCH_1):PAGE88
  J9L1   13 VSS<88> SCONN288_H44441003_PIP-SCONN,HA    I25 @BASEBOARD_FAB2_LIB.BASEBOARD_FAB2(SCH_1):PAGE88
  J9L1   11 VSS<89> SCONN288_H44441003_PIP-SCONN,HA    I25 @BASEBOARD_FAB2_LIB.BASEBOARD_FAB2(SCH_1):PAGE88
  J9L1    9 VSS<90> SCONN288_H44441003_PIP-SCONN,HA    I25 @BASEBOARD_FAB2_LIB.BASEBOARD_FAB2(SCH_1):PAGE88
  J9L1    6 VSS<91> SCONN288_H44441003_PIP-SCONN,HA    I25 @BASEBOARD_FAB2_LIB.BASEBOARD_FAB2(SCH_1):PAGE88
  J9L1    4 VSS<92> SCONN288_H44441003_PIP-SCONN,HA    I25 @BASEBOARD_FAB2_LIB.BASEBOARD_FAB2(SCH_1):PAGE88
  J9L1    2 VSS<93> SCONN288_H44441003_PIP-SCONN,HA    I25 @BASEBOARD_FAB2_LIB.BASEBOARD_FAB2(SCH_1):PAGE88
  J9L1  140  SA<1> SCONN288_H44441003_PIP-SCONN,HA   I111 @BASEBOARD_FAB2_LIB.BASEBOARD_FAB2(SCH_1):PAGE88
  C9L1    2      B CAP_A_0402V-0.01UF,25V,10%,X7RA   I177 @BASEBOARD_FAB2_LIB.BASEBOARD_FAB2(SCH_1):PAGE88
  Q8D1    4   E<0> NPN_DUAL_SSOPLF-MBT3904,XSTR,CA    I35 @BASEBOARD_FAB2_LIB.BASEBOARD_FAB2(SCH_1):PAGE89
 R6D14    1      A RES_0402-240,1.0%,1/16W,EMPTY,A    I52 @BASEBOARD_FAB2_LIB.BASEBOARD_FAB2(SCH_1):PAGE90
 R3D25    1      A RES_0402-240,1.0%,1/16W,EMPTY,A    I66 @BASEBOARD_FAB2_LIB.BASEBOARD_FAB2(SCH_1):PAGE90
  R4P6    1      A RES_0402-240,1.0%,1/16W,EMPTY,A    I68 @BASEBOARD_FAB2_LIB.BASEBOARD_FAB2(SCH_1):PAGE90
  R4P7    1      A RES_0402-240,1.0%,1/16W,EMPTY,A    I72 @BASEBOARD_FAB2_LIB.BASEBOARD_FAB2(SCH_1):PAGE90
 R7P15    1      A RES_0402-240,1.0%,1/16W,EMPTY,A    I74 @BASEBOARD_FAB2_LIB.BASEBOARD_FAB2(SCH_1):PAGE90
  R5P2    2      B RES_0402-49.9,1%,1/16W,CHIP,G2A    I79 @BASEBOARD_FAB2_LIB.BASEBOARD_FAB2(SCH_1):PAGE90
  R5P3    2      B RES_0402-49.9,1%,1/16W,CHIP,G2A    I80 @BASEBOARD_FAB2_LIB.BASEBOARD_FAB2(SCH_1):PAGE90
  R6D5    2      B RES_0402-49.9,1%,1/16W,CHIP,G2A    I81 @BASEBOARD_FAB2_LIB.BASEBOARD_FAB2(SCH_1):PAGE90
  R8P1    2      B RES_0402-49.9,1%,1/16W,CHIP,G2A    I85 @BASEBOARD_FAB2_LIB.BASEBOARD_FAB2(SCH_1):PAGE90
  R8P2    2      B RES_0402-49.9,1%,1/16W,CHIP,G2A    I86 @BASEBOARD_FAB2_LIB.BASEBOARD_FAB2(SCH_1):PAGE90
  R3D9    2      B RES_0402-49.9,1%,1/16W,CHIP,G2A    I88 @BASEBOARD_FAB2_LIB.BASEBOARD_FAB2(SCH_1):PAGE90
  J8B1    1    IO1 SCONN24_H46321001_SM-SCONN,H46A     I1 @BASEBOARD_FAB2_LIB.BASEBOARD_FAB2(SCH_1):PAGE91
  J8B1    7    IO7 SCONN24_H46321001_SM-SCONN,H46A     I1 @BASEBOARD_FAB2_LIB.BASEBOARD_FAB2(SCH_1):PAGE91
  J8B1    9    IO9 SCONN24_H46321001_SM-SCONN,H46A     I1 @BASEBOARD_FAB2_LIB.BASEBOARD_FAB2(SCH_1):PAGE91
  J8B1   15   IO15 SCONN24_H46321001_SM-SCONN,H46A     I1 @BASEBOARD_FAB2_LIB.BASEBOARD_FAB2(SCH_1):PAGE91
  J8B1   23   IO23 SCONN24_H46321001_SM-SCONN,H46A     I1 @BASEBOARD_FAB2_LIB.BASEBOARD_FAB2(SCH_1):PAGE91
  J8B1  MP1    MP1 SCONN24_H46321001_SM-SCONN,H46A     I1 @BASEBOARD_FAB2_LIB.BASEBOARD_FAB2(SCH_1):PAGE91
  J8B1  MP2    MP2 SCONN24_H46321001_SM-SCONN,H46A     I1 @BASEBOARD_FAB2_LIB.BASEBOARD_FAB2(SCH_1):PAGE91
  U3P2    7 GND<0> GTL2014_SM-IC,D66151-001     I1 @BASEBOARD_FAB2_LIB.BASEBOARD_FAB2(SCH_1):PAGE92
  U3P2    8 GND<1> GTL2014_SM-IC,D66151-001     I1 @BASEBOARD_FAB2_LIB.BASEBOARD_FAB2(SCH_1):PAGE92
  U3P2   11 GND<2> GTL2014_SM-IC,D66151-001     I1 @BASEBOARD_FAB2_LIB.BASEBOARD_FAB2(SCH_1):PAGE92
  U7D2    7 GND<0> GTL2014_SM-IC,D66151-001    I32 @BASEBOARD_FAB2_LIB.BASEBOARD_FAB2(SCH_1):PAGE92
  U7D2    8 GND<1> GTL2014_SM-IC,D66151-001    I32 @BASEBOARD_FAB2_LIB.BASEBOARD_FAB2(SCH_1):PAGE92
  U7D2   11 GND<2> GTL2014_SM-IC,D66151-001    I32 @BASEBOARD_FAB2_LIB.BASEBOARD_FAB2(SCH_1):PAGE92
 C3P49    2      B CAP_A_0402V-0.1UF,16V,10%,X7R,A    I37 @BASEBOARD_FAB2_LIB.BASEBOARD_FAB2(SCH_1):PAGE92
 R3P49    2      B RES_0402-100.0,1%,1/16W,CHIP,GA    I38 @BASEBOARD_FAB2_LIB.BASEBOARD_FAB2(SCH_1):PAGE92
  R3R1    2      B RES_0402-1.00K,1%,1/16W,CHIP,GA    I46 @BASEBOARD_FAB2_LIB.BASEBOARD_FAB2(SCH_1):PAGE92
 R7D32    2      B RES_0402-100.0,1%,1/16W,CHIP,GA    I48 @BASEBOARD_FAB2_LIB.BASEBOARD_FAB2(SCH_1):PAGE92
  C7D5    2      B CAP_A_0402V-0.1UF,16V,10%,X7R,A    I52 @BASEBOARD_FAB2_LIB.BASEBOARD_FAB2(SCH_1):PAGE92
 R7D26    2      B RES_0402-1.00K,1%,1/16W,CHIP,GA    I54 @BASEBOARD_FAB2_LIB.BASEBOARD_FAB2(SCH_1):PAGE92
  R3R2    2      B RES_0402-1.00K,1%,1/16W,CHIP,GA    I75 @BASEBOARD_FAB2_LIB.BASEBOARD_FAB2(SCH_1):PAGE92
  C7D4    2      B CAP_0402-1.0UF,16V,10%,X6S,D97A    I79 @BASEBOARD_FAB2_LIB.BASEBOARD_FAB2(SCH_1):PAGE92
 C3P50    2      B CAP_0402-1.0UF,16V,10%,X6S,D97A    I84 @BASEBOARD_FAB2_LIB.BASEBOARD_FAB2(SCH_1):PAGE92
  U2T4    7 GND<0> GTL2014_SM-IC,D66151-001    I30 @BASEBOARD_FAB2_LIB.BASEBOARD_FAB2(SCH_1):PAGE93
  U2T4    8 GND<1> GTL2014_SM-IC,D66151-001    I30 @BASEBOARD_FAB2_LIB.BASEBOARD_FAB2(SCH_1):PAGE93
  U2T4   11 GND<2> GTL2014_SM-IC,D66151-001    I30 @BASEBOARD_FAB2_LIB.BASEBOARD_FAB2(SCH_1):PAGE93
 C2T33    2      B CAP_A_0402V-1.0UF,6.3V,10%,X6SA    I72 @BASEBOARD_FAB2_LIB.BASEBOARD_FAB2(SCH_1):PAGE93
 C2T32    2      B CAP_A_0402V-0.1UF,16V,10%,X7R,A    I95 @BASEBOARD_FAB2_LIB.BASEBOARD_FAB2(SCH_1):PAGE93
 R2T39    2      B RES_0402-100.0,1%,1/16W,CHIP,GA    I98 @BASEBOARD_FAB2_LIB.BASEBOARD_FAB2(SCH_1):PAGE93
 R2T50    2      B RES_0402-1.00K,1%,1/16W,CHIP,GA   I127 @BASEBOARD_FAB2_LIB.BASEBOARD_FAB2(SCH_1):PAGE93
  Q3U1    1 SOURCE<0> FET_N_DUAL_SMLF-NTJD4001N,FET,A    I49 @BASEBOARD_FAB2_LIB.BASEBOARD_FAB2(SCH_1):PAGE94
  Q7E1    1 SOURCE<0> FET_N_DUAL_SMLF-NTJD4001N,FET,A    I60 @BASEBOARD_FAB2_LIB.BASEBOARD_FAB2(SCH_1):PAGE94
  Q7E1    4 SOURCE<0> FET_N_DUAL_SMLF-NTJD4001N,FET,A    I64 @BASEBOARD_FAB2_LIB.BASEBOARD_FAB2(SCH_1):PAGE94
  Q7E2    1 SOURCE<0> FET_N_DUAL_SMLF-NTJD4001N,FET,A    I69 @BASEBOARD_FAB2_LIB.BASEBOARD_FAB2(SCH_1):PAGE94
  Q7E2    4 SOURCE<0> FET_N_DUAL_SMLF-NTJD4001N,FET,A    I75 @BASEBOARD_FAB2_LIB.BASEBOARD_FAB2(SCH_1):PAGE94
  Q4B1    4 SOURCE<0> FET_N_DUAL_SMLF-NTJD4001N,FET,A    I77 @BASEBOARD_FAB2_LIB.BASEBOARD_FAB2(SCH_1):PAGE94
  Q4B1    1 SOURCE<0> FET_N_DUAL_SMLF-NTJD4001N,FET,A    I84 @BASEBOARD_FAB2_LIB.BASEBOARD_FAB2(SCH_1):PAGE94
  Q3U1    4 SOURCE<0> FET_N_DUAL_SMLF-NTJD4001N,FET,A    I89 @BASEBOARD_FAB2_LIB.BASEBOARD_FAB2(SCH_1):PAGE94
  Q4U1    1 SOURCE<0> FET_N_DUAL_SMLF-NTJD4001N,FET,A    I98 @BASEBOARD_FAB2_LIB.BASEBOARD_FAB2(SCH_1):PAGE94
  Q4U1    4 SOURCE<0> FET_N_DUAL_SMLF-NTJD4001N,FET,A   I102 @BASEBOARD_FAB2_LIB.BASEBOARD_FAB2(SCH_1):PAGE94
  R4U4    2      B RES_0402-33.0K,5%,1/16W,CHIP,GA   I104 @BASEBOARD_FAB2_LIB.BASEBOARD_FAB2(SCH_1):PAGE94
  Q2U1    1 SOURCE<0> FET_N_DUAL_SMLF-NTJD4001N,FET,A    I28 @BASEBOARD_FAB2_LIB.BASEBOARD_FAB2(SCH_1):PAGE95
  Q4B2    1 SOURCE<0> FET_N_DUAL_SMLF-NTJD4001N,FET,A    I32 @BASEBOARD_FAB2_LIB.BASEBOARD_FAB2(SCH_1):PAGE95
  Q4B2    4 SOURCE<0> FET_N_DUAL_SMLF-NTJD4001N,FET,A    I33 @BASEBOARD_FAB2_LIB.BASEBOARD_FAB2(SCH_1):PAGE95
  Q7E3    4 SOURCE<0> FET_N_DUAL_SMLF-NTJD4001N,FET,A    I51 @BASEBOARD_FAB2_LIB.BASEBOARD_FAB2(SCH_1):PAGE95
  Q7E3    1 SOURCE<0> FET_N_DUAL_SMLF-NTJD4001N,FET,A    I52 @BASEBOARD_FAB2_LIB.BASEBOARD_FAB2(SCH_1):PAGE95
  Q7E5    4 SOURCE<0> FET_N_DUAL_SMLF-NTJD4001N,FET,A    I59 @BASEBOARD_FAB2_LIB.BASEBOARD_FAB2(SCH_1):PAGE95
  Q7E6    4 SOURCE<0> FET_N_DUAL_SMLF-NTJD4001N,FET,A    I69 @BASEBOARD_FAB2_LIB.BASEBOARD_FAB2(SCH_1):PAGE95
  C7E3    2      B CAP_A_0402V-0.1UF,16V,10%,X7R,A    I92 @BASEBOARD_FAB2_LIB.BASEBOARD_FAB2(SCH_1):PAGE95
  Q7E5    1 SOURCE<0> FET_N_DUAL_SMLF-NTJD4001N,FET,A   I111 @BASEBOARD_FAB2_LIB.BASEBOARD_FAB2(SCH_1):PAGE95
  Q7E6    1 SOURCE<0> FET_N_DUAL_SMLF-NTJD4001N,FET,A   I112 @BASEBOARD_FAB2_LIB.BASEBOARD_FAB2(SCH_1):PAGE95
  Q2U1    4 SOURCE<0> FET_N_DUAL_SMLF-NTJD4001N,FET,A   I113 @BASEBOARD_FAB2_LIB.BASEBOARD_FAB2(SCH_1):PAGE95
  C7E4    2      B CAP_A_0402V-0.1UF,16V,10%,X7R,A   I115 @BASEBOARD_FAB2_LIB.BASEBOARD_FAB2(SCH_1):PAGE95
  U3P1    7 GND<0> GTL2014_SM-IC,D66151-001    I42 @BASEBOARD_FAB2_LIB.BASEBOARD_FAB2(SCH_1):PAGE96
  U3P1    8 GND<1> GTL2014_SM-IC,D66151-001    I42 @BASEBOARD_FAB2_LIB.BASEBOARD_FAB2(SCH_1):PAGE96
  U3P1   11 GND<2> GTL2014_SM-IC,D66151-001    I42 @BASEBOARD_FAB2_LIB.BASEBOARD_FAB2(SCH_1):PAGE96
  U4C2    7 GND<0> GTL2014_SM-IC,D66151-001    I46 @BASEBOARD_FAB2_LIB.BASEBOARD_FAB2(SCH_1):PAGE96
  U4C2    8 GND<1> GTL2014_SM-IC,D66151-001    I46 @BASEBOARD_FAB2_LIB.BASEBOARD_FAB2(SCH_1):PAGE96
  U4C2   11 GND<2> GTL2014_SM-IC,D66151-001    I46 @BASEBOARD_FAB2_LIB.BASEBOARD_FAB2(SCH_1):PAGE96
  R4C9    1      A RES_0402-1.00K,1%,1/16W,CHIP,GA    I69 @BASEBOARD_FAB2_LIB.BASEBOARD_FAB2(SCH_1):PAGE96
 R3P32    1      A RES_0402-1.00K,1%,1/16W,CHIP,GA    I71 @BASEBOARD_FAB2_LIB.BASEBOARD_FAB2(SCH_1):PAGE96
 C3P42    2      B CAP_A_0402V-1.0UF,6.3V,10%,X6SA    I73 @BASEBOARD_FAB2_LIB.BASEBOARD_FAB2(SCH_1):PAGE96
  C4C3    2      B CAP_A_0402V-1.0UF,6.3V,10%,X6SA    I75 @BASEBOARD_FAB2_LIB.BASEBOARD_FAB2(SCH_1):PAGE96
  R4P5    1      A RES_0402-10.0K,1%,1/16W,CHIP,GA    I80 @BASEBOARD_FAB2_LIB.BASEBOARD_FAB2(SCH_1):PAGE97
 R7P13    1      A RES_0402-10.0K,1%,1/16W,CHIP,GA    I81 @BASEBOARD_FAB2_LIB.BASEBOARD_FAB2(SCH_1):PAGE97
  R4F5    2      B RES_0402-1.00K,1%,1/16W,CHIP,GA     I4 @BASEBOARD_FAB2_LIB.BASEBOARD_FAB2(SCH_1):PAGE98
  C4F9    2      B CAP_A_0402V-0.01UF,25V,10%,X7RA     I7 @BASEBOARD_FAB2_LIB.BASEBOARD_FAB2(SCH_1):PAGE98
 R6L16    2      B RES_0402-1.00K,1%,1/16W,CHIP,GA    I12 @BASEBOARD_FAB2_LIB.BASEBOARD_FAB2(SCH_1):PAGE98
  C6M2    2      B CAP_A_0402V-0.01UF,25V,10%,X7RA    I33 @BASEBOARD_FAB2_LIB.BASEBOARD_FAB2(SCH_1):PAGE98
  R4G3    2      B RES_0402-1.00K,1%,1/16W,CHIP,GA    I40 @BASEBOARD_FAB2_LIB.BASEBOARD_FAB2(SCH_1):PAGE98
  C4G1    2      B CAP_A_0402V-0.01UF,25V,10%,X7RA    I43 @BASEBOARD_FAB2_LIB.BASEBOARD_FAB2(SCH_1):PAGE98
 R4G22    2      B RES_0402-1.00K,1%,1/16W,CHIP,GA    I48 @BASEBOARD_FAB2_LIB.BASEBOARD_FAB2(SCH_1):PAGE98
 C4G17    2      B CAP_A_0402V-0.01UF,25V,10%,X7RA    I51 @BASEBOARD_FAB2_LIB.BASEBOARD_FAB2(SCH_1):PAGE98
 R6L12    2      B RES_0402-1.00K,1%,1/16W,CHIP,GA    I56 @BASEBOARD_FAB2_LIB.BASEBOARD_FAB2(SCH_1):PAGE98
  C6L7    2      B CAP_A_0402V-0.01UF,25V,10%,X7RA    I59 @BASEBOARD_FAB2_LIB.BASEBOARD_FAB2(SCH_1):PAGE98
  R6L1    2      B RES_0402-1.00K,1%,1/16W,CHIP,GA    I64 @BASEBOARD_FAB2_LIB.BASEBOARD_FAB2(SCH_1):PAGE98
  C6L2    2      B CAP_A_0402V-0.01UF,25V,10%,X7RA    I67 @BASEBOARD_FAB2_LIB.BASEBOARD_FAB2(SCH_1):PAGE98
  C6F2    2      B CAP_A_0402V-0.1UF,16V,10%,X7R,A     I2 @BASEBOARD_FAB2_LIB.BASEBOARD_FAB2(SCH_1):PAGE99
  C6F3    2      B CAP_A_0402V-0.1UF,16V,10%,X7R,A     I7 @BASEBOARD_FAB2_LIB.BASEBOARD_FAB2(SCH_1):PAGE99
  C7E1    2      B CAP_A_0402V-0.1UF,16V,10%,X7R,A    I23 @BASEBOARD_FAB2_LIB.BASEBOARD_FAB2(SCH_1):PAGE99
 C4G22    2      B CAP_A_0402V-0.1UF,16V,10%,X7R,A    I27 @BASEBOARD_FAB2_LIB.BASEBOARD_FAB2(SCH_1):PAGE99
  C7E2    2      B CAP_A_0402V-0.1UF,16V,10%,X7R,A    I32 @BASEBOARD_FAB2_LIB.BASEBOARD_FAB2(SCH_1):PAGE99
 C4G25    2      B CAP_A_0402V-0.1UF,16V,10%,X7R,A    I41 @BASEBOARD_FAB2_LIB.BASEBOARD_FAB2(SCH_1):PAGE99
  C3B4    2      B CAP_A_0402V-0.1UF,16V,10%,X7R,A    I47 @BASEBOARD_FAB2_LIB.BASEBOARD_FAB2(SCH_1):PAGE99
  C3B5    2      B CAP_A_0402V-0.1UF,16V,10%,X7R,A    I53 @BASEBOARD_FAB2_LIB.BASEBOARD_FAB2(SCH_1):PAGE99
  R1F6    2      B RES_0402-1.00K,1%,1/16W,CHIP,GA     I2 @BASEBOARD_FAB2_LIB.BASEBOARD_FAB2(SCH_1):PAGE100
 R9L11    2      B RES_0402-1.00K,1%,1/16W,CHIP,GA     I4 @BASEBOARD_FAB2_LIB.BASEBOARD_FAB2(SCH_1):PAGE100
 C1F19    2      B CAP_A_0402V-0.01UF,25V,10%,X7RA     I8 @BASEBOARD_FAB2_LIB.BASEBOARD_FAB2(SCH_1):PAGE100
  C9M2    2      B CAP_A_0402V-0.01UF,25V,10%,X7RA    I15 @BASEBOARD_FAB2_LIB.BASEBOARD_FAB2(SCH_1):PAGE100
  R1G3    2      B RES_0402-1.00K,1%,1/16W,CHIP,GA    I20 @BASEBOARD_FAB2_LIB.BASEBOARD_FAB2(SCH_1):PAGE100
  R9L6    2      B RES_0402-1.00K,1%,1/16W,CHIP,GA    I24 @BASEBOARD_FAB2_LIB.BASEBOARD_FAB2(SCH_1):PAGE100
  C1G8    2      B CAP_A_0402V-0.01UF,25V,10%,X7RA    I26 @BASEBOARD_FAB2_LIB.BASEBOARD_FAB2(SCH_1):PAGE100
  C9L8    2      B CAP_A_0402V-0.01UF,25V,10%,X7RA    I30 @BASEBOARD_FAB2_LIB.BASEBOARD_FAB2(SCH_1):PAGE100
 R1G17    2      B RES_0402-1.00K,1%,1/16W,CHIP,GA    I36 @BASEBOARD_FAB2_LIB.BASEBOARD_FAB2(SCH_1):PAGE100
  R9L1    2      B RES_0402-1.00K,1%,1/16W,CHIP,GA    I40 @BASEBOARD_FAB2_LIB.BASEBOARD_FAB2(SCH_1):PAGE100
 C1G18    2      B CAP_A_0402V-0.01UF,25V,10%,X7RA    I42 @BASEBOARD_FAB2_LIB.BASEBOARD_FAB2(SCH_1):PAGE100
  C9L3    2      B CAP_A_0402V-0.01UF,25V,10%,X7RA    I46 @BASEBOARD_FAB2_LIB.BASEBOARD_FAB2(SCH_1):PAGE100
 R8F25    2      B RES_0402-475.0,1%,1/16W,CHIP,GA    I28 @BASEBOARD_FAB2_LIB.BASEBOARD_FAB2(SCH_1):PAGE101
 EU8F2    1 GND<0> ICS9FGP204_MLFP-IC,E95226-001    I34 @BASEBOARD_FAB2_LIB.BASEBOARD_FAB2(SCH_1):PAGE101
 EU8F2   41 GND<1> ICS9FGP204_MLFP-IC,E95226-001    I34 @BASEBOARD_FAB2_LIB.BASEBOARD_FAB2(SCH_1):PAGE101
 EU8F2   14 GND32K ICS9FGP204_MLFP-IC,E95226-001    I34 @BASEBOARD_FAB2_LIB.BASEBOARD_FAB2(SCH_1):PAGE101
 EU8F2   21  GND33 ICS9FGP204_MLFP-IC,E95226-001    I34 @BASEBOARD_FAB2_LIB.BASEBOARD_FAB2(SCH_1):PAGE101
 EU8F2   35 GND_RGMII ICS9FGP204_MLFP-IC,E95226-001    I34 @BASEBOARD_FAB2_LIB.BASEBOARD_FAB2(SCH_1):PAGE101
 EU8F2   10 GNDCPU ICS9FGP204_MLFP-IC,E95226-001    I34 @BASEBOARD_FAB2_LIB.BASEBOARD_FAB2(SCH_1):PAGE101
 EU8F2   18 GNDREF ICS9FGP204_MLFP-IC,E95226-001    I34 @BASEBOARD_FAB2_LIB.BASEBOARD_FAB2(SCH_1):PAGE101
 EU8F2   27 GNDRMII<0> ICS9FGP204_MLFP-IC,E95226-001    I34 @BASEBOARD_FAB2_LIB.BASEBOARD_FAB2(SCH_1):PAGE101
 EU8F2   30 GNDRMII<1> ICS9FGP204_MLFP-IC,E95226-001    I34 @BASEBOARD_FAB2_LIB.BASEBOARD_FAB2(SCH_1):PAGE101
 R2T25    2      B RES_0402-1.00K,1%,1/16W,CHIP,GA    I48 @BASEBOARD_FAB2_LIB.BASEBOARD_FAB2(SCH_1):PAGE101
 C2T31    2      B CAP_A_0402V-1.0UF,6.3V,10%,X6SA    I89 @BASEBOARD_FAB2_LIB.BASEBOARD_FAB2(SCH_1):PAGE101
 C2T27    2      B CAP_A_0402V-0.01UF,25V,10%,X7RA    I90 @BASEBOARD_FAB2_LIB.BASEBOARD_FAB2(SCH_1):PAGE101
 C2T38    2      B CAP_A_0402V-1.0UF,6.3V,10%,X6SA    I97 @BASEBOARD_FAB2_LIB.BASEBOARD_FAB2(SCH_1):PAGE101
 C2T37    2      B CAP_A_0402V-0.01UF,25V,10%,X7RA    I99 @BASEBOARD_FAB2_LIB.BASEBOARD_FAB2(SCH_1):PAGE101
 C2T18    2      B CAP_A_0402V-0.01UF,25V,10%,X7RA   I104 @BASEBOARD_FAB2_LIB.BASEBOARD_FAB2(SCH_1):PAGE101
 C2T19    2      B CAP_A_0402V-1.0UF,6.3V,10%,X6SA   I106 @BASEBOARD_FAB2_LIB.BASEBOARD_FAB2(SCH_1):PAGE101
 C2T34    2      B CAP_A_0402V-0.1UF,16V,10%,X7R,A   I109 @BASEBOARD_FAB2_LIB.BASEBOARD_FAB2(SCH_1):PAGE101
 C2T30    2      B CAP_A_0402V-0.1UF,16V,10%,X7R,A   I110 @BASEBOARD_FAB2_LIB.BASEBOARD_FAB2(SCH_1):PAGE101
 C2T25    2      B CAP_A_0402V-0.1UF,16V,10%,X7R,A   I111 @BASEBOARD_FAB2_LIB.BASEBOARD_FAB2(SCH_1):PAGE101
 C2T17    2      B CAP_A_0402V-0.1UF,16V,10%,X7R,A   I112 @BASEBOARD_FAB2_LIB.BASEBOARD_FAB2(SCH_1):PAGE101
 C2T22    2      B CAP_0805-10UF,16V,10%,X6S,C953A   I113 @BASEBOARD_FAB2_LIB.BASEBOARD_FAB2(SCH_1):PAGE101
 C2T28    2      B CAP_A_0402V-1.0UF,6.3V,10%,X6SA   I116 @BASEBOARD_FAB2_LIB.BASEBOARD_FAB2(SCH_1):PAGE101
 EU4D2    7 GND<0> NB3W1200L_LCC-IC,H13585-001     I1 @BASEBOARD_FAB2_LIB.BASEBOARD_FAB2(SCH_1):PAGE102
 EU4D2   23 GND<1> NB3W1200L_LCC-IC,H13585-001     I1 @BASEBOARD_FAB2_LIB.BASEBOARD_FAB2(SCH_1):PAGE102
 EU4D2   33 GND<2> NB3W1200L_LCC-IC,H13585-001     I1 @BASEBOARD_FAB2_LIB.BASEBOARD_FAB2(SCH_1):PAGE102
 EU4D2   41 GND<3> NB3W1200L_LCC-IC,H13585-001     I1 @BASEBOARD_FAB2_LIB.BASEBOARD_FAB2(SCH_1):PAGE102
 EU4D2   48 GND<4> NB3W1200L_LCC-IC,H13585-001     I1 @BASEBOARD_FAB2_LIB.BASEBOARD_FAB2(SCH_1):PAGE102
 EU4D2   58 GND<5> NB3W1200L_LCC-IC,H13585-001     I1 @BASEBOARD_FAB2_LIB.BASEBOARD_FAB2(SCH_1):PAGE102
 EU4D2    2   GNDA NB3W1200L_LCC-IC,H13585-001     I1 @BASEBOARD_FAB2_LIB.BASEBOARD_FAB2(SCH_1):PAGE102
 EU4D2   65  THPAD NB3W1200L_LCC-IC,H13585-001     I1 @BASEBOARD_FAB2_LIB.BASEBOARD_FAB2(SCH_1):PAGE102
 C3D22    2      B CAP_0805-10UF,16V,10%,X7R,G106A    I10 @BASEBOARD_FAB2_LIB.BASEBOARD_FAB2(SCH_1):PAGE102
  C6P4    2      B CAP_A_0402V-0.1UF,16V,10%,X7R,A    I11 @BASEBOARD_FAB2_LIB.BASEBOARD_FAB2(SCH_1):PAGE102
  C6P6    2      B CAP_A_0402V-0.1UF,16V,10%,X7R,A    I12 @BASEBOARD_FAB2_LIB.BASEBOARD_FAB2(SCH_1):PAGE102
 C6P10    2      B CAP_A_0402V-0.1UF,16V,10%,X7R,A    I13 @BASEBOARD_FAB2_LIB.BASEBOARD_FAB2(SCH_1):PAGE102
  C6P5    2      B CAP_A_0402V-0.1UF,16V,10%,X7R,A    I14 @BASEBOARD_FAB2_LIB.BASEBOARD_FAB2(SCH_1):PAGE102
 C6P12    2      B CAP_A_0402V-0.1UF,16V,10%,X7R,A    I15 @BASEBOARD_FAB2_LIB.BASEBOARD_FAB2(SCH_1):PAGE102
 C6P11    2      B CAP_A_0402V-0.1UF,16V,10%,X7R,A    I16 @BASEBOARD_FAB2_LIB.BASEBOARD_FAB2(SCH_1):PAGE102
 C4D24    2      B CAP_A_0402V-0.1UF,16V,10%,X7R,A    I18 @BASEBOARD_FAB2_LIB.BASEBOARD_FAB2(SCH_1):PAGE102
 C4D23    2      B CAP_A_0402V-1.0UF,6.3V,10%,X6SA    I19 @BASEBOARD_FAB2_LIB.BASEBOARD_FAB2(SCH_1):PAGE102
 C4D22    2      B CAP_A_0402V-0.1UF,16V,10%,X7R,A    I28 @BASEBOARD_FAB2_LIB.BASEBOARD_FAB2(SCH_1):PAGE102
 C4D27    2      B CAP_A_0402V-1.0UF,6.3V,10%,X6SA    I30 @BASEBOARD_FAB2_LIB.BASEBOARD_FAB2(SCH_1):PAGE102
 R6P23    2      B RES_0402-4.75K,1%,1/16W,EMPTY,A    I46 @BASEBOARD_FAB2_LIB.BASEBOARD_FAB2(SCH_1):PAGE102
 R6P22    2      B RES_0402-4.75K,1%,1/16W,EMPTY,A    I47 @BASEBOARD_FAB2_LIB.BASEBOARD_FAB2(SCH_1):PAGE102
  C6P9    2      B CAP_A_0402V-0.1UF,16V,10%,X7R,A    I79 @BASEBOARD_FAB2_LIB.BASEBOARD_FAB2(SCH_1):PAGE102
 R6P21    2      B RES_0402-1.00K,1%,1/16W,CHIP,GA    I80 @BASEBOARD_FAB2_LIB.BASEBOARD_FAB2(SCH_1):PAGE102
 R6P20    2      B RES_0402-1.00K,1%,1/16W,CHIP,GA    I81 @BASEBOARD_FAB2_LIB.BASEBOARD_FAB2(SCH_1):PAGE102
  R7P9    2      B RES_0402-42.2,1.0%,1/16W,EMPTYA   I121 @BASEBOARD_FAB2_LIB.BASEBOARD_FAB2(SCH_1):PAGE103
 R7P12    2      B RES_0402-42.2,1.0%,1/16W,EMPTYA   I123 @BASEBOARD_FAB2_LIB.BASEBOARD_FAB2(SCH_1):PAGE103
  R7P6    2      B RES_0402-42.2,1.0%,1/16W,EMPTYA   I125 @BASEBOARD_FAB2_LIB.BASEBOARD_FAB2(SCH_1):PAGE103
  R7P7    2      B RES_0402-42.2,1.0%,1/16W,EMPTYA   I127 @BASEBOARD_FAB2_LIB.BASEBOARD_FAB2(SCH_1):PAGE103
  R7P3    2      B RES_0402-42.2,1.0%,1/16W,EMPTYA   I129 @BASEBOARD_FAB2_LIB.BASEBOARD_FAB2(SCH_1):PAGE103
  R7P4    2      B RES_0402-42.2,1.0%,1/16W,EMPTYA   I131 @BASEBOARD_FAB2_LIB.BASEBOARD_FAB2(SCH_1):PAGE103
  R7P1    2      B RES_0402-42.2,1.0%,1/16W,EMPTYA   I133 @BASEBOARD_FAB2_LIB.BASEBOARD_FAB2(SCH_1):PAGE103
  R7P2    2      B RES_0402-42.2,1.0%,1/16W,EMPTYA   I135 @BASEBOARD_FAB2_LIB.BASEBOARD_FAB2(SCH_1):PAGE103
  R6P7    2      B RES_0402-42.2,1.0%,1/16W,EMPTYA   I137 @BASEBOARD_FAB2_LIB.BASEBOARD_FAB2(SCH_1):PAGE103
  R6P8    2      B RES_0402-42.2,1.0%,1/16W,EMPTYA   I139 @BASEBOARD_FAB2_LIB.BASEBOARD_FAB2(SCH_1):PAGE103
  R6P5    2      B RES_0402-42.2,1.0%,1/16W,EMPTYA   I141 @BASEBOARD_FAB2_LIB.BASEBOARD_FAB2(SCH_1):PAGE103
  R6P6    2      B RES_0402-42.2,1.0%,1/16W,EMPTYA   I143 @BASEBOARD_FAB2_LIB.BASEBOARD_FAB2(SCH_1):PAGE103
  R6P3    2      B RES_0402-42.2,1.0%,1/16W,EMPTYA   I145 @BASEBOARD_FAB2_LIB.BASEBOARD_FAB2(SCH_1):PAGE103
  R6P4    2      B RES_0402-42.2,1.0%,1/16W,EMPTYA   I147 @BASEBOARD_FAB2_LIB.BASEBOARD_FAB2(SCH_1):PAGE103
  R6P1    2      B RES_0402-42.2,1.0%,1/16W,EMPTYA   I149 @BASEBOARD_FAB2_LIB.BASEBOARD_FAB2(SCH_1):PAGE103
  R6P2    2      B RES_0402-42.2,1.0%,1/16W,EMPTYA   I151 @BASEBOARD_FAB2_LIB.BASEBOARD_FAB2(SCH_1):PAGE103
 R6P11    2      B RES_0402-42.2,1.0%,1/16W,EMPTYA   I153 @BASEBOARD_FAB2_LIB.BASEBOARD_FAB2(SCH_1):PAGE103
  R6P9    2      B RES_0402-42.2,1.0%,1/16W,EMPTYA   I155 @BASEBOARD_FAB2_LIB.BASEBOARD_FAB2(SCH_1):PAGE103
 R6P13    2      B RES_0402-42.2,1.0%,1/16W,EMPTYA   I157 @BASEBOARD_FAB2_LIB.BASEBOARD_FAB2(SCH_1):PAGE103
 R6P12    2      B RES_0402-42.2,1.0%,1/16W,EMPTYA   I159 @BASEBOARD_FAB2_LIB.BASEBOARD_FAB2(SCH_1):PAGE103
 R4D24    2      B RES_0402-42.2,1.0%,1/16W,EMPTYA   I161 @BASEBOARD_FAB2_LIB.BASEBOARD_FAB2(SCH_1):PAGE103
 R4D18    2      B RES_0402-42.2,1.0%,1/16W,EMPTYA   I163 @BASEBOARD_FAB2_LIB.BASEBOARD_FAB2(SCH_1):PAGE103
 R6P17    2      B RES_0402-42.2,1.0%,1/16W,EMPTYA   I165 @BASEBOARD_FAB2_LIB.BASEBOARD_FAB2(SCH_1):PAGE103
 R6P15    2      B RES_0402-42.2,1.0%,1/16W,EMPTYA   I167 @BASEBOARD_FAB2_LIB.BASEBOARD_FAB2(SCH_1):PAGE103
  C6F1    2      B CAP_A_0402V-0.1UF,16V,10%,X7R,A    I25 @BASEBOARD_FAB2_LIB.BASEBOARD_FAB2(SCH_1):PAGE104
  C3F2    2      B CAP_A_0402V-0.1UF,16V,10%,X7R,A    I34 @BASEBOARD_FAB2_LIB.BASEBOARD_FAB2(SCH_1):PAGE104
  Y6F1    3    GND OSC_C_6P10-156.25MHZ,OSC,G6383A    I71 @BASEBOARD_FAB2_LIB.BASEBOARD_FAB2(SCH_1):PAGE104
  Y3F1    3    GND OSC_C_6P10-156.25MHZ,OSC,G6383A    I72 @BASEBOARD_FAB2_LIB.BASEBOARD_FAB2(SCH_1):PAGE104
 C2U20    2      B CAP_A_0402V-0.1UF,16V,10%,X7R,A     I1 @BASEBOARD_FAB2_LIB.BASEBOARD_FAB2(SCH_1):PAGE108
 C2U24    2      B CAP_A_0402V-0.1UF,16V,10%,X7R,A     I2 @BASEBOARD_FAB2_LIB.BASEBOARD_FAB2(SCH_1):PAGE108
 C2U21    2      B CAP_A_0402V-0.1UF,16V,10%,X7R,A     I5 @BASEBOARD_FAB2_LIB.BASEBOARD_FAB2(SCH_1):PAGE108
 C2U25    2      B CAP_A_0402V-0.1UF,16V,10%,X7R,A     I7 @BASEBOARD_FAB2_LIB.BASEBOARD_FAB2(SCH_1):PAGE108
  J8G1   13   IO13 SCONN200_H68296001_SM-CONN,H68A   I258 @BASEBOARD_FAB2_LIB.BASEBOARD_FAB2(SCH_1):PAGE108
  J8G1   14   IO14 SCONN200_H68296001_SM-CONN,H68A   I258 @BASEBOARD_FAB2_LIB.BASEBOARD_FAB2(SCH_1):PAGE108
  J8G1   26   IO26 SCONN200_H68296001_SM-CONN,H68A   I258 @BASEBOARD_FAB2_LIB.BASEBOARD_FAB2(SCH_1):PAGE108
  J8G1   31   IO31 SCONN200_H68296001_SM-CONN,H68A   I258 @BASEBOARD_FAB2_LIB.BASEBOARD_FAB2(SCH_1):PAGE108
  J8G1   34   IO34 SCONN200_H68296001_SM-CONN,H68A   I258 @BASEBOARD_FAB2_LIB.BASEBOARD_FAB2(SCH_1):PAGE108
  J8G1   37   IO37 SCONN200_H68296001_SM-CONN,H68A   I258 @BASEBOARD_FAB2_LIB.BASEBOARD_FAB2(SCH_1):PAGE108
  J8G1   40   IO40 SCONN200_H68296001_SM-CONN,H68A   I258 @BASEBOARD_FAB2_LIB.BASEBOARD_FAB2(SCH_1):PAGE108
  J8G1   43   IO43 SCONN200_H68296001_SM-CONN,H68A   I258 @BASEBOARD_FAB2_LIB.BASEBOARD_FAB2(SCH_1):PAGE108
  J8G1   46   IO46 SCONN200_H68296001_SM-CONN,H68A   I258 @BASEBOARD_FAB2_LIB.BASEBOARD_FAB2(SCH_1):PAGE108
  J8G1   49   IO49 SCONN200_H68296001_SM-CONN,H68A   I258 @BASEBOARD_FAB2_LIB.BASEBOARD_FAB2(SCH_1):PAGE108
  J8G1   52   IO52 SCONN200_H68296001_SM-CONN,H68A   I258 @BASEBOARD_FAB2_LIB.BASEBOARD_FAB2(SCH_1):PAGE108
  J8G1   55   IO55 SCONN200_H68296001_SM-CONN,H68A   I258 @BASEBOARD_FAB2_LIB.BASEBOARD_FAB2(SCH_1):PAGE108
  J8G1   58   IO58 SCONN200_H68296001_SM-CONN,H68A   I258 @BASEBOARD_FAB2_LIB.BASEBOARD_FAB2(SCH_1):PAGE108
  J8G1   61   IO61 SCONN200_H68296001_SM-CONN,H68A   I258 @BASEBOARD_FAB2_LIB.BASEBOARD_FAB2(SCH_1):PAGE108
  J8G1   64   IO64 SCONN200_H68296001_SM-CONN,H68A   I258 @BASEBOARD_FAB2_LIB.BASEBOARD_FAB2(SCH_1):PAGE108
  J8G1   65   IO65 SCONN200_H68296001_SM-CONN,H68A   I258 @BASEBOARD_FAB2_LIB.BASEBOARD_FAB2(SCH_1):PAGE108
  J8G1   68   IO68 SCONN200_H68296001_SM-CONN,H68A   I258 @BASEBOARD_FAB2_LIB.BASEBOARD_FAB2(SCH_1):PAGE108
  J8G1   71   IO71 SCONN200_H68296001_SM-CONN,H68A   I258 @BASEBOARD_FAB2_LIB.BASEBOARD_FAB2(SCH_1):PAGE108
  J8G1   74   IO74 SCONN200_H68296001_SM-CONN,H68A   I258 @BASEBOARD_FAB2_LIB.BASEBOARD_FAB2(SCH_1):PAGE108
  J8G1   77   IO77 SCONN200_H68296001_SM-CONN,H68A   I258 @BASEBOARD_FAB2_LIB.BASEBOARD_FAB2(SCH_1):PAGE108
  J8G1   80   IO80 SCONN200_H68296001_SM-CONN,H68A   I258 @BASEBOARD_FAB2_LIB.BASEBOARD_FAB2(SCH_1):PAGE108
  J8G1   83   IO83 SCONN200_H68296001_SM-CONN,H68A   I258 @BASEBOARD_FAB2_LIB.BASEBOARD_FAB2(SCH_1):PAGE108
  J8G1   86   IO86 SCONN200_H68296001_SM-CONN,H68A   I258 @BASEBOARD_FAB2_LIB.BASEBOARD_FAB2(SCH_1):PAGE108
  J8G1   89   IO89 SCONN200_H68296001_SM-CONN,H68A   I258 @BASEBOARD_FAB2_LIB.BASEBOARD_FAB2(SCH_1):PAGE108
  J8G1   92   IO92 SCONN200_H68296001_SM-CONN,H68A   I258 @BASEBOARD_FAB2_LIB.BASEBOARD_FAB2(SCH_1):PAGE108
  J8G1   95   IO95 SCONN200_H68296001_SM-CONN,H68A   I258 @BASEBOARD_FAB2_LIB.BASEBOARD_FAB2(SCH_1):PAGE108
  J8G1   98   IO98 SCONN200_H68296001_SM-CONN,H68A   I258 @BASEBOARD_FAB2_LIB.BASEBOARD_FAB2(SCH_1):PAGE108
  J8G1  MH1    MH1 SCONN200_H68296001_SM-CONN,H68A   I258 @BASEBOARD_FAB2_LIB.BASEBOARD_FAB2(SCH_1):PAGE108
  J8G1  MH2    MH2 SCONN200_H68296001_SM-CONN,H68A   I258 @BASEBOARD_FAB2_LIB.BASEBOARD_FAB2(SCH_1):PAGE108
 C2U23    2      B CAP_A_0402V-0.1UF,16V,10%,X7R,A   I315 @BASEBOARD_FAB2_LIB.BASEBOARD_FAB2(SCH_1):PAGE108
 C2U22    2      B CAP_A_0402V-0.1UF,16V,10%,X7R,A   I318 @BASEBOARD_FAB2_LIB.BASEBOARD_FAB2(SCH_1):PAGE108
  C9A2    2      B CAP_A_0402V-0.1UF,16V,10%,X7R,A    I10 @BASEBOARD_FAB2_LIB.BASEBOARD_FAB2(SCH_1):PAGE111
  C9A5    2      B CAP_A_0402V-0.1UF,16V,10%,X7R,A    I12 @BASEBOARD_FAB2_LIB.BASEBOARD_FAB2(SCH_1):PAGE111
  C1L8    2      B CAP_A_0402V-0.1UF,16V,10%,X7R,A    I14 @BASEBOARD_FAB2_LIB.BASEBOARD_FAB2(SCH_1):PAGE111
  C9A6    2      B CAP_A_0402V-1.0UF,6.3V,10%,X6SA    I25 @BASEBOARD_FAB2_LIB.BASEBOARD_FAB2(SCH_1):PAGE111
  J9A3    2    IO2 SCONN60_C21100002_SMLF-CONN,C2A    I26 @BASEBOARD_FAB2_LIB.BASEBOARD_FAB2(SCH_1):PAGE111
  J9A3    7    IO7 SCONN60_C21100002_SMLF-CONN,C2A    I26 @BASEBOARD_FAB2_LIB.BASEBOARD_FAB2(SCH_1):PAGE111
  J9A3    8    IO8 SCONN60_C21100002_SMLF-CONN,C2A    I26 @BASEBOARD_FAB2_LIB.BASEBOARD_FAB2(SCH_1):PAGE111
  J9A3   13   IO13 SCONN60_C21100002_SMLF-CONN,C2A    I26 @BASEBOARD_FAB2_LIB.BASEBOARD_FAB2(SCH_1):PAGE111
  J9A3   14   IO14 SCONN60_C21100002_SMLF-CONN,C2A    I26 @BASEBOARD_FAB2_LIB.BASEBOARD_FAB2(SCH_1):PAGE111
  J9A3   19   IO19 SCONN60_C21100002_SMLF-CONN,C2A    I26 @BASEBOARD_FAB2_LIB.BASEBOARD_FAB2(SCH_1):PAGE111
  J9A3   20   IO20 SCONN60_C21100002_SMLF-CONN,C2A    I26 @BASEBOARD_FAB2_LIB.BASEBOARD_FAB2(SCH_1):PAGE111
  J9A3   25   IO25 SCONN60_C21100002_SMLF-CONN,C2A    I26 @BASEBOARD_FAB2_LIB.BASEBOARD_FAB2(SCH_1):PAGE111
  J9A3   26   IO26 SCONN60_C21100002_SMLF-CONN,C2A    I26 @BASEBOARD_FAB2_LIB.BASEBOARD_FAB2(SCH_1):PAGE111
  J9A3   31   IO31 SCONN60_C21100002_SMLF-CONN,C2A    I26 @BASEBOARD_FAB2_LIB.BASEBOARD_FAB2(SCH_1):PAGE111
  J9A3   32   IO32 SCONN60_C21100002_SMLF-CONN,C2A    I26 @BASEBOARD_FAB2_LIB.BASEBOARD_FAB2(SCH_1):PAGE111
  J9A3   37   IO37 SCONN60_C21100002_SMLF-CONN,C2A    I26 @BASEBOARD_FAB2_LIB.BASEBOARD_FAB2(SCH_1):PAGE111
  J9A3   38   IO38 SCONN60_C21100002_SMLF-CONN,C2A    I26 @BASEBOARD_FAB2_LIB.BASEBOARD_FAB2(SCH_1):PAGE111
  J9A3   49   IO49 SCONN60_C21100002_SMLF-CONN,C2A    I26 @BASEBOARD_FAB2_LIB.BASEBOARD_FAB2(SCH_1):PAGE111
  J9A3   50   IO50 SCONN60_C21100002_SMLF-CONN,C2A    I26 @BASEBOARD_FAB2_LIB.BASEBOARD_FAB2(SCH_1):PAGE111
  J9A3   59   IO59 SCONN60_C21100002_SMLF-CONN,C2A    I26 @BASEBOARD_FAB2_LIB.BASEBOARD_FAB2(SCH_1):PAGE111
  C1L5    2      B CAP_A_0402V-1.0UF,6.3V,10%,X6SA    I30 @BASEBOARD_FAB2_LIB.BASEBOARD_FAB2(SCH_1):PAGE111
  C9A4    2      B CAP_A_0402V-0.1UF,16V,10%,X7R,A    I59 @BASEBOARD_FAB2_LIB.BASEBOARD_FAB2(SCH_1):PAGE111
 C1L11    2      B CAP_A_0402V-0.1UF,16V,10%,X7R,A    I87 @BASEBOARD_FAB2_LIB.BASEBOARD_FAB2(SCH_1):PAGE111
  U1M7    2    GND NC7SB3157_SMLF-IC,C99406-001    I40 @BASEBOARD_FAB2_LIB.BASEBOARD_FAB2(SCH_1):PAGE112
 C1M36    2      B CAP_A_0402V-0.01UF,25V,10%,X7RA    I42 @BASEBOARD_FAB2_LIB.BASEBOARD_FAB2(SCH_1):PAGE112
 C1M37    2      B CAP_A_0402V-1.0UF,6.3V,10%,X6SA    I47 @BASEBOARD_FAB2_LIB.BASEBOARD_FAB2(SCH_1):PAGE112
 R7P29    2      B RES_0402-51.1,1.0%,1/16W,CHIP,A    I61 @BASEBOARD_FAB2_LIB.BASEBOARD_FAB2(SCH_1):PAGE112
  R6T5    2      B RES_0402-1.00K,1%,1/16W,CHIP,GA    I62 @BASEBOARD_FAB2_LIB.BASEBOARD_FAB2(SCH_1):PAGE112
 R3M10    2      B RES_0402-1.00K,1%,1/16W,CHIP,GA    I85 @BASEBOARD_FAB2_LIB.BASEBOARD_FAB2(SCH_1):PAGE112
  R8B2    2      B RES_0402-1.00K,1%,1/16W,CHIP,GA    I94 @BASEBOARD_FAB2_LIB.BASEBOARD_FAB2(SCH_1):PAGE112
  R8B1    2      B RES_0402-51.1,1.0%,1/16W,CHIP,A    I95 @BASEBOARD_FAB2_LIB.BASEBOARD_FAB2(SCH_1):PAGE112
 C1M30    2      B CAP_A_0402V-0.01UF,25V,10%,X7RA   I131 @BASEBOARD_FAB2_LIB.BASEBOARD_FAB2(SCH_1):PAGE112
  C1L1    2      B CAP_0402-1.0UF,16V,10%,X6S,D97A   I136 @BASEBOARD_FAB2_LIB.BASEBOARD_FAB2(SCH_1):PAGE112
 C1L19    2      B CAP_0402-1.0UF,16V,10%,X6S,D97A   I140 @BASEBOARD_FAB2_LIB.BASEBOARD_FAB2(SCH_1):PAGE112
  U1M2    2    GND NC7SB3157_SMLF-IC,C99406-001   I107 @BASEBOARD_FAB2_LIB.BASEBOARD_FAB2(SCH_1):PAGE113
 C1M31    2      B CAP_A_0402V-0.01UF,25V,10%,X7RA   I116 @BASEBOARD_FAB2_LIB.BASEBOARD_FAB2(SCH_1):PAGE113
 C1M32    2      B CAP_A_0402V-1.0UF,6.3V,10%,X6SA   I117 @BASEBOARD_FAB2_LIB.BASEBOARD_FAB2(SCH_1):PAGE113
 C1M28    2      B CAP_A_0402V-0.01UF,25V,10%,X7RA   I119 @BASEBOARD_FAB2_LIB.BASEBOARD_FAB2(SCH_1):PAGE113
 C1M29    2      B CAP_A_0402V-0.1UF,16V,10%,X7R,A   I147 @BASEBOARD_FAB2_LIB.BASEBOARD_FAB2(SCH_1):PAGE113
  J9B4    2    IO2 SCONN10_C12536004_SMLF-CONN,C1A   I175 @BASEBOARD_FAB2_LIB.BASEBOARD_FAB2(SCH_1):PAGE113
  J9B4   10   IO10 SCONN10_C12536004_SMLF-CONN,C1A   I175 @BASEBOARD_FAB2_LIB.BASEBOARD_FAB2(SCH_1):PAGE113
  R9B9    2      B RES_0402-1.00K,1%,1/16W,CHIP,GA   I179 @BASEBOARD_FAB2_LIB.BASEBOARD_FAB2(SCH_1):PAGE113
  U9A5    4      B 74CBTLV1G125_SMLF-IC,C88177-00A   I185 @BASEBOARD_FAB2_LIB.BASEBOARD_FAB2(SCH_1):PAGE113
 R1M23    2      B RES_0402-1.00K,1%,1/16W,EMPTY,A   I199 @BASEBOARD_FAB2_LIB.BASEBOARD_FAB2(SCH_1):PAGE113
  C4R2    2      B CAP_A_0402V-0.1UF,16V,10%,X7R,A   I246 @BASEBOARD_FAB2_LIB.BASEBOARD_FAB2(SCH_1):PAGE113
 C1M33    2      B CAP_A_0402V-0.1UF,16V,10%,X7R,A   I248 @BASEBOARD_FAB2_LIB.BASEBOARD_FAB2(SCH_1):PAGE113
  C6M6    2      B CAP_A_0402V-0.1UF,16V,10%,X7R,A   I250 @BASEBOARD_FAB2_LIB.BASEBOARD_FAB2(SCH_1):PAGE113
  U2M1    2    GND NC7SB3157_SMLF-IC,C99406-001   I255 @BASEBOARD_FAB2_LIB.BASEBOARD_FAB2(SCH_1):PAGE113
 C1M34    2      B CAP_A_0402V-0.01UF,25V,10%,X7RA   I265 @BASEBOARD_FAB2_LIB.BASEBOARD_FAB2(SCH_1):PAGE113
 C1M35    2      B CAP_A_0402V-0.01UF,25V,10%,X7RA   I266 @BASEBOARD_FAB2_LIB.BASEBOARD_FAB2(SCH_1):PAGE113
 C1L20    2      B CAP_A_0402V-0.01UF,25V,10%,X7RA   I267 @BASEBOARD_FAB2_LIB.BASEBOARD_FAB2(SCH_1):PAGE113
  C7C5    2      B CAP_0402LF-15.0PF,50V,5%,COG,AA    I47 @BASEBOARD_FAB2_LIB.BASEBOARD_FAB2(SCH_1):PAGE114
  C7C4    2      B CAP_0402LF-15.0PF,50V,5%,COG,AA    I50 @BASEBOARD_FAB2_LIB.BASEBOARD_FAB2(SCH_1):PAGE114
 R8B21    2      B RES_0402-49.9,1%,1/16W,EMPTY,GA   I124 @BASEBOARD_FAB2_LIB.BASEBOARD_FAB2(SCH_1):PAGE114
  R3N1    2      B RES_0402-169,1.0%,1/16W,CHIP,GA   I149 @BASEBOARD_FAB2_LIB.BASEBOARD_FAB2(SCH_1):PAGE114
  R8B9    2      B RES_0402-113,1%,1/16W,CHIP,G21A    I90 @BASEBOARD_FAB2_LIB.BASEBOARD_FAB2(SCH_1):PAGE115
 R8B32    2      B RES_0402-10.0K,1%,1/16W,CHIP,GA   I114 @BASEBOARD_FAB2_LIB.BASEBOARD_FAB2(SCH_1):PAGE115
  R7B8    2      B RES_0402-10.0K,1%,1/16W,EMPTY,A   I229 @BASEBOARD_FAB2_LIB.BASEBOARD_FAB2(SCH_1):PAGE116
  R7B7    2      B RES_0402-10.0K,1%,1/16W,EMPTY,A   I230 @BASEBOARD_FAB2_LIB.BASEBOARD_FAB2(SCH_1):PAGE116
  R3M9    2      B RES_0402-100.0K,1%,1/16W,CHIP,A   I234 @BASEBOARD_FAB2_LIB.BASEBOARD_FAB2(SCH_1):PAGE116
  R3M8    2      B RES_0402-100.0K,1%,1/16W,CHIP,A   I235 @BASEBOARD_FAB2_LIB.BASEBOARD_FAB2(SCH_1):PAGE116
 R3N14    2      B RES_0402-49.9,1%,1/16W,EMPTY,GA    I67 @BASEBOARD_FAB2_LIB.BASEBOARD_FAB2(SCH_1):PAGE118
  C7D1    2      B CAP_A_0402V-0.1UF,16V,10%,X7R,A   I136 @BASEBOARD_FAB2_LIB.BASEBOARD_FAB2(SCH_1):PAGE118
  Q9A2    1 SOURCE<0> FET_N_DUAL_SMLF-NTJD4001N,FET,A   I175 @BASEBOARD_FAB2_LIB.BASEBOARD_FAB2(SCH_1):PAGE119
  Q9A2    4 SOURCE<0> FET_N_DUAL_SMLF-NTJD4001N,FET,A   I180 @BASEBOARD_FAB2_LIB.BASEBOARD_FAB2(SCH_1):PAGE119
 R8C26    2      B RES_0402-100.0,1%,1/16W,CHIP,GA    I35 @BASEBOARD_FAB2_LIB.BASEBOARD_FAB2(SCH_1):PAGE121
 R7C20    2      B RES_0402-10.0K,1%,1/16W,CHIP,GA    I73 @BASEBOARD_FAB2_LIB.BASEBOARD_FAB2(SCH_1):PAGE121
  U7C1  N31 VSS<355> LBG_CORE_QAT_EXT_D_BGA1-IC,H91A    I13 @BASEBOARD_FAB2_LIB.BASEBOARD_FAB2(SCH_1):PAGE123
  U7C1  N27 VSS<356> LBG_CORE_QAT_EXT_D_BGA1-IC,H91A    I13 @BASEBOARD_FAB2_LIB.BASEBOARD_FAB2(SCH_1):PAGE123
  U7C1  N24 VSS<357> LBG_CORE_QAT_EXT_D_BGA1-IC,H91A    I13 @BASEBOARD_FAB2_LIB.BASEBOARD_FAB2(SCH_1):PAGE123
  U7C1  N20 VSS<358> LBG_CORE_QAT_EXT_D_BGA1-IC,H91A    I13 @BASEBOARD_FAB2_LIB.BASEBOARD_FAB2(SCH_1):PAGE123
  U7C1  N17 VSS<359> LBG_CORE_QAT_EXT_D_BGA1-IC,H91A    I13 @BASEBOARD_FAB2_LIB.BASEBOARD_FAB2(SCH_1):PAGE123
  U7C1  N13 VSS<360> LBG_CORE_QAT_EXT_D_BGA1-IC,H91A    I13 @BASEBOARD_FAB2_LIB.BASEBOARD_FAB2(SCH_1):PAGE123
  U7C1  M48 VSS<361> LBG_CORE_QAT_EXT_D_BGA1-IC,H91A    I13 @BASEBOARD_FAB2_LIB.BASEBOARD_FAB2(SCH_1):PAGE123
  U7C1  M44 VSS<362> LBG_CORE_QAT_EXT_D_BGA1-IC,H91A    I13 @BASEBOARD_FAB2_LIB.BASEBOARD_FAB2(SCH_1):PAGE123
  U7C1  N50 VSS<363> LBG_CORE_QAT_EXT_D_BGA1-IC,H91A    I13 @BASEBOARD_FAB2_LIB.BASEBOARD_FAB2(SCH_1):PAGE123
  U7C1  N42 VSS<364> LBG_CORE_QAT_EXT_D_BGA1-IC,H91A    I13 @BASEBOARD_FAB2_LIB.BASEBOARD_FAB2(SCH_1):PAGE123
  U7C1  M40 VSS<365> LBG_CORE_QAT_EXT_D_BGA1-IC,H91A    I13 @BASEBOARD_FAB2_LIB.BASEBOARD_FAB2(SCH_1):PAGE123
  U7C1   M4 VSS<366> LBG_CORE_QAT_EXT_D_BGA1-IC,H91A    I13 @BASEBOARD_FAB2_LIB.BASEBOARD_FAB2(SCH_1):PAGE123
  U7C1  M37 VSS<367> LBG_CORE_QAT_EXT_D_BGA1-IC,H91A    I13 @BASEBOARD_FAB2_LIB.BASEBOARD_FAB2(SCH_1):PAGE123
  U7C1  M33 VSS<368> LBG_CORE_QAT_EXT_D_BGA1-IC,H91A    I13 @BASEBOARD_FAB2_LIB.BASEBOARD_FAB2(SCH_1):PAGE123
  U7C1  M29 VSS<369> LBG_CORE_QAT_EXT_D_BGA1-IC,H91A    I13 @BASEBOARD_FAB2_LIB.BASEBOARD_FAB2(SCH_1):PAGE123
  U7C1  M26 VSS<370> LBG_CORE_QAT_EXT_D_BGA1-IC,H91A    I13 @BASEBOARD_FAB2_LIB.BASEBOARD_FAB2(SCH_1):PAGE123
  U7C1  M22 VSS<371> LBG_CORE_QAT_EXT_D_BGA1-IC,H91A    I13 @BASEBOARD_FAB2_LIB.BASEBOARD_FAB2(SCH_1):PAGE123
  U7C1   M2 VSS<372> LBG_CORE_QAT_EXT_D_BGA1-IC,H91A    I13 @BASEBOARD_FAB2_LIB.BASEBOARD_FAB2(SCH_1):PAGE123
  U7C1  L68 VSS<373> LBG_CORE_QAT_EXT_D_BGA1-IC,H91A    I13 @BASEBOARD_FAB2_LIB.BASEBOARD_FAB2(SCH_1):PAGE123
  U7C1   L5 VSS<374> LBG_CORE_QAT_EXT_D_BGA1-IC,H91A    I13 @BASEBOARD_FAB2_LIB.BASEBOARD_FAB2(SCH_1):PAGE123
  U7C1  K71 VSS<375> LBG_CORE_QAT_EXT_D_BGA1-IC,H91A    I13 @BASEBOARD_FAB2_LIB.BASEBOARD_FAB2(SCH_1):PAGE123
  U7C1  K69 VSS<376> LBG_CORE_QAT_EXT_D_BGA1-IC,H91A    I13 @BASEBOARD_FAB2_LIB.BASEBOARD_FAB2(SCH_1):PAGE123
  U7C1  K54 VSS<377> LBG_CORE_QAT_EXT_D_BGA1-IC,H91A    I13 @BASEBOARD_FAB2_LIB.BASEBOARD_FAB2(SCH_1):PAGE123
  U7C1  J70 VSS<378> LBG_CORE_QAT_EXT_D_BGA1-IC,H91A    I13 @BASEBOARD_FAB2_LIB.BASEBOARD_FAB2(SCH_1):PAGE123
  U7C1  J68 VSS<379> LBG_CORE_QAT_EXT_D_BGA1-IC,H91A    I13 @BASEBOARD_FAB2_LIB.BASEBOARD_FAB2(SCH_1):PAGE123
  U7C1  J59 VSS<380> LBG_CORE_QAT_EXT_D_BGA1-IC,H91A    I13 @BASEBOARD_FAB2_LIB.BASEBOARD_FAB2(SCH_1):PAGE123
  U7C1  J44 VSS<381> LBG_CORE_QAT_EXT_D_BGA1-IC,H91A    I13 @BASEBOARD_FAB2_LIB.BASEBOARD_FAB2(SCH_1):PAGE123
  U7C1  J37 VSS<382> LBG_CORE_QAT_EXT_D_BGA1-IC,H91A    I13 @BASEBOARD_FAB2_LIB.BASEBOARD_FAB2(SCH_1):PAGE123
  U7C1  J22 VSS<383> LBG_CORE_QAT_EXT_D_BGA1-IC,H91A    I13 @BASEBOARD_FAB2_LIB.BASEBOARD_FAB2(SCH_1):PAGE123
  U7C1  J15 VSS<384> LBG_CORE_QAT_EXT_D_BGA1-IC,H91A    I13 @BASEBOARD_FAB2_LIB.BASEBOARD_FAB2(SCH_1):PAGE123
  U7C1  J11 VSS<385> LBG_CORE_QAT_EXT_D_BGA1-IC,H91A    I13 @BASEBOARD_FAB2_LIB.BASEBOARD_FAB2(SCH_1):PAGE123
  U7C1  H65 VSS<386> LBG_CORE_QAT_EXT_D_BGA1-IC,H91A    I13 @BASEBOARD_FAB2_LIB.BASEBOARD_FAB2(SCH_1):PAGE123
  U7C1   J7 VSS<387> LBG_CORE_QAT_EXT_D_BGA1-IC,H91A    I13 @BASEBOARD_FAB2_LIB.BASEBOARD_FAB2(SCH_1):PAGE123
  U7C1   J5 VSS<388> LBG_CORE_QAT_EXT_D_BGA1-IC,H91A    I13 @BASEBOARD_FAB2_LIB.BASEBOARD_FAB2(SCH_1):PAGE123
  U7C1  J29 VSS<389> LBG_CORE_QAT_EXT_D_BGA1-IC,H91A    I13 @BASEBOARD_FAB2_LIB.BASEBOARD_FAB2(SCH_1):PAGE123
  U7C1  H58 VSS<390> LBG_CORE_QAT_EXT_D_BGA1-IC,H91A    I13 @BASEBOARD_FAB2_LIB.BASEBOARD_FAB2(SCH_1):PAGE123
  U7C1  G66 VSS<391> LBG_CORE_QAT_EXT_D_BGA1-IC,H91A    I13 @BASEBOARD_FAB2_LIB.BASEBOARD_FAB2(SCH_1):PAGE123
  U7C1  G63 VSS<392> LBG_CORE_QAT_EXT_D_BGA1-IC,H91A    I13 @BASEBOARD_FAB2_LIB.BASEBOARD_FAB2(SCH_1):PAGE123
  U7C1   G6 VSS<393> LBG_CORE_QAT_EXT_D_BGA1-IC,H91A    I13 @BASEBOARD_FAB2_LIB.BASEBOARD_FAB2(SCH_1):PAGE123
  U7C1  G48 VSS<394> LBG_CORE_QAT_EXT_D_BGA1-IC,H91A    I13 @BASEBOARD_FAB2_LIB.BASEBOARD_FAB2(SCH_1):PAGE123
  U7C1  G37 VSS<395> LBG_CORE_QAT_EXT_D_BGA1-IC,H91A    I13 @BASEBOARD_FAB2_LIB.BASEBOARD_FAB2(SCH_1):PAGE123
  U7C1  G29 VSS<396> LBG_CORE_QAT_EXT_D_BGA1-IC,H91A    I13 @BASEBOARD_FAB2_LIB.BASEBOARD_FAB2(SCH_1):PAGE123
  U7C1  G22 VSS<397> LBG_CORE_QAT_EXT_D_BGA1-IC,H91A    I13 @BASEBOARD_FAB2_LIB.BASEBOARD_FAB2(SCH_1):PAGE123
  U7C1   E9 VSS<398> LBG_CORE_QAT_EXT_D_BGA1-IC,H91A    I13 @BASEBOARD_FAB2_LIB.BASEBOARD_FAB2(SCH_1):PAGE123
  U7C1  G59 VSS<399> LBG_CORE_QAT_EXT_D_BGA1-IC,H91A    I13 @BASEBOARD_FAB2_LIB.BASEBOARD_FAB2(SCH_1):PAGE123
  U7C1  E63 VSS<400> LBG_CORE_QAT_EXT_D_BGA1-IC,H91A    I13 @BASEBOARD_FAB2_LIB.BASEBOARD_FAB2(SCH_1):PAGE123
  U7C1  E61 VSS<401> LBG_CORE_QAT_EXT_D_BGA1-IC,H91A    I13 @BASEBOARD_FAB2_LIB.BASEBOARD_FAB2(SCH_1):PAGE123
  U7C1   E6 VSS<402> LBG_CORE_QAT_EXT_D_BGA1-IC,H91A    I13 @BASEBOARD_FAB2_LIB.BASEBOARD_FAB2(SCH_1):PAGE123
  U7C1  E57 VSS<403> LBG_CORE_QAT_EXT_D_BGA1-IC,H91A    I13 @BASEBOARD_FAB2_LIB.BASEBOARD_FAB2(SCH_1):PAGE123
  U7C1  E54 VSS<404> LBG_CORE_QAT_EXT_D_BGA1-IC,H91A    I13 @BASEBOARD_FAB2_LIB.BASEBOARD_FAB2(SCH_1):PAGE123
  U7C1  E52 VSS<405> LBG_CORE_QAT_EXT_D_BGA1-IC,H91A    I13 @BASEBOARD_FAB2_LIB.BASEBOARD_FAB2(SCH_1):PAGE123
  U7C1  E50 VSS<406> LBG_CORE_QAT_EXT_D_BGA1-IC,H91A    I13 @BASEBOARD_FAB2_LIB.BASEBOARD_FAB2(SCH_1):PAGE123
  U7C1  E48 VSS<407> LBG_CORE_QAT_EXT_D_BGA1-IC,H91A    I13 @BASEBOARD_FAB2_LIB.BASEBOARD_FAB2(SCH_1):PAGE123
  U7C1  E45 VSS<408> LBG_CORE_QAT_EXT_D_BGA1-IC,H91A    I13 @BASEBOARD_FAB2_LIB.BASEBOARD_FAB2(SCH_1):PAGE123
  U7C1  E43 VSS<409> LBG_CORE_QAT_EXT_D_BGA1-IC,H91A    I13 @BASEBOARD_FAB2_LIB.BASEBOARD_FAB2(SCH_1):PAGE123
  U7C1  E41 VSS<410> LBG_CORE_QAT_EXT_D_BGA1-IC,H91A    I13 @BASEBOARD_FAB2_LIB.BASEBOARD_FAB2(SCH_1):PAGE123
  U7C1  E39 VSS<411> LBG_CORE_QAT_EXT_D_BGA1-IC,H91A    I13 @BASEBOARD_FAB2_LIB.BASEBOARD_FAB2(SCH_1):PAGE123
  U7C1  E37 VSS<412> LBG_CORE_QAT_EXT_D_BGA1-IC,H91A    I13 @BASEBOARD_FAB2_LIB.BASEBOARD_FAB2(SCH_1):PAGE123
  U7C1  E34 VSS<413> LBG_CORE_QAT_EXT_D_BGA1-IC,H91A    I13 @BASEBOARD_FAB2_LIB.BASEBOARD_FAB2(SCH_1):PAGE123
  U7C1  E32 VSS<414> LBG_CORE_QAT_EXT_D_BGA1-IC,H91A    I13 @BASEBOARD_FAB2_LIB.BASEBOARD_FAB2(SCH_1):PAGE123
  U7C1  E30 VSS<415> LBG_CORE_QAT_EXT_D_BGA1-IC,H91A    I13 @BASEBOARD_FAB2_LIB.BASEBOARD_FAB2(SCH_1):PAGE123
  U7C1  E28 VSS<416> LBG_CORE_QAT_EXT_D_BGA1-IC,H91A    I13 @BASEBOARD_FAB2_LIB.BASEBOARD_FAB2(SCH_1):PAGE123
  U7C1  E26 VSS<417> LBG_CORE_QAT_EXT_D_BGA1-IC,H91A    I13 @BASEBOARD_FAB2_LIB.BASEBOARD_FAB2(SCH_1):PAGE123
  U7C1  E24 VSS<418> LBG_CORE_QAT_EXT_D_BGA1-IC,H91A    I13 @BASEBOARD_FAB2_LIB.BASEBOARD_FAB2(SCH_1):PAGE123
  U7C1  E22 VSS<419> LBG_CORE_QAT_EXT_D_BGA1-IC,H91A    I13 @BASEBOARD_FAB2_LIB.BASEBOARD_FAB2(SCH_1):PAGE123
  U7C1  E20 VSS<420> LBG_CORE_QAT_EXT_D_BGA1-IC,H91A    I13 @BASEBOARD_FAB2_LIB.BASEBOARD_FAB2(SCH_1):PAGE123
  U7C1  E15 VSS<421> LBG_CORE_QAT_EXT_D_BGA1-IC,H91A    I13 @BASEBOARD_FAB2_LIB.BASEBOARD_FAB2(SCH_1):PAGE123
  U7C1  E13 VSS<422> LBG_CORE_QAT_EXT_D_BGA1-IC,H91A    I13 @BASEBOARD_FAB2_LIB.BASEBOARD_FAB2(SCH_1):PAGE123
  U7C1  E11 VSS<423> LBG_CORE_QAT_EXT_D_BGA1-IC,H91A    I13 @BASEBOARD_FAB2_LIB.BASEBOARD_FAB2(SCH_1):PAGE123
  U7C1  D47 VSS<424> LBG_CORE_QAT_EXT_D_BGA1-IC,H91A    I13 @BASEBOARD_FAB2_LIB.BASEBOARD_FAB2(SCH_1):PAGE123
  U7C1  E65 VSS<425> LBG_CORE_QAT_EXT_D_BGA1-IC,H91A    I13 @BASEBOARD_FAB2_LIB.BASEBOARD_FAB2(SCH_1):PAGE123
  U7C1  E59 VSS<426> LBG_CORE_QAT_EXT_D_BGA1-IC,H91A    I13 @BASEBOARD_FAB2_LIB.BASEBOARD_FAB2(SCH_1):PAGE123
  U7C1  D27 VSS<427> LBG_CORE_QAT_EXT_D_BGA1-IC,H91A    I13 @BASEBOARD_FAB2_LIB.BASEBOARD_FAB2(SCH_1):PAGE123
  U7C1  D25 VSS<428> LBG_CORE_QAT_EXT_D_BGA1-IC,H91A    I13 @BASEBOARD_FAB2_LIB.BASEBOARD_FAB2(SCH_1):PAGE123
  U7C1  D19 VSS<429> LBG_CORE_QAT_EXT_D_BGA1-IC,H91A    I13 @BASEBOARD_FAB2_LIB.BASEBOARD_FAB2(SCH_1):PAGE123
  U7C1  D16 VSS<430> LBG_CORE_QAT_EXT_D_BGA1-IC,H91A    I13 @BASEBOARD_FAB2_LIB.BASEBOARD_FAB2(SCH_1):PAGE123
  U7C1  D12 VSS<431> LBG_CORE_QAT_EXT_D_BGA1-IC,H91A    I13 @BASEBOARD_FAB2_LIB.BASEBOARD_FAB2(SCH_1):PAGE123
  U7C1  C65 VSS<432> LBG_CORE_QAT_EXT_D_BGA1-IC,H91A    I13 @BASEBOARD_FAB2_LIB.BASEBOARD_FAB2(SCH_1):PAGE123
  U7C1  C41 VSS<433> LBG_CORE_QAT_EXT_D_BGA1-IC,H91A    I13 @BASEBOARD_FAB2_LIB.BASEBOARD_FAB2(SCH_1):PAGE123
  U7C1  C37 VSS<434> LBG_CORE_QAT_EXT_D_BGA1-IC,H91A    I13 @BASEBOARD_FAB2_LIB.BASEBOARD_FAB2(SCH_1):PAGE123
  U7C1  C34 VSS<435> LBG_CORE_QAT_EXT_D_BGA1-IC,H91A    I13 @BASEBOARD_FAB2_LIB.BASEBOARD_FAB2(SCH_1):PAGE123
  U7C1  C30 VSS<436> LBG_CORE_QAT_EXT_D_BGA1-IC,H91A    I13 @BASEBOARD_FAB2_LIB.BASEBOARD_FAB2(SCH_1):PAGE123
  U7C1  C22 VSS<437> LBG_CORE_QAT_EXT_D_BGA1-IC,H91A    I13 @BASEBOARD_FAB2_LIB.BASEBOARD_FAB2(SCH_1):PAGE123
  U7C1  B47 VSS<438> LBG_CORE_QAT_EXT_D_BGA1-IC,H91A    I13 @BASEBOARD_FAB2_LIB.BASEBOARD_FAB2(SCH_1):PAGE123
  U7C1  B27 VSS<439> LBG_CORE_QAT_EXT_D_BGA1-IC,H91A    I13 @BASEBOARD_FAB2_LIB.BASEBOARD_FAB2(SCH_1):PAGE123
  U7C1  B25 VSS<440> LBG_CORE_QAT_EXT_D_BGA1-IC,H91A    I13 @BASEBOARD_FAB2_LIB.BASEBOARD_FAB2(SCH_1):PAGE123
  U7C1  B19 VSS<441> LBG_CORE_QAT_EXT_D_BGA1-IC,H91A    I13 @BASEBOARD_FAB2_LIB.BASEBOARD_FAB2(SCH_1):PAGE123
  U7C1  B12 VSS<442> LBG_CORE_QAT_EXT_D_BGA1-IC,H91A    I13 @BASEBOARD_FAB2_LIB.BASEBOARD_FAB2(SCH_1):PAGE123
  U7C1  A41 VSS<443> LBG_CORE_QAT_EXT_D_BGA1-IC,H91A    I13 @BASEBOARD_FAB2_LIB.BASEBOARD_FAB2(SCH_1):PAGE123
  U7C1  A37 VSS<444> LBG_CORE_QAT_EXT_D_BGA1-IC,H91A    I13 @BASEBOARD_FAB2_LIB.BASEBOARD_FAB2(SCH_1):PAGE123
  U7C1  A34 VSS<445> LBG_CORE_QAT_EXT_D_BGA1-IC,H91A    I13 @BASEBOARD_FAB2_LIB.BASEBOARD_FAB2(SCH_1):PAGE123
  U7C1  A30 VSS<446> LBG_CORE_QAT_EXT_D_BGA1-IC,H91A    I13 @BASEBOARD_FAB2_LIB.BASEBOARD_FAB2(SCH_1):PAGE123
  U7C1  A22 VSS<447> LBG_CORE_QAT_EXT_D_BGA1-IC,H91A    I13 @BASEBOARD_FAB2_LIB.BASEBOARD_FAB2(SCH_1):PAGE123
  U7C1  A18 VSS<448> LBG_CORE_QAT_EXT_D_BGA1-IC,H91A    I13 @BASEBOARD_FAB2_LIB.BASEBOARD_FAB2(SCH_1):PAGE123
  U7C1  Y70 VSS<449> LBG_CORE_QAT_EXT_D_BGA1-IC,H91A    I13 @BASEBOARD_FAB2_LIB.BASEBOARD_FAB2(SCH_1):PAGE123
  U7C1  Y72 VSS<450> LBG_CORE_QAT_EXT_D_BGA1-IC,H91A    I13 @BASEBOARD_FAB2_LIB.BASEBOARD_FAB2(SCH_1):PAGE123
  U7C1 AT37 VSS<451> LBG_CORE_QAT_EXT_D_BGA1-IC,H91A    I13 @BASEBOARD_FAB2_LIB.BASEBOARD_FAB2(SCH_1):PAGE123
  U7C1 BB48 VSS<452> LBG_CORE_QAT_EXT_D_BGA1-IC,H91A    I13 @BASEBOARD_FAB2_LIB.BASEBOARD_FAB2(SCH_1):PAGE123
  U7C1 CA70 VSS<453> LBG_CORE_QAT_EXT_D_BGA1-IC,H91A    I13 @BASEBOARD_FAB2_LIB.BASEBOARD_FAB2(SCH_1):PAGE123
  U7C1 BW72 VSS<454> LBG_CORE_QAT_EXT_D_BGA1-IC,H91A    I13 @BASEBOARD_FAB2_LIB.BASEBOARD_FAB2(SCH_1):PAGE123
  U7C1 BW70 VSS<455> LBG_CORE_QAT_EXT_D_BGA1-IC,H91A    I13 @BASEBOARD_FAB2_LIB.BASEBOARD_FAB2(SCH_1):PAGE123
  U7C1 BU72 VSS<456> LBG_CORE_QAT_EXT_D_BGA1-IC,H91A    I13 @BASEBOARD_FAB2_LIB.BASEBOARD_FAB2(SCH_1):PAGE123
  U7C1 BR72 VSS<457> LBG_CORE_QAT_EXT_D_BGA1-IC,H91A    I13 @BASEBOARD_FAB2_LIB.BASEBOARD_FAB2(SCH_1):PAGE123
  U7C1  G72 VSS<458> LBG_CORE_QAT_EXT_D_BGA1-IC,H91A    I13 @BASEBOARD_FAB2_LIB.BASEBOARD_FAB2(SCH_1):PAGE123
  U7C1   G1 VSS<459> LBG_CORE_QAT_EXT_D_BGA1-IC,H91A    I13 @BASEBOARD_FAB2_LIB.BASEBOARD_FAB2(SCH_1):PAGE123
  U7C1  E72 VSS<460> LBG_CORE_QAT_EXT_D_BGA1-IC,H91A    I13 @BASEBOARD_FAB2_LIB.BASEBOARD_FAB2(SCH_1):PAGE123
  U7C1   E1 VSS<461> LBG_CORE_QAT_EXT_D_BGA1-IC,H91A    I13 @BASEBOARD_FAB2_LIB.BASEBOARD_FAB2(SCH_1):PAGE123
  U7C1  C72 VSS<462> LBG_CORE_QAT_EXT_D_BGA1-IC,H91A    I13 @BASEBOARD_FAB2_LIB.BASEBOARD_FAB2(SCH_1):PAGE123
  U7C1   C3 VSS<463> LBG_CORE_QAT_EXT_D_BGA1-IC,H91A    I13 @BASEBOARD_FAB2_LIB.BASEBOARD_FAB2(SCH_1):PAGE123
  U7C1  BR1 VSS<464> LBG_CORE_QAT_EXT_D_BGA1-IC,H91A    I13 @BASEBOARD_FAB2_LIB.BASEBOARD_FAB2(SCH_1):PAGE123
  U7C1  BU1 VSS<465> LBG_CORE_QAT_EXT_D_BGA1-IC,H91A    I13 @BASEBOARD_FAB2_LIB.BASEBOARD_FAB2(SCH_1):PAGE123
  U7C1  BW1 VSS<466> LBG_CORE_QAT_EXT_D_BGA1-IC,H91A    I13 @BASEBOARD_FAB2_LIB.BASEBOARD_FAB2(SCH_1):PAGE123
  U7C1  CA3 VSS<467> LBG_CORE_QAT_EXT_D_BGA1-IC,H91A    I13 @BASEBOARD_FAB2_LIB.BASEBOARD_FAB2(SCH_1):PAGE123
  U7C1  A70 VSS<468> LBG_CORE_QAT_EXT_D_BGA1-IC,H91A    I13 @BASEBOARD_FAB2_LIB.BASEBOARD_FAB2(SCH_1):PAGE123
  U7C1  CA5 VSS<469> LBG_CORE_QAT_EXT_D_BGA1-IC,H91A    I13 @BASEBOARD_FAB2_LIB.BASEBOARD_FAB2(SCH_1):PAGE123
  U7C1  CA7 VSS<470> LBG_CORE_QAT_EXT_D_BGA1-IC,H91A    I13 @BASEBOARD_FAB2_LIB.BASEBOARD_FAB2(SCH_1):PAGE123
  U7C1  CA9 VSS<471> LBG_CORE_QAT_EXT_D_BGA1-IC,H91A    I13 @BASEBOARD_FAB2_LIB.BASEBOARD_FAB2(SCH_1):PAGE123
  U7C1 CA65 VSS<472> LBG_CORE_QAT_EXT_D_BGA1-IC,H91A    I13 @BASEBOARD_FAB2_LIB.BASEBOARD_FAB2(SCH_1):PAGE123
  U7C1 CA66 VSS<473> LBG_CORE_QAT_EXT_D_BGA1-IC,H91A    I13 @BASEBOARD_FAB2_LIB.BASEBOARD_FAB2(SCH_1):PAGE123
  U7C1 CA68 VSS<474> LBG_CORE_QAT_EXT_D_BGA1-IC,H91A    I13 @BASEBOARD_FAB2_LIB.BASEBOARD_FAB2(SCH_1):PAGE123
  U7C1 BN72 VSS<475> LBG_CORE_QAT_EXT_D_BGA1-IC,H91A    I13 @BASEBOARD_FAB2_LIB.BASEBOARD_FAB2(SCH_1):PAGE123
  U7C1  BN1 VSS<476> LBG_CORE_QAT_EXT_D_BGA1-IC,H91A    I13 @BASEBOARD_FAB2_LIB.BASEBOARD_FAB2(SCH_1):PAGE123
  U7C1  J72 VSS<477> LBG_CORE_QAT_EXT_D_BGA1-IC,H91A    I13 @BASEBOARD_FAB2_LIB.BASEBOARD_FAB2(SCH_1):PAGE123
  U7C1   J1 VSS<478> LBG_CORE_QAT_EXT_D_BGA1-IC,H91A    I13 @BASEBOARD_FAB2_LIB.BASEBOARD_FAB2(SCH_1):PAGE123
  U7C1  A68 VSS<479> LBG_CORE_QAT_EXT_D_BGA1-IC,H91A    I13 @BASEBOARD_FAB2_LIB.BASEBOARD_FAB2(SCH_1):PAGE123
  U7C1  A66 VSS<480> LBG_CORE_QAT_EXT_D_BGA1-IC,H91A    I13 @BASEBOARD_FAB2_LIB.BASEBOARD_FAB2(SCH_1):PAGE123
  U7C1  A65 VSS<481> LBG_CORE_QAT_EXT_D_BGA1-IC,H91A    I13 @BASEBOARD_FAB2_LIB.BASEBOARD_FAB2(SCH_1):PAGE123
  U7C1   A9 VSS<482> LBG_CORE_QAT_EXT_D_BGA1-IC,H91A    I13 @BASEBOARD_FAB2_LIB.BASEBOARD_FAB2(SCH_1):PAGE123
  U7C1   A7 VSS<483> LBG_CORE_QAT_EXT_D_BGA1-IC,H91A    I13 @BASEBOARD_FAB2_LIB.BASEBOARD_FAB2(SCH_1):PAGE123
  U7C1   A5 VSS<484> LBG_CORE_QAT_EXT_D_BGA1-IC,H91A    I13 @BASEBOARD_FAB2_LIB.BASEBOARD_FAB2(SCH_1):PAGE123
  U7C1   E3 VSS<485> LBG_CORE_QAT_EXT_D_BGA1-IC,H91A    I13 @BASEBOARD_FAB2_LIB.BASEBOARD_FAB2(SCH_1):PAGE123
  U7C1   F3 VSS<486> LBG_CORE_QAT_EXT_D_BGA1-IC,H91A    I13 @BASEBOARD_FAB2_LIB.BASEBOARD_FAB2(SCH_1):PAGE123
  U7C1  BR3 VSS<487> LBG_CORE_QAT_EXT_D_BGA1-IC,H91A    I13 @BASEBOARD_FAB2_LIB.BASEBOARD_FAB2(SCH_1):PAGE123
  U7C1  BU3 VSS<488> LBG_CORE_QAT_EXT_D_BGA1-IC,H91A    I13 @BASEBOARD_FAB2_LIB.BASEBOARD_FAB2(SCH_1):PAGE123
  U7C1  E70 VSS<489> LBG_CORE_QAT_EXT_D_BGA1-IC,H91A    I13 @BASEBOARD_FAB2_LIB.BASEBOARD_FAB2(SCH_1):PAGE123
  U7C1  F70 VSS<490> LBG_CORE_QAT_EXT_D_BGA1-IC,H91A    I13 @BASEBOARD_FAB2_LIB.BASEBOARD_FAB2(SCH_1):PAGE123
  U7C1 BR70 VSS<491> LBG_CORE_QAT_EXT_D_BGA1-IC,H91A    I13 @BASEBOARD_FAB2_LIB.BASEBOARD_FAB2(SCH_1):PAGE123
  U7C1 BU70 VSS<492> LBG_CORE_QAT_EXT_D_BGA1-IC,H91A    I13 @BASEBOARD_FAB2_LIB.BASEBOARD_FAB2(SCH_1):PAGE123
  U7C1 BT69 VSS<493> LBG_CORE_QAT_EXT_D_BGA1-IC,H91A    I13 @BASEBOARD_FAB2_LIB.BASEBOARD_FAB2(SCH_1):PAGE123
  U7C1 BP69 VSS<494> LBG_CORE_QAT_EXT_D_BGA1-IC,H91A    I13 @BASEBOARD_FAB2_LIB.BASEBOARD_FAB2(SCH_1):PAGE123
  U7C1 CA52 VSS<0> LBG_CORE_QAT_EXT_D_BGA1-IC,H91A    I15 @BASEBOARD_FAB2_LIB.BASEBOARD_FAB2(SCH_1):PAGE124
  U7C1 CA50 VSS<1> LBG_CORE_QAT_EXT_D_BGA1-IC,H91A    I15 @BASEBOARD_FAB2_LIB.BASEBOARD_FAB2(SCH_1):PAGE124
  U7C1 CA26 VSS<2> LBG_CORE_QAT_EXT_D_BGA1-IC,H91A    I15 @BASEBOARD_FAB2_LIB.BASEBOARD_FAB2(SCH_1):PAGE124
  U7C1 CA18 VSS<3> LBG_CORE_QAT_EXT_D_BGA1-IC,H91A    I15 @BASEBOARD_FAB2_LIB.BASEBOARD_FAB2(SCH_1):PAGE124
  U7C1 CA15 VSS<4> LBG_CORE_QAT_EXT_D_BGA1-IC,H91A    I15 @BASEBOARD_FAB2_LIB.BASEBOARD_FAB2(SCH_1):PAGE124
  U7C1 BY49 VSS<5> LBG_CORE_QAT_EXT_D_BGA1-IC,H91A    I15 @BASEBOARD_FAB2_LIB.BASEBOARD_FAB2(SCH_1):PAGE124
  U7C1 BY40 VSS<6> LBG_CORE_QAT_EXT_D_BGA1-IC,H91A    I15 @BASEBOARD_FAB2_LIB.BASEBOARD_FAB2(SCH_1):PAGE124
  U7C1 BW52 VSS<7> LBG_CORE_QAT_EXT_D_BGA1-IC,H91A    I15 @BASEBOARD_FAB2_LIB.BASEBOARD_FAB2(SCH_1):PAGE124
  U7C1 BW26 VSS<8> LBG_CORE_QAT_EXT_D_BGA1-IC,H91A    I15 @BASEBOARD_FAB2_LIB.BASEBOARD_FAB2(SCH_1):PAGE124
  U7C1 BW18 VSS<9> LBG_CORE_QAT_EXT_D_BGA1-IC,H91A    I15 @BASEBOARD_FAB2_LIB.BASEBOARD_FAB2(SCH_1):PAGE124
  U7C1 BW15 VSS<10> LBG_CORE_QAT_EXT_D_BGA1-IC,H91A    I15 @BASEBOARD_FAB2_LIB.BASEBOARD_FAB2(SCH_1):PAGE124
  U7C1 BV40 VSS<11> LBG_CORE_QAT_EXT_D_BGA1-IC,H91A    I15 @BASEBOARD_FAB2_LIB.BASEBOARD_FAB2(SCH_1):PAGE124
  U7C1  BU9 VSS<12> LBG_CORE_QAT_EXT_D_BGA1-IC,H91A    I15 @BASEBOARD_FAB2_LIB.BASEBOARD_FAB2(SCH_1):PAGE124
  U7C1 BU63 VSS<13> LBG_CORE_QAT_EXT_D_BGA1-IC,H91A    I15 @BASEBOARD_FAB2_LIB.BASEBOARD_FAB2(SCH_1):PAGE124
  U7C1 BU61 VSS<14> LBG_CORE_QAT_EXT_D_BGA1-IC,H91A    I15 @BASEBOARD_FAB2_LIB.BASEBOARD_FAB2(SCH_1):PAGE124
  U7C1 BU59 VSS<15> LBG_CORE_QAT_EXT_D_BGA1-IC,H91A    I15 @BASEBOARD_FAB2_LIB.BASEBOARD_FAB2(SCH_1):PAGE124
  U7C1 BU57 VSS<16> LBG_CORE_QAT_EXT_D_BGA1-IC,H91A    I15 @BASEBOARD_FAB2_LIB.BASEBOARD_FAB2(SCH_1):PAGE124
  U7C1 BU54 VSS<17> LBG_CORE_QAT_EXT_D_BGA1-IC,H91A    I15 @BASEBOARD_FAB2_LIB.BASEBOARD_FAB2(SCH_1):PAGE124
  U7C1 BU52 VSS<18> LBG_CORE_QAT_EXT_D_BGA1-IC,H91A    I15 @BASEBOARD_FAB2_LIB.BASEBOARD_FAB2(SCH_1):PAGE124
  U7C1 BU50 VSS<19> LBG_CORE_QAT_EXT_D_BGA1-IC,H91A    I15 @BASEBOARD_FAB2_LIB.BASEBOARD_FAB2(SCH_1):PAGE124
  U7C1 BU48 VSS<20> LBG_CORE_QAT_EXT_D_BGA1-IC,H91A    I15 @BASEBOARD_FAB2_LIB.BASEBOARD_FAB2(SCH_1):PAGE124
  U7C1 BU45 VSS<21> LBG_CORE_QAT_EXT_D_BGA1-IC,H91A    I15 @BASEBOARD_FAB2_LIB.BASEBOARD_FAB2(SCH_1):PAGE124
  U7C1 BU43 VSS<22> LBG_CORE_QAT_EXT_D_BGA1-IC,H91A    I15 @BASEBOARD_FAB2_LIB.BASEBOARD_FAB2(SCH_1):PAGE124
  U7C1 BU41 VSS<23> LBG_CORE_QAT_EXT_D_BGA1-IC,H91A    I15 @BASEBOARD_FAB2_LIB.BASEBOARD_FAB2(SCH_1):PAGE124
  U7C1 BU39 VSS<24> LBG_CORE_QAT_EXT_D_BGA1-IC,H91A    I15 @BASEBOARD_FAB2_LIB.BASEBOARD_FAB2(SCH_1):PAGE124
  U7C1 BU37 VSS<25> LBG_CORE_QAT_EXT_D_BGA1-IC,H91A    I15 @BASEBOARD_FAB2_LIB.BASEBOARD_FAB2(SCH_1):PAGE124
  U7C1 BU34 VSS<26> LBG_CORE_QAT_EXT_D_BGA1-IC,H91A    I15 @BASEBOARD_FAB2_LIB.BASEBOARD_FAB2(SCH_1):PAGE124
  U7C1 BU32 VSS<27> LBG_CORE_QAT_EXT_D_BGA1-IC,H91A    I15 @BASEBOARD_FAB2_LIB.BASEBOARD_FAB2(SCH_1):PAGE124
  U7C1 BU30 VSS<28> LBG_CORE_QAT_EXT_D_BGA1-IC,H91A    I15 @BASEBOARD_FAB2_LIB.BASEBOARD_FAB2(SCH_1):PAGE124
  U7C1 BU28 VSS<29> LBG_CORE_QAT_EXT_D_BGA1-IC,H91A    I15 @BASEBOARD_FAB2_LIB.BASEBOARD_FAB2(SCH_1):PAGE124
  U7C1 BU26 VSS<30> LBG_CORE_QAT_EXT_D_BGA1-IC,H91A    I15 @BASEBOARD_FAB2_LIB.BASEBOARD_FAB2(SCH_1):PAGE124
  U7C1 BU24 VSS<31> LBG_CORE_QAT_EXT_D_BGA1-IC,H91A    I15 @BASEBOARD_FAB2_LIB.BASEBOARD_FAB2(SCH_1):PAGE124
  U7C1 BU22 VSS<32> LBG_CORE_QAT_EXT_D_BGA1-IC,H91A    I15 @BASEBOARD_FAB2_LIB.BASEBOARD_FAB2(SCH_1):PAGE124
  U7C1 BU20 VSS<33> LBG_CORE_QAT_EXT_D_BGA1-IC,H91A    I15 @BASEBOARD_FAB2_LIB.BASEBOARD_FAB2(SCH_1):PAGE124
  U7C1 BU18 VSS<34> LBG_CORE_QAT_EXT_D_BGA1-IC,H91A    I15 @BASEBOARD_FAB2_LIB.BASEBOARD_FAB2(SCH_1):PAGE124
  U7C1 BU15 VSS<35> LBG_CORE_QAT_EXT_D_BGA1-IC,H91A    I15 @BASEBOARD_FAB2_LIB.BASEBOARD_FAB2(SCH_1):PAGE124
  U7C1 BV49 VSS<36> LBG_CORE_QAT_EXT_D_BGA1-IC,H91A    I15 @BASEBOARD_FAB2_LIB.BASEBOARD_FAB2(SCH_1):PAGE124
  U7C1 BU11 VSS<37> LBG_CORE_QAT_EXT_D_BGA1-IC,H91A    I15 @BASEBOARD_FAB2_LIB.BASEBOARD_FAB2(SCH_1):PAGE124
  U7C1 BU13 VSS<38> LBG_CORE_QAT_EXT_D_BGA1-IC,H91A    I15 @BASEBOARD_FAB2_LIB.BASEBOARD_FAB2(SCH_1):PAGE124
  U7C1 BT66 VSS<39> LBG_CORE_QAT_EXT_D_BGA1-IC,H91A    I15 @BASEBOARD_FAB2_LIB.BASEBOARD_FAB2(SCH_1):PAGE124
  U7C1  BR6 VSS<40> LBG_CORE_QAT_EXT_D_BGA1-IC,H91A    I15 @BASEBOARD_FAB2_LIB.BASEBOARD_FAB2(SCH_1):PAGE124
  U7C1 BR58 VSS<41> LBG_CORE_QAT_EXT_D_BGA1-IC,H91A    I15 @BASEBOARD_FAB2_LIB.BASEBOARD_FAB2(SCH_1):PAGE124
  U7C1 BR54 VSS<42> LBG_CORE_QAT_EXT_D_BGA1-IC,H91A    I15 @BASEBOARD_FAB2_LIB.BASEBOARD_FAB2(SCH_1):PAGE124
  U7C1  BT8 VSS<43> LBG_CORE_QAT_EXT_D_BGA1-IC,H91A    I15 @BASEBOARD_FAB2_LIB.BASEBOARD_FAB2(SCH_1):PAGE124
  U7C1 BR50 VSS<44> LBG_CORE_QAT_EXT_D_BGA1-IC,H91A    I15 @BASEBOARD_FAB2_LIB.BASEBOARD_FAB2(SCH_1):PAGE124
  U7C1 BR20 VSS<45> LBG_CORE_QAT_EXT_D_BGA1-IC,H91A    I15 @BASEBOARD_FAB2_LIB.BASEBOARD_FAB2(SCH_1):PAGE124
  U7C1 BN66 VSS<46> LBG_CORE_QAT_EXT_D_BGA1-IC,H91A    I15 @BASEBOARD_FAB2_LIB.BASEBOARD_FAB2(SCH_1):PAGE124
  U7C1 BN52 VSS<47> LBG_CORE_QAT_EXT_D_BGA1-IC,H91A    I15 @BASEBOARD_FAB2_LIB.BASEBOARD_FAB2(SCH_1):PAGE124
  U7C1  BN5 VSS<48> LBG_CORE_QAT_EXT_D_BGA1-IC,H91A    I15 @BASEBOARD_FAB2_LIB.BASEBOARD_FAB2(SCH_1):PAGE124
  U7C1 BN59 VSS<49> LBG_CORE_QAT_EXT_D_BGA1-IC,H91A    I15 @BASEBOARD_FAB2_LIB.BASEBOARD_FAB2(SCH_1):PAGE124
  U7C1 BN22 VSS<50> LBG_CORE_QAT_EXT_D_BGA1-IC,H91A    I15 @BASEBOARD_FAB2_LIB.BASEBOARD_FAB2(SCH_1):PAGE124
  U7C1  BM9 VSS<51> LBG_CORE_QAT_EXT_D_BGA1-IC,H91A    I15 @BASEBOARD_FAB2_LIB.BASEBOARD_FAB2(SCH_1):PAGE124
  U7C1 BM71 VSS<52> LBG_CORE_QAT_EXT_D_BGA1-IC,H91A    I15 @BASEBOARD_FAB2_LIB.BASEBOARD_FAB2(SCH_1):PAGE124
  U7C1 BM69 VSS<53> LBG_CORE_QAT_EXT_D_BGA1-IC,H91A    I15 @BASEBOARD_FAB2_LIB.BASEBOARD_FAB2(SCH_1):PAGE124
  U7C1 BM58 VSS<54> LBG_CORE_QAT_EXT_D_BGA1-IC,H91A    I15 @BASEBOARD_FAB2_LIB.BASEBOARD_FAB2(SCH_1):PAGE124
  U7C1 BM50 VSS<55> LBG_CORE_QAT_EXT_D_BGA1-IC,H91A    I15 @BASEBOARD_FAB2_LIB.BASEBOARD_FAB2(SCH_1):PAGE124
  U7C1 BM46 VSS<56> LBG_CORE_QAT_EXT_D_BGA1-IC,H91A    I15 @BASEBOARD_FAB2_LIB.BASEBOARD_FAB2(SCH_1):PAGE124
  U7C1 BN37 VSS<57> LBG_CORE_QAT_EXT_D_BGA1-IC,H91A    I15 @BASEBOARD_FAB2_LIB.BASEBOARD_FAB2(SCH_1):PAGE124
  U7C1 BM17 VSS<58> LBG_CORE_QAT_EXT_D_BGA1-IC,H91A    I15 @BASEBOARD_FAB2_LIB.BASEBOARD_FAB2(SCH_1):PAGE124
  U7C1 BM13 VSS<59> LBG_CORE_QAT_EXT_D_BGA1-IC,H91A    I15 @BASEBOARD_FAB2_LIB.BASEBOARD_FAB2(SCH_1):PAGE124
  U7C1 BL72 VSS<60> LBG_CORE_QAT_EXT_D_BGA1-IC,H91A    I15 @BASEBOARD_FAB2_LIB.BASEBOARD_FAB2(SCH_1):PAGE124
  U7C1 BL70 VSS<61> LBG_CORE_QAT_EXT_D_BGA1-IC,H91A    I15 @BASEBOARD_FAB2_LIB.BASEBOARD_FAB2(SCH_1):PAGE124
  U7C1 BL63 VSS<62> LBG_CORE_QAT_EXT_D_BGA1-IC,H91A    I15 @BASEBOARD_FAB2_LIB.BASEBOARD_FAB2(SCH_1):PAGE124
  U7C1  BL5 VSS<63> LBG_CORE_QAT_EXT_D_BGA1-IC,H91A    I15 @BASEBOARD_FAB2_LIB.BASEBOARD_FAB2(SCH_1):PAGE124
  U7C1 BL37 VSS<64> LBG_CORE_QAT_EXT_D_BGA1-IC,H91A    I15 @BASEBOARD_FAB2_LIB.BASEBOARD_FAB2(SCH_1):PAGE124
  U7C1 BL68 VSS<65> LBG_CORE_QAT_EXT_D_BGA1-IC,H91A    I15 @BASEBOARD_FAB2_LIB.BASEBOARD_FAB2(SCH_1):PAGE124
  U7C1 BL40 VSS<66> LBG_CORE_QAT_EXT_D_BGA1-IC,H91A    I15 @BASEBOARD_FAB2_LIB.BASEBOARD_FAB2(SCH_1):PAGE124
  U7C1 BL22 VSS<67> LBG_CORE_QAT_EXT_D_BGA1-IC,H91A    I15 @BASEBOARD_FAB2_LIB.BASEBOARD_FAB2(SCH_1):PAGE124
  U7C1 BK50 VSS<68> LBG_CORE_QAT_EXT_D_BGA1-IC,H91A    I15 @BASEBOARD_FAB2_LIB.BASEBOARD_FAB2(SCH_1):PAGE124
  U7C1 BK42 VSS<69> LBG_CORE_QAT_EXT_D_BGA1-IC,H91A    I15 @BASEBOARD_FAB2_LIB.BASEBOARD_FAB2(SCH_1):PAGE124
  U7C1 BK38 VSS<70> LBG_CORE_QAT_EXT_D_BGA1-IC,H91A    I15 @BASEBOARD_FAB2_LIB.BASEBOARD_FAB2(SCH_1):PAGE124
  U7C1 BK35 VSS<71> LBG_CORE_QAT_EXT_D_BGA1-IC,H91A    I15 @BASEBOARD_FAB2_LIB.BASEBOARD_FAB2(SCH_1):PAGE124
  U7C1 BK31 VSS<72> LBG_CORE_QAT_EXT_D_BGA1-IC,H91A    I15 @BASEBOARD_FAB2_LIB.BASEBOARD_FAB2(SCH_1):PAGE124
  U7C1 BK27 VSS<73> LBG_CORE_QAT_EXT_D_BGA1-IC,H91A    I15 @BASEBOARD_FAB2_LIB.BASEBOARD_FAB2(SCH_1):PAGE124
  U7C1 BK24 VSS<74> LBG_CORE_QAT_EXT_D_BGA1-IC,H91A    I15 @BASEBOARD_FAB2_LIB.BASEBOARD_FAB2(SCH_1):PAGE124
  U7C1 BJ68 VSS<75> LBG_CORE_QAT_EXT_D_BGA1-IC,H91A    I16 @BASEBOARD_FAB2_LIB.BASEBOARD_FAB2(SCH_1):PAGE124
  U7C1 BJ52 VSS<76> LBG_CORE_QAT_EXT_D_BGA1-IC,H91A    I16 @BASEBOARD_FAB2_LIB.BASEBOARD_FAB2(SCH_1):PAGE124
  U7C1 BJ33 VSS<77> LBG_CORE_QAT_EXT_D_BGA1-IC,H91A    I16 @BASEBOARD_FAB2_LIB.BASEBOARD_FAB2(SCH_1):PAGE124
  U7C1  BJ3 VSS<78> LBG_CORE_QAT_EXT_D_BGA1-IC,H91A    I16 @BASEBOARD_FAB2_LIB.BASEBOARD_FAB2(SCH_1):PAGE124
  U7C1 BJ26 VSS<79> LBG_CORE_QAT_EXT_D_BGA1-IC,H91A    I16 @BASEBOARD_FAB2_LIB.BASEBOARD_FAB2(SCH_1):PAGE124
  U7C1 BJ18 VSS<80> LBG_CORE_QAT_EXT_D_BGA1-IC,H91A    I16 @BASEBOARD_FAB2_LIB.BASEBOARD_FAB2(SCH_1):PAGE124
  U7C1 BJ15 VSS<81> LBG_CORE_QAT_EXT_D_BGA1-IC,H91A    I16 @BASEBOARD_FAB2_LIB.BASEBOARD_FAB2(SCH_1):PAGE124
  U7C1  BJ7 VSS<82> LBG_CORE_QAT_EXT_D_BGA1-IC,H91A    I16 @BASEBOARD_FAB2_LIB.BASEBOARD_FAB2(SCH_1):PAGE124
  U7C1  BJ5 VSS<83> LBG_CORE_QAT_EXT_D_BGA1-IC,H91A    I16 @BASEBOARD_FAB2_LIB.BASEBOARD_FAB2(SCH_1):PAGE124
  U7C1 BJ11 VSS<84> LBG_CORE_QAT_EXT_D_BGA1-IC,H91A    I16 @BASEBOARD_FAB2_LIB.BASEBOARD_FAB2(SCH_1):PAGE124
  U7C1  BJ1 VSS<85> LBG_CORE_QAT_EXT_D_BGA1-IC,H91A    I16 @BASEBOARD_FAB2_LIB.BASEBOARD_FAB2(SCH_1):PAGE124
  U7C1 BH54 VSS<86> LBG_CORE_QAT_EXT_D_BGA1-IC,H91A    I16 @BASEBOARD_FAB2_LIB.BASEBOARD_FAB2(SCH_1):PAGE124
  U7C1 BH46 VSS<87> LBG_CORE_QAT_EXT_D_BGA1-IC,H91A    I16 @BASEBOARD_FAB2_LIB.BASEBOARD_FAB2(SCH_1):PAGE124
  U7C1 BH42 VSS<88> LBG_CORE_QAT_EXT_D_BGA1-IC,H91A    I16 @BASEBOARD_FAB2_LIB.BASEBOARD_FAB2(SCH_1):PAGE124
  U7C1 BH38 VSS<89> LBG_CORE_QAT_EXT_D_BGA1-IC,H91A    I16 @BASEBOARD_FAB2_LIB.BASEBOARD_FAB2(SCH_1):PAGE124
  U7C1 BH27 VSS<90> LBG_CORE_QAT_EXT_D_BGA1-IC,H91A    I16 @BASEBOARD_FAB2_LIB.BASEBOARD_FAB2(SCH_1):PAGE124
  U7C1 BG63 VSS<91> LBG_CORE_QAT_EXT_D_BGA1-IC,H91A    I16 @BASEBOARD_FAB2_LIB.BASEBOARD_FAB2(SCH_1):PAGE124
  U7C1 BG59 VSS<92> LBG_CORE_QAT_EXT_D_BGA1-IC,H91A    I16 @BASEBOARD_FAB2_LIB.BASEBOARD_FAB2(SCH_1):PAGE124
  U7C1 BG48 VSS<93> LBG_CORE_QAT_EXT_D_BGA1-IC,H91A    I16 @BASEBOARD_FAB2_LIB.BASEBOARD_FAB2(SCH_1):PAGE124
  U7C1 BG33 VSS<94> LBG_CORE_QAT_EXT_D_BGA1-IC,H91A    I16 @BASEBOARD_FAB2_LIB.BASEBOARD_FAB2(SCH_1):PAGE124
  U7C1  BF9 VSS<95> LBG_CORE_QAT_EXT_D_BGA1-IC,H91A    I16 @BASEBOARD_FAB2_LIB.BASEBOARD_FAB2(SCH_1):PAGE124
  U7C1 BF68 VSS<96> LBG_CORE_QAT_EXT_D_BGA1-IC,H91A    I16 @BASEBOARD_FAB2_LIB.BASEBOARD_FAB2(SCH_1):PAGE124
  U7C1 BF65 VSS<97> LBG_CORE_QAT_EXT_D_BGA1-IC,H91A    I16 @BASEBOARD_FAB2_LIB.BASEBOARD_FAB2(SCH_1):PAGE124
  U7C1 BF61 VSS<98> LBG_CORE_QAT_EXT_D_BGA1-IC,H91A    I16 @BASEBOARD_FAB2_LIB.BASEBOARD_FAB2(SCH_1):PAGE124
  U7C1 BF58 VSS<99> LBG_CORE_QAT_EXT_D_BGA1-IC,H91A    I16 @BASEBOARD_FAB2_LIB.BASEBOARD_FAB2(SCH_1):PAGE124
  U7C1 BF50 VSS<100> LBG_CORE_QAT_EXT_D_BGA1-IC,H91A    I16 @BASEBOARD_FAB2_LIB.BASEBOARD_FAB2(SCH_1):PAGE124
  U7C1  BF5 VSS<101> LBG_CORE_QAT_EXT_D_BGA1-IC,H91A    I16 @BASEBOARD_FAB2_LIB.BASEBOARD_FAB2(SCH_1):PAGE124
  U7C1 BF42 VSS<102> LBG_CORE_QAT_EXT_D_BGA1-IC,H91A    I16 @BASEBOARD_FAB2_LIB.BASEBOARD_FAB2(SCH_1):PAGE124
  U7C1 BF38 VSS<103> LBG_CORE_QAT_EXT_D_BGA1-IC,H91A    I16 @BASEBOARD_FAB2_LIB.BASEBOARD_FAB2(SCH_1):PAGE124
  U7C1 BF27 VSS<104> LBG_CORE_QAT_EXT_D_BGA1-IC,H91A    I16 @BASEBOARD_FAB2_LIB.BASEBOARD_FAB2(SCH_1):PAGE124
  U7C1 BF24 VSS<105> LBG_CORE_QAT_EXT_D_BGA1-IC,H91A    I16 @BASEBOARD_FAB2_LIB.BASEBOARD_FAB2(SCH_1):PAGE124
  U7C1 BF20 VSS<106> LBG_CORE_QAT_EXT_D_BGA1-IC,H91A    I16 @BASEBOARD_FAB2_LIB.BASEBOARD_FAB2(SCH_1):PAGE124
  U7C1 BG44 VSS<107> LBG_CORE_QAT_EXT_D_BGA1-IC,H91A    I16 @BASEBOARD_FAB2_LIB.BASEBOARD_FAB2(SCH_1):PAGE124
  U7C1 BF54 VSS<108> LBG_CORE_QAT_EXT_D_BGA1-IC,H91A    I16 @BASEBOARD_FAB2_LIB.BASEBOARD_FAB2(SCH_1):PAGE124
  U7C1 BF17 VSS<109> LBG_CORE_QAT_EXT_D_BGA1-IC,H91A    I16 @BASEBOARD_FAB2_LIB.BASEBOARD_FAB2(SCH_1):PAGE124
  U7C1 BF13 VSS<110> LBG_CORE_QAT_EXT_D_BGA1-IC,H91A    I16 @BASEBOARD_FAB2_LIB.BASEBOARD_FAB2(SCH_1):PAGE124
  U7C1 BE66 VSS<111> LBG_CORE_QAT_EXT_D_BGA1-IC,H91A    I16 @BASEBOARD_FAB2_LIB.BASEBOARD_FAB2(SCH_1):PAGE124
  U7C1 BE63 VSS<112> LBG_CORE_QAT_EXT_D_BGA1-IC,H91A    I16 @BASEBOARD_FAB2_LIB.BASEBOARD_FAB2(SCH_1):PAGE124
  U7C1 BE59 VSS<113> LBG_CORE_QAT_EXT_D_BGA1-IC,H91A    I16 @BASEBOARD_FAB2_LIB.BASEBOARD_FAB2(SCH_1):PAGE124
  U7C1 BE56 VSS<114> LBG_CORE_QAT_EXT_D_BGA1-IC,H91A    I16 @BASEBOARD_FAB2_LIB.BASEBOARD_FAB2(SCH_1):PAGE124
  U7C1 BE37 VSS<115> LBG_CORE_QAT_EXT_D_BGA1-IC,H91A    I16 @BASEBOARD_FAB2_LIB.BASEBOARD_FAB2(SCH_1):PAGE124
  U7C1 BE33 VSS<116> LBG_CORE_QAT_EXT_D_BGA1-IC,H91A    I16 @BASEBOARD_FAB2_LIB.BASEBOARD_FAB2(SCH_1):PAGE124
  U7C1 BE29 VSS<117> LBG_CORE_QAT_EXT_D_BGA1-IC,H91A    I16 @BASEBOARD_FAB2_LIB.BASEBOARD_FAB2(SCH_1):PAGE124
  U7C1 BD68 VSS<118> LBG_CORE_QAT_EXT_D_BGA1-IC,H91A    I16 @BASEBOARD_FAB2_LIB.BASEBOARD_FAB2(SCH_1):PAGE124
  U7C1 BD54 VSS<119> LBG_CORE_QAT_EXT_D_BGA1-IC,H91A    I16 @BASEBOARD_FAB2_LIB.BASEBOARD_FAB2(SCH_1):PAGE124
  U7C1 BD50 VSS<120> LBG_CORE_QAT_EXT_D_BGA1-IC,H91A    I16 @BASEBOARD_FAB2_LIB.BASEBOARD_FAB2(SCH_1):PAGE124
  U7C1  BD5 VSS<121> LBG_CORE_QAT_EXT_D_BGA1-IC,H91A    I16 @BASEBOARD_FAB2_LIB.BASEBOARD_FAB2(SCH_1):PAGE124
  U7C1 BD35 VSS<122> LBG_CORE_QAT_EXT_D_BGA1-IC,H91A    I16 @BASEBOARD_FAB2_LIB.BASEBOARD_FAB2(SCH_1):PAGE124
  U7C1 BD31 VSS<123> LBG_CORE_QAT_EXT_D_BGA1-IC,H91A    I16 @BASEBOARD_FAB2_LIB.BASEBOARD_FAB2(SCH_1):PAGE124
  U7C1 BD27 VSS<124> LBG_CORE_QAT_EXT_D_BGA1-IC,H91A    I16 @BASEBOARD_FAB2_LIB.BASEBOARD_FAB2(SCH_1):PAGE124
  U7C1 BD24 VSS<125> LBG_CORE_QAT_EXT_D_BGA1-IC,H91A    I16 @BASEBOARD_FAB2_LIB.BASEBOARD_FAB2(SCH_1):PAGE124
  U7C1 BC71 VSS<126> LBG_CORE_QAT_EXT_D_BGA1-IC,H91A    I16 @BASEBOARD_FAB2_LIB.BASEBOARD_FAB2(SCH_1):PAGE124
  U7C1 BC69 VSS<127> LBG_CORE_QAT_EXT_D_BGA1-IC,H91A    I16 @BASEBOARD_FAB2_LIB.BASEBOARD_FAB2(SCH_1):PAGE124
  U7C1 BB72 VSS<128> LBG_CORE_QAT_EXT_D_BGA1-IC,H91A    I16 @BASEBOARD_FAB2_LIB.BASEBOARD_FAB2(SCH_1):PAGE124
  U7C1 BB70 VSS<129> LBG_CORE_QAT_EXT_D_BGA1-IC,H91A    I16 @BASEBOARD_FAB2_LIB.BASEBOARD_FAB2(SCH_1):PAGE124
  U7C1 BB68 VSS<130> LBG_CORE_QAT_EXT_D_BGA1-IC,H91A    I16 @BASEBOARD_FAB2_LIB.BASEBOARD_FAB2(SCH_1):PAGE124
  U7C1 BB66 VSS<131> LBG_CORE_QAT_EXT_D_BGA1-IC,H91A    I16 @BASEBOARD_FAB2_LIB.BASEBOARD_FAB2(SCH_1):PAGE124
  U7C1 BB59 VSS<132> LBG_CORE_QAT_EXT_D_BGA1-IC,H91A    I16 @BASEBOARD_FAB2_LIB.BASEBOARD_FAB2(SCH_1):PAGE124
  U7C1 BB44 VSS<133> LBG_CORE_QAT_EXT_D_BGA1-IC,H91A    I16 @BASEBOARD_FAB2_LIB.BASEBOARD_FAB2(SCH_1):PAGE124
  U7C1 BB22 VSS<134> LBG_CORE_QAT_EXT_D_BGA1-IC,H91A    I16 @BASEBOARD_FAB2_LIB.BASEBOARD_FAB2(SCH_1):PAGE124
  U7C1 BB18 VSS<135> LBG_CORE_QAT_EXT_D_BGA1-IC,H91A    I16 @BASEBOARD_FAB2_LIB.BASEBOARD_FAB2(SCH_1):PAGE124
  U7C1 BB15 VSS<136> LBG_CORE_QAT_EXT_D_BGA1-IC,H91A    I16 @BASEBOARD_FAB2_LIB.BASEBOARD_FAB2(SCH_1):PAGE124
  U7C1 BB11 VSS<137> LBG_CORE_QAT_EXT_D_BGA1-IC,H91A    I16 @BASEBOARD_FAB2_LIB.BASEBOARD_FAB2(SCH_1):PAGE124
  U7C1  BB7 VSS<138> LBG_CORE_QAT_EXT_D_BGA1-IC,H91A    I16 @BASEBOARD_FAB2_LIB.BASEBOARD_FAB2(SCH_1):PAGE124
  U7C1  BB5 VSS<139> LBG_CORE_QAT_EXT_D_BGA1-IC,H91A    I16 @BASEBOARD_FAB2_LIB.BASEBOARD_FAB2(SCH_1):PAGE124
  U7C1 BA58 VSS<140> LBG_CORE_QAT_EXT_D_BGA1-IC,H91A    I16 @BASEBOARD_FAB2_LIB.BASEBOARD_FAB2(SCH_1):PAGE124
  U7C1 BA54 VSS<141> LBG_CORE_QAT_EXT_D_BGA1-IC,H91A    I16 @BASEBOARD_FAB2_LIB.BASEBOARD_FAB2(SCH_1):PAGE124
  U7C1 BA50 VSS<142> LBG_CORE_QAT_EXT_D_BGA1-IC,H91A    I16 @BASEBOARD_FAB2_LIB.BASEBOARD_FAB2(SCH_1):PAGE124
  U7C1 AY68 VSS<143> LBG_CORE_QAT_EXT_D_BGA1-IC,H91A    I16 @BASEBOARD_FAB2_LIB.BASEBOARD_FAB2(SCH_1):PAGE124
  U7C1 AY63 VSS<144> LBG_CORE_QAT_EXT_D_BGA1-IC,H91A    I16 @BASEBOARD_FAB2_LIB.BASEBOARD_FAB2(SCH_1):PAGE124
  U7C1 AY56 VSS<145> LBG_CORE_QAT_EXT_D_BGA1-IC,H91A    I16 @BASEBOARD_FAB2_LIB.BASEBOARD_FAB2(SCH_1):PAGE124
  U7C1 AY22 VSS<146> LBG_CORE_QAT_EXT_D_BGA1-IC,H91A    I16 @BASEBOARD_FAB2_LIB.BASEBOARD_FAB2(SCH_1):PAGE124
  U7C1  AY5 VSS<147> LBG_CORE_QAT_EXT_D_BGA1-IC,H91A    I16 @BASEBOARD_FAB2_LIB.BASEBOARD_FAB2(SCH_1):PAGE124
  U7C1 AW61 VSS<148> LBG_CORE_QAT_EXT_D_BGA1-IC,H91A    I16 @BASEBOARD_FAB2_LIB.BASEBOARD_FAB2(SCH_1):PAGE124
  U7C1 AW58 VSS<149> LBG_CORE_QAT_EXT_D_BGA1-IC,H91A    I16 @BASEBOARD_FAB2_LIB.BASEBOARD_FAB2(SCH_1):PAGE124
  U7C1 AW50 VSS<150> LBG_CORE_QAT_EXT_D_BGA1-IC,H91A    I16 @BASEBOARD_FAB2_LIB.BASEBOARD_FAB2(SCH_1):PAGE124
  U7C1 AW46 VSS<151> LBG_CORE_QAT_EXT_D_BGA1-IC,H91A    I16 @BASEBOARD_FAB2_LIB.BASEBOARD_FAB2(SCH_1):PAGE124
  U7C1 AW41 VSS<152> LBG_CORE_QAT_EXT_D_BGA1-IC,H91A    I16 @BASEBOARD_FAB2_LIB.BASEBOARD_FAB2(SCH_1):PAGE124
  U7C1 AW39 VSS<153> LBG_CORE_QAT_EXT_D_BGA1-IC,H91A    I16 @BASEBOARD_FAB2_LIB.BASEBOARD_FAB2(SCH_1):PAGE124
  U7C1 AW37 VSS<154> LBG_CORE_QAT_EXT_D_BGA1-IC,H91A    I16 @BASEBOARD_FAB2_LIB.BASEBOARD_FAB2(SCH_1):PAGE124
  U7C1 AW36 VSS<155> LBG_CORE_QAT_EXT_D_BGA1-IC,H91A    I16 @BASEBOARD_FAB2_LIB.BASEBOARD_FAB2(SCH_1):PAGE124
  U7C1 AW34 VSS<156> LBG_CORE_QAT_EXT_D_BGA1-IC,H91A    I16 @BASEBOARD_FAB2_LIB.BASEBOARD_FAB2(SCH_1):PAGE124
  U7C1 AW32 VSS<157> LBG_CORE_QAT_EXT_D_BGA1-IC,H91A    I16 @BASEBOARD_FAB2_LIB.BASEBOARD_FAB2(SCH_1):PAGE124
  U7C1 AW30 VSS<158> LBG_CORE_QAT_EXT_D_BGA1-IC,H91A    I16 @BASEBOARD_FAB2_LIB.BASEBOARD_FAB2(SCH_1):PAGE124
  U7C1 AW26 VSS<159> LBG_CORE_QAT_EXT_D_BGA1-IC,H91A    I16 @BASEBOARD_FAB2_LIB.BASEBOARD_FAB2(SCH_1):PAGE124
  U7C1 AW17 VSS<160> LBG_CORE_QAT_EXT_D_BGA1-IC,H91A    I16 @BASEBOARD_FAB2_LIB.BASEBOARD_FAB2(SCH_1):PAGE124
  U7C1 AW13 VSS<161> LBG_CORE_QAT_EXT_D_BGA1-IC,H91A    I16 @BASEBOARD_FAB2_LIB.BASEBOARD_FAB2(SCH_1):PAGE124
  U7C1  AW9 VSS<162> LBG_CORE_QAT_EXT_D_BGA1-IC,H91A    I16 @BASEBOARD_FAB2_LIB.BASEBOARD_FAB2(SCH_1):PAGE124
  U7C1 AV68 VSS<163> LBG_CORE_QAT_EXT_D_BGA1-IC,H91A    I16 @BASEBOARD_FAB2_LIB.BASEBOARD_FAB2(SCH_1):PAGE124
  U7C1 AV59 VSS<164> LBG_CORE_QAT_EXT_D_BGA1-IC,H91A    I16 @BASEBOARD_FAB2_LIB.BASEBOARD_FAB2(SCH_1):PAGE124
  U7C1 AV22 VSS<165> LBG_CORE_QAT_EXT_D_BGA1-IC,H91A    I16 @BASEBOARD_FAB2_LIB.BASEBOARD_FAB2(SCH_1):PAGE124
  U7C1  AV5 VSS<166> LBG_CORE_QAT_EXT_D_BGA1-IC,H91A    I16 @BASEBOARD_FAB2_LIB.BASEBOARD_FAB2(SCH_1):PAGE124
  U7C1 AU61 VSS<167> LBG_CORE_QAT_EXT_D_BGA1-IC,H91A    I16 @BASEBOARD_FAB2_LIB.BASEBOARD_FAB2(SCH_1):PAGE124
  U7C1 AU54 VSS<168> LBG_CORE_QAT_EXT_D_BGA1-IC,H91A    I16 @BASEBOARD_FAB2_LIB.BASEBOARD_FAB2(SCH_1):PAGE124
  U7C1 AU50 VSS<169> LBG_CORE_QAT_EXT_D_BGA1-IC,H91A    I16 @BASEBOARD_FAB2_LIB.BASEBOARD_FAB2(SCH_1):PAGE124
  U7C1 AU46 VSS<170> LBG_CORE_QAT_EXT_D_BGA1-IC,H91A    I16 @BASEBOARD_FAB2_LIB.BASEBOARD_FAB2(SCH_1):PAGE124
  U7C1 AU41 VSS<171> LBG_CORE_QAT_EXT_D_BGA1-IC,H91A    I16 @BASEBOARD_FAB2_LIB.BASEBOARD_FAB2(SCH_1):PAGE124
  U7C1 AE22 VSS<172> LBG_CORE_QAT_EXT_D_BGA1-IC,H91A    I16 @BASEBOARD_FAB2_LIB.BASEBOARD_FAB2(SCH_1):PAGE124
  U7C1 AU30 VSS<173> LBG_CORE_QAT_EXT_D_BGA1-IC,H91A    I16 @BASEBOARD_FAB2_LIB.BASEBOARD_FAB2(SCH_1):PAGE124
  U7C1 AU26 VSS<174> LBG_CORE_QAT_EXT_D_BGA1-IC,H91A    I16 @BASEBOARD_FAB2_LIB.BASEBOARD_FAB2(SCH_1):PAGE124
  U7C1 AT59 VSS<175> LBG_CORE_QAT_EXT_D_BGA1-IC,H91A    I16 @BASEBOARD_FAB2_LIB.BASEBOARD_FAB2(SCH_1):PAGE124
  U7C1 AT46 VSS<176> LBG_CORE_QAT_EXT_D_BGA1-IC,H91A    I16 @BASEBOARD_FAB2_LIB.BASEBOARD_FAB2(SCH_1):PAGE124
  U7C1 AT41 VSS<177> LBG_CORE_QAT_EXT_D_BGA1-IC,H91A    I16 @BASEBOARD_FAB2_LIB.BASEBOARD_FAB2(SCH_1):PAGE124
  U7C1 AT30 VSS<178> LBG_CORE_QAT_EXT_D_BGA1-IC,H91A    I16 @BASEBOARD_FAB2_LIB.BASEBOARD_FAB2(SCH_1):PAGE124
  U7C1 AT26 VSS<179> LBG_CORE_QAT_EXT_D_BGA1-IC,H91A    I16 @BASEBOARD_FAB2_LIB.BASEBOARD_FAB2(SCH_1):PAGE124
  U7C1 AT22 VSS<180> LBG_CORE_QAT_EXT_D_BGA1-IC,H91A    I16 @BASEBOARD_FAB2_LIB.BASEBOARD_FAB2(SCH_1):PAGE124
  U7C1 AT18 VSS<181> LBG_CORE_QAT_EXT_D_BGA1-IC,H91A    I16 @BASEBOARD_FAB2_LIB.BASEBOARD_FAB2(SCH_1):PAGE124
  U7C1 AT15 VSS<182> LBG_CORE_QAT_EXT_D_BGA1-IC,H91A    I16 @BASEBOARD_FAB2_LIB.BASEBOARD_FAB2(SCH_1):PAGE124
  U7C1 AT11 VSS<183> LBG_CORE_QAT_EXT_D_BGA1-IC,H91A    I16 @BASEBOARD_FAB2_LIB.BASEBOARD_FAB2(SCH_1):PAGE124
  U7C1  AT7 VSS<184> LBG_CORE_QAT_EXT_D_BGA1-IC,H91A    I16 @BASEBOARD_FAB2_LIB.BASEBOARD_FAB2(SCH_1):PAGE124
  U7C1 AR72 VSS<185> LBG_CORE_QAT_EXT_D_BGA1-IC,H91A    I16 @BASEBOARD_FAB2_LIB.BASEBOARD_FAB2(SCH_1):PAGE124
  U7C1 AR70 VSS<186> LBG_CORE_QAT_EXT_D_BGA1-IC,H91A    I16 @BASEBOARD_FAB2_LIB.BASEBOARD_FAB2(SCH_1):PAGE124
  U7C1 AR68 VSS<187> LBG_CORE_QAT_EXT_D_BGA1-IC,H91A    I16 @BASEBOARD_FAB2_LIB.BASEBOARD_FAB2(SCH_1):PAGE124
  U7C1 AR65 VSS<188> LBG_CORE_QAT_EXT_D_BGA1-IC,H91A    I16 @BASEBOARD_FAB2_LIB.BASEBOARD_FAB2(SCH_1):PAGE124
  U7C1 AR58 VSS<189> LBG_CORE_QAT_EXT_D_BGA1-IC,H91A    I16 @BASEBOARD_FAB2_LIB.BASEBOARD_FAB2(SCH_1):PAGE124
  U7C1 AR50 VSS<190> LBG_CORE_QAT_EXT_D_BGA1-IC,H91A    I16 @BASEBOARD_FAB2_LIB.BASEBOARD_FAB2(SCH_1):PAGE124
  U7C1  AR5 VSS<191> LBG_CORE_QAT_EXT_D_BGA1-IC,H91A    I16 @BASEBOARD_FAB2_LIB.BASEBOARD_FAB2(SCH_1):PAGE124
  U7C1 AP66 VSS<192> LBG_CORE_QAT_EXT_D_BGA1-IC,H91A    I16 @BASEBOARD_FAB2_LIB.BASEBOARD_FAB2(SCH_1):PAGE124
  U7C1 AP52 VSS<193> LBG_CORE_QAT_EXT_D_BGA1-IC,H91A    I16 @BASEBOARD_FAB2_LIB.BASEBOARD_FAB2(SCH_1):PAGE124
  U7C1 AP46 VSS<194> LBG_CORE_QAT_EXT_D_BGA1-IC,H91A    I16 @BASEBOARD_FAB2_LIB.BASEBOARD_FAB2(SCH_1):PAGE124
  U7C1 AP41 VSS<195> LBG_CORE_QAT_EXT_D_BGA1-IC,H91A    I16 @BASEBOARD_FAB2_LIB.BASEBOARD_FAB2(SCH_1):PAGE124
  U7C1  AP4 VSS<196> LBG_CORE_QAT_EXT_D_BGA1-IC,H91A    I16 @BASEBOARD_FAB2_LIB.BASEBOARD_FAB2(SCH_1):PAGE124
  U7C1 AP30 VSS<197> LBG_CORE_QAT_EXT_D_BGA1-IC,H91A    I16 @BASEBOARD_FAB2_LIB.BASEBOARD_FAB2(SCH_1):PAGE124
  U7C1 AP26 VSS<198> LBG_CORE_QAT_EXT_D_BGA1-IC,H91A    I16 @BASEBOARD_FAB2_LIB.BASEBOARD_FAB2(SCH_1):PAGE124
  U7C1  AP2 VSS<199> LBG_CORE_QAT_EXT_D_BGA1-IC,H91A    I16 @BASEBOARD_FAB2_LIB.BASEBOARD_FAB2(SCH_1):PAGE124
  U7C1  AN9 VSS<200> LBG_CORE_QAT_EXT_D_BGA1-IC,H91A    I16 @BASEBOARD_FAB2_LIB.BASEBOARD_FAB2(SCH_1):PAGE124
  U7C1 AN58 VSS<201> LBG_CORE_QAT_EXT_D_BGA1-IC,H91A    I16 @BASEBOARD_FAB2_LIB.BASEBOARD_FAB2(SCH_1):PAGE124
  U7C1  AN5 VSS<202> LBG_CORE_QAT_EXT_D_BGA1-IC,H91A    I16 @BASEBOARD_FAB2_LIB.BASEBOARD_FAB2(SCH_1):PAGE124
  U7C1 AN20 VSS<203> LBG_CORE_QAT_EXT_D_BGA1-IC,H91A    I16 @BASEBOARD_FAB2_LIB.BASEBOARD_FAB2(SCH_1):PAGE124
  U7C1 AP22 VSS<204> LBG_CORE_QAT_EXT_D_BGA1-IC,H91A    I16 @BASEBOARD_FAB2_LIB.BASEBOARD_FAB2(SCH_1):PAGE124
  U7C1 AN68 VSS<205> LBG_CORE_QAT_EXT_D_BGA1-IC,H91A    I16 @BASEBOARD_FAB2_LIB.BASEBOARD_FAB2(SCH_1):PAGE124
  U7C1 AN17 VSS<206> LBG_CORE_QAT_EXT_D_BGA1-IC,H91A    I16 @BASEBOARD_FAB2_LIB.BASEBOARD_FAB2(SCH_1):PAGE124
  U7C1 AN13 VSS<207> LBG_CORE_QAT_EXT_D_BGA1-IC,H91A    I16 @BASEBOARD_FAB2_LIB.BASEBOARD_FAB2(SCH_1):PAGE124
  U7C1 AM46 VSS<208> LBG_CORE_QAT_EXT_D_BGA1-IC,H91A    I16 @BASEBOARD_FAB2_LIB.BASEBOARD_FAB2(SCH_1):PAGE124
  U7C1 AM41 VSS<209> LBG_CORE_QAT_EXT_D_BGA1-IC,H91A    I16 @BASEBOARD_FAB2_LIB.BASEBOARD_FAB2(SCH_1):PAGE124
  U7C1 AM30 VSS<210> LBG_CORE_QAT_EXT_D_BGA1-IC,H91A    I16 @BASEBOARD_FAB2_LIB.BASEBOARD_FAB2(SCH_1):PAGE124
  U7C1 AM26 VSS<211> LBG_CORE_QAT_EXT_D_BGA1-IC,H91A    I16 @BASEBOARD_FAB2_LIB.BASEBOARD_FAB2(SCH_1):PAGE124
  U7C1 AL72 VSS<212> LBG_CORE_QAT_EXT_D_BGA1-IC,H91A    I16 @BASEBOARD_FAB2_LIB.BASEBOARD_FAB2(SCH_1):PAGE124
  U7C1 AL70 VSS<213> LBG_CORE_QAT_EXT_D_BGA1-IC,H91A    I16 @BASEBOARD_FAB2_LIB.BASEBOARD_FAB2(SCH_1):PAGE124
  U7C1 AL68 VSS<214> LBG_CORE_QAT_EXT_D_BGA1-IC,H91A    I16 @BASEBOARD_FAB2_LIB.BASEBOARD_FAB2(SCH_1):PAGE124
  U7C1 AL59 VSS<215> LBG_CORE_QAT_EXT_D_BGA1-IC,H91A    I17 @BASEBOARD_FAB2_LIB.BASEBOARD_FAB2(SCH_1):PAGE124
  U7C1 AL52 VSS<216> LBG_CORE_QAT_EXT_D_BGA1-IC,H91A    I17 @BASEBOARD_FAB2_LIB.BASEBOARD_FAB2(SCH_1):PAGE124
  U7C1  AL5 VSS<217> LBG_CORE_QAT_EXT_D_BGA1-IC,H91A    I17 @BASEBOARD_FAB2_LIB.BASEBOARD_FAB2(SCH_1):PAGE124
  U7C1 AL22 VSS<218> LBG_CORE_QAT_EXT_D_BGA1-IC,H91A    I17 @BASEBOARD_FAB2_LIB.BASEBOARD_FAB2(SCH_1):PAGE124
  U7C1 AK71 VSS<219> LBG_CORE_QAT_EXT_D_BGA1-IC,H91A    I17 @BASEBOARD_FAB2_LIB.BASEBOARD_FAB2(SCH_1):PAGE124
  U7C1 AK69 VSS<220> LBG_CORE_QAT_EXT_D_BGA1-IC,H91A    I17 @BASEBOARD_FAB2_LIB.BASEBOARD_FAB2(SCH_1):PAGE124
  U7C1 AK61 VSS<221> LBG_CORE_QAT_EXT_D_BGA1-IC,H91A    I17 @BASEBOARD_FAB2_LIB.BASEBOARD_FAB2(SCH_1):PAGE124
  U7C1 AK58 VSS<222> LBG_CORE_QAT_EXT_D_BGA1-IC,H91A    I17 @BASEBOARD_FAB2_LIB.BASEBOARD_FAB2(SCH_1):PAGE124
  U7C1 AK48 VSS<223> LBG_CORE_QAT_EXT_D_BGA1-IC,H91A    I17 @BASEBOARD_FAB2_LIB.BASEBOARD_FAB2(SCH_1):PAGE124
  U7C1 AK46 VSS<224> LBG_CORE_QAT_EXT_D_BGA1-IC,H91A    I17 @BASEBOARD_FAB2_LIB.BASEBOARD_FAB2(SCH_1):PAGE124
  U7C1 AK41 VSS<225> LBG_CORE_QAT_EXT_D_BGA1-IC,H91A    I17 @BASEBOARD_FAB2_LIB.BASEBOARD_FAB2(SCH_1):PAGE124
  U7C1 AK26 VSS<226> LBG_CORE_QAT_EXT_D_BGA1-IC,H91A    I17 @BASEBOARD_FAB2_LIB.BASEBOARD_FAB2(SCH_1):PAGE124
  U7C1  AJ7 VSS<227> LBG_CORE_QAT_EXT_D_BGA1-IC,H91A    I17 @BASEBOARD_FAB2_LIB.BASEBOARD_FAB2(SCH_1):PAGE124
  U7C1 AJ68 VSS<228> LBG_CORE_QAT_EXT_D_BGA1-IC,H91A    I17 @BASEBOARD_FAB2_LIB.BASEBOARD_FAB2(SCH_1):PAGE124
  U7C1 AJ66 VSS<229> LBG_CORE_QAT_EXT_D_BGA1-IC,H91A    I17 @BASEBOARD_FAB2_LIB.BASEBOARD_FAB2(SCH_1):PAGE124
  U7C1 AJ59 VSS<230> LBG_CORE_QAT_EXT_D_BGA1-IC,H91A    I17 @BASEBOARD_FAB2_LIB.BASEBOARD_FAB2(SCH_1):PAGE124
  U7C1 AJ52 VSS<231> LBG_CORE_QAT_EXT_D_BGA1-IC,H91A    I17 @BASEBOARD_FAB2_LIB.BASEBOARD_FAB2(SCH_1):PAGE124
  U7C1  AJ5 VSS<232> LBG_CORE_QAT_EXT_D_BGA1-IC,H91A    I17 @BASEBOARD_FAB2_LIB.BASEBOARD_FAB2(SCH_1):PAGE124
  U7C1 AJ41 VSS<233> LBG_CORE_QAT_EXT_D_BGA1-IC,H91A    I17 @BASEBOARD_FAB2_LIB.BASEBOARD_FAB2(SCH_1):PAGE124
  U7C1 AJ39 VSS<234> LBG_CORE_QAT_EXT_D_BGA1-IC,H91A    I17 @BASEBOARD_FAB2_LIB.BASEBOARD_FAB2(SCH_1):PAGE124
  U7C1 AJ37 VSS<235> LBG_CORE_QAT_EXT_D_BGA1-IC,H91A    I17 @BASEBOARD_FAB2_LIB.BASEBOARD_FAB2(SCH_1):PAGE124
  U7C1 AJ36 VSS<236> LBG_CORE_QAT_EXT_D_BGA1-IC,H91A    I17 @BASEBOARD_FAB2_LIB.BASEBOARD_FAB2(SCH_1):PAGE124
  U7C1 AJ34 VSS<237> LBG_CORE_QAT_EXT_D_BGA1-IC,H91A    I17 @BASEBOARD_FAB2_LIB.BASEBOARD_FAB2(SCH_1):PAGE124
  U7C1 AJ30 VSS<238> LBG_CORE_QAT_EXT_D_BGA1-IC,H91A    I17 @BASEBOARD_FAB2_LIB.BASEBOARD_FAB2(SCH_1):PAGE124
  U7C1 AJ26 VSS<239> LBG_CORE_QAT_EXT_D_BGA1-IC,H91A    I17 @BASEBOARD_FAB2_LIB.BASEBOARD_FAB2(SCH_1):PAGE124
  U7C1 AJ22 VSS<240> LBG_CORE_QAT_EXT_D_BGA1-IC,H91A    I17 @BASEBOARD_FAB2_LIB.BASEBOARD_FAB2(SCH_1):PAGE124
  U7C1 AJ18 VSS<241> LBG_CORE_QAT_EXT_D_BGA1-IC,H91A    I17 @BASEBOARD_FAB2_LIB.BASEBOARD_FAB2(SCH_1):PAGE124
  U7C1 AJ15 VSS<242> LBG_CORE_QAT_EXT_D_BGA1-IC,H91A    I17 @BASEBOARD_FAB2_LIB.BASEBOARD_FAB2(SCH_1):PAGE124
  U7C1 AK30 VSS<243> LBG_CORE_QAT_EXT_D_BGA1-IC,H91A    I17 @BASEBOARD_FAB2_LIB.BASEBOARD_FAB2(SCH_1):PAGE124
  U7C1 AJ56 VSS<244> LBG_CORE_QAT_EXT_D_BGA1-IC,H91A    I17 @BASEBOARD_FAB2_LIB.BASEBOARD_FAB2(SCH_1):PAGE124
  U7C1 AJ32 VSS<245> LBG_CORE_QAT_EXT_D_BGA1-IC,H91A    I17 @BASEBOARD_FAB2_LIB.BASEBOARD_FAB2(SCH_1):PAGE124
  U7C1 AJ11 VSS<246> LBG_CORE_QAT_EXT_D_BGA1-IC,H91A    I17 @BASEBOARD_FAB2_LIB.BASEBOARD_FAB2(SCH_1):PAGE124
  U7C1 AH20 VSS<247> LBG_CORE_QAT_EXT_D_BGA1-IC,H91A    I17 @BASEBOARD_FAB2_LIB.BASEBOARD_FAB2(SCH_1):PAGE124
  U7C1 AG66 VSS<248> LBG_CORE_QAT_EXT_D_BGA1-IC,H91A    I17 @BASEBOARD_FAB2_LIB.BASEBOARD_FAB2(SCH_1):PAGE124
  U7C1 AG59 VSS<249> LBG_CORE_QAT_EXT_D_BGA1-IC,H91A    I17 @BASEBOARD_FAB2_LIB.BASEBOARD_FAB2(SCH_1):PAGE124
  U7C1 AG56 VSS<250> LBG_CORE_QAT_EXT_D_BGA1-IC,H91A    I17 @BASEBOARD_FAB2_LIB.BASEBOARD_FAB2(SCH_1):PAGE124
  U7C1 AG52 VSS<251> LBG_CORE_QAT_EXT_D_BGA1-IC,H91A    I17 @BASEBOARD_FAB2_LIB.BASEBOARD_FAB2(SCH_1):PAGE124
  U7C1 AG43 VSS<252> LBG_CORE_QAT_EXT_D_BGA1-IC,H91A    I17 @BASEBOARD_FAB2_LIB.BASEBOARD_FAB2(SCH_1):PAGE124
  U7C1 AG41 VSS<253> LBG_CORE_QAT_EXT_D_BGA1-IC,H91A    I17 @BASEBOARD_FAB2_LIB.BASEBOARD_FAB2(SCH_1):PAGE124
  U7C1 AG30 VSS<254> LBG_CORE_QAT_EXT_D_BGA1-IC,H91A    I17 @BASEBOARD_FAB2_LIB.BASEBOARD_FAB2(SCH_1):PAGE124
  U7C1 AG26 VSS<255> LBG_CORE_QAT_EXT_D_BGA1-IC,H91A    I17 @BASEBOARD_FAB2_LIB.BASEBOARD_FAB2(SCH_1):PAGE124
  U7C1 AF68 VSS<256> LBG_CORE_QAT_EXT_D_BGA1-IC,H91A    I17 @BASEBOARD_FAB2_LIB.BASEBOARD_FAB2(SCH_1):PAGE124
  U7C1  AF3 VSS<257> LBG_CORE_QAT_EXT_D_BGA1-IC,H91A    I17 @BASEBOARD_FAB2_LIB.BASEBOARD_FAB2(SCH_1):PAGE124
  U7C1 AF24 VSS<258> LBG_CORE_QAT_EXT_D_BGA1-IC,H91A    I17 @BASEBOARD_FAB2_LIB.BASEBOARD_FAB2(SCH_1):PAGE124
  U7C1 AF17 VSS<259> LBG_CORE_QAT_EXT_D_BGA1-IC,H91A    I17 @BASEBOARD_FAB2_LIB.BASEBOARD_FAB2(SCH_1):PAGE124
  U7C1  AF9 VSS<260> LBG_CORE_QAT_EXT_D_BGA1-IC,H91A    I17 @BASEBOARD_FAB2_LIB.BASEBOARD_FAB2(SCH_1):PAGE124
  U7C1  AF5 VSS<261> LBG_CORE_QAT_EXT_D_BGA1-IC,H91A    I17 @BASEBOARD_FAB2_LIB.BASEBOARD_FAB2(SCH_1):PAGE124
  U7C1 AF13 VSS<262> LBG_CORE_QAT_EXT_D_BGA1-IC,H91A    I17 @BASEBOARD_FAB2_LIB.BASEBOARD_FAB2(SCH_1):PAGE124
  U7C1  AF1 VSS<263> LBG_CORE_QAT_EXT_D_BGA1-IC,H91A    I17 @BASEBOARD_FAB2_LIB.BASEBOARD_FAB2(SCH_1):PAGE124
  U7C1 AE66 VSS<264> LBG_CORE_QAT_EXT_D_BGA1-IC,H91A    I17 @BASEBOARD_FAB2_LIB.BASEBOARD_FAB2(SCH_1):PAGE124
  U7C1 AE63 VSS<265> LBG_CORE_QAT_EXT_D_BGA1-IC,H91A    I17 @BASEBOARD_FAB2_LIB.BASEBOARD_FAB2(SCH_1):PAGE124
  U7C1 AE59 VSS<266> LBG_CORE_QAT_EXT_D_BGA1-IC,H91A    I17 @BASEBOARD_FAB2_LIB.BASEBOARD_FAB2(SCH_1):PAGE124
  U7C1 AE56 VSS<267> LBG_CORE_QAT_EXT_D_BGA1-IC,H91A    I17 @BASEBOARD_FAB2_LIB.BASEBOARD_FAB2(SCH_1):PAGE124
  U7C1 AE52 VSS<268> LBG_CORE_QAT_EXT_D_BGA1-IC,H91A    I17 @BASEBOARD_FAB2_LIB.BASEBOARD_FAB2(SCH_1):PAGE124
  U7C1 AE48 VSS<269> LBG_CORE_QAT_EXT_D_BGA1-IC,H91A    I17 @BASEBOARD_FAB2_LIB.BASEBOARD_FAB2(SCH_1):PAGE124
  U7C1  J18 VSS<270> LBG_CORE_QAT_EXT_D_BGA1-IC,H91A    I17 @BASEBOARD_FAB2_LIB.BASEBOARD_FAB2(SCH_1):PAGE124
  U7C1 AE29 VSS<271> LBG_CORE_QAT_EXT_D_BGA1-IC,H91A    I17 @BASEBOARD_FAB2_LIB.BASEBOARD_FAB2(SCH_1):PAGE124
  U7C1 AD68 VSS<272> LBG_CORE_QAT_EXT_D_BGA1-IC,H91A    I17 @BASEBOARD_FAB2_LIB.BASEBOARD_FAB2(SCH_1):PAGE124
  U7C1 AD65 VSS<273> LBG_CORE_QAT_EXT_D_BGA1-IC,H91A    I17 @BASEBOARD_FAB2_LIB.BASEBOARD_FAB2(SCH_1):PAGE124
  U7C1  AD5 VSS<274> LBG_CORE_QAT_EXT_D_BGA1-IC,H91A    I17 @BASEBOARD_FAB2_LIB.BASEBOARD_FAB2(SCH_1):PAGE124
  U7C1  AC7 VSS<275> LBG_CORE_QAT_EXT_D_BGA1-IC,H91A    I17 @BASEBOARD_FAB2_LIB.BASEBOARD_FAB2(SCH_1):PAGE124
  U7C1 AC66 VSS<276> LBG_CORE_QAT_EXT_D_BGA1-IC,H91A    I17 @BASEBOARD_FAB2_LIB.BASEBOARD_FAB2(SCH_1):PAGE124
  U7C1 AC63 VSS<277> LBG_CORE_QAT_EXT_D_BGA1-IC,H91A    I17 @BASEBOARD_FAB2_LIB.BASEBOARD_FAB2(SCH_1):PAGE124
  U7C1 AC59 VSS<278> LBG_CORE_QAT_EXT_D_BGA1-IC,H91A    I17 @BASEBOARD_FAB2_LIB.BASEBOARD_FAB2(SCH_1):PAGE124
  U7C1 AC52 VSS<279> LBG_CORE_QAT_EXT_D_BGA1-IC,H91A    I17 @BASEBOARD_FAB2_LIB.BASEBOARD_FAB2(SCH_1):PAGE124
  U7C1 AC48 VSS<280> LBG_CORE_QAT_EXT_D_BGA1-IC,H91A    I17 @BASEBOARD_FAB2_LIB.BASEBOARD_FAB2(SCH_1):PAGE124
  U7C1 AC46 VSS<281> LBG_CORE_QAT_EXT_D_BGA1-IC,H91A    I17 @BASEBOARD_FAB2_LIB.BASEBOARD_FAB2(SCH_1):PAGE124
  U7C1 AC43 VSS<282> LBG_CORE_QAT_EXT_D_BGA1-IC,H91A    I17 @BASEBOARD_FAB2_LIB.BASEBOARD_FAB2(SCH_1):PAGE124
  U7C1 AC27 VSS<283> LBG_CORE_QAT_EXT_D_BGA1-IC,H91A    I17 @BASEBOARD_FAB2_LIB.BASEBOARD_FAB2(SCH_1):PAGE124
  U7C1 AD58 VSS<284> LBG_CORE_QAT_EXT_D_BGA1-IC,H91A    I17 @BASEBOARD_FAB2_LIB.BASEBOARD_FAB2(SCH_1):PAGE124
  U7C1 AC45 VSS<285> LBG_CORE_QAT_EXT_D_BGA1-IC,H91A    I17 @BASEBOARD_FAB2_LIB.BASEBOARD_FAB2(SCH_1):PAGE124
  U7C1 AC22 VSS<286> LBG_CORE_QAT_EXT_D_BGA1-IC,H91A    I17 @BASEBOARD_FAB2_LIB.BASEBOARD_FAB2(SCH_1):PAGE124
  U7C1 AC18 VSS<287> LBG_CORE_QAT_EXT_D_BGA1-IC,H91A    I17 @BASEBOARD_FAB2_LIB.BASEBOARD_FAB2(SCH_1):PAGE124
  U7C1 AC15 VSS<288> LBG_CORE_QAT_EXT_D_BGA1-IC,H91A    I17 @BASEBOARD_FAB2_LIB.BASEBOARD_FAB2(SCH_1):PAGE124
  U7C1 AC11 VSS<289> LBG_CORE_QAT_EXT_D_BGA1-IC,H91A    I17 @BASEBOARD_FAB2_LIB.BASEBOARD_FAB2(SCH_1):PAGE124
  U7C1 AB72 VSS<290> LBG_CORE_QAT_EXT_D_BGA1-IC,H91A    I17 @BASEBOARD_FAB2_LIB.BASEBOARD_FAB2(SCH_1):PAGE124
  U7C1 AB70 VSS<291> LBG_CORE_QAT_EXT_D_BGA1-IC,H91A    I17 @BASEBOARD_FAB2_LIB.BASEBOARD_FAB2(SCH_1):PAGE124
  U7C1 AB68 VSS<292> LBG_CORE_QAT_EXT_D_BGA1-IC,H91A    I17 @BASEBOARD_FAB2_LIB.BASEBOARD_FAB2(SCH_1):PAGE124
  U7C1  AB5 VSS<293> LBG_CORE_QAT_EXT_D_BGA1-IC,H91A    I17 @BASEBOARD_FAB2_LIB.BASEBOARD_FAB2(SCH_1):PAGE124
  U7C1 AA48 VSS<294> LBG_CORE_QAT_EXT_D_BGA1-IC,H91A    I17 @BASEBOARD_FAB2_LIB.BASEBOARD_FAB2(SCH_1):PAGE124
  U7C1 AA43 VSS<295> LBG_CORE_QAT_EXT_D_BGA1-IC,H91A    I17 @BASEBOARD_FAB2_LIB.BASEBOARD_FAB2(SCH_1):PAGE124
  U7C1 AA27 VSS<296> LBG_CORE_QAT_EXT_D_BGA1-IC,H91A    I17 @BASEBOARD_FAB2_LIB.BASEBOARD_FAB2(SCH_1):PAGE124
  U7C1 AA26 VSS<297> LBG_CORE_QAT_EXT_D_BGA1-IC,H91A    I17 @BASEBOARD_FAB2_LIB.BASEBOARD_FAB2(SCH_1):PAGE124
  U7C1  Y68 VSS<298> LBG_CORE_QAT_EXT_D_BGA1-IC,H91A    I17 @BASEBOARD_FAB2_LIB.BASEBOARD_FAB2(SCH_1):PAGE124
  U7C1  Y63 VSS<299> LBG_CORE_QAT_EXT_D_BGA1-IC,H91A    I17 @BASEBOARD_FAB2_LIB.BASEBOARD_FAB2(SCH_1):PAGE124
  U7C1  Y59 VSS<300> LBG_CORE_QAT_EXT_D_BGA1-IC,H91A    I17 @BASEBOARD_FAB2_LIB.BASEBOARD_FAB2(SCH_1):PAGE124
  U7C1  Y52 VSS<301> LBG_CORE_QAT_EXT_D_BGA1-IC,H91A    I17 @BASEBOARD_FAB2_LIB.BASEBOARD_FAB2(SCH_1):PAGE124
  U7C1   Y5 VSS<302> LBG_CORE_QAT_EXT_D_BGA1-IC,H91A    I17 @BASEBOARD_FAB2_LIB.BASEBOARD_FAB2(SCH_1):PAGE124
  U7C1  Y48 VSS<303> LBG_CORE_QAT_EXT_D_BGA1-IC,H91A    I17 @BASEBOARD_FAB2_LIB.BASEBOARD_FAB2(SCH_1):PAGE124
  U7C1  Y27 VSS<304> LBG_CORE_QAT_EXT_D_BGA1-IC,H91A    I17 @BASEBOARD_FAB2_LIB.BASEBOARD_FAB2(SCH_1):PAGE124
  U7C1  Y22 VSS<305> LBG_CORE_QAT_EXT_D_BGA1-IC,H91A    I17 @BASEBOARD_FAB2_LIB.BASEBOARD_FAB2(SCH_1):PAGE124
  U7C1   W9 VSS<306> LBG_CORE_QAT_EXT_D_BGA1-IC,H91A    I17 @BASEBOARD_FAB2_LIB.BASEBOARD_FAB2(SCH_1):PAGE124
  U7C1  W61 VSS<307> LBG_CORE_QAT_EXT_D_BGA1-IC,H91A    I17 @BASEBOARD_FAB2_LIB.BASEBOARD_FAB2(SCH_1):PAGE124
  U7C1  Y43 VSS<308> LBG_CORE_QAT_EXT_D_BGA1-IC,H91A    I17 @BASEBOARD_FAB2_LIB.BASEBOARD_FAB2(SCH_1):PAGE124
  U7C1 AA50 VSS<309> LBG_CORE_QAT_EXT_D_BGA1-IC,H91A    I17 @BASEBOARD_FAB2_LIB.BASEBOARD_FAB2(SCH_1):PAGE124
  U7C1  W24 VSS<310> LBG_CORE_QAT_EXT_D_BGA1-IC,H91A    I17 @BASEBOARD_FAB2_LIB.BASEBOARD_FAB2(SCH_1):PAGE124
  U7C1  W20 VSS<311> LBG_CORE_QAT_EXT_D_BGA1-IC,H91A    I17 @BASEBOARD_FAB2_LIB.BASEBOARD_FAB2(SCH_1):PAGE124
  U7C1  W17 VSS<312> LBG_CORE_QAT_EXT_D_BGA1-IC,H91A    I17 @BASEBOARD_FAB2_LIB.BASEBOARD_FAB2(SCH_1):PAGE124
  U7C1  W13 VSS<313> LBG_CORE_QAT_EXT_D_BGA1-IC,H91A    I17 @BASEBOARD_FAB2_LIB.BASEBOARD_FAB2(SCH_1):PAGE124
  U7C1  V68 VSS<314> LBG_CORE_QAT_EXT_D_BGA1-IC,H91A    I17 @BASEBOARD_FAB2_LIB.BASEBOARD_FAB2(SCH_1):PAGE124
  U7C1  V66 VSS<315> LBG_CORE_QAT_EXT_D_BGA1-IC,H91A    I17 @BASEBOARD_FAB2_LIB.BASEBOARD_FAB2(SCH_1):PAGE124
  U7C1  W58 VSS<316> LBG_CORE_QAT_EXT_D_BGA1-IC,H91A    I17 @BASEBOARD_FAB2_LIB.BASEBOARD_FAB2(SCH_1):PAGE124
  U7C1  V52 VSS<317> LBG_CORE_QAT_EXT_D_BGA1-IC,H91A    I17 @BASEBOARD_FAB2_LIB.BASEBOARD_FAB2(SCH_1):PAGE124
  U7C1   V5 VSS<318> LBG_CORE_QAT_EXT_D_BGA1-IC,H91A    I17 @BASEBOARD_FAB2_LIB.BASEBOARD_FAB2(SCH_1):PAGE124
  U7C1  V48 VSS<319> LBG_CORE_QAT_EXT_D_BGA1-IC,H91A    I17 @BASEBOARD_FAB2_LIB.BASEBOARD_FAB2(SCH_1):PAGE124
  U7C1  V26 VSS<320> LBG_CORE_QAT_EXT_D_BGA1-IC,H91A    I17 @BASEBOARD_FAB2_LIB.BASEBOARD_FAB2(SCH_1):PAGE124
  U7C1  U58 VSS<321> LBG_CORE_QAT_EXT_D_BGA1-IC,H91A    I17 @BASEBOARD_FAB2_LIB.BASEBOARD_FAB2(SCH_1):PAGE124
  U7C1 AG46 VSS<322> LBG_CORE_QAT_EXT_D_BGA1-IC,H91A    I17 @BASEBOARD_FAB2_LIB.BASEBOARD_FAB2(SCH_1):PAGE124
  U7C1 AF50 VSS<323> LBG_CORE_QAT_EXT_D_BGA1-IC,H91A    I17 @BASEBOARD_FAB2_LIB.BASEBOARD_FAB2(SCH_1):PAGE124
  U7C1   T7 VSS<324> LBG_CORE_QAT_EXT_D_BGA1-IC,H91A    I17 @BASEBOARD_FAB2_LIB.BASEBOARD_FAB2(SCH_1):PAGE124
  U7C1  T66 VSS<325> LBG_CORE_QAT_EXT_D_BGA1-IC,H91A    I17 @BASEBOARD_FAB2_LIB.BASEBOARD_FAB2(SCH_1):PAGE124
  U7C1  T52 VSS<326> LBG_CORE_QAT_EXT_D_BGA1-IC,H91A    I17 @BASEBOARD_FAB2_LIB.BASEBOARD_FAB2(SCH_1):PAGE124
  U7C1  T48 VSS<327> LBG_CORE_QAT_EXT_D_BGA1-IC,H91A    I17 @BASEBOARD_FAB2_LIB.BASEBOARD_FAB2(SCH_1):PAGE124
  U7C1 AJ45 VSS<328> LBG_CORE_QAT_EXT_D_BGA1-IC,H91A    I17 @BASEBOARD_FAB2_LIB.BASEBOARD_FAB2(SCH_1):PAGE124
  U7C1  T40 VSS<329> LBG_CORE_QAT_EXT_D_BGA1-IC,H91A    I17 @BASEBOARD_FAB2_LIB.BASEBOARD_FAB2(SCH_1):PAGE124
  U7C1  T37 VSS<330> LBG_CORE_QAT_EXT_D_BGA1-IC,H91A    I17 @BASEBOARD_FAB2_LIB.BASEBOARD_FAB2(SCH_1):PAGE124
  U7C1  T33 VSS<331> LBG_CORE_QAT_EXT_D_BGA1-IC,H91A    I17 @BASEBOARD_FAB2_LIB.BASEBOARD_FAB2(SCH_1):PAGE124
  U7C1  T29 VSS<332> LBG_CORE_QAT_EXT_D_BGA1-IC,H91A    I17 @BASEBOARD_FAB2_LIB.BASEBOARD_FAB2(SCH_1):PAGE124
  U7C1  T26 VSS<333> LBG_CORE_QAT_EXT_D_BGA1-IC,H91A    I17 @BASEBOARD_FAB2_LIB.BASEBOARD_FAB2(SCH_1):PAGE124
  U7C1  T22 VSS<334> LBG_CORE_QAT_EXT_D_BGA1-IC,H91A    I17 @BASEBOARD_FAB2_LIB.BASEBOARD_FAB2(SCH_1):PAGE124
  U7C1  T18 VSS<335> LBG_CORE_QAT_EXT_D_BGA1-IC,H91A    I17 @BASEBOARD_FAB2_LIB.BASEBOARD_FAB2(SCH_1):PAGE124
  U7C1  T15 VSS<336> LBG_CORE_QAT_EXT_D_BGA1-IC,H91A    I17 @BASEBOARD_FAB2_LIB.BASEBOARD_FAB2(SCH_1):PAGE124
  U7C1  T11 VSS<337> LBG_CORE_QAT_EXT_D_BGA1-IC,H91A    I17 @BASEBOARD_FAB2_LIB.BASEBOARD_FAB2(SCH_1):PAGE124
  U7C1  R68 VSS<338> LBG_CORE_QAT_EXT_D_BGA1-IC,H91A    I17 @BASEBOARD_FAB2_LIB.BASEBOARD_FAB2(SCH_1):PAGE124
  U7C1  R58 VSS<339> LBG_CORE_QAT_EXT_D_BGA1-IC,H91A    I17 @BASEBOARD_FAB2_LIB.BASEBOARD_FAB2(SCH_1):PAGE124
  U7C1  T56 VSS<340> LBG_CORE_QAT_EXT_D_BGA1-IC,H91A    I17 @BASEBOARD_FAB2_LIB.BASEBOARD_FAB2(SCH_1):PAGE124
  U7C1  R54 VSS<341> LBG_CORE_QAT_EXT_D_BGA1-IC,H91A    I17 @BASEBOARD_FAB2_LIB.BASEBOARD_FAB2(SCH_1):PAGE124
  U7C1  R50 VSS<342> LBG_CORE_QAT_EXT_D_BGA1-IC,H91A    I17 @BASEBOARD_FAB2_LIB.BASEBOARD_FAB2(SCH_1):PAGE124
  U7C1   R5 VSS<343> LBG_CORE_QAT_EXT_D_BGA1-IC,H91A    I17 @BASEBOARD_FAB2_LIB.BASEBOARD_FAB2(SCH_1):PAGE124
  U7C1  U42 VSS<344> LBG_CORE_QAT_EXT_D_BGA1-IC,H91A    I17 @BASEBOARD_FAB2_LIB.BASEBOARD_FAB2(SCH_1):PAGE124
  U7C1  R27 VSS<345> LBG_CORE_QAT_EXT_D_BGA1-IC,H91A    I17 @BASEBOARD_FAB2_LIB.BASEBOARD_FAB2(SCH_1):PAGE124
  U7C1  P63 VSS<346> LBG_CORE_QAT_EXT_D_BGA1-IC,H91A    I17 @BASEBOARD_FAB2_LIB.BASEBOARD_FAB2(SCH_1):PAGE124
  U7C1 AE43 VSS<347> LBG_CORE_QAT_EXT_D_BGA1-IC,H91A    I17 @BASEBOARD_FAB2_LIB.BASEBOARD_FAB2(SCH_1):PAGE124
  U7C1   N9 VSS<348> LBG_CORE_QAT_EXT_D_BGA1-IC,H91A    I17 @BASEBOARD_FAB2_LIB.BASEBOARD_FAB2(SCH_1):PAGE124
  U7C1  N68 VSS<349> LBG_CORE_QAT_EXT_D_BGA1-IC,H91A    I17 @BASEBOARD_FAB2_LIB.BASEBOARD_FAB2(SCH_1):PAGE124
  U7C1  R38 VSS<350> LBG_CORE_QAT_EXT_D_BGA1-IC,H91A    I17 @BASEBOARD_FAB2_LIB.BASEBOARD_FAB2(SCH_1):PAGE124
  U7C1   N5 VSS<351> LBG_CORE_QAT_EXT_D_BGA1-IC,H91A    I17 @BASEBOARD_FAB2_LIB.BASEBOARD_FAB2(SCH_1):PAGE124
  U7C1  N46 VSS<352> LBG_CORE_QAT_EXT_D_BGA1-IC,H91A    I17 @BASEBOARD_FAB2_LIB.BASEBOARD_FAB2(SCH_1):PAGE124
  U7C1  N38 VSS<353> LBG_CORE_QAT_EXT_D_BGA1-IC,H91A    I17 @BASEBOARD_FAB2_LIB.BASEBOARD_FAB2(SCH_1):PAGE124
  U7C1  N35 VSS<354> LBG_CORE_QAT_EXT_D_BGA1-IC,H91A    I17 @BASEBOARD_FAB2_LIB.BASEBOARD_FAB2(SCH_1):PAGE124
 R2R11    2      B RES_0402-1.00K,1%,1/16W,EMPTY,A    I11 @BASEBOARD_FAB2_LIB.BASEBOARD_FAB2(SCH_1):PAGE125
  R8E4    2      B RES_0402-1.00K,1%,1/16W,EMPTY,A    I24 @BASEBOARD_FAB2_LIB.BASEBOARD_FAB2(SCH_1):PAGE125
 R8C17    2      B RES_0402-1.00K,1%,1/16W,EMPTY,A    I41 @BASEBOARD_FAB2_LIB.BASEBOARD_FAB2(SCH_1):PAGE125
  R8D5    2      B RES_0402-1.00K,1%,1/16W,EMPTY,A    I50 @BASEBOARD_FAB2_LIB.BASEBOARD_FAB2(SCH_1):PAGE125
 R7D19    2      B RES_0402-1.00K,1%,1/16W,EMPTY,A     I6 @BASEBOARD_FAB2_LIB.BASEBOARD_FAB2(SCH_1):PAGE126
  Q8E2    2    SRC FET_N_SOT23LF-2N7002,FET,C7925A    I13 @BASEBOARD_FAB2_LIB.BASEBOARD_FAB2(SCH_1):PAGE126
 R3P64    2      B RES_0402-1.00K,1%,1/16W,EMPTY,A    I23 @BASEBOARD_FAB2_LIB.BASEBOARD_FAB2(SCH_1):PAGE126
 C3M21    2      B CAP_A_0402V-1.0UF,6.3V,10%,X6SA     I9 @BASEBOARD_FAB2_LIB.BASEBOARD_FAB2(SCH_1):PAGE127
 C3M22    2      B CAP_A_0402V-1.0UF,6.3V,10%,X6SA    I18 @BASEBOARD_FAB2_LIB.BASEBOARD_FAB2(SCH_1):PAGE127
 C3M30    2      B CAP_A_0402V-1.0UF,6.3V,10%,X6SA    I27 @BASEBOARD_FAB2_LIB.BASEBOARD_FAB2(SCH_1):PAGE127
  C2M5    2      B CAP_0603LF-10UF,4V,20%,X6S,E15A    I43 @BASEBOARD_FAB2_LIB.BASEBOARD_FAB2(SCH_1):PAGE127
  C2M7    2      B CAP_A_0402V-1.0UF,6.3V,10%,X6SA    I44 @BASEBOARD_FAB2_LIB.BASEBOARD_FAB2(SCH_1):PAGE127
 C2M10    2      B CAP_0603LF-10UF,4V,20%,X6S,E15A    I49 @BASEBOARD_FAB2_LIB.BASEBOARD_FAB2(SCH_1):PAGE127
  C2M9    2      B CAP_A_0402V-1.0UF,6.3V,10%,X6SA    I50 @BASEBOARD_FAB2_LIB.BASEBOARD_FAB2(SCH_1):PAGE127
 C3M31    2      B CAP_A_0402V-1.0UF,6.3V,10%,X6SA    I57 @BASEBOARD_FAB2_LIB.BASEBOARD_FAB2(SCH_1):PAGE127
  C2N6    2      B CAP_0603LF-10UF,4V,20%,X6S,E15A    I64 @BASEBOARD_FAB2_LIB.BASEBOARD_FAB2(SCH_1):PAGE127
  C2N5    2      B CAP_A_0402V-1.0UF,6.3V,10%,X6SA    I65 @BASEBOARD_FAB2_LIB.BASEBOARD_FAB2(SCH_1):PAGE127
  C2M8    2      B CAP_A_0402V-1.0UF,6.3V,10%,X6SA    I74 @BASEBOARD_FAB2_LIB.BASEBOARD_FAB2(SCH_1):PAGE127
  C2M6    2      B CAP_A_0402V-1.0UF,6.3V,10%,X6SA    I76 @BASEBOARD_FAB2_LIB.BASEBOARD_FAB2(SCH_1):PAGE127
 C2M25    2      B CAP_A_0402V-1.0UF,6.3V,10%,X6SA    I78 @BASEBOARD_FAB2_LIB.BASEBOARD_FAB2(SCH_1):PAGE127
 C3M29    2      B CAP_A_0402V-1.0UF,6.3V,10%,X6SA    I80 @BASEBOARD_FAB2_LIB.BASEBOARD_FAB2(SCH_1):PAGE127
 C3M24    2      B CAP_0603LF-10UF,4V,20%,X6S,E15A    I81 @BASEBOARD_FAB2_LIB.BASEBOARD_FAB2(SCH_1):PAGE127
 C3M23    2      B CAP_0603LF-10UF,4V,20%,X6S,E15A    I82 @BASEBOARD_FAB2_LIB.BASEBOARD_FAB2(SCH_1):PAGE127
 C3M27    2      B CAP_A_0402V-1.0UF,6.3V,10%,X6SA    I83 @BASEBOARD_FAB2_LIB.BASEBOARD_FAB2(SCH_1):PAGE127
 C3M20    2      B CAP_A_0402V-1.0UF,6.3V,10%,X6SA    I84 @BASEBOARD_FAB2_LIB.BASEBOARD_FAB2(SCH_1):PAGE127
 C3M18    2      B CAP_0603LF-10UF,4V,20%,X6S,E15A    I85 @BASEBOARD_FAB2_LIB.BASEBOARD_FAB2(SCH_1):PAGE127
 C3M17    2      B CAP_0603LF-10UF,4V,20%,X6S,E15A    I86 @BASEBOARD_FAB2_LIB.BASEBOARD_FAB2(SCH_1):PAGE127
 C3M19    2      B CAP_A_0402V-1.0UF,6.3V,10%,X6SA    I87 @BASEBOARD_FAB2_LIB.BASEBOARD_FAB2(SCH_1):PAGE127
  C7D2    2      B CAP_0603-10UF,6.3V,20%,X6S,E15A     I2 @BASEBOARD_FAB2_LIB.BASEBOARD_FAB2(SCH_1):PAGE130
 C2N26    2      B CAP_A_0402V-1.0UF,6.3V,10%,X6SA     I4 @BASEBOARD_FAB2_LIB.BASEBOARD_FAB2(SCH_1):PAGE130
 C2N19    2      B CAP_A_0402V-1.0UF,6.3V,10%,X6SA     I7 @BASEBOARD_FAB2_LIB.BASEBOARD_FAB2(SCH_1):PAGE130
 C2N24    2      B CAP_0603-10UF,6.3V,20%,X6S,E15A     I8 @BASEBOARD_FAB2_LIB.BASEBOARD_FAB2(SCH_1):PAGE130
 C2N22    2      B CAP_0603-10UF,6.3V,20%,X6S,E15A     I9 @BASEBOARD_FAB2_LIB.BASEBOARD_FAB2(SCH_1):PAGE130
 C2N20    2      B CAP_A_0402V-1.0UF,6.3V,10%,X6SA    I12 @BASEBOARD_FAB2_LIB.BASEBOARD_FAB2(SCH_1):PAGE130
 C2N21    2      B CAP_0603-10UF,6.3V,20%,X6S,E15A    I15 @BASEBOARD_FAB2_LIB.BASEBOARD_FAB2(SCH_1):PAGE130
 C3N29    2      B CAP_A_0402V-0.1UF,16V,10%,X7R,A    I16 @BASEBOARD_FAB2_LIB.BASEBOARD_FAB2(SCH_1):PAGE130
  C8C3    2      B CAP_0603-10UF,6.3V,20%,X6S,E15A    I19 @BASEBOARD_FAB2_LIB.BASEBOARD_FAB2(SCH_1):PAGE130
  C8C4    2      B CAP_0603-10UF,6.3V,20%,X6S,E15A    I20 @BASEBOARD_FAB2_LIB.BASEBOARD_FAB2(SCH_1):PAGE130
  C8C5    2      B CAP_0603-10UF,6.3V,20%,X6S,E15A    I21 @BASEBOARD_FAB2_LIB.BASEBOARD_FAB2(SCH_1):PAGE130
  C8C6    2      B CAP_0603-10UF,6.3V,20%,X6S,E15A    I22 @BASEBOARD_FAB2_LIB.BASEBOARD_FAB2(SCH_1):PAGE130
 C2N23    2      B CAP_0603-10UF,6.3V,20%,X6S,E15A    I24 @BASEBOARD_FAB2_LIB.BASEBOARD_FAB2(SCH_1):PAGE130
 C2N14    2      B CAP_0603-10UF,6.3V,20%,X6S,E15A    I25 @BASEBOARD_FAB2_LIB.BASEBOARD_FAB2(SCH_1):PAGE130
 C2N17    2      B CAP_0603-10UF,6.3V,20%,X6S,E15A    I28 @BASEBOARD_FAB2_LIB.BASEBOARD_FAB2(SCH_1):PAGE130
 C2N18    2      B CAP_A_0402V-1.0UF,6.3V,10%,X6SA    I29 @BASEBOARD_FAB2_LIB.BASEBOARD_FAB2(SCH_1):PAGE130
  C8B2    2      B CAP_A_0603V-22.0UF,4V,20%,X6S,A    I30 @BASEBOARD_FAB2_LIB.BASEBOARD_FAB2(SCH_1):PAGE130
  C8B3    2      B CAP_A_0603V-22.0UF,4V,20%,X6S,A    I32 @BASEBOARD_FAB2_LIB.BASEBOARD_FAB2(SCH_1):PAGE130
 C2N25    2      B CAP_A_0402V-1.0UF,6.3V,10%,X6SA    I34 @BASEBOARD_FAB2_LIB.BASEBOARD_FAB2(SCH_1):PAGE130
 C2M16    2      B CAP_A_0402V-1.0UF,6.3V,10%,X6SA    I37 @BASEBOARD_FAB2_LIB.BASEBOARD_FAB2(SCH_1):PAGE130
  C7D3    2      B CAP_A_0603V-22.0UF,4V,20%,X6S,A    I38 @BASEBOARD_FAB2_LIB.BASEBOARD_FAB2(SCH_1):PAGE130
  C8B4    2      B CAP_A_0603V-22.0UF,4V,20%,X6S,A    I39 @BASEBOARD_FAB2_LIB.BASEBOARD_FAB2(SCH_1):PAGE130
  C8B1    2      B CAP_A_0603V-22.0UF,4V,20%,X6S,A    I41 @BASEBOARD_FAB2_LIB.BASEBOARD_FAB2(SCH_1):PAGE130
 C3N23    2      B CAP_A_0402V-1.0UF,6.3V,10%,X6SA    I42 @BASEBOARD_FAB2_LIB.BASEBOARD_FAB2(SCH_1):PAGE130
  C2M1    2      B CAP_A_0603V-22.0UF,4V,20%,X6S,A    I43 @BASEBOARD_FAB2_LIB.BASEBOARD_FAB2(SCH_1):PAGE130
  C2M2    2      B CAP_A_0603V-22.0UF,4V,20%,X6S,A    I45 @BASEBOARD_FAB2_LIB.BASEBOARD_FAB2(SCH_1):PAGE130
 C2N15    2      B CAP_A_0402V-1.0UF,6.3V,10%,X6SA    I47 @BASEBOARD_FAB2_LIB.BASEBOARD_FAB2(SCH_1):PAGE130
 C3N21    2      B CAP_A_0402V-1.0UF,6.3V,10%,X6SA    I49 @BASEBOARD_FAB2_LIB.BASEBOARD_FAB2(SCH_1):PAGE130
 C3N25    2      B CAP_A_0402V-1.0UF,6.3V,10%,X6SA    I50 @BASEBOARD_FAB2_LIB.BASEBOARD_FAB2(SCH_1):PAGE130
 C2N16    2      B CAP_A_0402V-1.0UF,6.3V,10%,X6SA    I52 @BASEBOARD_FAB2_LIB.BASEBOARD_FAB2(SCH_1):PAGE130
 C3N22    2      B CAP_A_0402V-1.0UF,6.3V,10%,X6SA    I53 @BASEBOARD_FAB2_LIB.BASEBOARD_FAB2(SCH_1):PAGE130
 C7B15    2      B CAP_A_0603V-22.0UF,4V,20%,X6S,A     I1 @BASEBOARD_FAB2_LIB.BASEBOARD_FAB2(SCH_1):PAGE131
 C7B19    2      B CAP_A_0603V-22.0UF,4V,20%,X6S,A     I2 @BASEBOARD_FAB2_LIB.BASEBOARD_FAB2(SCH_1):PAGE131
 C7B16    2      B CAP_A_0603V-22.0UF,4V,20%,X6S,A     I3 @BASEBOARD_FAB2_LIB.BASEBOARD_FAB2(SCH_1):PAGE131
 C7B21    2      B CAP_A_0603V-22.0UF,4V,20%,X6S,A     I4 @BASEBOARD_FAB2_LIB.BASEBOARD_FAB2(SCH_1):PAGE131
 C7B20    2      B CAP_A_0603V-22.0UF,4V,20%,X6S,A     I6 @BASEBOARD_FAB2_LIB.BASEBOARD_FAB2(SCH_1):PAGE131
 C7B23    2      B CAP_A_0603V-22.0UF,4V,20%,X6S,A     I7 @BASEBOARD_FAB2_LIB.BASEBOARD_FAB2(SCH_1):PAGE131
 C8B10    2      B CAP_A_0603V-22.0UF,4V,20%,X6S,A     I8 @BASEBOARD_FAB2_LIB.BASEBOARD_FAB2(SCH_1):PAGE131
 C7B22    2      B CAP_A_0603V-22.0UF,4V,20%,X6S,A    I10 @BASEBOARD_FAB2_LIB.BASEBOARD_FAB2(SCH_1):PAGE131
 C7B24    2      B CAP_A_0603V-22.0UF,4V,20%,X6S,A    I11 @BASEBOARD_FAB2_LIB.BASEBOARD_FAB2(SCH_1):PAGE131
 C7B18    2      B CAP_A_0603V-22.0UF,4V,20%,X6S,A    I12 @BASEBOARD_FAB2_LIB.BASEBOARD_FAB2(SCH_1):PAGE131
  C8B9    2      B CAP_A_0603V-22.0UF,4V,20%,X6S,A    I14 @BASEBOARD_FAB2_LIB.BASEBOARD_FAB2(SCH_1):PAGE131
 C8B11    2      B CAP_A_0603V-22.0UF,4V,20%,X6S,A    I15 @BASEBOARD_FAB2_LIB.BASEBOARD_FAB2(SCH_1):PAGE131
 C8B14    2      B CAP_A_0603V-22.0UF,4V,20%,X6S,A    I16 @BASEBOARD_FAB2_LIB.BASEBOARD_FAB2(SCH_1):PAGE131
 C7B17    2      B CAP_A_0603V-22.0UF,4V,20%,X6S,A    I18 @BASEBOARD_FAB2_LIB.BASEBOARD_FAB2(SCH_1):PAGE131
 C8B13    2      B CAP_A_0603V-22.0UF,4V,20%,X6S,A    I20 @BASEBOARD_FAB2_LIB.BASEBOARD_FAB2(SCH_1):PAGE131
 C8B16    2      B CAP_0805-47UF,4V,20%,X6S,C9533A    I22 @BASEBOARD_FAB2_LIB.BASEBOARD_FAB2(SCH_1):PAGE131
 C8B15    2      B CAP_0805-47UF,4V,20%,X6S,C9533A    I24 @BASEBOARD_FAB2_LIB.BASEBOARD_FAB2(SCH_1):PAGE131
 C2M22    2      B CAP_A_0402V-1.0UF,6.3V,10%,X6SA    I27 @BASEBOARD_FAB2_LIB.BASEBOARD_FAB2(SCH_1):PAGE131
 C2M21    2      B CAP_A_0402V-1.0UF,6.3V,10%,X6SA    I28 @BASEBOARD_FAB2_LIB.BASEBOARD_FAB2(SCH_1):PAGE131
 C2M18    2      B CAP_A_0402V-1.0UF,6.3V,10%,X6SA    I29 @BASEBOARD_FAB2_LIB.BASEBOARD_FAB2(SCH_1):PAGE131
 C2M19    2      B CAP_A_0402V-1.0UF,6.3V,10%,X6SA    I31 @BASEBOARD_FAB2_LIB.BASEBOARD_FAB2(SCH_1):PAGE131
 C3M38    2      B CAP_A_0402V-1.0UF,6.3V,10%,X6SA    I32 @BASEBOARD_FAB2_LIB.BASEBOARD_FAB2(SCH_1):PAGE131
 C2M17    2      B CAP_0805-47UF,4V,20%,X6S,C9533A    I34 @BASEBOARD_FAB2_LIB.BASEBOARD_FAB2(SCH_1):PAGE131
 C2M11    2      B CAP_0805-47UF,4V,20%,X6S,C9533A    I35 @BASEBOARD_FAB2_LIB.BASEBOARD_FAB2(SCH_1):PAGE131
 C8A13    2      B CAP_0805-47UF,4V,20%,X6S,C9533A    I37 @BASEBOARD_FAB2_LIB.BASEBOARD_FAB2(SCH_1):PAGE131
 C2M20    2      B CAP_A_0402V-1.0UF,6.3V,10%,X6SA    I39 @BASEBOARD_FAB2_LIB.BASEBOARD_FAB2(SCH_1):PAGE131
 C2N13    2      B CAP_A_0402V-1.0UF,6.3V,10%,X6SA    I40 @BASEBOARD_FAB2_LIB.BASEBOARD_FAB2(SCH_1):PAGE131
  C2N2    2      B CAP_A_0402V-1.0UF,6.3V,10%,X6SA    I41 @BASEBOARD_FAB2_LIB.BASEBOARD_FAB2(SCH_1):PAGE131
 C3M43    2      B CAP_A_0402V-1.0UF,6.3V,10%,X6SA    I42 @BASEBOARD_FAB2_LIB.BASEBOARD_FAB2(SCH_1):PAGE131
  C2N7    2      B CAP_A_0402V-1.0UF,6.3V,10%,X6SA    I43 @BASEBOARD_FAB2_LIB.BASEBOARD_FAB2(SCH_1):PAGE131
 C3M39    2      B CAP_A_0402V-1.0UF,6.3V,10%,X6SA    I44 @BASEBOARD_FAB2_LIB.BASEBOARD_FAB2(SCH_1):PAGE131
 C3M42    2      B CAP_A_0402V-1.0UF,6.3V,10%,X6SA    I45 @BASEBOARD_FAB2_LIB.BASEBOARD_FAB2(SCH_1):PAGE131
  C2N8    2      B CAP_A_0402V-1.0UF,6.3V,10%,X6SA    I47 @BASEBOARD_FAB2_LIB.BASEBOARD_FAB2(SCH_1):PAGE131
 C2M13    2      B CAP_A_0603V-22.0UF,4V,20%,X6S,A    I48 @BASEBOARD_FAB2_LIB.BASEBOARD_FAB2(SCH_1):PAGE131
 C2N10    2      B CAP_A_0603V-22.0UF,4V,20%,X6S,A    I50 @BASEBOARD_FAB2_LIB.BASEBOARD_FAB2(SCH_1):PAGE131
 C2M12    2      B CAP_A_0603V-22.0UF,4V,20%,X6S,A    I52 @BASEBOARD_FAB2_LIB.BASEBOARD_FAB2(SCH_1):PAGE131
 C3L25    2      B CAP_A_0603V-22.0UF,4V,20%,X6S,A     I1 @BASEBOARD_FAB2_LIB.BASEBOARD_FAB2(SCH_1):PAGE132
  C3M7    2      B CAP_A_0603V-22.0UF,4V,20%,X6S,A     I2 @BASEBOARD_FAB2_LIB.BASEBOARD_FAB2(SCH_1):PAGE132
 C3L26    2      B CAP_A_0603V-22.0UF,4V,20%,X6S,A     I3 @BASEBOARD_FAB2_LIB.BASEBOARD_FAB2(SCH_1):PAGE132
 C3L27    2      B CAP_A_0603V-22.0UF,4V,20%,X6S,A     I4 @BASEBOARD_FAB2_LIB.BASEBOARD_FAB2(SCH_1):PAGE132
  C3M6    2      B CAP_A_0603V-22.0UF,4V,20%,X6S,A     I6 @BASEBOARD_FAB2_LIB.BASEBOARD_FAB2(SCH_1):PAGE132
  C7C9    2      B CAP_A_0603V-22.0UF,4V,20%,X6S,A     I7 @BASEBOARD_FAB2_LIB.BASEBOARD_FAB2(SCH_1):PAGE132
 C3N27    2      B CAP_A_0603V-22.0UF,4V,20%,X6S,A     I8 @BASEBOARD_FAB2_LIB.BASEBOARD_FAB2(SCH_1):PAGE132
 C3N30    2      B CAP_A_0603V-22.0UF,4V,20%,X6S,A     I9 @BASEBOARD_FAB2_LIB.BASEBOARD_FAB2(SCH_1):PAGE132
 C7A36    2      B CAP_A_0603V-22.0UF,4V,20%,X6S,A    I11 @BASEBOARD_FAB2_LIB.BASEBOARD_FAB2(SCH_1):PAGE132
 C3N12    2      B CAP_A_0603V-22.0UF,4V,20%,X6S,A    I12 @BASEBOARD_FAB2_LIB.BASEBOARD_FAB2(SCH_1):PAGE132
 C3N10    2      B CAP_A_0603V-22.0UF,4V,20%,X6S,A    I13 @BASEBOARD_FAB2_LIB.BASEBOARD_FAB2(SCH_1):PAGE132
 C3N24    2      B CAP_A_0603V-22.0UF,4V,20%,X6S,A    I16 @BASEBOARD_FAB2_LIB.BASEBOARD_FAB2(SCH_1):PAGE132
 C3N28    2      B CAP_A_0603V-22.0UF,4V,20%,X6S,A    I17 @BASEBOARD_FAB2_LIB.BASEBOARD_FAB2(SCH_1):PAGE132
 C3N11    2      B CAP_A_0603V-22.0UF,4V,20%,X6S,A    I19 @BASEBOARD_FAB2_LIB.BASEBOARD_FAB2(SCH_1):PAGE132
 C3N31    2      B CAP_A_0603V-22.0UF,4V,20%,X6S,A    I20 @BASEBOARD_FAB2_LIB.BASEBOARD_FAB2(SCH_1):PAGE132
 C7A33    2      B CAP_0805-47UF,4V,20%,X6S,C9533A    I23 @BASEBOARD_FAB2_LIB.BASEBOARD_FAB2(SCH_1):PAGE132
  C7B4    2      B CAP_0805-47UF,4V,20%,X6S,C9533A    I24 @BASEBOARD_FAB2_LIB.BASEBOARD_FAB2(SCH_1):PAGE132
  C2N9    2      B CAP_A_0402V-1.0UF,6.3V,10%,X6SA    I26 @BASEBOARD_FAB2_LIB.BASEBOARD_FAB2(SCH_1):PAGE132
  C2N3    2      B CAP_A_0402V-1.0UF,6.3V,10%,X6SA    I27 @BASEBOARD_FAB2_LIB.BASEBOARD_FAB2(SCH_1):PAGE132
  C2N4    2      B CAP_A_0402V-1.0UF,6.3V,10%,X6SA    I28 @BASEBOARD_FAB2_LIB.BASEBOARD_FAB2(SCH_1):PAGE132
 C2N12    2      B CAP_A_0402V-1.0UF,6.3V,10%,X6SA    I29 @BASEBOARD_FAB2_LIB.BASEBOARD_FAB2(SCH_1):PAGE132
 C2N11    2      B CAP_A_0402V-1.0UF,6.3V,10%,X6SA    I30 @BASEBOARD_FAB2_LIB.BASEBOARD_FAB2(SCH_1):PAGE132
 C3N19    2      B CAP_A_0402V-1.0UF,6.3V,10%,X6SA    I31 @BASEBOARD_FAB2_LIB.BASEBOARD_FAB2(SCH_1):PAGE132
  C3N3    2      B CAP_A_0402V-1.0UF,6.3V,10%,X6SA    I32 @BASEBOARD_FAB2_LIB.BASEBOARD_FAB2(SCH_1):PAGE132
  C3N1    2      B CAP_A_0402V-1.0UF,6.3V,10%,X6SA    I34 @BASEBOARD_FAB2_LIB.BASEBOARD_FAB2(SCH_1):PAGE132
  C3N7    2      B CAP_A_0402V-1.0UF,6.3V,10%,X6SA    I35 @BASEBOARD_FAB2_LIB.BASEBOARD_FAB2(SCH_1):PAGE132
 C3N16    2      B CAP_A_0402V-1.0UF,6.3V,10%,X6SA    I36 @BASEBOARD_FAB2_LIB.BASEBOARD_FAB2(SCH_1):PAGE132
 C7A32    2      B CAP_0805-47UF,4V,20%,X6S,C9533A    I38 @BASEBOARD_FAB2_LIB.BASEBOARD_FAB2(SCH_1):PAGE132
 C7A31    2      B CAP_0805-47UF,4V,20%,X6S,C9533A    I40 @BASEBOARD_FAB2_LIB.BASEBOARD_FAB2(SCH_1):PAGE132
 C3N18    2      B CAP_A_0402V-1.0UF,6.3V,10%,X6SA    I42 @BASEBOARD_FAB2_LIB.BASEBOARD_FAB2(SCH_1):PAGE132
  C3N2    2      B CAP_A_0402V-1.0UF,6.3V,10%,X6SA    I43 @BASEBOARD_FAB2_LIB.BASEBOARD_FAB2(SCH_1):PAGE132
  C3N6    2      B CAP_A_0402V-1.0UF,6.3V,10%,X6SA    I44 @BASEBOARD_FAB2_LIB.BASEBOARD_FAB2(SCH_1):PAGE132
 C3N17    2      B CAP_A_0402V-1.0UF,6.3V,10%,X6SA    I45 @BASEBOARD_FAB2_LIB.BASEBOARD_FAB2(SCH_1):PAGE132
  C3N4    2      B CAP_A_0402V-1.0UF,6.3V,10%,X6SA    I46 @BASEBOARD_FAB2_LIB.BASEBOARD_FAB2(SCH_1):PAGE132
  C3N5    2      B CAP_A_0402V-1.0UF,6.3V,10%,X6SA    I48 @BASEBOARD_FAB2_LIB.BASEBOARD_FAB2(SCH_1):PAGE132
 C3N15    2      B CAP_A_0402V-1.0UF,6.3V,10%,X6SA    I49 @BASEBOARD_FAB2_LIB.BASEBOARD_FAB2(SCH_1):PAGE132
 C3N20    2      B CAP_A_0402V-1.0UF,6.3V,10%,X6SA    I51 @BASEBOARD_FAB2_LIB.BASEBOARD_FAB2(SCH_1):PAGE132
 C3L23    2      B CAP_A_0603V-22.0UF,4V,20%,X6S,A    I52 @BASEBOARD_FAB2_LIB.BASEBOARD_FAB2(SCH_1):PAGE132
 C3L22    2      B CAP_A_0603V-22.0UF,4V,20%,X6S,A    I54 @BASEBOARD_FAB2_LIB.BASEBOARD_FAB2(SCH_1):PAGE132
 C3L24    2      B CAP_A_0603V-22.0UF,4V,20%,X6S,A    I56 @BASEBOARD_FAB2_LIB.BASEBOARD_FAB2(SCH_1):PAGE132
  R3N3    1      A RES_0402-2.0K,1%,1/16W,CHIP,G2A   I120 @BASEBOARD_FAB2_LIB.BASEBOARD_FAB2(SCH_1):PAGE133
 R2N12    1      A RES_0402-10.0K,1%,1/16W,EMPTY,A   I122 @BASEBOARD_FAB2_LIB.BASEBOARD_FAB2(SCH_1):PAGE133
 R2N24    2      B RES_0402-1.00K,1%,1/16W,EMPTY,A   I113 @BASEBOARD_FAB2_LIB.BASEBOARD_FAB2(SCH_1):PAGE135
  J8G2    5    IO5 CONN12_C73564003_PIP-CONN,C735A   I124 @BASEBOARD_FAB2_LIB.BASEBOARD_FAB2(SCH_1):PAGE135
  J8G2    6    IO6 CONN12_C73564003_PIP-CONN,C735A   I124 @BASEBOARD_FAB2_LIB.BASEBOARD_FAB2(SCH_1):PAGE135
  J8G2   11   IO11 CONN12_C73564003_PIP-CONN,C735A   I124 @BASEBOARD_FAB2_LIB.BASEBOARD_FAB2(SCH_1):PAGE135
  J8G2   12   IO12 CONN12_C73564003_PIP-CONN,C735A   I124 @BASEBOARD_FAB2_LIB.BASEBOARD_FAB2(SCH_1):PAGE135
  J9A1    1    IO1 CONN4_D42317002_PIP-CONN,D4231A   I131 @BASEBOARD_FAB2_LIB.BASEBOARD_FAB2(SCH_1):PAGE135
  J9A1    3    IO3 CONN4_D42317002_PIP-CONN,D4231A   I131 @BASEBOARD_FAB2_LIB.BASEBOARD_FAB2(SCH_1):PAGE135
 R7G28    2      B RES_0402-1.00K,1%,1/16W,CHIP,GA   I102 @BASEBOARD_FAB2_LIB.BASEBOARD_FAB2(SCH_1):PAGE136
  C8E8    2      B CAP_A_0402V-0.1UF,16V,10%,X7R,A   I128 @BASEBOARD_FAB2_LIB.BASEBOARD_FAB2(SCH_1):PAGE136
  Q8E1    2    SRC FET_N_SOT23LF-2N7002,FET,C7925A   I134 @BASEBOARD_FAB2_LIB.BASEBOARD_FAB2(SCH_1):PAGE136
 R8E16    2      B RES_0402-20.0K,1%,1/16W,CHIP,GA   I140 @BASEBOARD_FAB2_LIB.BASEBOARD_FAB2(SCH_1):PAGE136
 R7G29    2      B RES_0402-1.00K,1%,1/16W,CHIP,GA   I148 @BASEBOARD_FAB2_LIB.BASEBOARD_FAB2(SCH_1):PAGE136
 R3T14    2      B RES_0402-10.0K,1%,1/16W,CHIP,GA   I156 @BASEBOARD_FAB2_LIB.BASEBOARD_FAB2(SCH_1):PAGE136
 R7C11    1      A RES_0402-1.0M,1%,1/16W,EMPTY,GA    I11 @BASEBOARD_FAB2_LIB.BASEBOARD_FAB2(SCH_1):PAGE137
 C7C19    2      B CAP_A_0402V-1.0UF,6.3V,10%,X6SA    I14 @BASEBOARD_FAB2_LIB.BASEBOARD_FAB2(SCH_1):PAGE137
 R1U63    2      B RES_0402-1.00K,1%,1/16W,CHIP,GA    I15 @BASEBOARD_FAB2_LIB.BASEBOARD_FAB2(SCH_1):PAGE137
 C3N32    2      B CAP_A_0402V-1.0UF,6.3V,10%,X6SA    I20 @BASEBOARD_FAB2_LIB.BASEBOARD_FAB2(SCH_1):PAGE137
 R1U64    2      B RES_0402-1.00K,1%,1/16W,CHIP,GA    I69 @BASEBOARD_FAB2_LIB.BASEBOARD_FAB2(SCH_1):PAGE137
 EU9E1   65    GND SPRINGVILLE_SM1-IC,G47144-004    I72 @BASEBOARD_FAB2_LIB.BASEBOARD_FAB2(SCH_1):PAGE139
  C1T4    2      B CAP_0603-10UF,6.3V,20%,X6S,E15A   I134 @BASEBOARD_FAB2_LIB.BASEBOARD_FAB2(SCH_1):PAGE139
 C1R30    2      B CAP_0603-10UF,6.3V,20%,X6S,E15A   I135 @BASEBOARD_FAB2_LIB.BASEBOARD_FAB2(SCH_1):PAGE139
 C1R22    2      B CAP_0603-10UF,6.3V,20%,X6S,E15A   I136 @BASEBOARD_FAB2_LIB.BASEBOARD_FAB2(SCH_1):PAGE139
 C1R13    2      B CAP_0603-10UF,6.3V,20%,X6S,E15A   I142 @BASEBOARD_FAB2_LIB.BASEBOARD_FAB2(SCH_1):PAGE139
 C1R20    2      B CAP_A_0402V-0.1UF,16V,10%,X7R,A   I143 @BASEBOARD_FAB2_LIB.BASEBOARD_FAB2(SCH_1):PAGE139
  C1T3    2      B CAP_A_0402V-0.1UF,16V,10%,X7R,A   I144 @BASEBOARD_FAB2_LIB.BASEBOARD_FAB2(SCH_1):PAGE139
 C1R14    2      B CAP_A_0402V-0.1UF,16V,10%,X7R,A   I145 @BASEBOARD_FAB2_LIB.BASEBOARD_FAB2(SCH_1):PAGE139
 C1R21    2      B CAP_A_0402V-0.1UF,16V,10%,X7R,A   I146 @BASEBOARD_FAB2_LIB.BASEBOARD_FAB2(SCH_1):PAGE139
 C1R26    2      B CAP_A_0402V-0.1UF,16V,10%,X7R,A   I149 @BASEBOARD_FAB2_LIB.BASEBOARD_FAB2(SCH_1):PAGE139
 C1R29    2      B CAP_A_0402V-0.1UF,16V,10%,X7R,A   I150 @BASEBOARD_FAB2_LIB.BASEBOARD_FAB2(SCH_1):PAGE139
 C1R19    2      B CAP_A_0402V-0.1UF,16V,10%,X7R,A   I151 @BASEBOARD_FAB2_LIB.BASEBOARD_FAB2(SCH_1):PAGE139
 C1R31    2      B CAP_A_0402V-0.1UF,16V,10%,X7R,A   I152 @BASEBOARD_FAB2_LIB.BASEBOARD_FAB2(SCH_1):PAGE139
 C1R17    2      B CAP_0603-10UF,6.3V,20%,X6S,E15A   I153 @BASEBOARD_FAB2_LIB.BASEBOARD_FAB2(SCH_1):PAGE139
 C1R18    2      B CAP_A_0402V-0.1UF,16V,10%,X7R,A   I157 @BASEBOARD_FAB2_LIB.BASEBOARD_FAB2(SCH_1):PAGE139
  C1T5    2      B CAP_A_0402V-0.1UF,16V,10%,X7R,A   I158 @BASEBOARD_FAB2_LIB.BASEBOARD_FAB2(SCH_1):PAGE139
 C1R24    2      B CAP_A_0402V-0.1UF,16V,10%,X7R,A   I159 @BASEBOARD_FAB2_LIB.BASEBOARD_FAB2(SCH_1):PAGE139
 C1R15    2      B CAP_A_0402V-0.1UF,16V,10%,X7R,A   I160 @BASEBOARD_FAB2_LIB.BASEBOARD_FAB2(SCH_1):PAGE139
 C1R16    2      B CAP_0603-10UF,6.3V,20%,X6S,E15A   I161 @BASEBOARD_FAB2_LIB.BASEBOARD_FAB2(SCH_1):PAGE139
  C9E1    2      B CAP_A_0603V-22.0UF,4V,20%,EMPTA   I163 @BASEBOARD_FAB2_LIB.BASEBOARD_FAB2(SCH_1):PAGE139
 R9E23    2      B RES_0402-4.99K,1%,1/16W,CHIP,GA   I174 @BASEBOARD_FAB2_LIB.BASEBOARD_FAB2(SCH_1):PAGE139
 R9E13    2      B RES_0402-10.0K,1%,1/16W,CHIP,GA   I212 @BASEBOARD_FAB2_LIB.BASEBOARD_FAB2(SCH_1):PAGE139
 R1R12    2      B RES_0402-10.0K,1%,1/16W,CHIP,GA   I213 @BASEBOARD_FAB2_LIB.BASEBOARD_FAB2(SCH_1):PAGE139
  R1T1    2      B RES_0402-10.0K,1%,1/16W,CHIP,GA   I214 @BASEBOARD_FAB2_LIB.BASEBOARD_FAB2(SCH_1):PAGE139
 C9E12    2      B CAP_A_0603V-22.0UF,4V,20%,EMPTA   I241 @BASEBOARD_FAB2_LIB.BASEBOARD_FAB2(SCH_1):PAGE139
  U9E1    4    VSS M25PE16_SM-IC,H77797-001     I1 @BASEBOARD_FAB2_LIB.BASEBOARD_FAB2(SCH_1):PAGE140
 C1R25    2      B CAP_A_0402V-0.1UF,16V,10%,X7R,A     I3 @BASEBOARD_FAB2_LIB.BASEBOARD_FAB2(SCH_1):PAGE140
  R1R6    2      B RES_0402-3.32K,1%,1/16W,EMPTY,A    I14 @BASEBOARD_FAB2_LIB.BASEBOARD_FAB2(SCH_1):PAGE140
  C9G4    2      B CAP_A_0402V-0.1UF,16V,10%,X7R,A    I46 @BASEBOARD_FAB2_LIB.BASEBOARD_FAB2(SCH_1):PAGE141
  C9G6    2      B CAP_A_0402V-0.1UF,16V,10%,X7R,A    I47 @BASEBOARD_FAB2_LIB.BASEBOARD_FAB2(SCH_1):PAGE141
  C9G5    2      B CAP_0402-1.0UF,16V,10%,X7S,G71A    I48 @BASEBOARD_FAB2_LIB.BASEBOARD_FAB2(SCH_1):PAGE141
  C8E5    2      B CAP_A_0402V-0.1UF,16V,10%,X7R,A    I20 @BASEBOARD_FAB2_LIB.BASEBOARD_FAB2(SCH_1):PAGE142
  U9G1    7 GND<0> GTL2014_SM-IC,D66151-001     I1 @BASEBOARD_FAB2_LIB.BASEBOARD_FAB2(SCH_1):PAGE152
  U9G1    8 GND<1> GTL2014_SM-IC,D66151-001     I1 @BASEBOARD_FAB2_LIB.BASEBOARD_FAB2(SCH_1):PAGE152
  U9G1   11 GND<2> GTL2014_SM-IC,D66151-001     I1 @BASEBOARD_FAB2_LIB.BASEBOARD_FAB2(SCH_1):PAGE152
 R1U30    2      B RES_0402-1.00K,1%,1/16W,CHIP,GA     I2 @BASEBOARD_FAB2_LIB.BASEBOARD_FAB2(SCH_1):PAGE152
 C1U19    2      B CAP_0402-1.0UF,16V,10%,X6S,D97A    I18 @BASEBOARD_FAB2_LIB.BASEBOARD_FAB2(SCH_1):PAGE152
 R1U37    2      B RES_0402-100.0,1%,1/16W,CHIP,GA    I26 @BASEBOARD_FAB2_LIB.BASEBOARD_FAB2(SCH_1):PAGE152
 C1U22    2      B CAP_A_0402V-0.1UF,16V,10%,X7R,A    I27 @BASEBOARD_FAB2_LIB.BASEBOARD_FAB2(SCH_1):PAGE152
  C7F2    2      B CAP_A_0402V-1.0UF,6.3V,10%,X6SA   I130 @BASEBOARD_FAB2_LIB.BASEBOARD_FAB2(SCH_1):PAGE153
  C7F1    2      B CAP_A_0402V-0.01UF,25V,10%,X7RA   I131 @BASEBOARD_FAB2_LIB.BASEBOARD_FAB2(SCH_1):PAGE153
  C3T5    2      B CAP_A_0402V-0.01UF,25V,10%,X7RA   I136 @BASEBOARD_FAB2_LIB.BASEBOARD_FAB2(SCH_1):PAGE153
  C3T4    2      B CAP_A_0402V-1.0UF,6.3V,10%,X6SA   I138 @BASEBOARD_FAB2_LIB.BASEBOARD_FAB2(SCH_1):PAGE153
  U7F1   10    GND W25Q256_XSOI-IC,H25002-001   I146 @BASEBOARD_FAB2_LIB.BASEBOARD_FAB2(SCH_1):PAGE153
 R7F30    2      B RES_0402-10.0K,1%,1/16W,EMPTY,A   I170 @BASEBOARD_FAB2_LIB.BASEBOARD_FAB2(SCH_1):PAGE153
  R3T9    2      B RES_0402-10.0K,1%,1/16W,EMPTY,A   I179 @BASEBOARD_FAB2_LIB.BASEBOARD_FAB2(SCH_1):PAGE153
 C8E18    2      B CAP_A_0402V-0.1UF,16V,10%,X7R,A    I14 @BASEBOARD_FAB2_LIB.BASEBOARD_FAB2(SCH_1):PAGE154
  U8F1   15     EN PI3B3257A_TSSOPLF-IC,E16801-001    I74 @BASEBOARD_FAB2_LIB.BASEBOARD_FAB2(SCH_1):PAGE154
  U8F1    8    GND PI3B3257A_TSSOPLF-IC,E16801-001    I74 @BASEBOARD_FAB2_LIB.BASEBOARD_FAB2(SCH_1):PAGE154
  U2T1   15     EN PI3B3257A_TSSOPLF-IC,E16801-001    I75 @BASEBOARD_FAB2_LIB.BASEBOARD_FAB2(SCH_1):PAGE154
  U2T1    8    GND PI3B3257A_TSSOPLF-IC,E16801-001    I75 @BASEBOARD_FAB2_LIB.BASEBOARD_FAB2(SCH_1):PAGE154
  C2T1    2      B CAP_A_0402V-0.1UF,16V,10%,X7R,A    I94 @BASEBOARD_FAB2_LIB.BASEBOARD_FAB2(SCH_1):PAGE154
  Q8F1    2    SRC FET_N_SOT23LF-2N7002,FET,C7925A   I126 @BASEBOARD_FAB2_LIB.BASEBOARD_FAB2(SCH_1):PAGE154
  R1U6    2      B RES_0402-10.0K,1%,1/16W,CHIP,GA   I128 @BASEBOARD_FAB2_LIB.BASEBOARD_FAB2(SCH_1):PAGE154
 C2T12    2      B CAP_A_0402V-0.1UF,16V,10%,X7R,A   I132 @BASEBOARD_FAB2_LIB.BASEBOARD_FAB2(SCH_1):PAGE154
  C2T8    2      B CAP_A_0402V-0.1UF,16V,10%,X7R,A   I135 @BASEBOARD_FAB2_LIB.BASEBOARD_FAB2(SCH_1):PAGE154
  C9A1    2      B CAP_A_0402V-0.1UF,16V,10%,X7R,A   I127 @BASEBOARD_FAB2_LIB.BASEBOARD_FAB2(SCH_1):PAGE155
  J9A2   13   IO13 CONN14_H54902001_PIP-CONN,H549A   I171 @BASEBOARD_FAB2_LIB.BASEBOARD_FAB2(SCH_1):PAGE155
 C1T56    2      B CAP_A_0402V-0.1UF,16V,10%,X7R,A   I184 @BASEBOARD_FAB2_LIB.BASEBOARD_FAB2(SCH_1):PAGE155
  Q1L2    4 SOURCE<0> FET_N_DUAL_SMLF-NTJD4001N,FET,A   I187 @BASEBOARD_FAB2_LIB.BASEBOARD_FAB2(SCH_1):PAGE155
 C2T35    2      B CAP_A_0402V-0.1UF,16V,10%,X7R,A   I273 @BASEBOARD_FAB2_LIB.BASEBOARD_FAB2(SCH_1):PAGE156
 C8F16    2      B CAP_A_0402V-0.1UF,16V,10%,X7R,A   I275 @BASEBOARD_FAB2_LIB.BASEBOARD_FAB2(SCH_1):PAGE156
  J9B2    2    IO2 CONN3_C95678002_PIP-CONN,C9567A   I281 @BASEBOARD_FAB2_LIB.BASEBOARD_FAB2(SCH_1):PAGE156
  J8C1    2    IO2 CONN3_C95678002_PIP-CONN,C9567A   I285 @BASEBOARD_FAB2_LIB.BASEBOARD_FAB2(SCH_1):PAGE156
 R6N14    1      A RES_0402-1.00K,1%,1/16W,CHIP,GA   I302 @BASEBOARD_FAB2_LIB.BASEBOARD_FAB2(SCH_1):PAGE156
 R6N13    1      A RES_0402-1.00K,1%,1/16W,CHIP,GA   I303 @BASEBOARD_FAB2_LIB.BASEBOARD_FAB2(SCH_1):PAGE156
 R6N15    1      A RES_0402-1.00K,1%,1/16W,CHIP,GA   I304 @BASEBOARD_FAB2_LIB.BASEBOARD_FAB2(SCH_1):PAGE156
 R1C32    1      A RES_0402-1.00K,1%,1/16W,CHIP,GA   I312 @BASEBOARD_FAB2_LIB.BASEBOARD_FAB2(SCH_1):PAGE156
 R1C33    1      A RES_0402-1.00K,1%,1/16W,CHIP,GA   I313 @BASEBOARD_FAB2_LIB.BASEBOARD_FAB2(SCH_1):PAGE156
 R3P56    2      B RES_0402-1.00K,1%,1/16W,CHIP,GA   I333 @BASEBOARD_FAB2_LIB.BASEBOARD_FAB2(SCH_1):PAGE156
 R1C36    2      B RES_0402-1.00K,1%,1/16W,CHIP,GA   I337 @BASEBOARD_FAB2_LIB.BASEBOARD_FAB2(SCH_1):PAGE156
  Q2T1    2      E NPN_SM-MMBT3904,IC,C52245-001   I330 @BASEBOARD_FAB2_LIB.BASEBOARD_FAB2(SCH_1):PAGE157
  Q2T2    2    SRC FET_N_SOT23LF-2N7002,FET,C7925A   I340 @BASEBOARD_FAB2_LIB.BASEBOARD_FAB2(SCH_1):PAGE157
  S8E1    1      A SWITCH_D90553001_SMLF-IC,D9055A   I351 @BASEBOARD_FAB2_LIB.BASEBOARD_FAB2(SCH_1):PAGE157
 C2R12    2      B CAP_A_0402V-1.0UF,6.3V,10%,X6SA   I353 @BASEBOARD_FAB2_LIB.BASEBOARD_FAB2(SCH_1):PAGE157
  C2T3    2      B CAP_A_0402V-0.1UF,16V,10%,X7R,A   I370 @BASEBOARD_FAB2_LIB.BASEBOARD_FAB2(SCH_1):PAGE157
  C8D1    2      B CAP_A_0402V-0.1UF,16V,10%,X7R,A   I376 @BASEBOARD_FAB2_LIB.BASEBOARD_FAB2(SCH_1):PAGE157
 C1T10    2      B CAP_A_0402V-0.1UF,16V,10%,X7R,A    I70 @BASEBOARD_FAB2_LIB.BASEBOARD_FAB2(SCH_1):PAGE158
  U9F2    4    GND FSA3357_SM-IC,C63273-001    I74 @BASEBOARD_FAB2_LIB.BASEBOARD_FAB2(SCH_1):PAGE158
  U9F1    4    GND FSA3357_SM-IC,C63273-001    I75 @BASEBOARD_FAB2_LIB.BASEBOARD_FAB2(SCH_1):PAGE158
 C1T11    2      B CAP_A_0402V-0.1UF,16V,10%,X7R,A    I97 @BASEBOARD_FAB2_LIB.BASEBOARD_FAB2(SCH_1):PAGE158
 C1E21    2      B CAP_0805-10UF,16V,10%,X6S,C953A     I3 @BASEBOARD_FAB2_LIB.BASEBOARD_FAB2(SCH_1):PAGE161
 C1E20    2      B CAP_A_0402V-0.1UF,16V,10%,X7R,A     I4 @BASEBOARD_FAB2_LIB.BASEBOARD_FAB2(SCH_1):PAGE161
  C9M5    2      B CAP_A_0402V-0.1UF,16V,10%,X7R,A    I26 @BASEBOARD_FAB2_LIB.BASEBOARD_FAB2(SCH_1):PAGE161
  C9M4    2      B CAP_0805-10UF,16V,10%,X6S,C953A    I27 @BASEBOARD_FAB2_LIB.BASEBOARD_FAB2(SCH_1):PAGE161
  C1F9    2      B CAP_A_0402V-0.01UF,25V,10%,X7RA    I46 @BASEBOARD_FAB2_LIB.BASEBOARD_FAB2(SCH_1):PAGE161
 C1B15    2      B CAP_A_0402V-0.01UF,25V,10%,X7RA    I68 @BASEBOARD_FAB2_LIB.BASEBOARD_FAB2(SCH_1):PAGE161
 C2U27    2      B CAP_A_0402V-0.1UF,16V,10%,X7R,A    I90 @BASEBOARD_FAB2_LIB.BASEBOARD_FAB2(SCH_1):PAGE161
 C2U28    2      B CAP_A_0402V-0.1UF,16V,10%,X7R,A    I93 @BASEBOARD_FAB2_LIB.BASEBOARD_FAB2(SCH_1):PAGE161
 C1E22    2      B CAP_A_0402V-0.1UF,16V,10%,X7R,A   I113 @BASEBOARD_FAB2_LIB.BASEBOARD_FAB2(SCH_1):PAGE161
 R8F35    2      B RES_0402-1.00K,1%,1/16W,EMPTY,A    I24 @BASEBOARD_FAB2_LIB.BASEBOARD_FAB2(SCH_1):PAGE162
  C8F5    2      B CAP_A_0402V-0.01UF,25V,10%,X7RA    I28 @BASEBOARD_FAB2_LIB.BASEBOARD_FAB2(SCH_1):PAGE162
  C8F4    2      B CAP_A_0402V-1.0UF,6.3V,10%,X6SA    I30 @BASEBOARD_FAB2_LIB.BASEBOARD_FAB2(SCH_1):PAGE162
  U8F2   10    GND W25Q128_SKT16-IC,H12709-001    I32 @BASEBOARD_FAB2_LIB.BASEBOARD_FAB2(SCH_1):PAGE162
  C9M8    2      B CAP_A_0402V-0.1UF,16V,10%,X7R,A    I10 @BASEBOARD_FAB2_LIB.BASEBOARD_FAB2(SCH_1):PAGE163
  C9M7    2      B CAP_A_0402V-0.1UF,16V,10%,X7R,A    I12 @BASEBOARD_FAB2_LIB.BASEBOARD_FAB2(SCH_1):PAGE163
 R1T11    2      B RES_0402-1.00K,1%,1/16W,CHIP,GA     I7 @BASEBOARD_FAB2_LIB.BASEBOARD_FAB2(SCH_1):PAGE164
 R1U17    2      B RES_0402-1.00K,1%,1/16W,CHIP,GA    I21 @BASEBOARD_FAB2_LIB.BASEBOARD_FAB2(SCH_1):PAGE164
 R2N18    2      B RES_0402-1.00K,1%,1/16W,CHIP,GA    I32 @BASEBOARD_FAB2_LIB.BASEBOARD_FAB2(SCH_1):PAGE164
 R7D15    2      B RES_0402-348,1%,1/16W,CHIP,G21A    I32 @BASEBOARD_FAB2_LIB.BASEBOARD_FAB2(SCH_1):PAGE166
  U9B4    5    GND TMP421_TSSOP-IC,G62962-001     I1 @BASEBOARD_FAB2_LIB.BASEBOARD_FAB2(SCH_1):PAGE167
  R9B8    2      B RES_0402-1.00K,1%,1/16W,CHIP,GA    I10 @BASEBOARD_FAB2_LIB.BASEBOARD_FAB2(SCH_1):PAGE167
  U1E1    5    GND TMP421_TSSOP-IC,G62962-001    I30 @BASEBOARD_FAB2_LIB.BASEBOARD_FAB2(SCH_1):PAGE167
  C9B7    2      B CAP_A_0402V-0.1UF,16V,10%,X7R,A    I39 @BASEBOARD_FAB2_LIB.BASEBOARD_FAB2(SCH_1):PAGE167
 C9R14    2      B CAP_A_0402V-0.1UF,16V,10%,X7R,A    I41 @BASEBOARD_FAB2_LIB.BASEBOARD_FAB2(SCH_1):PAGE167
 C9R13    2      B CAP_A_0402V-0.1UF,16V,10%,X7R,A    I42 @BASEBOARD_FAB2_LIB.BASEBOARD_FAB2(SCH_1):PAGE167
  U8D4    1     A0 AT24C64_SOICLF-IC,C47049-001-GA    I49 @BASEBOARD_FAB2_LIB.BASEBOARD_FAB2(SCH_1):PAGE167
  U8D4    2     A1 AT24C64_SOICLF-IC,C47049-001-GA    I49 @BASEBOARD_FAB2_LIB.BASEBOARD_FAB2(SCH_1):PAGE167
 R8D27    2      B RES_0402-1.00K,1%,1/16W,CHIP,GA    I50 @BASEBOARD_FAB2_LIB.BASEBOARD_FAB2(SCH_1):PAGE167
  Q1L3    2      E NPN_SM-MMBT3904,IC,C52245-001     I8 @BASEBOARD_FAB2_LIB.BASEBOARD_FAB2(SCH_1):PAGE168
  Q1L4    1 SOURCE<0> FET_N_DUAL_SMLF-2N7002DW,FET,DA    I19 @BASEBOARD_FAB2_LIB.BASEBOARD_FAB2(SCH_1):PAGE168
 C1U21    2      B CAP_0402LF-47.0PF,50V,5%,COG,AA    I56 @BASEBOARD_FAB2_LIB.BASEBOARD_FAB2(SCH_1):PAGE169
 C9G21    2      B CAP_0402LF-47.0PF,50V,5%,COG,AA    I68 @BASEBOARD_FAB2_LIB.BASEBOARD_FAB2(SCH_1):PAGE169
 C9G17    2      B CAP_0402LF-47.0PF,50V,5%,COG,AA    I80 @BASEBOARD_FAB2_LIB.BASEBOARD_FAB2(SCH_1):PAGE169
 C9G20    2      B CAP_0402LF-47.0PF,50V,5%,COG,AA    I86 @BASEBOARD_FAB2_LIB.BASEBOARD_FAB2(SCH_1):PAGE169
 R9G26    2      B RES_0402-100.0K,1%,1/16W,CHIP,A   I106 @BASEBOARD_FAB2_LIB.BASEBOARD_FAB2(SCH_1):PAGE169
 C9G22    2      B CAP_0402LF-10.0PF,50V,5%,COG,AA   I108 @BASEBOARD_FAB2_LIB.BASEBOARD_FAB2(SCH_1):PAGE169
 C9G15    2      B CAP_0402LF-47.0PF,50V,5%,COG,AA   I139 @BASEBOARD_FAB2_LIB.BASEBOARD_FAB2(SCH_1):PAGE169
 C9G14    2      B CAP_0402LF-47.0PF,50V,5%,COG,AA   I146 @BASEBOARD_FAB2_LIB.BASEBOARD_FAB2(SCH_1):PAGE169
 C9G18    2      B CAP_0402LF-47.0PF,50V,5%,COG,AA   I153 @BASEBOARD_FAB2_LIB.BASEBOARD_FAB2(SCH_1):PAGE169
  Q9G1    1 SOURCE<0> FET_N_DUAL_SMLF-NTJD4001N,FET,A   I162 @BASEBOARD_FAB2_LIB.BASEBOARD_FAB2(SCH_1):PAGE169
  C2P1    2      B CAP_A_0402V-0.1UF,16V,10%,X7R,A     I8 @BASEBOARD_FAB2_LIB.BASEBOARD_FAB2(SCH_1):PAGE170
 C1R27    2      B CAP_A_0402V-0.1UF,16V,10%,X7R,A    I30 @BASEBOARD_FAB2_LIB.BASEBOARD_FAB2(SCH_1):PAGE170
  C8D2    2      B CAP_A_0402V-0.1UF,16V,10%,X7R,A    I33 @BASEBOARD_FAB2_LIB.BASEBOARD_FAB2(SCH_1):PAGE170
  C8E2    2      B CAP_A_0402V-0.1UF,16V,10%,X7R,A    I40 @BASEBOARD_FAB2_LIB.BASEBOARD_FAB2(SCH_1):PAGE170
  C8D3    2      B CAP_0402LF-470PF,50V,10%,EMPTYA    I42 @BASEBOARD_FAB2_LIB.BASEBOARD_FAB2(SCH_1):PAGE170
 C1R28    2      B CAP_A_0402V-0.1UF,16V,10%,X7R,A    I49 @BASEBOARD_FAB2_LIB.BASEBOARD_FAB2(SCH_1):PAGE170
  Q2P1    2    SRC FET_N_SOT23LF-2N7002,FET,C7925A    I58 @BASEBOARD_FAB2_LIB.BASEBOARD_FAB2(SCH_1):PAGE170
 R2P11    2      B RES_0402-1.00K,1%,1/16W,EMPTY,A    I63 @BASEBOARD_FAB2_LIB.BASEBOARD_FAB2(SCH_1):PAGE170
  Q8F2    2    SRC FET_N_SOT23LF-2N7002,FET,C7925A    I67 @BASEBOARD_FAB2_LIB.BASEBOARD_FAB2(SCH_1):PAGE170
  C9B2    2      B CAP_0805-10UF,16V,10%,X6S,C953A    I36 @BASEBOARD_FAB2_LIB.BASEBOARD_FAB2(SCH_1):PAGE172
  C9B1    2      B CAP_0805-10UF,16V,10%,X6S,C953A    I39 @BASEBOARD_FAB2_LIB.BASEBOARD_FAB2(SCH_1):PAGE172
  J8A1  2D9 GND<0> CONN72_G97614002_A_CP-CONN,G97A   I163 @BASEBOARD_FAB2_LIB.BASEBOARD_FAB2(SCH_1):PAGE173
  J8A1  2D6 GND<1> CONN72_G97614002_A_CP-CONN,G97A   I163 @BASEBOARD_FAB2_LIB.BASEBOARD_FAB2(SCH_1):PAGE173
  J8A1  2D3 GND<2> CONN72_G97614002_A_CP-CONN,G97A   I163 @BASEBOARD_FAB2_LIB.BASEBOARD_FAB2(SCH_1):PAGE173
  J8A1  2C9 GND<3> CONN72_G97614002_A_CP-CONN,G97A   I163 @BASEBOARD_FAB2_LIB.BASEBOARD_FAB2(SCH_1):PAGE173
  J8A1  2C6 GND<4> CONN72_G97614002_A_CP-CONN,G97A   I163 @BASEBOARD_FAB2_LIB.BASEBOARD_FAB2(SCH_1):PAGE173
  J8A1  2C3 GND<5> CONN72_G97614002_A_CP-CONN,G97A   I163 @BASEBOARD_FAB2_LIB.BASEBOARD_FAB2(SCH_1):PAGE173
  J8A1  2B9 GND<6> CONN72_G97614002_A_CP-CONN,G97A   I163 @BASEBOARD_FAB2_LIB.BASEBOARD_FAB2(SCH_1):PAGE173
  J8A1  2B6 GND<7> CONN72_G97614002_A_CP-CONN,G97A   I163 @BASEBOARD_FAB2_LIB.BASEBOARD_FAB2(SCH_1):PAGE173
  J8A1  2B3 GND<8> CONN72_G97614002_A_CP-CONN,G97A   I163 @BASEBOARD_FAB2_LIB.BASEBOARD_FAB2(SCH_1):PAGE173
  J8A1  2A9 GND<9> CONN72_G97614002_A_CP-CONN,G97A   I163 @BASEBOARD_FAB2_LIB.BASEBOARD_FAB2(SCH_1):PAGE173
  J8A1  2A6 GND<10> CONN72_G97614002_A_CP-CONN,G97A   I163 @BASEBOARD_FAB2_LIB.BASEBOARD_FAB2(SCH_1):PAGE173
  J8A1  2A3 GND<11> CONN72_G97614002_A_CP-CONN,G97A   I163 @BASEBOARD_FAB2_LIB.BASEBOARD_FAB2(SCH_1):PAGE173
  J8A1  1D9 GND<12> CONN72_G97614002_A_CP-CONN,G97A   I163 @BASEBOARD_FAB2_LIB.BASEBOARD_FAB2(SCH_1):PAGE173
  J8A1  1D6 GND<13> CONN72_G97614002_A_CP-CONN,G97A   I163 @BASEBOARD_FAB2_LIB.BASEBOARD_FAB2(SCH_1):PAGE173
  J8A1  1D3 GND<14> CONN72_G97614002_A_CP-CONN,G97A   I163 @BASEBOARD_FAB2_LIB.BASEBOARD_FAB2(SCH_1):PAGE173
  J8A1  1C9 GND<15> CONN72_G97614002_A_CP-CONN,G97A   I163 @BASEBOARD_FAB2_LIB.BASEBOARD_FAB2(SCH_1):PAGE173
  J8A1  1C6 GND<16> CONN72_G97614002_A_CP-CONN,G97A   I163 @BASEBOARD_FAB2_LIB.BASEBOARD_FAB2(SCH_1):PAGE173
  J8A1  1C3 GND<17> CONN72_G97614002_A_CP-CONN,G97A   I163 @BASEBOARD_FAB2_LIB.BASEBOARD_FAB2(SCH_1):PAGE173
  J8A1  1B9 GND<18> CONN72_G97614002_A_CP-CONN,G97A   I163 @BASEBOARD_FAB2_LIB.BASEBOARD_FAB2(SCH_1):PAGE173
  J8A1  1B6 GND<19> CONN72_G97614002_A_CP-CONN,G97A   I163 @BASEBOARD_FAB2_LIB.BASEBOARD_FAB2(SCH_1):PAGE173
  J8A1  1B3 GND<20> CONN72_G97614002_A_CP-CONN,G97A   I163 @BASEBOARD_FAB2_LIB.BASEBOARD_FAB2(SCH_1):PAGE173
  J8A1  1A9 GND<21> CONN72_G97614002_A_CP-CONN,G97A   I163 @BASEBOARD_FAB2_LIB.BASEBOARD_FAB2(SCH_1):PAGE173
  J8A1  1A6 GND<22> CONN72_G97614002_A_CP-CONN,G97A   I163 @BASEBOARD_FAB2_LIB.BASEBOARD_FAB2(SCH_1):PAGE173
  J8A1  1A3 GND<23> CONN72_G97614002_A_CP-CONN,G97A   I163 @BASEBOARD_FAB2_LIB.BASEBOARD_FAB2(SCH_1):PAGE173
  J8A1  1C2 SIDEBANDA_2 CONN72_G97614002_A_CP-CONN,G97A   I163 @BASEBOARD_FAB2_LIB.BASEBOARD_FAB2(SCH_1):PAGE173
  J8A1  1B1 SIDEBANDA_3 CONN72_G97614002_A_CP-CONN,G97A   I163 @BASEBOARD_FAB2_LIB.BASEBOARD_FAB2(SCH_1):PAGE173
  J8A1  2C2 SIDEBANDB_2 CONN72_G97614002_A_CP-CONN,G97A   I163 @BASEBOARD_FAB2_LIB.BASEBOARD_FAB2(SCH_1):PAGE173
  J8A1  2B1 SIDEBANDB_3 CONN72_G97614002_A_CP-CONN,G97A   I163 @BASEBOARD_FAB2_LIB.BASEBOARD_FAB2(SCH_1):PAGE173
 R2L22    2      B RES_0402-1.00K,1%,1/16W,CHIP,GA   I264 @BASEBOARD_FAB2_LIB.BASEBOARD_FAB2(SCH_1):PAGE173
 R2L18    2      B RES_0402-1.00K,1%,1/16W,CHIP,GA   I266 @BASEBOARD_FAB2_LIB.BASEBOARD_FAB2(SCH_1):PAGE173
 C1L18    2      B CAP_A_0402V-1.0UF,6.3V,10%,X6SA    I11 @BASEBOARD_FAB2_LIB.BASEBOARD_FAB2(SCH_1):PAGE175
 C1L10    2      B CAP_A_0402V-1.0UF,6.3V,10%,X6SA    I19 @BASEBOARD_FAB2_LIB.BASEBOARD_FAB2(SCH_1):PAGE175
 C1L17    2      B CAP_A_0402V-0.1UF,16V,10%,X7R,A    I37 @BASEBOARD_FAB2_LIB.BASEBOARD_FAB2(SCH_1):PAGE175
  C1L9    2      B CAP_A_0402V-0.1UF,16V,10%,X7R,A    I38 @BASEBOARD_FAB2_LIB.BASEBOARD_FAB2(SCH_1):PAGE175
  C9A3    2      B CAP_A_0402V-0.1UF,16V,10%,X7R,A    I40 @BASEBOARD_FAB2_LIB.BASEBOARD_FAB2(SCH_1):PAGE175
  Q9A3    2    SRC FET_N_SOT23LF-2N7002,FET,C7925A    I49 @BASEBOARD_FAB2_LIB.BASEBOARD_FAB2(SCH_1):PAGE175
  C1L4    2      B CAP_A_0402V-0.1UF,16V,10%,X7R,A    I64 @BASEBOARD_FAB2_LIB.BASEBOARD_FAB2(SCH_1):PAGE175
  S9A1    3   PIN3 SWITCH_D37771002_SM-IC,D37771-A    I78 @BASEBOARD_FAB2_LIB.BASEBOARD_FAB2(SCH_1):PAGE175
  S9A1    4   PIN4 SWITCH_D37771002_SM-IC,D37771-A    I78 @BASEBOARD_FAB2_LIB.BASEBOARD_FAB2(SCH_1):PAGE175
  J9B1    4    GND CONN9_H51826001_PIP2-CONN,H518A    I69 @BASEBOARD_FAB2_LIB.BASEBOARD_FAB2(SCH_1):PAGE176
  J9B1  MH1    MH1 CONN9_H51826001_PIP2-CONN,H518A    I69 @BASEBOARD_FAB2_LIB.BASEBOARD_FAB2(SCH_1):PAGE176
  J9B1  MH2    MH2 CONN9_H51826001_PIP2-CONN,H518A    I69 @BASEBOARD_FAB2_LIB.BASEBOARD_FAB2(SCH_1):PAGE176
  J9B1  MH3    MH3 CONN9_H51826001_PIP2-CONN,H518A    I69 @BASEBOARD_FAB2_LIB.BASEBOARD_FAB2(SCH_1):PAGE176
  J9B1  MH4    MH4 CONN9_H51826001_PIP2-CONN,H518A    I69 @BASEBOARD_FAB2_LIB.BASEBOARD_FAB2(SCH_1):PAGE176
 CR1M2    3 GND<0> DIODEAC_DUAL_ARRAY_SM9-ESD3V3UA    I98 @BASEBOARD_FAB2_LIB.BASEBOARD_FAB2(SCH_1):PAGE176
  U1M3    2    GND TPS2061_SM-IC,H66405-001   I100 @BASEBOARD_FAB2_LIB.BASEBOARD_FAB2(SCH_1):PAGE176
 C1M38    2      B CAP_A_0402V-0.1UF,16V,10%,X7R,A   I108 @BASEBOARD_FAB2_LIB.BASEBOARD_FAB2(SCH_1):PAGE176
 R1M25    2      B RES_0402-10.0K,1%,1/16W,CHIP,GA   I111 @BASEBOARD_FAB2_LIB.BASEBOARD_FAB2(SCH_1):PAGE176
  C9B8    2      B CAPP_7343HLF-330UF,10V,20%,POSA   I113 @BASEBOARD_FAB2_LIB.BASEBOARD_FAB2(SCH_1):PAGE176
  C1M3    2      B CAP_A_0402V-1.0UF,6.3V,10%,X6SA    I20 @BASEBOARD_FAB2_LIB.BASEBOARD_FAB2(SCH_1):PAGE177
 DS9A6    2      C LED_A1LF-GREEN,IC,C97278-010    I31 @BASEBOARD_FAB2_LIB.BASEBOARD_FAB2(SCH_1):PAGE177
  Q9F1    4 SOURCE<0> FET_N_DUAL_SMLF-NTJD4001N,FET,A    I79 @BASEBOARD_FAB2_LIB.BASEBOARD_FAB2(SCH_1):PAGE177
  Q9F1    1 SOURCE<0> FET_N_DUAL_SMLF-NTJD4001N,FET,A    I80 @BASEBOARD_FAB2_LIB.BASEBOARD_FAB2(SCH_1):PAGE177
  J8E1   11   IO11 SCONN11_H67026001_SM-CONN,H670A    I87 @BASEBOARD_FAB2_LIB.BASEBOARD_FAB2(SCH_1):PAGE184
  J8E1  MP1    MP1 SCONN11_H67026001_SM-CONN,H670A    I87 @BASEBOARD_FAB2_LIB.BASEBOARD_FAB2(SCH_1):PAGE184
  J8E1  MP2    MP2 SCONN11_H67026001_SM-CONN,H670A    I87 @BASEBOARD_FAB2_LIB.BASEBOARD_FAB2(SCH_1):PAGE184
 RM8D1    1    IO1 STANDOFF_TH1-SO,H72821-001   I104 @BASEBOARD_FAB2_LIB.BASEBOARD_FAB2(SCH_1):PAGE184
  C2P9    2      B CAP_A_0402V-0.1UF,16V,10%,X7R,A   I117 @BASEBOARD_FAB2_LIB.BASEBOARD_FAB2(SCH_1):PAGE185
 C2T29    2      B CAP_A_0402V-0.1UF,16V,10%,X7R,A   I120 @BASEBOARD_FAB2_LIB.BASEBOARD_FAB2(SCH_1):PAGE185
 C2T26    2      B CAP_A_0402V-0.1UF,16V,10%,X7R,A   I123 @BASEBOARD_FAB2_LIB.BASEBOARD_FAB2(SCH_1):PAGE185
 C2T21    2      B CAP_A_0402V-0.1UF,16V,10%,X7R,A   I124 @BASEBOARD_FAB2_LIB.BASEBOARD_FAB2(SCH_1):PAGE185
 C2T16    2      B CAP_A_0402V-0.1UF,16V,10%,X7R,A   I126 @BASEBOARD_FAB2_LIB.BASEBOARD_FAB2(SCH_1):PAGE185
 C2T15    2      B CAP_A_0402V-0.1UF,16V,10%,X7R,A   I127 @BASEBOARD_FAB2_LIB.BASEBOARD_FAB2(SCH_1):PAGE185
 C2T24    2      B CAP_A_0402V-0.1UF,16V,10%,X7R,A   I129 @BASEBOARD_FAB2_LIB.BASEBOARD_FAB2(SCH_1):PAGE185
  C2T2    2      B CAP_A_0402V-0.1UF,16V,10%,X7R,A   I131 @BASEBOARD_FAB2_LIB.BASEBOARD_FAB2(SCH_1):PAGE185
  C2T4    2      B CAP_A_0402V-0.1UF,16V,10%,X7R,A   I132 @BASEBOARD_FAB2_LIB.BASEBOARD_FAB2(SCH_1):PAGE185
  C2T5    2      B CAP_A_0402V-0.1UF,16V,10%,X7R,A   I135 @BASEBOARD_FAB2_LIB.BASEBOARD_FAB2(SCH_1):PAGE185
 C1M27    2      B CAP_0805-10UF,16V,10%,X6S,C953A     I3 @BASEBOARD_FAB2_LIB.BASEBOARD_FAB2(SCH_1):PAGE186
 C1M26    2      B CAP_0805-10UF,16V,10%,X6S,C953A     I6 @BASEBOARD_FAB2_LIB.BASEBOARD_FAB2(SCH_1):PAGE186
 C1M23    2      B CAP_A_0402V-0.1UF,16V,10%,X7R,A     I7 @BASEBOARD_FAB2_LIB.BASEBOARD_FAB2(SCH_1):PAGE186
 C1M22    2      B CAP_A_0402V-0.1UF,16V,10%,X7R,A     I8 @BASEBOARD_FAB2_LIB.BASEBOARD_FAB2(SCH_1):PAGE186
 C1M24    2      B CAP_A_0402V-0.1UF,16V,10%,X7R,A    I10 @BASEBOARD_FAB2_LIB.BASEBOARD_FAB2(SCH_1):PAGE186
 C1M20    2      B CAP_A_0402V-0.1UF,16V,10%,X7R,A   I270 @BASEBOARD_FAB2_LIB.BASEBOARD_FAB2(SCH_1):PAGE186
 C1M21    2      B CAP_A_0402V-1.0UF,6.3V,10%,X6SA   I334 @BASEBOARD_FAB2_LIB.BASEBOARD_FAB2(SCH_1):PAGE186
 C1M25    2      B CAP_A_0402V-1.0UF,6.3V,10%,X6SA   I335 @BASEBOARD_FAB2_LIB.BASEBOARD_FAB2(SCH_1):PAGE186
  J9B3    8    IO8 SCONN120_A28699018_SM-SCONN,A2A   I336 @BASEBOARD_FAB2_LIB.BASEBOARD_FAB2(SCH_1):PAGE186
  J9B3    9    IO9 SCONN120_A28699018_SM-SCONN,A2A   I336 @BASEBOARD_FAB2_LIB.BASEBOARD_FAB2(SCH_1):PAGE186
  J9B3   10   IO10 SCONN120_A28699018_SM-SCONN,A2A   I336 @BASEBOARD_FAB2_LIB.BASEBOARD_FAB2(SCH_1):PAGE186
  J9B3   11   IO11 SCONN120_A28699018_SM-SCONN,A2A   I336 @BASEBOARD_FAB2_LIB.BASEBOARD_FAB2(SCH_1):PAGE186
  J9B3   14   IO14 SCONN120_A28699018_SM-SCONN,A2A   I336 @BASEBOARD_FAB2_LIB.BASEBOARD_FAB2(SCH_1):PAGE186
  J9B3   15   IO15 SCONN120_A28699018_SM-SCONN,A2A   I336 @BASEBOARD_FAB2_LIB.BASEBOARD_FAB2(SCH_1):PAGE186
  J9B3   16   IO16 SCONN120_A28699018_SM-SCONN,A2A   I336 @BASEBOARD_FAB2_LIB.BASEBOARD_FAB2(SCH_1):PAGE186
  J9B3   17   IO17 SCONN120_A28699018_SM-SCONN,A2A   I336 @BASEBOARD_FAB2_LIB.BASEBOARD_FAB2(SCH_1):PAGE186
  J9B3   26   IO26 SCONN120_A28699018_SM-SCONN,A2A   I336 @BASEBOARD_FAB2_LIB.BASEBOARD_FAB2(SCH_1):PAGE186
  J9B3   38   IO38 SCONN120_A28699018_SM-SCONN,A2A   I336 @BASEBOARD_FAB2_LIB.BASEBOARD_FAB2(SCH_1):PAGE186
  J9B3   39   IO39 SCONN120_A28699018_SM-SCONN,A2A   I336 @BASEBOARD_FAB2_LIB.BASEBOARD_FAB2(SCH_1):PAGE186
  J9B3   41   IO41 SCONN120_A28699018_SM-SCONN,A2A   I336 @BASEBOARD_FAB2_LIB.BASEBOARD_FAB2(SCH_1):PAGE186
  J9B3   44   IO44 SCONN120_A28699018_SM-SCONN,A2A   I336 @BASEBOARD_FAB2_LIB.BASEBOARD_FAB2(SCH_1):PAGE186
  J9B3   46   IO46 SCONN120_A28699018_SM-SCONN,A2A   I336 @BASEBOARD_FAB2_LIB.BASEBOARD_FAB2(SCH_1):PAGE186
  J9B3   47   IO47 SCONN120_A28699018_SM-SCONN,A2A   I336 @BASEBOARD_FAB2_LIB.BASEBOARD_FAB2(SCH_1):PAGE186
  J9B3   49   IO49 SCONN120_A28699018_SM-SCONN,A2A   I336 @BASEBOARD_FAB2_LIB.BASEBOARD_FAB2(SCH_1):PAGE186
  J9B3   52   IO52 SCONN120_A28699018_SM-SCONN,A2A   I336 @BASEBOARD_FAB2_LIB.BASEBOARD_FAB2(SCH_1):PAGE186
  J9B3   54   IO54 SCONN120_A28699018_SM-SCONN,A2A   I336 @BASEBOARD_FAB2_LIB.BASEBOARD_FAB2(SCH_1):PAGE186
  J9B3   55   IO55 SCONN120_A28699018_SM-SCONN,A2A   I336 @BASEBOARD_FAB2_LIB.BASEBOARD_FAB2(SCH_1):PAGE186
  J9B3   57   IO57 SCONN120_A28699018_SM-SCONN,A2A   I336 @BASEBOARD_FAB2_LIB.BASEBOARD_FAB2(SCH_1):PAGE186
  J9B3   60   IO60 SCONN120_A28699018_SM-SCONN,A2A   I336 @BASEBOARD_FAB2_LIB.BASEBOARD_FAB2(SCH_1):PAGE186
  J9B3   62   IO62 SCONN120_A28699018_SM-SCONN,A2A   I336 @BASEBOARD_FAB2_LIB.BASEBOARD_FAB2(SCH_1):PAGE186
  J9B3   63   IO63 SCONN120_A28699018_SM-SCONN,A2A   I336 @BASEBOARD_FAB2_LIB.BASEBOARD_FAB2(SCH_1):PAGE186
  J9B3   65   IO65 SCONN120_A28699018_SM-SCONN,A2A   I336 @BASEBOARD_FAB2_LIB.BASEBOARD_FAB2(SCH_1):PAGE186
  J9B3   68   IO68 SCONN120_A28699018_SM-SCONN,A2A   I336 @BASEBOARD_FAB2_LIB.BASEBOARD_FAB2(SCH_1):PAGE186
  J9B3   70   IO70 SCONN120_A28699018_SM-SCONN,A2A   I336 @BASEBOARD_FAB2_LIB.BASEBOARD_FAB2(SCH_1):PAGE186
  J9B3   71   IO71 SCONN120_A28699018_SM-SCONN,A2A   I336 @BASEBOARD_FAB2_LIB.BASEBOARD_FAB2(SCH_1):PAGE186
  J9B3   73   IO73 SCONN120_A28699018_SM-SCONN,A2A   I336 @BASEBOARD_FAB2_LIB.BASEBOARD_FAB2(SCH_1):PAGE186
  J9B3   76   IO76 SCONN120_A28699018_SM-SCONN,A2A   I336 @BASEBOARD_FAB2_LIB.BASEBOARD_FAB2(SCH_1):PAGE186
  J9B3   78   IO78 SCONN120_A28699018_SM-SCONN,A2A   I336 @BASEBOARD_FAB2_LIB.BASEBOARD_FAB2(SCH_1):PAGE186
  J9B3   79   IO79 SCONN120_A28699018_SM-SCONN,A2A   I336 @BASEBOARD_FAB2_LIB.BASEBOARD_FAB2(SCH_1):PAGE186
  J9B3   81   IO81 SCONN120_A28699018_SM-SCONN,A2A   I336 @BASEBOARD_FAB2_LIB.BASEBOARD_FAB2(SCH_1):PAGE186
  J9B3   84   IO84 SCONN120_A28699018_SM-SCONN,A2A   I336 @BASEBOARD_FAB2_LIB.BASEBOARD_FAB2(SCH_1):PAGE186
  J9B3   86   IO86 SCONN120_A28699018_SM-SCONN,A2A   I336 @BASEBOARD_FAB2_LIB.BASEBOARD_FAB2(SCH_1):PAGE186
  J9B3   87   IO87 SCONN120_A28699018_SM-SCONN,A2A   I336 @BASEBOARD_FAB2_LIB.BASEBOARD_FAB2(SCH_1):PAGE186
  J9B3   89   IO89 SCONN120_A28699018_SM-SCONN,A2A   I336 @BASEBOARD_FAB2_LIB.BASEBOARD_FAB2(SCH_1):PAGE186
  J9B3   92   IO92 SCONN120_A28699018_SM-SCONN,A2A   I336 @BASEBOARD_FAB2_LIB.BASEBOARD_FAB2(SCH_1):PAGE186
  J9B3   94   IO94 SCONN120_A28699018_SM-SCONN,A2A   I336 @BASEBOARD_FAB2_LIB.BASEBOARD_FAB2(SCH_1):PAGE186
  J9B3   95   IO95 SCONN120_A28699018_SM-SCONN,A2A   I336 @BASEBOARD_FAB2_LIB.BASEBOARD_FAB2(SCH_1):PAGE186
  J9B3   97   IO97 SCONN120_A28699018_SM-SCONN,A2A   I336 @BASEBOARD_FAB2_LIB.BASEBOARD_FAB2(SCH_1):PAGE186
  J9B3  100  IO100 SCONN120_A28699018_SM-SCONN,A2A   I336 @BASEBOARD_FAB2_LIB.BASEBOARD_FAB2(SCH_1):PAGE186
  J9B3  102  IO102 SCONN120_A28699018_SM-SCONN,A2A   I336 @BASEBOARD_FAB2_LIB.BASEBOARD_FAB2(SCH_1):PAGE186
  J9B3  103  IO103 SCONN120_A28699018_SM-SCONN,A2A   I336 @BASEBOARD_FAB2_LIB.BASEBOARD_FAB2(SCH_1):PAGE186
  J9B3  105  IO105 SCONN120_A28699018_SM-SCONN,A2A   I336 @BASEBOARD_FAB2_LIB.BASEBOARD_FAB2(SCH_1):PAGE186
  J9B3  108  IO108 SCONN120_A28699018_SM-SCONN,A2A   I336 @BASEBOARD_FAB2_LIB.BASEBOARD_FAB2(SCH_1):PAGE186
  J9B3  110  IO110 SCONN120_A28699018_SM-SCONN,A2A   I336 @BASEBOARD_FAB2_LIB.BASEBOARD_FAB2(SCH_1):PAGE186
  J9B3  111  IO111 SCONN120_A28699018_SM-SCONN,A2A   I336 @BASEBOARD_FAB2_LIB.BASEBOARD_FAB2(SCH_1):PAGE186
  J9B3  113  IO113 SCONN120_A28699018_SM-SCONN,A2A   I336 @BASEBOARD_FAB2_LIB.BASEBOARD_FAB2(SCH_1):PAGE186
  J9B3  116  IO116 SCONN120_A28699018_SM-SCONN,A2A   I336 @BASEBOARD_FAB2_LIB.BASEBOARD_FAB2(SCH_1):PAGE186
  J9B3  118  IO118 SCONN120_A28699018_SM-SCONN,A2A   I336 @BASEBOARD_FAB2_LIB.BASEBOARD_FAB2(SCH_1):PAGE186
  J9B3  119  IO119 SCONN120_A28699018_SM-SCONN,A2A   I336 @BASEBOARD_FAB2_LIB.BASEBOARD_FAB2(SCH_1):PAGE186
 C9B10    2      B CAP_A_0402V-0.1UF,16V,10%,X7R,A   I345 @BASEBOARD_FAB2_LIB.BASEBOARD_FAB2(SCH_1):PAGE186
  J8E3    3    IO3 SCONN80_E67482007_SM-CONN,E674A   I119 @BASEBOARD_FAB2_LIB.BASEBOARD_FAB2(SCH_1):PAGE187
  J8E3    8    IO8 SCONN80_E67482007_SM-CONN,E674A   I119 @BASEBOARD_FAB2_LIB.BASEBOARD_FAB2(SCH_1):PAGE187
  J8E3    9    IO9 SCONN80_E67482007_SM-CONN,E674A   I119 @BASEBOARD_FAB2_LIB.BASEBOARD_FAB2(SCH_1):PAGE187
  J8E3   11   IO11 SCONN80_E67482007_SM-CONN,E674A   I119 @BASEBOARD_FAB2_LIB.BASEBOARD_FAB2(SCH_1):PAGE187
  J8E3   14   IO14 SCONN80_E67482007_SM-CONN,E674A   I119 @BASEBOARD_FAB2_LIB.BASEBOARD_FAB2(SCH_1):PAGE187
  J8E3   16   IO16 SCONN80_E67482007_SM-CONN,E674A   I119 @BASEBOARD_FAB2_LIB.BASEBOARD_FAB2(SCH_1):PAGE187
  J8E3   17   IO17 SCONN80_E67482007_SM-CONN,E674A   I119 @BASEBOARD_FAB2_LIB.BASEBOARD_FAB2(SCH_1):PAGE187
  J8E3   19   IO19 SCONN80_E67482007_SM-CONN,E674A   I119 @BASEBOARD_FAB2_LIB.BASEBOARD_FAB2(SCH_1):PAGE187
  J8E3   22   IO22 SCONN80_E67482007_SM-CONN,E674A   I119 @BASEBOARD_FAB2_LIB.BASEBOARD_FAB2(SCH_1):PAGE187
  J8E3   24   IO24 SCONN80_E67482007_SM-CONN,E674A   I119 @BASEBOARD_FAB2_LIB.BASEBOARD_FAB2(SCH_1):PAGE187
  J8E3   25   IO25 SCONN80_E67482007_SM-CONN,E674A   I119 @BASEBOARD_FAB2_LIB.BASEBOARD_FAB2(SCH_1):PAGE187
  J8E3   27   IO27 SCONN80_E67482007_SM-CONN,E674A   I119 @BASEBOARD_FAB2_LIB.BASEBOARD_FAB2(SCH_1):PAGE187
  J8E3   30   IO30 SCONN80_E67482007_SM-CONN,E674A   I119 @BASEBOARD_FAB2_LIB.BASEBOARD_FAB2(SCH_1):PAGE187
  J8E3   32   IO32 SCONN80_E67482007_SM-CONN,E674A   I119 @BASEBOARD_FAB2_LIB.BASEBOARD_FAB2(SCH_1):PAGE187
  J8E3   33   IO33 SCONN80_E67482007_SM-CONN,E674A   I119 @BASEBOARD_FAB2_LIB.BASEBOARD_FAB2(SCH_1):PAGE187
  J8E3   35   IO35 SCONN80_E67482007_SM-CONN,E674A   I119 @BASEBOARD_FAB2_LIB.BASEBOARD_FAB2(SCH_1):PAGE187
  J8E3   38   IO38 SCONN80_E67482007_SM-CONN,E674A   I119 @BASEBOARD_FAB2_LIB.BASEBOARD_FAB2(SCH_1):PAGE187
  J8E3   40   IO40 SCONN80_E67482007_SM-CONN,E674A   I119 @BASEBOARD_FAB2_LIB.BASEBOARD_FAB2(SCH_1):PAGE187
  J8E3   41   IO41 SCONN80_E67482007_SM-CONN,E674A   I119 @BASEBOARD_FAB2_LIB.BASEBOARD_FAB2(SCH_1):PAGE187
  J8E3   43   IO43 SCONN80_E67482007_SM-CONN,E674A   I119 @BASEBOARD_FAB2_LIB.BASEBOARD_FAB2(SCH_1):PAGE187
  J8E3   46   IO46 SCONN80_E67482007_SM-CONN,E674A   I119 @BASEBOARD_FAB2_LIB.BASEBOARD_FAB2(SCH_1):PAGE187
  J8E3   48   IO48 SCONN80_E67482007_SM-CONN,E674A   I119 @BASEBOARD_FAB2_LIB.BASEBOARD_FAB2(SCH_1):PAGE187
  J8E3   49   IO49 SCONN80_E67482007_SM-CONN,E674A   I119 @BASEBOARD_FAB2_LIB.BASEBOARD_FAB2(SCH_1):PAGE187
  J8E3   51   IO51 SCONN80_E67482007_SM-CONN,E674A   I119 @BASEBOARD_FAB2_LIB.BASEBOARD_FAB2(SCH_1):PAGE187
  J8E3   54   IO54 SCONN80_E67482007_SM-CONN,E674A   I119 @BASEBOARD_FAB2_LIB.BASEBOARD_FAB2(SCH_1):PAGE187
  J8E3   56   IO56 SCONN80_E67482007_SM-CONN,E674A   I119 @BASEBOARD_FAB2_LIB.BASEBOARD_FAB2(SCH_1):PAGE187
  J8E3   57   IO57 SCONN80_E67482007_SM-CONN,E674A   I119 @BASEBOARD_FAB2_LIB.BASEBOARD_FAB2(SCH_1):PAGE187
  J8E3   59   IO59 SCONN80_E67482007_SM-CONN,E674A   I119 @BASEBOARD_FAB2_LIB.BASEBOARD_FAB2(SCH_1):PAGE187
  J8E3   62   IO62 SCONN80_E67482007_SM-CONN,E674A   I119 @BASEBOARD_FAB2_LIB.BASEBOARD_FAB2(SCH_1):PAGE187
  J8E3   64   IO64 SCONN80_E67482007_SM-CONN,E674A   I119 @BASEBOARD_FAB2_LIB.BASEBOARD_FAB2(SCH_1):PAGE187
  J8E3   65   IO65 SCONN80_E67482007_SM-CONN,E674A   I119 @BASEBOARD_FAB2_LIB.BASEBOARD_FAB2(SCH_1):PAGE187
  J8E3   67   IO67 SCONN80_E67482007_SM-CONN,E674A   I119 @BASEBOARD_FAB2_LIB.BASEBOARD_FAB2(SCH_1):PAGE187
  J8E3   70   IO70 SCONN80_E67482007_SM-CONN,E674A   I119 @BASEBOARD_FAB2_LIB.BASEBOARD_FAB2(SCH_1):PAGE187
  J8E3   72   IO72 SCONN80_E67482007_SM-CONN,E674A   I119 @BASEBOARD_FAB2_LIB.BASEBOARD_FAB2(SCH_1):PAGE187
  J8E3   73   IO73 SCONN80_E67482007_SM-CONN,E674A   I119 @BASEBOARD_FAB2_LIB.BASEBOARD_FAB2(SCH_1):PAGE187
  J8E3   78   IO78 SCONN80_E67482007_SM-CONN,E674A   I119 @BASEBOARD_FAB2_LIB.BASEBOARD_FAB2(SCH_1):PAGE187
 C2R15    2      B CAP_A_0402V-0.1UF,16V,10%,X7R,A     I2 @BASEBOARD_FAB2_LIB.BASEBOARD_FAB2(SCH_1):PAGE188
 C2R18    2      B CAP_A_0402V-0.1UF,16V,10%,X7R,A     I3 @BASEBOARD_FAB2_LIB.BASEBOARD_FAB2(SCH_1):PAGE188
 C2P11    2      B CAP_A_0402V-0.1UF,16V,10%,X7R,A    I21 @BASEBOARD_FAB2_LIB.BASEBOARD_FAB2(SCH_1):PAGE188
 C2P12    2      B CAP_A_0402V-0.1UF,16V,10%,X7R,A    I23 @BASEBOARD_FAB2_LIB.BASEBOARD_FAB2(SCH_1):PAGE188
 C2R17    2      B CAP_A_0402V-0.1UF,16V,10%,X7R,A    I25 @BASEBOARD_FAB2_LIB.BASEBOARD_FAB2(SCH_1):PAGE188
  J8E4    4    IO4 SCONN64_H87568002_A_SMT-CONN,HA    I27 @BASEBOARD_FAB2_LIB.BASEBOARD_FAB2(SCH_1):PAGE188
  J8E4    7    IO7 SCONN64_H87568002_A_SMT-CONN,HA    I27 @BASEBOARD_FAB2_LIB.BASEBOARD_FAB2(SCH_1):PAGE188
  J8E4   10   IO10 SCONN64_H87568002_A_SMT-CONN,HA    I27 @BASEBOARD_FAB2_LIB.BASEBOARD_FAB2(SCH_1):PAGE188
  J8E4   13   IO13 SCONN64_H87568002_A_SMT-CONN,HA    I27 @BASEBOARD_FAB2_LIB.BASEBOARD_FAB2(SCH_1):PAGE188
  J8E4   16   IO16 SCONN64_H87568002_A_SMT-CONN,HA    I27 @BASEBOARD_FAB2_LIB.BASEBOARD_FAB2(SCH_1):PAGE188
  J8E4   19   IO19 SCONN64_H87568002_A_SMT-CONN,HA    I27 @BASEBOARD_FAB2_LIB.BASEBOARD_FAB2(SCH_1):PAGE188
  J8E4   22   IO22 SCONN64_H87568002_A_SMT-CONN,HA    I27 @BASEBOARD_FAB2_LIB.BASEBOARD_FAB2(SCH_1):PAGE188
  J8E4   25   IO25 SCONN64_H87568002_A_SMT-CONN,HA    I27 @BASEBOARD_FAB2_LIB.BASEBOARD_FAB2(SCH_1):PAGE188
  J8E4   28   IO28 SCONN64_H87568002_A_SMT-CONN,HA    I27 @BASEBOARD_FAB2_LIB.BASEBOARD_FAB2(SCH_1):PAGE188
  J8E4   39   IO39 SCONN64_H87568002_A_SMT-CONN,HA    I27 @BASEBOARD_FAB2_LIB.BASEBOARD_FAB2(SCH_1):PAGE188
  J8E4   42   IO42 SCONN64_H87568002_A_SMT-CONN,HA    I27 @BASEBOARD_FAB2_LIB.BASEBOARD_FAB2(SCH_1):PAGE188
  J8E4   45   IO45 SCONN64_H87568002_A_SMT-CONN,HA    I27 @BASEBOARD_FAB2_LIB.BASEBOARD_FAB2(SCH_1):PAGE188
  J8E4   48   IO48 SCONN64_H87568002_A_SMT-CONN,HA    I27 @BASEBOARD_FAB2_LIB.BASEBOARD_FAB2(SCH_1):PAGE188
  J8E4   51   IO51 SCONN64_H87568002_A_SMT-CONN,HA    I27 @BASEBOARD_FAB2_LIB.BASEBOARD_FAB2(SCH_1):PAGE188
  J8E4   54   IO54 SCONN64_H87568002_A_SMT-CONN,HA    I27 @BASEBOARD_FAB2_LIB.BASEBOARD_FAB2(SCH_1):PAGE188
  J8E4   57   IO57 SCONN64_H87568002_A_SMT-CONN,HA    I27 @BASEBOARD_FAB2_LIB.BASEBOARD_FAB2(SCH_1):PAGE188
  J8E4   60   IO60 SCONN64_H87568002_A_SMT-CONN,HA    I27 @BASEBOARD_FAB2_LIB.BASEBOARD_FAB2(SCH_1):PAGE188
  J8E4   63   IO63 SCONN64_H87568002_A_SMT-CONN,HA    I27 @BASEBOARD_FAB2_LIB.BASEBOARD_FAB2(SCH_1):PAGE188
 C2R16    2      B CAP_A_0402V-0.1UF,16V,10%,X7R,A    I40 @BASEBOARD_FAB2_LIB.BASEBOARD_FAB2(SCH_1):PAGE188
 C2P10    2      B CAP_1206LF-22UF,16V,10%,X6S,D3A    I41 @BASEBOARD_FAB2_LIB.BASEBOARD_FAB2(SCH_1):PAGE188
 C2P16    2      B CAP_A_0402V-0.1UF,16V,10%,X7R,A    I53 @BASEBOARD_FAB2_LIB.BASEBOARD_FAB2(SCH_1):PAGE188
 C2P15    2      B CAP_A_0402V-0.1UF,16V,10%,X7R,A    I55 @BASEBOARD_FAB2_LIB.BASEBOARD_FAB2(SCH_1):PAGE188
 C2P14    2      B CAP_A_0402V-0.1UF,16V,10%,X7R,A    I56 @BASEBOARD_FAB2_LIB.BASEBOARD_FAB2(SCH_1):PAGE188
 C2P13    2      B CAP_A_0402V-0.1UF,16V,10%,X7R,A    I57 @BASEBOARD_FAB2_LIB.BASEBOARD_FAB2(SCH_1):PAGE188
 R3R11    2      B RES_0402-10.0K,1%,1/16W,EMPTY,A    I45 @BASEBOARD_FAB2_LIB.BASEBOARD_FAB2(SCH_1):PAGE189
  J7G2    7    IO7 CONN8_C77962004_PIP-CONN,C7796A    I47 @BASEBOARD_FAB2_LIB.BASEBOARD_FAB2(SCH_1):PAGE189
 R8G23    2      B RES_0402-4.75K,1%,1/16W,CHIP,GA    I56 @BASEBOARD_FAB2_LIB.BASEBOARD_FAB2(SCH_1):PAGE189
  C2P8    2      B CAP_A_0402V-0.01UF,25V,10%,X7RA     I1 @BASEBOARD_FAB2_LIB.BASEBOARD_FAB2(SCH_1):PAGE192
  C2P5    2      B CAP_A_0402V-0.1UF,16V,10%,X7R,A     I3 @BASEBOARD_FAB2_LIB.BASEBOARD_FAB2(SCH_1):PAGE192
  C3R1    2      B CAP_A_0402V-0.1UF,16V,10%,X7R,A     I4 @BASEBOARD_FAB2_LIB.BASEBOARD_FAB2(SCH_1):PAGE192
 C3P43    2      B CAP_A_0402V-0.1UF,16V,10%,X7R,A     I6 @BASEBOARD_FAB2_LIB.BASEBOARD_FAB2(SCH_1):PAGE192
  C3R3    2      B CAP_A_0402V-0.1UF,16V,10%,X7R,A     I7 @BASEBOARD_FAB2_LIB.BASEBOARD_FAB2(SCH_1):PAGE192
  C2R1    2      B CAP_A_0402V-0.1UF,16V,10%,X7R,A     I8 @BASEBOARD_FAB2_LIB.BASEBOARD_FAB2(SCH_1):PAGE192
  C2P2    2      B CAP_A_0402V-0.1UF,16V,10%,X7R,A     I9 @BASEBOARD_FAB2_LIB.BASEBOARD_FAB2(SCH_1):PAGE192
  C3R2    2      B CAP_A_0402V-0.1UF,16V,10%,X7R,A    I10 @BASEBOARD_FAB2_LIB.BASEBOARD_FAB2(SCH_1):PAGE192
 C3P51    2      B CAP_A_0402V-0.1UF,16V,10%,X7R,A    I11 @BASEBOARD_FAB2_LIB.BASEBOARD_FAB2(SCH_1):PAGE192
 C3P47    2      B CAP_A_0402V-0.1UF,16V,10%,X7R,A    I12 @BASEBOARD_FAB2_LIB.BASEBOARD_FAB2(SCH_1):PAGE192
  U8D7   B2 GND<0> LCMXO2_A_256BGA-IC,H63395-001    I14 @BASEBOARD_FAB2_LIB.BASEBOARD_FAB2(SCH_1):PAGE192
  U8D7  B15 GND<1> LCMXO2_A_256BGA-IC,H63395-001    I14 @BASEBOARD_FAB2_LIB.BASEBOARD_FAB2(SCH_1):PAGE192
  U8D7   C3 GND<2> LCMXO2_A_256BGA-IC,H63395-001    I14 @BASEBOARD_FAB2_LIB.BASEBOARD_FAB2(SCH_1):PAGE192
  U8D7  C14 GND<3> LCMXO2_A_256BGA-IC,H63395-001    I14 @BASEBOARD_FAB2_LIB.BASEBOARD_FAB2(SCH_1):PAGE192
  U8D7   D4 GND<4> LCMXO2_A_256BGA-IC,H63395-001    I14 @BASEBOARD_FAB2_LIB.BASEBOARD_FAB2(SCH_1):PAGE192
  U8D7  D13 GND<5> LCMXO2_A_256BGA-IC,H63395-001    I14 @BASEBOARD_FAB2_LIB.BASEBOARD_FAB2(SCH_1):PAGE192
  U8D7   E5 GND<6> LCMXO2_A_256BGA-IC,H63395-001    I14 @BASEBOARD_FAB2_LIB.BASEBOARD_FAB2(SCH_1):PAGE192
  U8D7  E12 GND<7> LCMXO2_A_256BGA-IC,H63395-001    I14 @BASEBOARD_FAB2_LIB.BASEBOARD_FAB2(SCH_1):PAGE192
  U8D7   F6 GND<8> LCMXO2_A_256BGA-IC,H63395-001    I14 @BASEBOARD_FAB2_LIB.BASEBOARD_FAB2(SCH_1):PAGE192
  U8D7  F11 GND<9> LCMXO2_A_256BGA-IC,H63395-001    I14 @BASEBOARD_FAB2_LIB.BASEBOARD_FAB2(SCH_1):PAGE192
  U8D7   H8 GND<10> LCMXO2_A_256BGA-IC,H63395-001    I14 @BASEBOARD_FAB2_LIB.BASEBOARD_FAB2(SCH_1):PAGE192
  U8D7   H9 GND<11> LCMXO2_A_256BGA-IC,H63395-001    I14 @BASEBOARD_FAB2_LIB.BASEBOARD_FAB2(SCH_1):PAGE192
  U8D7   J8 GND<12> LCMXO2_A_256BGA-IC,H63395-001    I14 @BASEBOARD_FAB2_LIB.BASEBOARD_FAB2(SCH_1):PAGE192
  U8D7   J9 GND<13> LCMXO2_A_256BGA-IC,H63395-001    I14 @BASEBOARD_FAB2_LIB.BASEBOARD_FAB2(SCH_1):PAGE192
  U8D7   L6 GND<14> LCMXO2_A_256BGA-IC,H63395-001    I14 @BASEBOARD_FAB2_LIB.BASEBOARD_FAB2(SCH_1):PAGE192
  U8D7  L11 GND<15> LCMXO2_A_256BGA-IC,H63395-001    I14 @BASEBOARD_FAB2_LIB.BASEBOARD_FAB2(SCH_1):PAGE192
  U8D7   M5 GND<16> LCMXO2_A_256BGA-IC,H63395-001    I14 @BASEBOARD_FAB2_LIB.BASEBOARD_FAB2(SCH_1):PAGE192
  U8D7  M12 GND<17> LCMXO2_A_256BGA-IC,H63395-001    I14 @BASEBOARD_FAB2_LIB.BASEBOARD_FAB2(SCH_1):PAGE192
  U8D7   N4 GND<18> LCMXO2_A_256BGA-IC,H63395-001    I14 @BASEBOARD_FAB2_LIB.BASEBOARD_FAB2(SCH_1):PAGE192
  U8D7  N13 GND<19> LCMXO2_A_256BGA-IC,H63395-001    I14 @BASEBOARD_FAB2_LIB.BASEBOARD_FAB2(SCH_1):PAGE192
  U8D7   P3 GND<20> LCMXO2_A_256BGA-IC,H63395-001    I14 @BASEBOARD_FAB2_LIB.BASEBOARD_FAB2(SCH_1):PAGE192
  U8D7  P14 GND<21> LCMXO2_A_256BGA-IC,H63395-001    I14 @BASEBOARD_FAB2_LIB.BASEBOARD_FAB2(SCH_1):PAGE192
  U8D7   R2 GND<22> LCMXO2_A_256BGA-IC,H63395-001    I14 @BASEBOARD_FAB2_LIB.BASEBOARD_FAB2(SCH_1):PAGE192
  U8D7  R15 GND<23> LCMXO2_A_256BGA-IC,H63395-001    I14 @BASEBOARD_FAB2_LIB.BASEBOARD_FAB2(SCH_1):PAGE192
  C2R5    2      B CAP_A_0402V-0.1UF,16V,10%,X7R,A    I15 @BASEBOARD_FAB2_LIB.BASEBOARD_FAB2(SCH_1):PAGE192
  C2P4    2      B CAP_A_0402V-0.1UF,16V,10%,X7R,A    I16 @BASEBOARD_FAB2_LIB.BASEBOARD_FAB2(SCH_1):PAGE192
 C3P52    2      B CAP_A_0402V-0.1UF,16V,10%,X7R,A    I17 @BASEBOARD_FAB2_LIB.BASEBOARD_FAB2(SCH_1):PAGE192
  C2P6    2      B CAP_A_0402V-0.1UF,16V,10%,X7R,A    I18 @BASEBOARD_FAB2_LIB.BASEBOARD_FAB2(SCH_1):PAGE192
  C2R3    2      B CAP_A_0402V-0.1UF,16V,10%,X7R,A    I19 @BASEBOARD_FAB2_LIB.BASEBOARD_FAB2(SCH_1):PAGE192
  C2P7    2      B CAP_A_0402V-0.1UF,16V,10%,X7R,A    I20 @BASEBOARD_FAB2_LIB.BASEBOARD_FAB2(SCH_1):PAGE192
  C2R4    2      B CAP_A_0402V-0.1UF,16V,10%,X7R,A    I21 @BASEBOARD_FAB2_LIB.BASEBOARD_FAB2(SCH_1):PAGE192
  C2P3    2      B CAP_A_0402V-0.1UF,16V,10%,X7R,A    I22 @BASEBOARD_FAB2_LIB.BASEBOARD_FAB2(SCH_1):PAGE192
 C3P44    2      B CAP_A_0402V-0.1UF,16V,10%,X7R,A    I23 @BASEBOARD_FAB2_LIB.BASEBOARD_FAB2(SCH_1):PAGE192
 C3P48    2      B CAP_A_0402V-0.1UF,16V,10%,X7R,A    I25 @BASEBOARD_FAB2_LIB.BASEBOARD_FAB2(SCH_1):PAGE192
  C2R2    2      B CAP_A_0402V-0.1UF,16V,10%,X7R,A    I28 @BASEBOARD_FAB2_LIB.BASEBOARD_FAB2(SCH_1):PAGE192
 R7E20    2      B RES_0402-1.00K,1%,1/16W,CHIP,GA    I59 @BASEBOARD_FAB2_LIB.BASEBOARD_FAB2(SCH_1):PAGE192
  C4C1    2      B CAPP_3018-470UF,2.5V,20%,ALUM,A    I29 @BASEBOARD_FAB2_LIB.BASEBOARD_FAB2(SCH_1):PAGE193
  C3C2    2      B CAP_A_0402V-1.0UF,6.3V,10%,X6SA    I31 @BASEBOARD_FAB2_LIB.BASEBOARD_FAB2(SCH_1):PAGE193
  C3C1    2      B CAP_A_0402V-1.0UF,6.3V,10%,X6SA    I38 @BASEBOARD_FAB2_LIB.BASEBOARD_FAB2(SCH_1):PAGE193
  J4E1  A19  IOA19 SCONN120_H61426002_SM-CONN,H61A    I45 @BASEBOARD_FAB2_LIB.BASEBOARD_FAB2(SCH_1):PAGE193
  J4E1  A20  IOA20 SCONN120_H61426002_SM-CONN,H61A    I45 @BASEBOARD_FAB2_LIB.BASEBOARD_FAB2(SCH_1):PAGE193
  J4E1  B19  IOB19 SCONN120_H61426002_SM-CONN,H61A    I45 @BASEBOARD_FAB2_LIB.BASEBOARD_FAB2(SCH_1):PAGE193
  J4E1  B20  IOB20 SCONN120_H61426002_SM-CONN,H61A    I45 @BASEBOARD_FAB2_LIB.BASEBOARD_FAB2(SCH_1):PAGE193
  J4E1  C19  IOC19 SCONN120_H61426002_SM-CONN,H61A    I45 @BASEBOARD_FAB2_LIB.BASEBOARD_FAB2(SCH_1):PAGE193
  J4E1  C20  IOC20 SCONN120_H61426002_SM-CONN,H61A    I45 @BASEBOARD_FAB2_LIB.BASEBOARD_FAB2(SCH_1):PAGE193
  J4E1   D4   IOD4 SCONN120_H61426002_SM-CONN,H61A    I45 @BASEBOARD_FAB2_LIB.BASEBOARD_FAB2(SCH_1):PAGE193
  J4E1   D5   IOD5 SCONN120_H61426002_SM-CONN,H61A    I45 @BASEBOARD_FAB2_LIB.BASEBOARD_FAB2(SCH_1):PAGE193
  J4E1   D6   IOD6 SCONN120_H61426002_SM-CONN,H61A    I45 @BASEBOARD_FAB2_LIB.BASEBOARD_FAB2(SCH_1):PAGE193
  J4E1   D7   IOD7 SCONN120_H61426002_SM-CONN,H61A    I45 @BASEBOARD_FAB2_LIB.BASEBOARD_FAB2(SCH_1):PAGE193
  J4E1   D8   IOD8 SCONN120_H61426002_SM-CONN,H61A    I45 @BASEBOARD_FAB2_LIB.BASEBOARD_FAB2(SCH_1):PAGE193
  J4E1   D9   IOD9 SCONN120_H61426002_SM-CONN,H61A    I45 @BASEBOARD_FAB2_LIB.BASEBOARD_FAB2(SCH_1):PAGE193
  J4E1  D10  IOD10 SCONN120_H61426002_SM-CONN,H61A    I45 @BASEBOARD_FAB2_LIB.BASEBOARD_FAB2(SCH_1):PAGE193
  J4E1  D11  IOD11 SCONN120_H61426002_SM-CONN,H61A    I45 @BASEBOARD_FAB2_LIB.BASEBOARD_FAB2(SCH_1):PAGE193
  J4E1  D12  IOD12 SCONN120_H61426002_SM-CONN,H61A    I45 @BASEBOARD_FAB2_LIB.BASEBOARD_FAB2(SCH_1):PAGE193
  J4E1  D13  IOD13 SCONN120_H61426002_SM-CONN,H61A    I45 @BASEBOARD_FAB2_LIB.BASEBOARD_FAB2(SCH_1):PAGE193
  J4E1  D14  IOD14 SCONN120_H61426002_SM-CONN,H61A    I45 @BASEBOARD_FAB2_LIB.BASEBOARD_FAB2(SCH_1):PAGE193
  J4E1  D15  IOD15 SCONN120_H61426002_SM-CONN,H61A    I45 @BASEBOARD_FAB2_LIB.BASEBOARD_FAB2(SCH_1):PAGE193
  J4E1  D16  IOD16 SCONN120_H61426002_SM-CONN,H61A    I45 @BASEBOARD_FAB2_LIB.BASEBOARD_FAB2(SCH_1):PAGE193
  J4E1  D17  IOD17 SCONN120_H61426002_SM-CONN,H61A    I45 @BASEBOARD_FAB2_LIB.BASEBOARD_FAB2(SCH_1):PAGE193
  J4E1  D18  IOD18 SCONN120_H61426002_SM-CONN,H61A    I45 @BASEBOARD_FAB2_LIB.BASEBOARD_FAB2(SCH_1):PAGE193
  J4E1  D19  IOD19 SCONN120_H61426002_SM-CONN,H61A    I45 @BASEBOARD_FAB2_LIB.BASEBOARD_FAB2(SCH_1):PAGE193
  J4E1  D20  IOD20 SCONN120_H61426002_SM-CONN,H61A    I45 @BASEBOARD_FAB2_LIB.BASEBOARD_FAB2(SCH_1):PAGE193
  J4E1   E4   IOE4 SCONN120_H61426002_SM-CONN,H61A    I45 @BASEBOARD_FAB2_LIB.BASEBOARD_FAB2(SCH_1):PAGE193
  J4E1   E6   IOE6 SCONN120_H61426002_SM-CONN,H61A    I45 @BASEBOARD_FAB2_LIB.BASEBOARD_FAB2(SCH_1):PAGE193
  J4E1   E7   IOE7 SCONN120_H61426002_SM-CONN,H61A    I45 @BASEBOARD_FAB2_LIB.BASEBOARD_FAB2(SCH_1):PAGE193
  J4E1   E8   IOE8 SCONN120_H61426002_SM-CONN,H61A    I45 @BASEBOARD_FAB2_LIB.BASEBOARD_FAB2(SCH_1):PAGE193
  J4E1   E9   IOE9 SCONN120_H61426002_SM-CONN,H61A    I45 @BASEBOARD_FAB2_LIB.BASEBOARD_FAB2(SCH_1):PAGE193
  J4E1  E10  IOE10 SCONN120_H61426002_SM-CONN,H61A    I45 @BASEBOARD_FAB2_LIB.BASEBOARD_FAB2(SCH_1):PAGE193
  J4E1  E11  IOE11 SCONN120_H61426002_SM-CONN,H61A    I45 @BASEBOARD_FAB2_LIB.BASEBOARD_FAB2(SCH_1):PAGE193
  J4E1  E12  IOE12 SCONN120_H61426002_SM-CONN,H61A    I45 @BASEBOARD_FAB2_LIB.BASEBOARD_FAB2(SCH_1):PAGE193
  J4E1  E13  IOE13 SCONN120_H61426002_SM-CONN,H61A    I45 @BASEBOARD_FAB2_LIB.BASEBOARD_FAB2(SCH_1):PAGE193
  J4E1  E14  IOE14 SCONN120_H61426002_SM-CONN,H61A    I45 @BASEBOARD_FAB2_LIB.BASEBOARD_FAB2(SCH_1):PAGE193
  J4E1  E15  IOE15 SCONN120_H61426002_SM-CONN,H61A    I45 @BASEBOARD_FAB2_LIB.BASEBOARD_FAB2(SCH_1):PAGE193
  J4E1  E16  IOE16 SCONN120_H61426002_SM-CONN,H61A    I45 @BASEBOARD_FAB2_LIB.BASEBOARD_FAB2(SCH_1):PAGE193
  J4E1  E17  IOE17 SCONN120_H61426002_SM-CONN,H61A    I45 @BASEBOARD_FAB2_LIB.BASEBOARD_FAB2(SCH_1):PAGE193
  J4E1  E18  IOE18 SCONN120_H61426002_SM-CONN,H61A    I45 @BASEBOARD_FAB2_LIB.BASEBOARD_FAB2(SCH_1):PAGE193
  J4E1  E19  IOE19 SCONN120_H61426002_SM-CONN,H61A    I45 @BASEBOARD_FAB2_LIB.BASEBOARD_FAB2(SCH_1):PAGE193
  J4E1  E20  IOE20 SCONN120_H61426002_SM-CONN,H61A    I45 @BASEBOARD_FAB2_LIB.BASEBOARD_FAB2(SCH_1):PAGE193
  J4E1   F4   IOF4 SCONN120_H61426002_SM-CONN,H61A    I45 @BASEBOARD_FAB2_LIB.BASEBOARD_FAB2(SCH_1):PAGE193
  J4E1   F6   IOF6 SCONN120_H61426002_SM-CONN,H61A    I45 @BASEBOARD_FAB2_LIB.BASEBOARD_FAB2(SCH_1):PAGE193
  J4E1   F7   IOF7 SCONN120_H61426002_SM-CONN,H61A    I45 @BASEBOARD_FAB2_LIB.BASEBOARD_FAB2(SCH_1):PAGE193
  J4E1   F8   IOF8 SCONN120_H61426002_SM-CONN,H61A    I45 @BASEBOARD_FAB2_LIB.BASEBOARD_FAB2(SCH_1):PAGE193
  J4E1   F9   IOF9 SCONN120_H61426002_SM-CONN,H61A    I45 @BASEBOARD_FAB2_LIB.BASEBOARD_FAB2(SCH_1):PAGE193
  J4E1  F10  IOF10 SCONN120_H61426002_SM-CONN,H61A    I45 @BASEBOARD_FAB2_LIB.BASEBOARD_FAB2(SCH_1):PAGE193
  J4E1  F11  IOF11 SCONN120_H61426002_SM-CONN,H61A    I45 @BASEBOARD_FAB2_LIB.BASEBOARD_FAB2(SCH_1):PAGE193
  J4E1  F12  IOF12 SCONN120_H61426002_SM-CONN,H61A    I45 @BASEBOARD_FAB2_LIB.BASEBOARD_FAB2(SCH_1):PAGE193
  J4E1  F13  IOF13 SCONN120_H61426002_SM-CONN,H61A    I45 @BASEBOARD_FAB2_LIB.BASEBOARD_FAB2(SCH_1):PAGE193
  J4E1  F14  IOF14 SCONN120_H61426002_SM-CONN,H61A    I45 @BASEBOARD_FAB2_LIB.BASEBOARD_FAB2(SCH_1):PAGE193
  J4E1  F15  IOF15 SCONN120_H61426002_SM-CONN,H61A    I45 @BASEBOARD_FAB2_LIB.BASEBOARD_FAB2(SCH_1):PAGE193
  J4E1  F16  IOF16 SCONN120_H61426002_SM-CONN,H61A    I45 @BASEBOARD_FAB2_LIB.BASEBOARD_FAB2(SCH_1):PAGE193
  J4E1  F17  IOF17 SCONN120_H61426002_SM-CONN,H61A    I45 @BASEBOARD_FAB2_LIB.BASEBOARD_FAB2(SCH_1):PAGE193
  J4E1  F18  IOF18 SCONN120_H61426002_SM-CONN,H61A    I45 @BASEBOARD_FAB2_LIB.BASEBOARD_FAB2(SCH_1):PAGE193
  J4E1  F19  IOF19 SCONN120_H61426002_SM-CONN,H61A    I45 @BASEBOARD_FAB2_LIB.BASEBOARD_FAB2(SCH_1):PAGE193
  J4E1  F20  IOF20 SCONN120_H61426002_SM-CONN,H61A    I45 @BASEBOARD_FAB2_LIB.BASEBOARD_FAB2(SCH_1):PAGE193
  J4B2   A9   IOA9 SCONN120_H61426002_SM-CONN,H61A    I46 @BASEBOARD_FAB2_LIB.BASEBOARD_FAB2(SCH_1):PAGE193
  J4B2  A10  IOA10 SCONN120_H61426002_SM-CONN,H61A    I46 @BASEBOARD_FAB2_LIB.BASEBOARD_FAB2(SCH_1):PAGE193
  J4B2  A12  IOA12 SCONN120_H61426002_SM-CONN,H61A    I46 @BASEBOARD_FAB2_LIB.BASEBOARD_FAB2(SCH_1):PAGE193
  J4B2  A14  IOA14 SCONN120_H61426002_SM-CONN,H61A    I46 @BASEBOARD_FAB2_LIB.BASEBOARD_FAB2(SCH_1):PAGE193
  J4B2  A17  IOA17 SCONN120_H61426002_SM-CONN,H61A    I46 @BASEBOARD_FAB2_LIB.BASEBOARD_FAB2(SCH_1):PAGE193
  J4B2   B9   IOB9 SCONN120_H61426002_SM-CONN,H61A    I46 @BASEBOARD_FAB2_LIB.BASEBOARD_FAB2(SCH_1):PAGE193
  J4B2  B10  IOB10 SCONN120_H61426002_SM-CONN,H61A    I46 @BASEBOARD_FAB2_LIB.BASEBOARD_FAB2(SCH_1):PAGE193
  J4B2  B12  IOB12 SCONN120_H61426002_SM-CONN,H61A    I46 @BASEBOARD_FAB2_LIB.BASEBOARD_FAB2(SCH_1):PAGE193
  J4B2  B14  IOB14 SCONN120_H61426002_SM-CONN,H61A    I46 @BASEBOARD_FAB2_LIB.BASEBOARD_FAB2(SCH_1):PAGE193
  J4B2  B17  IOB17 SCONN120_H61426002_SM-CONN,H61A    I46 @BASEBOARD_FAB2_LIB.BASEBOARD_FAB2(SCH_1):PAGE193
  J4B2   C1   IOC1 SCONN120_H61426002_SM-CONN,H61A    I46 @BASEBOARD_FAB2_LIB.BASEBOARD_FAB2(SCH_1):PAGE193
  J4B2   C2   IOC2 SCONN120_H61426002_SM-CONN,H61A    I46 @BASEBOARD_FAB2_LIB.BASEBOARD_FAB2(SCH_1):PAGE193
  J4B2   C3   IOC3 SCONN120_H61426002_SM-CONN,H61A    I46 @BASEBOARD_FAB2_LIB.BASEBOARD_FAB2(SCH_1):PAGE193
  J4B2   C4   IOC4 SCONN120_H61426002_SM-CONN,H61A    I46 @BASEBOARD_FAB2_LIB.BASEBOARD_FAB2(SCH_1):PAGE193
  J4B2   C5   IOC5 SCONN120_H61426002_SM-CONN,H61A    I46 @BASEBOARD_FAB2_LIB.BASEBOARD_FAB2(SCH_1):PAGE193
  J4B2   C6   IOC6 SCONN120_H61426002_SM-CONN,H61A    I46 @BASEBOARD_FAB2_LIB.BASEBOARD_FAB2(SCH_1):PAGE193
  J4B2   C7   IOC7 SCONN120_H61426002_SM-CONN,H61A    I46 @BASEBOARD_FAB2_LIB.BASEBOARD_FAB2(SCH_1):PAGE193
  J4B2   C8   IOC8 SCONN120_H61426002_SM-CONN,H61A    I46 @BASEBOARD_FAB2_LIB.BASEBOARD_FAB2(SCH_1):PAGE193
  J4B2   C9   IOC9 SCONN120_H61426002_SM-CONN,H61A    I46 @BASEBOARD_FAB2_LIB.BASEBOARD_FAB2(SCH_1):PAGE193
  J4B2  C10  IOC10 SCONN120_H61426002_SM-CONN,H61A    I46 @BASEBOARD_FAB2_LIB.BASEBOARD_FAB2(SCH_1):PAGE193
  J4B2  C12  IOC12 SCONN120_H61426002_SM-CONN,H61A    I46 @BASEBOARD_FAB2_LIB.BASEBOARD_FAB2(SCH_1):PAGE193
  J4B2  C14  IOC14 SCONN120_H61426002_SM-CONN,H61A    I46 @BASEBOARD_FAB2_LIB.BASEBOARD_FAB2(SCH_1):PAGE193
  J4B2  C15  IOC15 SCONN120_H61426002_SM-CONN,H61A    I46 @BASEBOARD_FAB2_LIB.BASEBOARD_FAB2(SCH_1):PAGE193
  J4B2  C16  IOC16 SCONN120_H61426002_SM-CONN,H61A    I46 @BASEBOARD_FAB2_LIB.BASEBOARD_FAB2(SCH_1):PAGE193
  J4B2   D2   IOD2 SCONN120_H61426002_SM-CONN,H61A    I46 @BASEBOARD_FAB2_LIB.BASEBOARD_FAB2(SCH_1):PAGE193
  J4B2   D3   IOD3 SCONN120_H61426002_SM-CONN,H61A    I46 @BASEBOARD_FAB2_LIB.BASEBOARD_FAB2(SCH_1):PAGE193
  J4B2   D4   IOD4 SCONN120_H61426002_SM-CONN,H61A    I46 @BASEBOARD_FAB2_LIB.BASEBOARD_FAB2(SCH_1):PAGE193
  J4B2   D5   IOD5 SCONN120_H61426002_SM-CONN,H61A    I46 @BASEBOARD_FAB2_LIB.BASEBOARD_FAB2(SCH_1):PAGE193
  J4B2   D6   IOD6 SCONN120_H61426002_SM-CONN,H61A    I46 @BASEBOARD_FAB2_LIB.BASEBOARD_FAB2(SCH_1):PAGE193
  J4B2   D7   IOD7 SCONN120_H61426002_SM-CONN,H61A    I46 @BASEBOARD_FAB2_LIB.BASEBOARD_FAB2(SCH_1):PAGE193
  J4B2   D8   IOD8 SCONN120_H61426002_SM-CONN,H61A    I46 @BASEBOARD_FAB2_LIB.BASEBOARD_FAB2(SCH_1):PAGE193
  J4B2   D9   IOD9 SCONN120_H61426002_SM-CONN,H61A    I46 @BASEBOARD_FAB2_LIB.BASEBOARD_FAB2(SCH_1):PAGE193
  J4B2  D10  IOD10 SCONN120_H61426002_SM-CONN,H61A    I46 @BASEBOARD_FAB2_LIB.BASEBOARD_FAB2(SCH_1):PAGE193
  J4B2  D11  IOD11 SCONN120_H61426002_SM-CONN,H61A    I46 @BASEBOARD_FAB2_LIB.BASEBOARD_FAB2(SCH_1):PAGE193
  J4B2  D12  IOD12 SCONN120_H61426002_SM-CONN,H61A    I46 @BASEBOARD_FAB2_LIB.BASEBOARD_FAB2(SCH_1):PAGE193
  J4B2  D13  IOD13 SCONN120_H61426002_SM-CONN,H61A    I46 @BASEBOARD_FAB2_LIB.BASEBOARD_FAB2(SCH_1):PAGE193
  J4B2  D14  IOD14 SCONN120_H61426002_SM-CONN,H61A    I46 @BASEBOARD_FAB2_LIB.BASEBOARD_FAB2(SCH_1):PAGE193
  J4B2  D15  IOD15 SCONN120_H61426002_SM-CONN,H61A    I46 @BASEBOARD_FAB2_LIB.BASEBOARD_FAB2(SCH_1):PAGE193
  J4B2  D16  IOD16 SCONN120_H61426002_SM-CONN,H61A    I46 @BASEBOARD_FAB2_LIB.BASEBOARD_FAB2(SCH_1):PAGE193
  J4B2   E2   IOE2 SCONN120_H61426002_SM-CONN,H61A    I46 @BASEBOARD_FAB2_LIB.BASEBOARD_FAB2(SCH_1):PAGE193
  J4B2   E3   IOE3 SCONN120_H61426002_SM-CONN,H61A    I46 @BASEBOARD_FAB2_LIB.BASEBOARD_FAB2(SCH_1):PAGE193
  J4B2   E4   IOE4 SCONN120_H61426002_SM-CONN,H61A    I46 @BASEBOARD_FAB2_LIB.BASEBOARD_FAB2(SCH_1):PAGE193
  J4B2   E5   IOE5 SCONN120_H61426002_SM-CONN,H61A    I46 @BASEBOARD_FAB2_LIB.BASEBOARD_FAB2(SCH_1):PAGE193
  J4B2   E6   IOE6 SCONN120_H61426002_SM-CONN,H61A    I46 @BASEBOARD_FAB2_LIB.BASEBOARD_FAB2(SCH_1):PAGE193
  J4B2   E7   IOE7 SCONN120_H61426002_SM-CONN,H61A    I46 @BASEBOARD_FAB2_LIB.BASEBOARD_FAB2(SCH_1):PAGE193
  J4B2   E9   IOE9 SCONN120_H61426002_SM-CONN,H61A    I46 @BASEBOARD_FAB2_LIB.BASEBOARD_FAB2(SCH_1):PAGE193
  J4B2  E11  IOE11 SCONN120_H61426002_SM-CONN,H61A    I46 @BASEBOARD_FAB2_LIB.BASEBOARD_FAB2(SCH_1):PAGE193
  J4B2  E12  IOE12 SCONN120_H61426002_SM-CONN,H61A    I46 @BASEBOARD_FAB2_LIB.BASEBOARD_FAB2(SCH_1):PAGE193
  J4B2  E13  IOE13 SCONN120_H61426002_SM-CONN,H61A    I46 @BASEBOARD_FAB2_LIB.BASEBOARD_FAB2(SCH_1):PAGE193
  J4B2  E14  IOE14 SCONN120_H61426002_SM-CONN,H61A    I46 @BASEBOARD_FAB2_LIB.BASEBOARD_FAB2(SCH_1):PAGE193
  J4B2   F2   IOF2 SCONN120_H61426002_SM-CONN,H61A    I46 @BASEBOARD_FAB2_LIB.BASEBOARD_FAB2(SCH_1):PAGE193
  J4B2   F3   IOF3 SCONN120_H61426002_SM-CONN,H61A    I46 @BASEBOARD_FAB2_LIB.BASEBOARD_FAB2(SCH_1):PAGE193
  J4B2   F4   IOF4 SCONN120_H61426002_SM-CONN,H61A    I46 @BASEBOARD_FAB2_LIB.BASEBOARD_FAB2(SCH_1):PAGE193
  J4B2   F5   IOF5 SCONN120_H61426002_SM-CONN,H61A    I46 @BASEBOARD_FAB2_LIB.BASEBOARD_FAB2(SCH_1):PAGE193
  J4B2   F6   IOF6 SCONN120_H61426002_SM-CONN,H61A    I46 @BASEBOARD_FAB2_LIB.BASEBOARD_FAB2(SCH_1):PAGE193
  J4B2   F7   IOF7 SCONN120_H61426002_SM-CONN,H61A    I46 @BASEBOARD_FAB2_LIB.BASEBOARD_FAB2(SCH_1):PAGE193
  J4B2   F9   IOF9 SCONN120_H61426002_SM-CONN,H61A    I46 @BASEBOARD_FAB2_LIB.BASEBOARD_FAB2(SCH_1):PAGE193
  J4B2  F11  IOF11 SCONN120_H61426002_SM-CONN,H61A    I46 @BASEBOARD_FAB2_LIB.BASEBOARD_FAB2(SCH_1):PAGE193
  J4B2  F12  IOF12 SCONN120_H61426002_SM-CONN,H61A    I46 @BASEBOARD_FAB2_LIB.BASEBOARD_FAB2(SCH_1):PAGE193
  J4B2  F13  IOF13 SCONN120_H61426002_SM-CONN,H61A    I46 @BASEBOARD_FAB2_LIB.BASEBOARD_FAB2(SCH_1):PAGE193
  J4B2  F14  IOF14 SCONN120_H61426002_SM-CONN,H61A    I46 @BASEBOARD_FAB2_LIB.BASEBOARD_FAB2(SCH_1):PAGE193
 C4E24    2      B CAPP_3018-470UF,2.5V,20%,ALUM,A    I61 @BASEBOARD_FAB2_LIB.BASEBOARD_FAB2(SCH_1):PAGE193
 C6R16    2      B CAPP_3018-470UF,2.5V,20%,ALUM,A    I62 @BASEBOARD_FAB2_LIB.BASEBOARD_FAB2(SCH_1):PAGE193
  C4F1    2      B CAP_A_0402V-1.0UF,6.3V,10%,X6SA    I68 @BASEBOARD_FAB2_LIB.BASEBOARD_FAB2(SCH_1):PAGE193
  C4F3    2      B CAP_A_0402V-1.0UF,6.3V,10%,X6SA    I70 @BASEBOARD_FAB2_LIB.BASEBOARD_FAB2(SCH_1):PAGE193
  C3F1    2      B CAP_A_0603V-47UF,4V,20%,X5R,60A   I140 @BASEBOARD_FAB2_LIB.BASEBOARD_FAB2(SCH_1):PAGE193
  C4F2    2      B CAP_A_0603V-47UF,4V,20%,X5R,60A   I141 @BASEBOARD_FAB2_LIB.BASEBOARD_FAB2(SCH_1):PAGE193
 R4C12    2      B RES_0402-8.06K,1%,1/16W,CHIP,GA   I169 @BASEBOARD_FAB2_LIB.BASEBOARD_FAB2(SCH_1):PAGE193
 R4C11    2      B RES_0402-3.16K,1%,1/16W,CHIP,GA   I170 @BASEBOARD_FAB2_LIB.BASEBOARD_FAB2(SCH_1):PAGE193
  C4T2    2      B CAP_A_0402V-1.0UF,6.3V,10%,X6SA     I9 @BASEBOARD_FAB2_LIB.BASEBOARD_FAB2(SCH_1):PAGE194
  C4T1    2      B CAP_A_0402V-1.0UF,6.3V,10%,X6SA    I16 @BASEBOARD_FAB2_LIB.BASEBOARD_FAB2(SCH_1):PAGE194
  C4R1    2      B CAPP_3018-470UF,2.5V,20%,ALUM,A    I29 @BASEBOARD_FAB2_LIB.BASEBOARD_FAB2(SCH_1):PAGE194
  C3R4    2      B CAPP_3018-470UF,2.5V,20%,ALUM,A    I31 @BASEBOARD_FAB2_LIB.BASEBOARD_FAB2(SCH_1):PAGE194
  J6E1  A19  IOA19 SCONN120_H61426002_SM-CONN,H61A    I55 @BASEBOARD_FAB2_LIB.BASEBOARD_FAB2(SCH_1):PAGE194
  J6E1  A20  IOA20 SCONN120_H61426002_SM-CONN,H61A    I55 @BASEBOARD_FAB2_LIB.BASEBOARD_FAB2(SCH_1):PAGE194
  J6E1  B19  IOB19 SCONN120_H61426002_SM-CONN,H61A    I55 @BASEBOARD_FAB2_LIB.BASEBOARD_FAB2(SCH_1):PAGE194
  J6E1  B20  IOB20 SCONN120_H61426002_SM-CONN,H61A    I55 @BASEBOARD_FAB2_LIB.BASEBOARD_FAB2(SCH_1):PAGE194
  J6E1  C19  IOC19 SCONN120_H61426002_SM-CONN,H61A    I55 @BASEBOARD_FAB2_LIB.BASEBOARD_FAB2(SCH_1):PAGE194
  J6E1  C20  IOC20 SCONN120_H61426002_SM-CONN,H61A    I55 @BASEBOARD_FAB2_LIB.BASEBOARD_FAB2(SCH_1):PAGE194
  J6E1   D4   IOD4 SCONN120_H61426002_SM-CONN,H61A    I55 @BASEBOARD_FAB2_LIB.BASEBOARD_FAB2(SCH_1):PAGE194
  J6E1   D5   IOD5 SCONN120_H61426002_SM-CONN,H61A    I55 @BASEBOARD_FAB2_LIB.BASEBOARD_FAB2(SCH_1):PAGE194
  J6E1   D6   IOD6 SCONN120_H61426002_SM-CONN,H61A    I55 @BASEBOARD_FAB2_LIB.BASEBOARD_FAB2(SCH_1):PAGE194
  J6E1   D7   IOD7 SCONN120_H61426002_SM-CONN,H61A    I55 @BASEBOARD_FAB2_LIB.BASEBOARD_FAB2(SCH_1):PAGE194
  J6E1   D8   IOD8 SCONN120_H61426002_SM-CONN,H61A    I55 @BASEBOARD_FAB2_LIB.BASEBOARD_FAB2(SCH_1):PAGE194
  J6E1   D9   IOD9 SCONN120_H61426002_SM-CONN,H61A    I55 @BASEBOARD_FAB2_LIB.BASEBOARD_FAB2(SCH_1):PAGE194
  J6E1  D10  IOD10 SCONN120_H61426002_SM-CONN,H61A    I55 @BASEBOARD_FAB2_LIB.BASEBOARD_FAB2(SCH_1):PAGE194
  J6E1  D11  IOD11 SCONN120_H61426002_SM-CONN,H61A    I55 @BASEBOARD_FAB2_LIB.BASEBOARD_FAB2(SCH_1):PAGE194
  J6E1  D12  IOD12 SCONN120_H61426002_SM-CONN,H61A    I55 @BASEBOARD_FAB2_LIB.BASEBOARD_FAB2(SCH_1):PAGE194
  J6E1  D13  IOD13 SCONN120_H61426002_SM-CONN,H61A    I55 @BASEBOARD_FAB2_LIB.BASEBOARD_FAB2(SCH_1):PAGE194
  J6E1  D14  IOD14 SCONN120_H61426002_SM-CONN,H61A    I55 @BASEBOARD_FAB2_LIB.BASEBOARD_FAB2(SCH_1):PAGE194
  J6E1  D15  IOD15 SCONN120_H61426002_SM-CONN,H61A    I55 @BASEBOARD_FAB2_LIB.BASEBOARD_FAB2(SCH_1):PAGE194
  J6E1  D16  IOD16 SCONN120_H61426002_SM-CONN,H61A    I55 @BASEBOARD_FAB2_LIB.BASEBOARD_FAB2(SCH_1):PAGE194
  J6E1  D17  IOD17 SCONN120_H61426002_SM-CONN,H61A    I55 @BASEBOARD_FAB2_LIB.BASEBOARD_FAB2(SCH_1):PAGE194
  J6E1  D18  IOD18 SCONN120_H61426002_SM-CONN,H61A    I55 @BASEBOARD_FAB2_LIB.BASEBOARD_FAB2(SCH_1):PAGE194
  J6E1  D19  IOD19 SCONN120_H61426002_SM-CONN,H61A    I55 @BASEBOARD_FAB2_LIB.BASEBOARD_FAB2(SCH_1):PAGE194
  J6E1  D20  IOD20 SCONN120_H61426002_SM-CONN,H61A    I55 @BASEBOARD_FAB2_LIB.BASEBOARD_FAB2(SCH_1):PAGE194
  J6E1   E4   IOE4 SCONN120_H61426002_SM-CONN,H61A    I55 @BASEBOARD_FAB2_LIB.BASEBOARD_FAB2(SCH_1):PAGE194
  J6E1   E6   IOE6 SCONN120_H61426002_SM-CONN,H61A    I55 @BASEBOARD_FAB2_LIB.BASEBOARD_FAB2(SCH_1):PAGE194
  J6E1   E7   IOE7 SCONN120_H61426002_SM-CONN,H61A    I55 @BASEBOARD_FAB2_LIB.BASEBOARD_FAB2(SCH_1):PAGE194
  J6E1   E8   IOE8 SCONN120_H61426002_SM-CONN,H61A    I55 @BASEBOARD_FAB2_LIB.BASEBOARD_FAB2(SCH_1):PAGE194
  J6E1   E9   IOE9 SCONN120_H61426002_SM-CONN,H61A    I55 @BASEBOARD_FAB2_LIB.BASEBOARD_FAB2(SCH_1):PAGE194
  J6E1  E10  IOE10 SCONN120_H61426002_SM-CONN,H61A    I55 @BASEBOARD_FAB2_LIB.BASEBOARD_FAB2(SCH_1):PAGE194
  J6E1  E11  IOE11 SCONN120_H61426002_SM-CONN,H61A    I55 @BASEBOARD_FAB2_LIB.BASEBOARD_FAB2(SCH_1):PAGE194
  J6E1  E12  IOE12 SCONN120_H61426002_SM-CONN,H61A    I55 @BASEBOARD_FAB2_LIB.BASEBOARD_FAB2(SCH_1):PAGE194
  J6E1  E13  IOE13 SCONN120_H61426002_SM-CONN,H61A    I55 @BASEBOARD_FAB2_LIB.BASEBOARD_FAB2(SCH_1):PAGE194
  J6E1  E14  IOE14 SCONN120_H61426002_SM-CONN,H61A    I55 @BASEBOARD_FAB2_LIB.BASEBOARD_FAB2(SCH_1):PAGE194
  J6E1  E15  IOE15 SCONN120_H61426002_SM-CONN,H61A    I55 @BASEBOARD_FAB2_LIB.BASEBOARD_FAB2(SCH_1):PAGE194
  J6E1  E16  IOE16 SCONN120_H61426002_SM-CONN,H61A    I55 @BASEBOARD_FAB2_LIB.BASEBOARD_FAB2(SCH_1):PAGE194
  J6E1  E17  IOE17 SCONN120_H61426002_SM-CONN,H61A    I55 @BASEBOARD_FAB2_LIB.BASEBOARD_FAB2(SCH_1):PAGE194
  J6E1  E18  IOE18 SCONN120_H61426002_SM-CONN,H61A    I55 @BASEBOARD_FAB2_LIB.BASEBOARD_FAB2(SCH_1):PAGE194
  J6E1  E19  IOE19 SCONN120_H61426002_SM-CONN,H61A    I55 @BASEBOARD_FAB2_LIB.BASEBOARD_FAB2(SCH_1):PAGE194
  J6E1  E20  IOE20 SCONN120_H61426002_SM-CONN,H61A    I55 @BASEBOARD_FAB2_LIB.BASEBOARD_FAB2(SCH_1):PAGE194
  J6E1   F4   IOF4 SCONN120_H61426002_SM-CONN,H61A    I55 @BASEBOARD_FAB2_LIB.BASEBOARD_FAB2(SCH_1):PAGE194
  J6E1   F6   IOF6 SCONN120_H61426002_SM-CONN,H61A    I55 @BASEBOARD_FAB2_LIB.BASEBOARD_FAB2(SCH_1):PAGE194
  J6E1   F7   IOF7 SCONN120_H61426002_SM-CONN,H61A    I55 @BASEBOARD_FAB2_LIB.BASEBOARD_FAB2(SCH_1):PAGE194
  J6E1   F8   IOF8 SCONN120_H61426002_SM-CONN,H61A    I55 @BASEBOARD_FAB2_LIB.BASEBOARD_FAB2(SCH_1):PAGE194
  J6E1   F9   IOF9 SCONN120_H61426002_SM-CONN,H61A    I55 @BASEBOARD_FAB2_LIB.BASEBOARD_FAB2(SCH_1):PAGE194
  J6E1  F10  IOF10 SCONN120_H61426002_SM-CONN,H61A    I55 @BASEBOARD_FAB2_LIB.BASEBOARD_FAB2(SCH_1):PAGE194
  J6E1  F11  IOF11 SCONN120_H61426002_SM-CONN,H61A    I55 @BASEBOARD_FAB2_LIB.BASEBOARD_FAB2(SCH_1):PAGE194
  J6E1  F12  IOF12 SCONN120_H61426002_SM-CONN,H61A    I55 @BASEBOARD_FAB2_LIB.BASEBOARD_FAB2(SCH_1):PAGE194
  J6E1  F13  IOF13 SCONN120_H61426002_SM-CONN,H61A    I55 @BASEBOARD_FAB2_LIB.BASEBOARD_FAB2(SCH_1):PAGE194
  J6E1  F14  IOF14 SCONN120_H61426002_SM-CONN,H61A    I55 @BASEBOARD_FAB2_LIB.BASEBOARD_FAB2(SCH_1):PAGE194
  J6E1  F15  IOF15 SCONN120_H61426002_SM-CONN,H61A    I55 @BASEBOARD_FAB2_LIB.BASEBOARD_FAB2(SCH_1):PAGE194
  J6E1  F16  IOF16 SCONN120_H61426002_SM-CONN,H61A    I55 @BASEBOARD_FAB2_LIB.BASEBOARD_FAB2(SCH_1):PAGE194
  J6E1  F17  IOF17 SCONN120_H61426002_SM-CONN,H61A    I55 @BASEBOARD_FAB2_LIB.BASEBOARD_FAB2(SCH_1):PAGE194
  J6E1  F18  IOF18 SCONN120_H61426002_SM-CONN,H61A    I55 @BASEBOARD_FAB2_LIB.BASEBOARD_FAB2(SCH_1):PAGE194
  J6E1  F19  IOF19 SCONN120_H61426002_SM-CONN,H61A    I55 @BASEBOARD_FAB2_LIB.BASEBOARD_FAB2(SCH_1):PAGE194
  J6E1  F20  IOF20 SCONN120_H61426002_SM-CONN,H61A    I55 @BASEBOARD_FAB2_LIB.BASEBOARD_FAB2(SCH_1):PAGE194
  J6B1   A9   IOA9 SCONN120_H61426002_SM-CONN,H61A    I56 @BASEBOARD_FAB2_LIB.BASEBOARD_FAB2(SCH_1):PAGE194
  J6B1  A10  IOA10 SCONN120_H61426002_SM-CONN,H61A    I56 @BASEBOARD_FAB2_LIB.BASEBOARD_FAB2(SCH_1):PAGE194
  J6B1  A12  IOA12 SCONN120_H61426002_SM-CONN,H61A    I56 @BASEBOARD_FAB2_LIB.BASEBOARD_FAB2(SCH_1):PAGE194
  J6B1  A14  IOA14 SCONN120_H61426002_SM-CONN,H61A    I56 @BASEBOARD_FAB2_LIB.BASEBOARD_FAB2(SCH_1):PAGE194
  J6B1  A17  IOA17 SCONN120_H61426002_SM-CONN,H61A    I56 @BASEBOARD_FAB2_LIB.BASEBOARD_FAB2(SCH_1):PAGE194
  J6B1   B9   IOB9 SCONN120_H61426002_SM-CONN,H61A    I56 @BASEBOARD_FAB2_LIB.BASEBOARD_FAB2(SCH_1):PAGE194
  J6B1  B10  IOB10 SCONN120_H61426002_SM-CONN,H61A    I56 @BASEBOARD_FAB2_LIB.BASEBOARD_FAB2(SCH_1):PAGE194
  J6B1  B12  IOB12 SCONN120_H61426002_SM-CONN,H61A    I56 @BASEBOARD_FAB2_LIB.BASEBOARD_FAB2(SCH_1):PAGE194
  J6B1  B14  IOB14 SCONN120_H61426002_SM-CONN,H61A    I56 @BASEBOARD_FAB2_LIB.BASEBOARD_FAB2(SCH_1):PAGE194
  J6B1  B17  IOB17 SCONN120_H61426002_SM-CONN,H61A    I56 @BASEBOARD_FAB2_LIB.BASEBOARD_FAB2(SCH_1):PAGE194
  J6B1   C1   IOC1 SCONN120_H61426002_SM-CONN,H61A    I56 @BASEBOARD_FAB2_LIB.BASEBOARD_FAB2(SCH_1):PAGE194
  J6B1   C2   IOC2 SCONN120_H61426002_SM-CONN,H61A    I56 @BASEBOARD_FAB2_LIB.BASEBOARD_FAB2(SCH_1):PAGE194
  J6B1   C3   IOC3 SCONN120_H61426002_SM-CONN,H61A    I56 @BASEBOARD_FAB2_LIB.BASEBOARD_FAB2(SCH_1):PAGE194
  J6B1   C4   IOC4 SCONN120_H61426002_SM-CONN,H61A    I56 @BASEBOARD_FAB2_LIB.BASEBOARD_FAB2(SCH_1):PAGE194
  J6B1   C5   IOC5 SCONN120_H61426002_SM-CONN,H61A    I56 @BASEBOARD_FAB2_LIB.BASEBOARD_FAB2(SCH_1):PAGE194
  J6B1   C6   IOC6 SCONN120_H61426002_SM-CONN,H61A    I56 @BASEBOARD_FAB2_LIB.BASEBOARD_FAB2(SCH_1):PAGE194
  J6B1   C7   IOC7 SCONN120_H61426002_SM-CONN,H61A    I56 @BASEBOARD_FAB2_LIB.BASEBOARD_FAB2(SCH_1):PAGE194
  J6B1   C8   IOC8 SCONN120_H61426002_SM-CONN,H61A    I56 @BASEBOARD_FAB2_LIB.BASEBOARD_FAB2(SCH_1):PAGE194
  J6B1   C9   IOC9 SCONN120_H61426002_SM-CONN,H61A    I56 @BASEBOARD_FAB2_LIB.BASEBOARD_FAB2(SCH_1):PAGE194
  J6B1  C10  IOC10 SCONN120_H61426002_SM-CONN,H61A    I56 @BASEBOARD_FAB2_LIB.BASEBOARD_FAB2(SCH_1):PAGE194
  J6B1  C12  IOC12 SCONN120_H61426002_SM-CONN,H61A    I56 @BASEBOARD_FAB2_LIB.BASEBOARD_FAB2(SCH_1):PAGE194
  J6B1  C14  IOC14 SCONN120_H61426002_SM-CONN,H61A    I56 @BASEBOARD_FAB2_LIB.BASEBOARD_FAB2(SCH_1):PAGE194
  J6B1  C15  IOC15 SCONN120_H61426002_SM-CONN,H61A    I56 @BASEBOARD_FAB2_LIB.BASEBOARD_FAB2(SCH_1):PAGE194
  J6B1  C16  IOC16 SCONN120_H61426002_SM-CONN,H61A    I56 @BASEBOARD_FAB2_LIB.BASEBOARD_FAB2(SCH_1):PAGE194
  J6B1   D2   IOD2 SCONN120_H61426002_SM-CONN,H61A    I56 @BASEBOARD_FAB2_LIB.BASEBOARD_FAB2(SCH_1):PAGE194
  J6B1   D3   IOD3 SCONN120_H61426002_SM-CONN,H61A    I56 @BASEBOARD_FAB2_LIB.BASEBOARD_FAB2(SCH_1):PAGE194
  J6B1   D4   IOD4 SCONN120_H61426002_SM-CONN,H61A    I56 @BASEBOARD_FAB2_LIB.BASEBOARD_FAB2(SCH_1):PAGE194
  J6B1   D5   IOD5 SCONN120_H61426002_SM-CONN,H61A    I56 @BASEBOARD_FAB2_LIB.BASEBOARD_FAB2(SCH_1):PAGE194
  J6B1   D6   IOD6 SCONN120_H61426002_SM-CONN,H61A    I56 @BASEBOARD_FAB2_LIB.BASEBOARD_FAB2(SCH_1):PAGE194
  J6B1   D7   IOD7 SCONN120_H61426002_SM-CONN,H61A    I56 @BASEBOARD_FAB2_LIB.BASEBOARD_FAB2(SCH_1):PAGE194
  J6B1   D8   IOD8 SCONN120_H61426002_SM-CONN,H61A    I56 @BASEBOARD_FAB2_LIB.BASEBOARD_FAB2(SCH_1):PAGE194
  J6B1   D9   IOD9 SCONN120_H61426002_SM-CONN,H61A    I56 @BASEBOARD_FAB2_LIB.BASEBOARD_FAB2(SCH_1):PAGE194
  J6B1  D10  IOD10 SCONN120_H61426002_SM-CONN,H61A    I56 @BASEBOARD_FAB2_LIB.BASEBOARD_FAB2(SCH_1):PAGE194
  J6B1  D11  IOD11 SCONN120_H61426002_SM-CONN,H61A    I56 @BASEBOARD_FAB2_LIB.BASEBOARD_FAB2(SCH_1):PAGE194
  J6B1  D12  IOD12 SCONN120_H61426002_SM-CONN,H61A    I56 @BASEBOARD_FAB2_LIB.BASEBOARD_FAB2(SCH_1):PAGE194
  J6B1  D13  IOD13 SCONN120_H61426002_SM-CONN,H61A    I56 @BASEBOARD_FAB2_LIB.BASEBOARD_FAB2(SCH_1):PAGE194
  J6B1  D14  IOD14 SCONN120_H61426002_SM-CONN,H61A    I56 @BASEBOARD_FAB2_LIB.BASEBOARD_FAB2(SCH_1):PAGE194
  J6B1  D15  IOD15 SCONN120_H61426002_SM-CONN,H61A    I56 @BASEBOARD_FAB2_LIB.BASEBOARD_FAB2(SCH_1):PAGE194
  J6B1  D16  IOD16 SCONN120_H61426002_SM-CONN,H61A    I56 @BASEBOARD_FAB2_LIB.BASEBOARD_FAB2(SCH_1):PAGE194
  J6B1   E2   IOE2 SCONN120_H61426002_SM-CONN,H61A    I56 @BASEBOARD_FAB2_LIB.BASEBOARD_FAB2(SCH_1):PAGE194
  J6B1   E3   IOE3 SCONN120_H61426002_SM-CONN,H61A    I56 @BASEBOARD_FAB2_LIB.BASEBOARD_FAB2(SCH_1):PAGE194
  J6B1   E4   IOE4 SCONN120_H61426002_SM-CONN,H61A    I56 @BASEBOARD_FAB2_LIB.BASEBOARD_FAB2(SCH_1):PAGE194
  J6B1   E5   IOE5 SCONN120_H61426002_SM-CONN,H61A    I56 @BASEBOARD_FAB2_LIB.BASEBOARD_FAB2(SCH_1):PAGE194
  J6B1   E6   IOE6 SCONN120_H61426002_SM-CONN,H61A    I56 @BASEBOARD_FAB2_LIB.BASEBOARD_FAB2(SCH_1):PAGE194
  J6B1   E7   IOE7 SCONN120_H61426002_SM-CONN,H61A    I56 @BASEBOARD_FAB2_LIB.BASEBOARD_FAB2(SCH_1):PAGE194
  J6B1   E9   IOE9 SCONN120_H61426002_SM-CONN,H61A    I56 @BASEBOARD_FAB2_LIB.BASEBOARD_FAB2(SCH_1):PAGE194
  J6B1  E11  IOE11 SCONN120_H61426002_SM-CONN,H61A    I56 @BASEBOARD_FAB2_LIB.BASEBOARD_FAB2(SCH_1):PAGE194
  J6B1  E12  IOE12 SCONN120_H61426002_SM-CONN,H61A    I56 @BASEBOARD_FAB2_LIB.BASEBOARD_FAB2(SCH_1):PAGE194
  J6B1  E13  IOE13 SCONN120_H61426002_SM-CONN,H61A    I56 @BASEBOARD_FAB2_LIB.BASEBOARD_FAB2(SCH_1):PAGE194
  J6B1  E14  IOE14 SCONN120_H61426002_SM-CONN,H61A    I56 @BASEBOARD_FAB2_LIB.BASEBOARD_FAB2(SCH_1):PAGE194
  J6B1   F2   IOF2 SCONN120_H61426002_SM-CONN,H61A    I56 @BASEBOARD_FAB2_LIB.BASEBOARD_FAB2(SCH_1):PAGE194
  J6B1   F3   IOF3 SCONN120_H61426002_SM-CONN,H61A    I56 @BASEBOARD_FAB2_LIB.BASEBOARD_FAB2(SCH_1):PAGE194
  J6B1   F4   IOF4 SCONN120_H61426002_SM-CONN,H61A    I56 @BASEBOARD_FAB2_LIB.BASEBOARD_FAB2(SCH_1):PAGE194
  J6B1   F5   IOF5 SCONN120_H61426002_SM-CONN,H61A    I56 @BASEBOARD_FAB2_LIB.BASEBOARD_FAB2(SCH_1):PAGE194
  J6B1   F6   IOF6 SCONN120_H61426002_SM-CONN,H61A    I56 @BASEBOARD_FAB2_LIB.BASEBOARD_FAB2(SCH_1):PAGE194
  J6B1   F7   IOF7 SCONN120_H61426002_SM-CONN,H61A    I56 @BASEBOARD_FAB2_LIB.BASEBOARD_FAB2(SCH_1):PAGE194
  J6B1   F9   IOF9 SCONN120_H61426002_SM-CONN,H61A    I56 @BASEBOARD_FAB2_LIB.BASEBOARD_FAB2(SCH_1):PAGE194
  J6B1  F11  IOF11 SCONN120_H61426002_SM-CONN,H61A    I56 @BASEBOARD_FAB2_LIB.BASEBOARD_FAB2(SCH_1):PAGE194
  J6B1  F12  IOF12 SCONN120_H61426002_SM-CONN,H61A    I56 @BASEBOARD_FAB2_LIB.BASEBOARD_FAB2(SCH_1):PAGE194
  J6B1  F13  IOF13 SCONN120_H61426002_SM-CONN,H61A    I56 @BASEBOARD_FAB2_LIB.BASEBOARD_FAB2(SCH_1):PAGE194
  J6B1  F14  IOF14 SCONN120_H61426002_SM-CONN,H61A    I56 @BASEBOARD_FAB2_LIB.BASEBOARD_FAB2(SCH_1):PAGE194
 C3N40    2      B CAP_A_0402V-1.0UF,6.3V,10%,X6SA    I86 @BASEBOARD_FAB2_LIB.BASEBOARD_FAB2(SCH_1):PAGE194
 C3M46    2      B CAP_A_0402V-1.0UF,6.3V,10%,X6SA    I99 @BASEBOARD_FAB2_LIB.BASEBOARD_FAB2(SCH_1):PAGE194
 C3N14    2      B CAPP_3018-470UF,2.5V,20%,ALUM,A   I101 @BASEBOARD_FAB2_LIB.BASEBOARD_FAB2(SCH_1):PAGE194
  C3T1    2      B CAP_A_0603V-47UF,4V,20%,X5R,60A   I149 @BASEBOARD_FAB2_LIB.BASEBOARD_FAB2(SCH_1):PAGE194
  C3T2    2      B CAP_A_0603V-47UF,4V,20%,X5R,60A   I150 @BASEBOARD_FAB2_LIB.BASEBOARD_FAB2(SCH_1):PAGE194
 R7C24    2      B RES_0402-4.02K,1%,1/16W,CHIP,GA   I155 @BASEBOARD_FAB2_LIB.BASEBOARD_FAB2(SCH_1):PAGE194
 R3N29    2      B RES_0402-16K,1.0%,1/16W,CHIP,GA   I156 @BASEBOARD_FAB2_LIB.BASEBOARD_FAB2(SCH_1):PAGE194
 RM1E1    1    IO1 CONN3_G98259001_PIP-CONN,G9825A    I26 @BASEBOARD_FAB2_LIB.BASEBOARD_FAB2(SCH_1):PAGE195
 RM1E1    2    IO2 CONN3_G98259001_PIP-CONN,G9825A    I26 @BASEBOARD_FAB2_LIB.BASEBOARD_FAB2(SCH_1):PAGE195
 RM1E1    3    IO3 CONN3_G98259001_PIP-CONN,G9825A    I26 @BASEBOARD_FAB2_LIB.BASEBOARD_FAB2(SCH_1):PAGE195
  C9R5    2      B CAP_0805-10UF,16V,10%,X6S,C953A    I31 @BASEBOARD_FAB2_LIB.BASEBOARD_FAB2(SCH_1):PAGE195
 C1E12    2      B CAP_0805-10UF,16V,10%,X6S,C953A    I32 @BASEBOARD_FAB2_LIB.BASEBOARD_FAB2(SCH_1):PAGE195
 C1E15    2      B CAP_0805-10UF,16V,10%,X6S,C953A    I35 @BASEBOARD_FAB2_LIB.BASEBOARD_FAB2(SCH_1):PAGE195
 C9R12    2      B CAP_A_0402V-0.1UF,16V,10%,X7R,A    I36 @BASEBOARD_FAB2_LIB.BASEBOARD_FAB2(SCH_1):PAGE195
  C9R6    2      B CAP_A_0402V-0.1UF,16V,10%,X7R,A    I37 @BASEBOARD_FAB2_LIB.BASEBOARD_FAB2(SCH_1):PAGE195
 C1E17    2      B CAP_A_0402V-0.1UF,16V,10%,X7R,A    I38 @BASEBOARD_FAB2_LIB.BASEBOARD_FAB2(SCH_1):PAGE195
 C1E16    2      B CAP_A_0402V-0.1UF,16V,10%,X7R,A    I39 @BASEBOARD_FAB2_LIB.BASEBOARD_FAB2(SCH_1):PAGE195
 TH4G1    1      1 MTG_KEYHOLE_TH-EMPTY,NA    I49 @BASEBOARD_FAB2_LIB.BASEBOARD_FAB2(SCH_1):PAGE195
 TH9G1    1      1 MTG_KEYHOLE_TH-EMPTY,NA    I52 @BASEBOARD_FAB2_LIB.BASEBOARD_FAB2(SCH_1):PAGE195
 TH9A1    1      1 MTG_KEYHOLE_TH-EMPTY,NA    I54 @BASEBOARD_FAB2_LIB.BASEBOARD_FAB2(SCH_1):PAGE195
 TH1A1    1      1 MTG_KEYHOLE_TH-EMPTY,NA    I56 @BASEBOARD_FAB2_LIB.BASEBOARD_FAB2(SCH_1):PAGE195
 TH4A1    1      1 MTG_KEYHOLE_TH-EMPTY,NA    I62 @BASEBOARD_FAB2_LIB.BASEBOARD_FAB2(SCH_1):PAGE195
 TH7A1    1      1 MTG_KEYHOLE_TH-EMPTY,NA    I65 @BASEBOARD_FAB2_LIB.BASEBOARD_FAB2(SCH_1):PAGE195
 TH7G1    1      1 MTG_KEYHOLE_TH-EMPTY,NA    I67 @BASEBOARD_FAB2_LIB.BASEBOARD_FAB2(SCH_1):PAGE195
  C4F6    2      B CAPP_4040LF-470UF,16V,20%,ALUMA    I82 @BASEBOARD_FAB2_LIB.BASEBOARD_FAB2(SCH_1):PAGE195
 C4B13    2      B CAPP_4040LF-470UF,16V,20%,ALUMA    I83 @BASEBOARD_FAB2_LIB.BASEBOARD_FAB2(SCH_1):PAGE195
 C1B14    2      B CAPP_4040LF-470UF,16V,20%,ALUMA    I84 @BASEBOARD_FAB2_LIB.BASEBOARD_FAB2(SCH_1):PAGE195
  C1F7    2      B CAPP_4040LF-470UF,16V,20%,ALUMA    I85 @BASEBOARD_FAB2_LIB.BASEBOARD_FAB2(SCH_1):PAGE195
  C4F5    2      B CAPP_3018-68UF,16V,20%,TANT,72A    I96 @BASEBOARD_FAB2_LIB.BASEBOARD_FAB2(SCH_1):PAGE195
 C4B14    2      B CAPP_3018-68UF,16V,20%,TANT,72A    I97 @BASEBOARD_FAB2_LIB.BASEBOARD_FAB2(SCH_1):PAGE195
  C3T6    2      B CAPP_3018-68UF,16V,20%,TANT,72A    I98 @BASEBOARD_FAB2_LIB.BASEBOARD_FAB2(SCH_1):PAGE195
  C9M3    2      B CAPP_3018-68UF,16V,20%,TANT,72A    I99 @BASEBOARD_FAB2_LIB.BASEBOARD_FAB2(SCH_1):PAGE195
  C3B6    2      B CAPP_3018-68UF,16V,20%,TANT,72A   I100 @BASEBOARD_FAB2_LIB.BASEBOARD_FAB2(SCH_1):PAGE195
 C1R23    2      B CAPP_3018-68UF,16V,20%,TANT,72A   I101 @BASEBOARD_FAB2_LIB.BASEBOARD_FAB2(SCH_1):PAGE195
  C4M6    2      B CAPP_3018-68UF,16V,20%,TANT,72A   I102 @BASEBOARD_FAB2_LIB.BASEBOARD_FAB2(SCH_1):PAGE195
  C1M5    2      B CAPP_3018-68UF,16V,20%,TANT,72A   I103 @BASEBOARD_FAB2_LIB.BASEBOARD_FAB2(SCH_1):PAGE195
 C3T13    2      B CAPP_3018-68UF,16V,20%,TANT,72A   I104 @BASEBOARD_FAB2_LIB.BASEBOARD_FAB2(SCH_1):PAGE195
  C4M7    2      B CAPP_3018-68UF,16V,20%,TANT,72A   I105 @BASEBOARD_FAB2_LIB.BASEBOARD_FAB2(SCH_1):PAGE195
 C3T15    2      B CAPP_3018-68UF,16V,20%,TANT,72A   I106 @BASEBOARD_FAB2_LIB.BASEBOARD_FAB2(SCH_1):PAGE195
  C7M6    2      B CAPP_3018-68UF,16V,20%,TANT,72A   I108 @BASEBOARD_FAB2_LIB.BASEBOARD_FAB2(SCH_1):PAGE195
  C6N5    2      B CAPP_3018-68UF,16V,20%,TANT,72A   I109 @BASEBOARD_FAB2_LIB.BASEBOARD_FAB2(SCH_1):PAGE195
  C9T3    2      B CAPP_3018-68UF,16V,20%,TANT,72A   I111 @BASEBOARD_FAB2_LIB.BASEBOARD_FAB2(SCH_1):PAGE195
  C4F4    2      B CAPP_3018-68UF,16V,20%,TANT,72A   I112 @BASEBOARD_FAB2_LIB.BASEBOARD_FAB2(SCH_1):PAGE195
  C3T3    2      B CAPP_3018-68UF,16V,20%,TANT,72A   I113 @BASEBOARD_FAB2_LIB.BASEBOARD_FAB2(SCH_1):PAGE195
XBT8G1    3      N VERT_BATT_3PIN_PIP-3PVERT,C686A    I51 @BASEBOARD_FAB2_LIB.BASEBOARD_FAB2(SCH_1):PAGE196
 C3P45    2      B CAP_0402-0.047UF,25V,10%,X7R,AA    I60 @BASEBOARD_FAB2_LIB.BASEBOARD_FAB2(SCH_1):PAGE196
  U7D3    2    GND ADM1085_SMT-IC,H46130-001    I70 @BASEBOARD_FAB2_LIB.BASEBOARD_FAB2(SCH_1):PAGE196
 C3P46    2      B CAP_A_0402V-0.1UF,16V,10%,X7R,A    I72 @BASEBOARD_FAB2_LIB.BASEBOARD_FAB2(SCH_1):PAGE196
 R3P51    2      B RES_0402-6.34K,1%,1/16W,CHIP,GA    I75 @BASEBOARD_FAB2_LIB.BASEBOARD_FAB2(SCH_1):PAGE196
 C1L16    2      B CAP_A_0402V-0.1UF,16V,10%,X7R,A    I81 @BASEBOARD_FAB2_LIB.BASEBOARD_FAB2(SCH_1):PAGE196
  C8E3    2      B CAP_A_0402V-0.1UF,16V,10%,X7R,A    I94 @BASEBOARD_FAB2_LIB.BASEBOARD_FAB2(SCH_1):PAGE196
 C2U26    2      B CAP_A_0402V-1.0UF,6.3V,10%,X6SA   I102 @BASEBOARD_FAB2_LIB.BASEBOARD_FAB2(SCH_1):PAGE196
  U8D8    5    GND TPS3700_SM-IC,H69492-001   I104 @BASEBOARD_FAB2_LIB.BASEBOARD_FAB2(SCH_1):PAGE196
  C8D4    2      B CAP_A_0402V-0.1UF,16V,10%,X7R,A   I105 @BASEBOARD_FAB2_LIB.BASEBOARD_FAB2(SCH_1):PAGE196
 R8D37    2      B RES_0402-4.75K,1%,1/16W,CHIP,GA   I115 @BASEBOARD_FAB2_LIB.BASEBOARD_FAB2(SCH_1):PAGE196
 EU2T1    4    GND SLG55021_SM-IC,G56246-001     I1 @BASEBOARD_FAB2_LIB.BASEBOARD_FAB2(SCH_1):PAGE198
 EU2T1    9  THPAD SLG55021_SM-IC,G56246-001     I1 @BASEBOARD_FAB2_LIB.BASEBOARD_FAB2(SCH_1):PAGE198
 EU8B1    4    GND SLG55021_SM-IC,G56246-001    I13 @BASEBOARD_FAB2_LIB.BASEBOARD_FAB2(SCH_1):PAGE198
 EU8B1    9  THPAD SLG55021_SM-IC,G56246-001    I13 @BASEBOARD_FAB2_LIB.BASEBOARD_FAB2(SCH_1):PAGE198
 EU7E1    4    GND SLG55021_SM-IC,G56246-001    I19 @BASEBOARD_FAB2_LIB.BASEBOARD_FAB2(SCH_1):PAGE198
 EU7E1    9  THPAD SLG55021_SM-IC,G56246-001    I19 @BASEBOARD_FAB2_LIB.BASEBOARD_FAB2(SCH_1):PAGE198
 C8F17    2      B CAP_A_0402V-0.1UF,16V,10%,X7R,A    I24 @BASEBOARD_FAB2_LIB.BASEBOARD_FAB2(SCH_1):PAGE198
  C8B8    2      B CAP_A_0402V-0.1UF,16V,10%,X7R,A    I26 @BASEBOARD_FAB2_LIB.BASEBOARD_FAB2(SCH_1):PAGE198
 C8E19    2      B CAP_A_0402V-0.1UF,16V,10%,X7R,A    I28 @BASEBOARD_FAB2_LIB.BASEBOARD_FAB2(SCH_1):PAGE198
  C8B5    2      B CAP_A_0402V-0.1UF,16V,10%,X7R,A    I37 @BASEBOARD_FAB2_LIB.BASEBOARD_FAB2(SCH_1):PAGE198
 C8B12    2      B CAP_0805-10UF,16V,10%,X6S,C953A    I38 @BASEBOARD_FAB2_LIB.BASEBOARD_FAB2(SCH_1):PAGE198
  C8B6    2      B CAP_0805-10UF,16V,10%,X6S,C953A    I40 @BASEBOARD_FAB2_LIB.BASEBOARD_FAB2(SCH_1):PAGE198
  C8B7    2      B CAP_A_0402V-0.1UF,16V,10%,X7R,A    I41 @BASEBOARD_FAB2_LIB.BASEBOARD_FAB2(SCH_1):PAGE198
 C2T36    2      B CAP_A_0402V-0.1UF,16V,10%,X7R,A    I43 @BASEBOARD_FAB2_LIB.BASEBOARD_FAB2(SCH_1):PAGE198
  C2U1    2      B CAP_0805-10UF,16V,10%,X6S,C953A    I44 @BASEBOARD_FAB2_LIB.BASEBOARD_FAB2(SCH_1):PAGE198
 C2U19    2      B CAP_A_0402V-0.1UF,16V,10%,X7R,A    I46 @BASEBOARD_FAB2_LIB.BASEBOARD_FAB2(SCH_1):PAGE198
  C2U2    2      B CAP_0805-10UF,16V,10%,X6S,C953A    I47 @BASEBOARD_FAB2_LIB.BASEBOARD_FAB2(SCH_1):PAGE198
  C7E9    2      B CAP_A_0402V-0.1UF,16V,10%,X7R,A    I49 @BASEBOARD_FAB2_LIB.BASEBOARD_FAB2(SCH_1):PAGE198
  C7E8    2      B CAP_0805-10UF,16V,10%,X6S,C953A    I50 @BASEBOARD_FAB2_LIB.BASEBOARD_FAB2(SCH_1):PAGE198
  C7E5    2      B CAP_A_0402V-0.1UF,16V,10%,X7R,A    I52 @BASEBOARD_FAB2_LIB.BASEBOARD_FAB2(SCH_1):PAGE198
  C7E6    2      B CAP_0805-10UF,16V,10%,X6S,C953A    I53 @BASEBOARD_FAB2_LIB.BASEBOARD_FAB2(SCH_1):PAGE198
 C1B18    2      B CAP_0805-10UF,16V,10%,X6S,C953A    I61 @BASEBOARD_FAB2_LIB.BASEBOARD_FAB2(SCH_1):PAGE198
 C1B19    2      B CAP_A_0402V-0.1UF,16V,10%,X7R,A    I64 @BASEBOARD_FAB2_LIB.BASEBOARD_FAB2(SCH_1):PAGE198
  C9M6    2      B CAP_A_0402V-0.1UF,16V,10%,X7R,A    I67 @BASEBOARD_FAB2_LIB.BASEBOARD_FAB2(SCH_1):PAGE198
 EU9M1    4    GND SLG55021_SM-IC,G56246-001    I69 @BASEBOARD_FAB2_LIB.BASEBOARD_FAB2(SCH_1):PAGE198
 EU9M1    9  THPAD SLG55021_SM-IC,G56246-001    I69 @BASEBOARD_FAB2_LIB.BASEBOARD_FAB2(SCH_1):PAGE198
 C9M10    2      B CAP_0805-10UF,16V,10%,X6S,C953A    I74 @BASEBOARD_FAB2_LIB.BASEBOARD_FAB2(SCH_1):PAGE198
  C9M9    2      B CAP_A_0402V-0.1UF,16V,10%,X7R,A    I76 @BASEBOARD_FAB2_LIB.BASEBOARD_FAB2(SCH_1):PAGE198
  R8B4    2      B RES_0402-100.0K,1%,1/16W,CHIP,A    I83 @BASEBOARD_FAB2_LIB.BASEBOARD_FAB2(SCH_1):PAGE198
 EU1D2   23   PGND ADM1278_SM-IC,G99251-001    I10 @BASEBOARD_FAB2_LIB.BASEBOARD_FAB2(SCH_1):PAGE199
 R1D41    1      A RES_0805-0.0,5%,1/8W,CHIP,G221A    I19 @BASEBOARD_FAB2_LIB.BASEBOARD_FAB2(SCH_1):PAGE199
 R1D31    2      B RES_0402-6.19K,1%,1/16W,CHIP,GA    I43 @BASEBOARD_FAB2_LIB.BASEBOARD_FAB2(SCH_1):PAGE199
 VR1D1    2      A ZENER_SM-13V,IC,H69095-001    I99 @BASEBOARD_FAB2_LIB.BASEBOARD_FAB2(SCH_1):PAGE199
  C1E2    2      B CAP_1206-0.068UF,50V,20%,X7R,1A   I155 @BASEBOARD_FAB2_LIB.BASEBOARD_FAB2(SCH_1):PAGE200
  U9P1    5    GND TPS3700_SM-IC,H69492-001   I163 @BASEBOARD_FAB2_LIB.BASEBOARD_FAB2(SCH_1):PAGE200
  U1D2    5    GND TPS3700_SM-IC,H69492-001   I170 @BASEBOARD_FAB2_LIB.BASEBOARD_FAB2(SCH_1):PAGE200
  Q9P1    1 SOURCE<0> FET_N_DUAL_SMLF-2N7002DW,FET,DA   I196 @BASEBOARD_FAB2_LIB.BASEBOARD_FAB2(SCH_1):PAGE200
  Q9P1    4 SOURCE<0> FET_N_DUAL_SMLF-2N7002DW,FET,DA   I199 @BASEBOARD_FAB2_LIB.BASEBOARD_FAB2(SCH_1):PAGE200
  U9P2    5    GND TPS3700_SM-IC,H69492-001   I200 @BASEBOARD_FAB2_LIB.BASEBOARD_FAB2(SCH_1):PAGE200
 C9P11    2      B CAP_A_0402V-0.1UF,16V,10%,X7R,A   I201 @BASEBOARD_FAB2_LIB.BASEBOARD_FAB2(SCH_1):PAGE200
  Q1D2    2    SRC FET_N_SOT23LF-2N7002,FET,C7925A   I203 @BASEBOARD_FAB2_LIB.BASEBOARD_FAB2(SCH_1):PAGE200
 CR1F5    2      A DIODE_SM-MBRS340T3G,EMPTY,C819A   I220 @BASEBOARD_FAB2_LIB.BASEBOARD_FAB2(SCH_1):PAGE200
 C4D25    2      B CAP_A_0402V-1.0UF,6.3V,10%,X6SA    I30 @BASEBOARD_FAB2_LIB.BASEBOARD_FAB2(SCH_1):PAGE201
 C4D26    2      B CAP_A_0402V-0.1UF,16V,10%,X7R,A    I32 @BASEBOARD_FAB2_LIB.BASEBOARD_FAB2(SCH_1):PAGE201
 C4D15    2      B CAP_A_0402V-1.0UF,6.3V,10%,X6SA    I37 @BASEBOARD_FAB2_LIB.BASEBOARD_FAB2(SCH_1):PAGE201
 C4D19    2      B CAP_A_0402V-0.1UF,16V,10%,X7R,A    I39 @BASEBOARD_FAB2_LIB.BASEBOARD_FAB2(SCH_1):PAGE201
 R4D32    2      B RES_0402-1.5K,1%,1/16W,CHIP,G2A    I55 @BASEBOARD_FAB2_LIB.BASEBOARD_FAB2(SCH_1):PAGE201
 C4D17    2      B CAP_0402LF-220PF,50V,10%,X7R,AA    I66 @BASEBOARD_FAB2_LIB.BASEBOARD_FAB2(SCH_1):PAGE201
 C4D18    2      B CAP_0402LF-220PF,50V,10%,X7R,AA    I68 @BASEBOARD_FAB2_LIB.BASEBOARD_FAB2(SCH_1):PAGE201
 R6P27    2      B RES_0402-4.02K,1%,1/16W,CHIP,GA   I120 @BASEBOARD_FAB2_LIB.BASEBOARD_FAB2(SCH_1):PAGE201
 R6P28    2      B RES_0402-4.02K,1%,1/16W,CHIP,GA   I121 @BASEBOARD_FAB2_LIB.BASEBOARD_FAB2(SCH_1):PAGE201
 C4D42    2      B CAP_0402LF-1000PF,50V,10%,X7R,A   I125 @BASEBOARD_FAB2_LIB.BASEBOARD_FAB2(SCH_1):PAGE201
 EU4D4   49  THPAD PXE1610B_QFN-IC,H79206-001   I155 @BASEBOARD_FAB2_LIB.BASEBOARD_FAB2(SCH_1):PAGE201
  C6R7    2      B CAP_A_0603V-22.0UF,4V,20%,X6S,A     I9 @BASEBOARD_FAB2_LIB.BASEBOARD_FAB2(SCH_1):PAGE202
  C4E5    2      B CAP_0402-0.22UF,16V,10%,X7R,A3A    I18 @BASEBOARD_FAB2_LIB.BASEBOARD_FAB2(SCH_1):PAGE202
 C4E27    2      B CAP_0402-0.22UF,16V,10%,X7R,A3A    I24 @BASEBOARD_FAB2_LIB.BASEBOARD_FAB2(SCH_1):PAGE202
 C4E11    2      B CAP_A_0603V-22.0UF,4V,20%,X6S,A    I27 @BASEBOARD_FAB2_LIB.BASEBOARD_FAB2(SCH_1):PAGE202
 C4E10    2      B CAP_0402-1.0UF,16V,10%,X6S,D97A    I34 @BASEBOARD_FAB2_LIB.BASEBOARD_FAB2(SCH_1):PAGE202
 C4E20    2      B CAP_A_0402V-0.1UF,16V,10%,X7R,A    I35 @BASEBOARD_FAB2_LIB.BASEBOARD_FAB2(SCH_1):PAGE202
 C4E19    2      B CAP_0402-1.0UF,16V,10%,X6S,D97A    I36 @BASEBOARD_FAB2_LIB.BASEBOARD_FAB2(SCH_1):PAGE202
 C6R11    2      B CAP_0805-10UF,16V,10%,X6S,C953A    I37 @BASEBOARD_FAB2_LIB.BASEBOARD_FAB2(SCH_1):PAGE202
 C6P13    2      B CAP_0805-10UF,16V,10%,X6S,C953A    I38 @BASEBOARD_FAB2_LIB.BASEBOARD_FAB2(SCH_1):PAGE202
 C6R13    2      B CAP_0805-10UF,16V,10%,X6S,C953A    I42 @BASEBOARD_FAB2_LIB.BASEBOARD_FAB2(SCH_1):PAGE202
 C4E26    2      B CAP_0402-1.0UF,16V,10%,X6S,D97A    I45 @BASEBOARD_FAB2_LIB.BASEBOARD_FAB2(SCH_1):PAGE202
 C4D49    2      B CAP_A_0402V-0.1UF,16V,10%,X7R,A    I46 @BASEBOARD_FAB2_LIB.BASEBOARD_FAB2(SCH_1):PAGE202
 C4D48    2      B CAP_0402-1.0UF,16V,10%,X6S,D97A    I47 @BASEBOARD_FAB2_LIB.BASEBOARD_FAB2(SCH_1):PAGE202
  C6R4    2      B CAP_0805-10UF,16V,10%,X6S,C953A    I48 @BASEBOARD_FAB2_LIB.BASEBOARD_FAB2(SCH_1):PAGE202
 C6P22    2      B CAP_0805-10UF,16V,10%,X6S,C953A    I49 @BASEBOARD_FAB2_LIB.BASEBOARD_FAB2(SCH_1):PAGE202
  C6N8    2      B CAP_0805-10UF,16V,10%,X6S,C953A    I51 @BASEBOARD_FAB2_LIB.BASEBOARD_FAB2(SCH_1):PAGE202
  C4E3    2      B CAP_A_0603V-22.0UF,4V,20%,X6S,A    I61 @BASEBOARD_FAB2_LIB.BASEBOARD_FAB2(SCH_1):PAGE202
 C6P16    2      B CAP_A_0603V-22.0UF,4V,20%,X6S,A    I62 @BASEBOARD_FAB2_LIB.BASEBOARD_FAB2(SCH_1):PAGE202
 EU4E1    2   LGND IR354XX_SM-IR35411,IC,H73688-0A    I63 @BASEBOARD_FAB2_LIB.BASEBOARD_FAB2(SCH_1):PAGE202
 EU4E1    5 PGND<0> IR354XX_SM-IR35411,IC,H73688-0A    I63 @BASEBOARD_FAB2_LIB.BASEBOARD_FAB2(SCH_1):PAGE202
 EU4E1    7 PGND<1> IR354XX_SM-IR35411,IC,H73688-0A    I63 @BASEBOARD_FAB2_LIB.BASEBOARD_FAB2(SCH_1):PAGE202
 EU4E1   40 PGND<2> IR354XX_SM-IR35411,IC,H73688-0A    I63 @BASEBOARD_FAB2_LIB.BASEBOARD_FAB2(SCH_1):PAGE202
 EU4D6    2   LGND IR354XX_SM-IR35411,IC,H73688-0A    I64 @BASEBOARD_FAB2_LIB.BASEBOARD_FAB2(SCH_1):PAGE202
 EU4D6    5 PGND<0> IR354XX_SM-IR35411,IC,H73688-0A    I64 @BASEBOARD_FAB2_LIB.BASEBOARD_FAB2(SCH_1):PAGE202
 EU4D6    7 PGND<1> IR354XX_SM-IR35411,IC,H73688-0A    I64 @BASEBOARD_FAB2_LIB.BASEBOARD_FAB2(SCH_1):PAGE202
 EU4D6   40 PGND<2> IR354XX_SM-IR35411,IC,H73688-0A    I64 @BASEBOARD_FAB2_LIB.BASEBOARD_FAB2(SCH_1):PAGE202
 R4E22    2      B RES_0402-68.1K,1%,1/16W,EMPTY,A    I65 @BASEBOARD_FAB2_LIB.BASEBOARD_FAB2(SCH_1):PAGE202
 R4E19    2      B RES_0402-68.1K,1%,1/16W,EMPTY,A    I67 @BASEBOARD_FAB2_LIB.BASEBOARD_FAB2(SCH_1):PAGE202
 C6P24    2      B CAP_0805-10UF,16V,10%,X6S,C953A     I1 @BASEBOARD_FAB2_LIB.BASEBOARD_FAB2(SCH_1):PAGE203
  C6R6    2      B CAP_0805-10UF,16V,10%,X6S,C953A     I2 @BASEBOARD_FAB2_LIB.BASEBOARD_FAB2(SCH_1):PAGE203
  C6R3    2      B CAPP_3018-470UF,2.5V,20%,ALUM,A    I16 @BASEBOARD_FAB2_LIB.BASEBOARD_FAB2(SCH_1):PAGE203
  C6R9    2      B CAPP_3018-470UF,2.5V,20%,ALUM,A    I18 @BASEBOARD_FAB2_LIB.BASEBOARD_FAB2(SCH_1):PAGE203
  C6P3    2      B CAP_A_0603V-22.0UF,4V,20%,X6S,A    I25 @BASEBOARD_FAB2_LIB.BASEBOARD_FAB2(SCH_1):PAGE203
 C6P23    2      B CAPP_3018-470UF,2.5V,20%,ALUM,A    I28 @BASEBOARD_FAB2_LIB.BASEBOARD_FAB2(SCH_1):PAGE203
 C6P14    2      B CAPP_3018-470UF,2.5V,20%,ALUM,A    I29 @BASEBOARD_FAB2_LIB.BASEBOARD_FAB2(SCH_1):PAGE203
 C6P18    2      B CAPP_3018-470UF,2.5V,20%,ALUM,A    I30 @BASEBOARD_FAB2_LIB.BASEBOARD_FAB2(SCH_1):PAGE203
  C6P8    2      B CAPP_3018-470UF,2.5V,20%,ALUM,A    I32 @BASEBOARD_FAB2_LIB.BASEBOARD_FAB2(SCH_1):PAGE203
  C6N9    2      B CAPP_3018-470UF,2.5V,20%,ALUM,A    I34 @BASEBOARD_FAB2_LIB.BASEBOARD_FAB2(SCH_1):PAGE203
 C4D13    2      B CAP_0402-0.22UF,16V,10%,X7R,A3A    I40 @BASEBOARD_FAB2_LIB.BASEBOARD_FAB2(SCH_1):PAGE203
 C4D16    2      B CAP_0402-1.0UF,16V,10%,X6S,D97A    I45 @BASEBOARD_FAB2_LIB.BASEBOARD_FAB2(SCH_1):PAGE203
 C4D35    2      B CAP_A_0402V-0.1UF,16V,10%,X7R,A    I46 @BASEBOARD_FAB2_LIB.BASEBOARD_FAB2(SCH_1):PAGE203
 C4D30    2      B CAP_0402-1.0UF,16V,10%,X6S,D97A    I47 @BASEBOARD_FAB2_LIB.BASEBOARD_FAB2(SCH_1):PAGE203
  C4D5    2      B CAP_0402-0.22UF,16V,10%,X7R,A3A    I48 @BASEBOARD_FAB2_LIB.BASEBOARD_FAB2(SCH_1):PAGE203
  C4D7    2      B CAP_0402-1.0UF,16V,10%,X6S,D97A    I51 @BASEBOARD_FAB2_LIB.BASEBOARD_FAB2(SCH_1):PAGE203
 C4D11    2      B CAP_A_0402V-0.1UF,16V,10%,X7R,A    I52 @BASEBOARD_FAB2_LIB.BASEBOARD_FAB2(SCH_1):PAGE203
 C4D10    2      B CAP_0402-1.0UF,16V,10%,X6S,D97A    I53 @BASEBOARD_FAB2_LIB.BASEBOARD_FAB2(SCH_1):PAGE203
 C6P19    2      B CAP_0805-10UF,16V,10%,X6S,C953A    I54 @BASEBOARD_FAB2_LIB.BASEBOARD_FAB2(SCH_1):PAGE203
 C6P20    2      B CAP_0805-10UF,16V,10%,X6S,C953A    I57 @BASEBOARD_FAB2_LIB.BASEBOARD_FAB2(SCH_1):PAGE203
 C6P15    2      B CAP_0805-10UF,16V,10%,X6S,C953A    I58 @BASEBOARD_FAB2_LIB.BASEBOARD_FAB2(SCH_1):PAGE203
  C6P7    2      B CAP_0805-10UF,16V,10%,X6S,C953A    I59 @BASEBOARD_FAB2_LIB.BASEBOARD_FAB2(SCH_1):PAGE203
 C6P21    2      B CAP_A_0603V-22.0UF,4V,20%,X6S,A    I66 @BASEBOARD_FAB2_LIB.BASEBOARD_FAB2(SCH_1):PAGE203
 R4E13    2      B RES_0603-100.0,1%,1/10W,CHIP,GA    I67 @BASEBOARD_FAB2_LIB.BASEBOARD_FAB2(SCH_1):PAGE203
 C4D34    2      B CAP_A_0603V-22.0UF,4V,20%,X6S,A    I68 @BASEBOARD_FAB2_LIB.BASEBOARD_FAB2(SCH_1):PAGE203
  C4D4    2      B CAP_A_0603V-22.0UF,4V,20%,X6S,A    I69 @BASEBOARD_FAB2_LIB.BASEBOARD_FAB2(SCH_1):PAGE203
 EU4D3    2   LGND IR354XX_SM-IR35411,IC,H73688-0A    I70 @BASEBOARD_FAB2_LIB.BASEBOARD_FAB2(SCH_1):PAGE203
 EU4D3    5 PGND<0> IR354XX_SM-IR35411,IC,H73688-0A    I70 @BASEBOARD_FAB2_LIB.BASEBOARD_FAB2(SCH_1):PAGE203
 EU4D3    7 PGND<1> IR354XX_SM-IR35411,IC,H73688-0A    I70 @BASEBOARD_FAB2_LIB.BASEBOARD_FAB2(SCH_1):PAGE203
 EU4D3   40 PGND<2> IR354XX_SM-IR35411,IC,H73688-0A    I70 @BASEBOARD_FAB2_LIB.BASEBOARD_FAB2(SCH_1):PAGE203
 EU4D1    2   LGND IR354XX_SM-IR35411,IC,H73688-0A    I71 @BASEBOARD_FAB2_LIB.BASEBOARD_FAB2(SCH_1):PAGE203
 EU4D1    5 PGND<0> IR354XX_SM-IR35411,IC,H73688-0A    I71 @BASEBOARD_FAB2_LIB.BASEBOARD_FAB2(SCH_1):PAGE203
 EU4D1    7 PGND<1> IR354XX_SM-IR35411,IC,H73688-0A    I71 @BASEBOARD_FAB2_LIB.BASEBOARD_FAB2(SCH_1):PAGE203
 EU4D1   40 PGND<2> IR354XX_SM-IR35411,IC,H73688-0A    I71 @BASEBOARD_FAB2_LIB.BASEBOARD_FAB2(SCH_1):PAGE203
 R4D72    2      B RES_0402-68.1K,1%,1/16W,EMPTY,A    I89 @BASEBOARD_FAB2_LIB.BASEBOARD_FAB2(SCH_1):PAGE203
 R4D71    2      B RES_0402-68.1K,1%,1/16W,EMPTY,A    I91 @BASEBOARD_FAB2_LIB.BASEBOARD_FAB2(SCH_1):PAGE203
 C4D12    2      B CAP_A_0603V-22.0UF,4V,20%,X6S,A     I9 @BASEBOARD_FAB2_LIB.BASEBOARD_FAB2(SCH_1):PAGE204
 C4D47    2      B CAP_0402-0.22UF,16V,10%,X7R,A3A    I18 @BASEBOARD_FAB2_LIB.BASEBOARD_FAB2(SCH_1):PAGE204
 C4D46    2      B CAP_0402-1.0UF,16V,10%,X6S,D97A    I34 @BASEBOARD_FAB2_LIB.BASEBOARD_FAB2(SCH_1):PAGE204
 C4C19    2      B CAP_A_0402V-0.1UF,16V,10%,X7R,A    I35 @BASEBOARD_FAB2_LIB.BASEBOARD_FAB2(SCH_1):PAGE204
 C4C18    2      B CAP_0402-1.0UF,16V,10%,X6S,D97A    I36 @BASEBOARD_FAB2_LIB.BASEBOARD_FAB2(SCH_1):PAGE204
 C6N10    2      B CAP_0805-10UF,16V,10%,X6S,C953A    I37 @BASEBOARD_FAB2_LIB.BASEBOARD_FAB2(SCH_1):PAGE204
 C6P17    2      B CAP_0805-10UF,16V,10%,X6S,C953A    I38 @BASEBOARD_FAB2_LIB.BASEBOARD_FAB2(SCH_1):PAGE204
 C6N11    2      B CAP_0805-10UF,16V,10%,X6S,C953A    I42 @BASEBOARD_FAB2_LIB.BASEBOARD_FAB2(SCH_1):PAGE204
  C4D2    2      B CAPP_2626-270UF,16V,20%,OSCON,A    I48 @BASEBOARD_FAB2_LIB.BASEBOARD_FAB2(SCH_1):PAGE204
 C4E16    2      B CAPP_2626-270UF,16V,20%,OSCON,A    I50 @BASEBOARD_FAB2_LIB.BASEBOARD_FAB2(SCH_1):PAGE204
 R4E18    2      B RES_0402-100.0,1%,1/16W,CHIP,GA    I64 @BASEBOARD_FAB2_LIB.BASEBOARD_FAB2(SCH_1):PAGE204
 C4C12    2      B CAPP_2626-270UF,16V,20%,OSCON,A    I67 @BASEBOARD_FAB2_LIB.BASEBOARD_FAB2(SCH_1):PAGE204
  C6R2    2      B CAP_A_0603V-22.0UF,4V,20%,X6S,A    I70 @BASEBOARD_FAB2_LIB.BASEBOARD_FAB2(SCH_1):PAGE204
 EU4C2    2   LGND IR354XX_SM-IR35411,IC,H73688-0A    I71 @BASEBOARD_FAB2_LIB.BASEBOARD_FAB2(SCH_1):PAGE204
 EU4C2    5 PGND<0> IR354XX_SM-IR35411,IC,H73688-0A    I71 @BASEBOARD_FAB2_LIB.BASEBOARD_FAB2(SCH_1):PAGE204
 EU4C2    7 PGND<1> IR354XX_SM-IR35411,IC,H73688-0A    I71 @BASEBOARD_FAB2_LIB.BASEBOARD_FAB2(SCH_1):PAGE204
 EU4C2   40 PGND<2> IR354XX_SM-IR35411,IC,H73688-0A    I71 @BASEBOARD_FAB2_LIB.BASEBOARD_FAB2(SCH_1):PAGE204
 R4D68    2      B RES_0402-68.1K,1%,1/16W,EMPTY,A    I83 @BASEBOARD_FAB2_LIB.BASEBOARD_FAB2(SCH_1):PAGE204
  C6N7    2      B CAP_A_0603V-22.0UF,4V,20%,X6S,A     I5 @BASEBOARD_FAB2_LIB.BASEBOARD_FAB2(SCH_1):PAGE205
  C6N1    2      B CAPP_3018-470UF,2.5V,20%,ALUM,A    I12 @BASEBOARD_FAB2_LIB.BASEBOARD_FAB2(SCH_1):PAGE205
  C6N4    2      B CAPP_3018-470UF,2.5V,20%,ALUM,A    I14 @BASEBOARD_FAB2_LIB.BASEBOARD_FAB2(SCH_1):PAGE205
  C4C5    2      B CAP_0402-0.22UF,16V,10%,X7R,A3A    I16 @BASEBOARD_FAB2_LIB.BASEBOARD_FAB2(SCH_1):PAGE205
  C4C6    2      B CAP_0402-1.0UF,16V,10%,X6S,D97A    I20 @BASEBOARD_FAB2_LIB.BASEBOARD_FAB2(SCH_1):PAGE205
  R4C1    2      B RES_0402-100.0,1%,1/16W,CHIP,GA    I29 @BASEBOARD_FAB2_LIB.BASEBOARD_FAB2(SCH_1):PAGE205
 C4C10    2      B CAP_A_0402V-0.1UF,16V,10%,X7R,A    I31 @BASEBOARD_FAB2_LIB.BASEBOARD_FAB2(SCH_1):PAGE205
  C4C9    2      B CAP_0402-1.0UF,16V,10%,X6S,D97A    I32 @BASEBOARD_FAB2_LIB.BASEBOARD_FAB2(SCH_1):PAGE205
  C6N2    2      B CAP_0805-10UF,16V,10%,X6S,C953A    I33 @BASEBOARD_FAB2_LIB.BASEBOARD_FAB2(SCH_1):PAGE205
  C6N3    2      B CAP_0805-10UF,16V,10%,X6S,C953A    I34 @BASEBOARD_FAB2_LIB.BASEBOARD_FAB2(SCH_1):PAGE205
  C6N6    2      B CAP_0805-10UF,16V,10%,X6S,C953A    I35 @BASEBOARD_FAB2_LIB.BASEBOARD_FAB2(SCH_1):PAGE205
 C4C11    2      B CAP_A_0603V-22.0UF,4V,20%,X6S,A    I43 @BASEBOARD_FAB2_LIB.BASEBOARD_FAB2(SCH_1):PAGE205
  R6N4    2      B RES_0402-51.1,1.0%,1/16W,CHIP,A    I45 @BASEBOARD_FAB2_LIB.BASEBOARD_FAB2(SCH_1):PAGE205
 EU4C1    2   LGND IR354XX_SM-IR35412,IC,H73684-0A    I46 @BASEBOARD_FAB2_LIB.BASEBOARD_FAB2(SCH_1):PAGE205
 EU4C1    5 PGND<0> IR354XX_SM-IR35412,IC,H73684-0A    I46 @BASEBOARD_FAB2_LIB.BASEBOARD_FAB2(SCH_1):PAGE205
 EU4C1    7 PGND<1> IR354XX_SM-IR35412,IC,H73684-0A    I46 @BASEBOARD_FAB2_LIB.BASEBOARD_FAB2(SCH_1):PAGE205
 EU4C1   40 PGND<2> IR354XX_SM-IR35412,IC,H73684-0A    I46 @BASEBOARD_FAB2_LIB.BASEBOARD_FAB2(SCH_1):PAGE205
 R4C13    2      B RES_0402-68.1K,1%,1/16W,EMPTY,A    I62 @BASEBOARD_FAB2_LIB.BASEBOARD_FAB2(SCH_1):PAGE205
 C1C13    2      B CAP_A_0402V-1.0UF,6.3V,10%,X6SA    I29 @BASEBOARD_FAB2_LIB.BASEBOARD_FAB2(SCH_1):PAGE206
 C1C14    2      B CAP_A_0402V-0.1UF,16V,10%,X7R,A    I31 @BASEBOARD_FAB2_LIB.BASEBOARD_FAB2(SCH_1):PAGE206
  C1C7    2      B CAP_A_0402V-1.0UF,6.3V,10%,X6SA    I41 @BASEBOARD_FAB2_LIB.BASEBOARD_FAB2(SCH_1):PAGE206
  C1C9    2      B CAP_A_0402V-0.1UF,16V,10%,X7R,A    I42 @BASEBOARD_FAB2_LIB.BASEBOARD_FAB2(SCH_1):PAGE206
 R1C16    2      B RES_0402-1.5K,1%,1/16W,CHIP,G2A    I56 @BASEBOARD_FAB2_LIB.BASEBOARD_FAB2(SCH_1):PAGE206
 C1C10    2      B CAP_0402LF-220PF,50V,10%,X7R,AA    I69 @BASEBOARD_FAB2_LIB.BASEBOARD_FAB2(SCH_1):PAGE206
 C1C11    2      B CAP_0402LF-220PF,50V,10%,X7R,AA    I71 @BASEBOARD_FAB2_LIB.BASEBOARD_FAB2(SCH_1):PAGE206
  R9N7    2      B RES_0402-3.16K,1%,1/16W,CHIP,GA   I111 @BASEBOARD_FAB2_LIB.BASEBOARD_FAB2(SCH_1):PAGE206
  R9N8    2      B RES_0402-4.02K,1%,1/16W,CHIP,GA   I112 @BASEBOARD_FAB2_LIB.BASEBOARD_FAB2(SCH_1):PAGE206
 C1C23    2      B CAP_0402LF-1000PF,50V,10%,X7R,A   I114 @BASEBOARD_FAB2_LIB.BASEBOARD_FAB2(SCH_1):PAGE206
 EU1C2   49  THPAD PXE1610B_QFN-IC,H79206-001   I130 @BASEBOARD_FAB2_LIB.BASEBOARD_FAB2(SCH_1):PAGE206
  C9R8    2      B CAP_A_0603V-22.0UF,4V,20%,X6S,A     I8 @BASEBOARD_FAB2_LIB.BASEBOARD_FAB2(SCH_1):PAGE207
  C1E3    2      B CAP_A_0603V-22.0UF,4V,20%,X6S,A    I18 @BASEBOARD_FAB2_LIB.BASEBOARD_FAB2(SCH_1):PAGE207
 EU1E2    2   LGND IR354XX_SM-IR35411,IC,H73688-0A    I20 @BASEBOARD_FAB2_LIB.BASEBOARD_FAB2(SCH_1):PAGE207
 EU1E2    5 PGND<0> IR354XX_SM-IR35411,IC,H73688-0A    I20 @BASEBOARD_FAB2_LIB.BASEBOARD_FAB2(SCH_1):PAGE207
 EU1E2    7 PGND<1> IR354XX_SM-IR35411,IC,H73688-0A    I20 @BASEBOARD_FAB2_LIB.BASEBOARD_FAB2(SCH_1):PAGE207
 EU1E2   40 PGND<2> IR354XX_SM-IR35411,IC,H73688-0A    I20 @BASEBOARD_FAB2_LIB.BASEBOARD_FAB2(SCH_1):PAGE207
  C1E7    2      B CAP_0402-0.22UF,16V,10%,X7R,A3A    I28 @BASEBOARD_FAB2_LIB.BASEBOARD_FAB2(SCH_1):PAGE207
  C1E8    2      B CAP_0402-1.0UF,16V,10%,X6S,D97A    I32 @BASEBOARD_FAB2_LIB.BASEBOARD_FAB2(SCH_1):PAGE207
 C1E14    2      B CAP_A_0402V-0.1UF,16V,10%,X7R,A    I33 @BASEBOARD_FAB2_LIB.BASEBOARD_FAB2(SCH_1):PAGE207
 C1E13    2      B CAP_0402-1.0UF,16V,10%,X6S,D97A    I34 @BASEBOARD_FAB2_LIB.BASEBOARD_FAB2(SCH_1):PAGE207
 C1E25    2      B CAP_0402-0.22UF,16V,10%,X7R,A3A    I36 @BASEBOARD_FAB2_LIB.BASEBOARD_FAB2(SCH_1):PAGE207
 C1E24    2      B CAP_0402-1.0UF,16V,10%,X6S,D97A    I40 @BASEBOARD_FAB2_LIB.BASEBOARD_FAB2(SCH_1):PAGE207
 C1D34    2      B CAP_A_0402V-0.1UF,16V,10%,X7R,A    I41 @BASEBOARD_FAB2_LIB.BASEBOARD_FAB2(SCH_1):PAGE207
 C1D35    2      B CAP_0402-1.0UF,16V,10%,X6S,D97A    I42 @BASEBOARD_FAB2_LIB.BASEBOARD_FAB2(SCH_1):PAGE207
  C9R7    2      B CAP_0805-10UF,16V,10%,X6S,C953A    I43 @BASEBOARD_FAB2_LIB.BASEBOARD_FAB2(SCH_1):PAGE207
 C9R10    2      B CAP_0805-10UF,16V,10%,X6S,C953A    I44 @BASEBOARD_FAB2_LIB.BASEBOARD_FAB2(SCH_1):PAGE207
 C9R11    2      B CAP_0805-10UF,16V,10%,X6S,C953A    I48 @BASEBOARD_FAB2_LIB.BASEBOARD_FAB2(SCH_1):PAGE207
 C9P22    2      B CAP_0805-10UF,16V,10%,X6S,C953A    I50 @BASEBOARD_FAB2_LIB.BASEBOARD_FAB2(SCH_1):PAGE207
 C9P25    2      B CAP_0805-10UF,16V,10%,X6S,C953A    I51 @BASEBOARD_FAB2_LIB.BASEBOARD_FAB2(SCH_1):PAGE207
 C9P26    2      B CAP_0805-10UF,16V,10%,X6S,C953A    I54 @BASEBOARD_FAB2_LIB.BASEBOARD_FAB2(SCH_1):PAGE207
  C1E9    2      B CAP_A_0603V-22.0UF,4V,20%,X6S,A    I58 @BASEBOARD_FAB2_LIB.BASEBOARD_FAB2(SCH_1):PAGE207
  C9P3    2      B CAP_A_0603V-22.0UF,4V,20%,X6S,A    I59 @BASEBOARD_FAB2_LIB.BASEBOARD_FAB2(SCH_1):PAGE207
 R1E13    2      B RES_0402-68.1K,1%,1/16W,EMPTY,A    I67 @BASEBOARD_FAB2_LIB.BASEBOARD_FAB2(SCH_1):PAGE207
 R1E14    2      B RES_0402-68.1K,1%,1/16W,EMPTY,A    I68 @BASEBOARD_FAB2_LIB.BASEBOARD_FAB2(SCH_1):PAGE207
  R1E3    2      B RES_0603-100.0,1%,1/10W,CHIP,GA     I7 @BASEBOARD_FAB2_LIB.BASEBOARD_FAB2(SCH_1):PAGE208
 C1D14    2      B CAP_A_0603V-22.0UF,4V,20%,X6S,A     I9 @BASEBOARD_FAB2_LIB.BASEBOARD_FAB2(SCH_1):PAGE208
  C9P8    2      B CAPP_3018-470UF,2.5V,20%,ALUM,A    I12 @BASEBOARD_FAB2_LIB.BASEBOARD_FAB2(SCH_1):PAGE208
  C9P5    2      B CAPP_3018-470UF,2.5V,20%,ALUM,A    I14 @BASEBOARD_FAB2_LIB.BASEBOARD_FAB2(SCH_1):PAGE208
  C1D3    2      B CAP_A_0603V-22.0UF,4V,20%,X6S,A    I22 @BASEBOARD_FAB2_LIB.BASEBOARD_FAB2(SCH_1):PAGE208
 C9N24    2      B CAPP_3018-470UF,2.5V,20%,ALUM,A    I24 @BASEBOARD_FAB2_LIB.BASEBOARD_FAB2(SCH_1):PAGE208
  C9R9    2      B CAPP_3018-470UF,2.5V,20%,ALUM,A    I25 @BASEBOARD_FAB2_LIB.BASEBOARD_FAB2(SCH_1):PAGE208
  C9R3    2      B CAPP_3018-470UF,2.5V,20%,ALUM,A    I26 @BASEBOARD_FAB2_LIB.BASEBOARD_FAB2(SCH_1):PAGE208
 EU1D3    2   LGND IR354XX_SM-IR35411,IC,H73688-0A    I27 @BASEBOARD_FAB2_LIB.BASEBOARD_FAB2(SCH_1):PAGE208
 EU1D3    5 PGND<0> IR354XX_SM-IR35411,IC,H73688-0A    I27 @BASEBOARD_FAB2_LIB.BASEBOARD_FAB2(SCH_1):PAGE208
 EU1D3    7 PGND<1> IR354XX_SM-IR35411,IC,H73688-0A    I27 @BASEBOARD_FAB2_LIB.BASEBOARD_FAB2(SCH_1):PAGE208
 EU1D3   40 PGND<2> IR354XX_SM-IR35411,IC,H73688-0A    I27 @BASEBOARD_FAB2_LIB.BASEBOARD_FAB2(SCH_1):PAGE208
 C9P23    2      B CAPP_3018-470UF,2.5V,20%,ALUM,A    I28 @BASEBOARD_FAB2_LIB.BASEBOARD_FAB2(SCH_1):PAGE208
 C9P18    2      B CAPP_3018-470UF,2.5V,20%,ALUM,A    I30 @BASEBOARD_FAB2_LIB.BASEBOARD_FAB2(SCH_1):PAGE208
 C1D16    2      B CAP_0402-0.22UF,16V,10%,X7R,A3A    I38 @BASEBOARD_FAB2_LIB.BASEBOARD_FAB2(SCH_1):PAGE208
 C1D17    2      B CAP_0402-1.0UF,16V,10%,X6S,D97A    I43 @BASEBOARD_FAB2_LIB.BASEBOARD_FAB2(SCH_1):PAGE208
 C1D28    2      B CAP_A_0402V-0.1UF,16V,10%,X7R,A    I44 @BASEBOARD_FAB2_LIB.BASEBOARD_FAB2(SCH_1):PAGE208
 C1D23    2      B CAP_0402-1.0UF,16V,10%,X6S,D97A    I45 @BASEBOARD_FAB2_LIB.BASEBOARD_FAB2(SCH_1):PAGE208
  C1D6    2      B CAP_0402-0.22UF,16V,10%,X7R,A3A    I46 @BASEBOARD_FAB2_LIB.BASEBOARD_FAB2(SCH_1):PAGE208
  C1D7    2      B CAP_0402-1.0UF,16V,10%,X6S,D97A    I50 @BASEBOARD_FAB2_LIB.BASEBOARD_FAB2(SCH_1):PAGE208
 C1D13    2      B CAP_A_0402V-0.1UF,16V,10%,X7R,A    I51 @BASEBOARD_FAB2_LIB.BASEBOARD_FAB2(SCH_1):PAGE208
 C1D12    2      B CAP_0402-1.0UF,16V,10%,X6S,D97A    I52 @BASEBOARD_FAB2_LIB.BASEBOARD_FAB2(SCH_1):PAGE208
  C9P4    2      B CAP_0805-10UF,16V,10%,X6S,C953A    I53 @BASEBOARD_FAB2_LIB.BASEBOARD_FAB2(SCH_1):PAGE208
  C9P7    2      B CAP_0805-10UF,16V,10%,X6S,C953A    I54 @BASEBOARD_FAB2_LIB.BASEBOARD_FAB2(SCH_1):PAGE208
  C9P9    2      B CAP_0805-10UF,16V,10%,X6S,C953A    I55 @BASEBOARD_FAB2_LIB.BASEBOARD_FAB2(SCH_1):PAGE208
 C9P24    2      B CAP_0805-10UF,16V,10%,X6S,C953A    I58 @BASEBOARD_FAB2_LIB.BASEBOARD_FAB2(SCH_1):PAGE208
  C9P1    2      B CAP_0805-10UF,16V,10%,X6S,C953A    I59 @BASEBOARD_FAB2_LIB.BASEBOARD_FAB2(SCH_1):PAGE208
  C9P2    2      B CAP_0805-10UF,16V,10%,X6S,C953A    I60 @BASEBOARD_FAB2_LIB.BASEBOARD_FAB2(SCH_1):PAGE208
 C9P10    2      B CAP_A_0603V-22.0UF,4V,20%,X6S,A    I66 @BASEBOARD_FAB2_LIB.BASEBOARD_FAB2(SCH_1):PAGE208
  C9R2    2      B CAP_A_0603V-22.0UF,4V,20%,X6S,A    I67 @BASEBOARD_FAB2_LIB.BASEBOARD_FAB2(SCH_1):PAGE208
 EU1D1    2   LGND IR354XX_SM-IR35411,IC,H73688-0A    I71 @BASEBOARD_FAB2_LIB.BASEBOARD_FAB2(SCH_1):PAGE208
 EU1D1    5 PGND<0> IR354XX_SM-IR35411,IC,H73688-0A    I71 @BASEBOARD_FAB2_LIB.BASEBOARD_FAB2(SCH_1):PAGE208
 EU1D1    7 PGND<1> IR354XX_SM-IR35411,IC,H73688-0A    I71 @BASEBOARD_FAB2_LIB.BASEBOARD_FAB2(SCH_1):PAGE208
 EU1D1   40 PGND<2> IR354XX_SM-IR35411,IC,H73688-0A    I71 @BASEBOARD_FAB2_LIB.BASEBOARD_FAB2(SCH_1):PAGE208
 R1D54    2      B RES_0402-68.1K,1%,1/16W,EMPTY,A    I75 @BASEBOARD_FAB2_LIB.BASEBOARD_FAB2(SCH_1):PAGE208
 R1D55    2      B RES_0402-68.1K,1%,1/16W,EMPTY,A    I76 @BASEBOARD_FAB2_LIB.BASEBOARD_FAB2(SCH_1):PAGE208
 C9N27    2      B CAP_0805-10UF,16V,10%,X6S,C953A     I5 @BASEBOARD_FAB2_LIB.BASEBOARD_FAB2(SCH_1):PAGE209
 C9N26    2      B CAP_0805-10UF,16V,10%,X6S,C953A     I7 @BASEBOARD_FAB2_LIB.BASEBOARD_FAB2(SCH_1):PAGE209
 C9N25    2      B CAP_0805-10UF,16V,10%,X6S,C953A     I8 @BASEBOARD_FAB2_LIB.BASEBOARD_FAB2(SCH_1):PAGE209
  R1E8    2      B RES_0402-100.0,1%,1/16W,CHIP,GA     I9 @BASEBOARD_FAB2_LIB.BASEBOARD_FAB2(SCH_1):PAGE209
 C1C26    2      B CAP_0402-1.0UF,16V,10%,X6S,D97A    I16 @BASEBOARD_FAB2_LIB.BASEBOARD_FAB2(SCH_1):PAGE209
 C1C25    2      B CAP_A_0402V-0.1UF,16V,10%,X7R,A    I17 @BASEBOARD_FAB2_LIB.BASEBOARD_FAB2(SCH_1):PAGE209
 C1D32    2      B CAP_0402-1.0UF,16V,10%,X6S,D97A    I18 @BASEBOARD_FAB2_LIB.BASEBOARD_FAB2(SCH_1):PAGE209
 C1D33    2      B CAP_0402-0.22UF,16V,10%,X7R,A3A    I22 @BASEBOARD_FAB2_LIB.BASEBOARD_FAB2(SCH_1):PAGE209
  C1C1    2      B CAPP_2626-270UF,16V,20%,OSCON,A    I35 @BASEBOARD_FAB2_LIB.BASEBOARD_FAB2(SCH_1):PAGE209
 C1E18    2      B CAPP_2626-270UF,16V,20%,OSCON,A    I37 @BASEBOARD_FAB2_LIB.BASEBOARD_FAB2(SCH_1):PAGE209
  C1C2    2      B CAPP_2626-270UF,16V,20%,OSCON,A    I38 @BASEBOARD_FAB2_LIB.BASEBOARD_FAB2(SCH_1):PAGE209
 C1D24    2      B CAP_A_0603V-22.0UF,4V,20%,X6S,A    I42 @BASEBOARD_FAB2_LIB.BASEBOARD_FAB2(SCH_1):PAGE209
 C9P20    2      B CAP_A_0603V-22.0UF,4V,20%,X6S,A    I55 @BASEBOARD_FAB2_LIB.BASEBOARD_FAB2(SCH_1):PAGE209
 EU1C3    2   LGND IR354XX_SM-IR35411,IC,H73688-0A    I56 @BASEBOARD_FAB2_LIB.BASEBOARD_FAB2(SCH_1):PAGE209
 EU1C3    5 PGND<0> IR354XX_SM-IR35411,IC,H73688-0A    I56 @BASEBOARD_FAB2_LIB.BASEBOARD_FAB2(SCH_1):PAGE209
 EU1C3    7 PGND<1> IR354XX_SM-IR35411,IC,H73688-0A    I56 @BASEBOARD_FAB2_LIB.BASEBOARD_FAB2(SCH_1):PAGE209
 EU1C3   40 PGND<2> IR354XX_SM-IR35411,IC,H73688-0A    I56 @BASEBOARD_FAB2_LIB.BASEBOARD_FAB2(SCH_1):PAGE209
 R1D52    2      B RES_0402-68.1K,1%,1/16W,EMPTY,A    I59 @BASEBOARD_FAB2_LIB.BASEBOARD_FAB2(SCH_1):PAGE209
 C1C19    2      B CAP_A_0603V-22.0UF,4V,20%,X6S,A     I8 @BASEBOARD_FAB2_LIB.BASEBOARD_FAB2(SCH_1):PAGE210
 C9N11    2      B CAPP_3018-470UF,2.5V,20%,ALUM,A    I12 @BASEBOARD_FAB2_LIB.BASEBOARD_FAB2(SCH_1):PAGE210
 C9N20    2      B CAPP_3018-470UF,2.5V,20%,ALUM,A    I14 @BASEBOARD_FAB2_LIB.BASEBOARD_FAB2(SCH_1):PAGE210
  C1C4    2      B CAP_0402-0.22UF,16V,10%,X7R,A3A    I22 @BASEBOARD_FAB2_LIB.BASEBOARD_FAB2(SCH_1):PAGE210
  C1C5    2      B CAP_0402-1.0UF,16V,10%,X6S,D97A    I26 @BASEBOARD_FAB2_LIB.BASEBOARD_FAB2(SCH_1):PAGE210
 C1C17    2      B CAP_A_0402V-0.1UF,16V,10%,X7R,A    I27 @BASEBOARD_FAB2_LIB.BASEBOARD_FAB2(SCH_1):PAGE210
 C1C15    2      B CAP_0402-1.0UF,16V,10%,X6S,D97A    I28 @BASEBOARD_FAB2_LIB.BASEBOARD_FAB2(SCH_1):PAGE210
  R1C4    2      B RES_0402-100.0,1%,1/16W,CHIP,GA    I33 @BASEBOARD_FAB2_LIB.BASEBOARD_FAB2(SCH_1):PAGE210
 C9N13    2      B CAP_0805-10UF,16V,10%,X6S,C953A    I35 @BASEBOARD_FAB2_LIB.BASEBOARD_FAB2(SCH_1):PAGE210
 C9N19    2      B CAP_0805-10UF,16V,10%,X6S,C953A    I36 @BASEBOARD_FAB2_LIB.BASEBOARD_FAB2(SCH_1):PAGE210
 C9N21    2      B CAP_0805-10UF,16V,10%,X6S,C953A    I38 @BASEBOARD_FAB2_LIB.BASEBOARD_FAB2(SCH_1):PAGE210
 C9N22    2      B CAP_A_0603V-22.0UF,4V,20%,X6S,A    I44 @BASEBOARD_FAB2_LIB.BASEBOARD_FAB2(SCH_1):PAGE210
  R9N4    2      B RES_0402-51.1,1.0%,1/16W,CHIP,A    I45 @BASEBOARD_FAB2_LIB.BASEBOARD_FAB2(SCH_1):PAGE210
 EU1C1    2   LGND IR354XX_SM-IR35412,IC,H73684-0A    I51 @BASEBOARD_FAB2_LIB.BASEBOARD_FAB2(SCH_1):PAGE210
 EU1C1    5 PGND<0> IR354XX_SM-IR35412,IC,H73684-0A    I51 @BASEBOARD_FAB2_LIB.BASEBOARD_FAB2(SCH_1):PAGE210
 EU1C1    7 PGND<1> IR354XX_SM-IR35412,IC,H73684-0A    I51 @BASEBOARD_FAB2_LIB.BASEBOARD_FAB2(SCH_1):PAGE210
 EU1C1   40 PGND<2> IR354XX_SM-IR35412,IC,H73684-0A    I51 @BASEBOARD_FAB2_LIB.BASEBOARD_FAB2(SCH_1):PAGE210
 R1C37    2      B RES_0402-68.1K,1%,1/16W,EMPTY,A    I52 @BASEBOARD_FAB2_LIB.BASEBOARD_FAB2(SCH_1):PAGE210
  C3P4    2      B CAP_A_0402V-1.0UF,6.3V,10%,X6SA    I11 @BASEBOARD_FAB2_LIB.BASEBOARD_FAB2(SCH_1):PAGE211
  C3P5    2      B CAP_A_0402V-0.1UF,16V,10%,X7R,A    I13 @BASEBOARD_FAB2_LIB.BASEBOARD_FAB2(SCH_1):PAGE211
  C3P3    2      B CAP_A_0402V-1.0UF,6.3V,10%,X6SA    I20 @BASEBOARD_FAB2_LIB.BASEBOARD_FAB2(SCH_1):PAGE211
  C3P7    2      B CAP_A_0402V-0.1UF,16V,10%,X7R,A    I22 @BASEBOARD_FAB2_LIB.BASEBOARD_FAB2(SCH_1):PAGE211
 R3P16    2      B RES_0402-1.5K,1%,1/16W,CHIP,G2A    I32 @BASEBOARD_FAB2_LIB.BASEBOARD_FAB2(SCH_1):PAGE211
 R3N31    2      B RES_0402-3.16K,1%,1/16W,CHIP,GA    I52 @BASEBOARD_FAB2_LIB.BASEBOARD_FAB2(SCH_1):PAGE211
  C3P6    2      B CAP_0402LF-1000PF,50V,10%,X7R,A    I71 @BASEBOARD_FAB2_LIB.BASEBOARD_FAB2(SCH_1):PAGE211
 EU3P1   26 BISEN1 PXE1110B_QFN-IC,H89187-001    I93 @BASEBOARD_FAB2_LIB.BASEBOARD_FAB2(SCH_1):PAGE211
 EU3P1   27 GND<0> PXE1110B_QFN-IC,H89187-001    I93 @BASEBOARD_FAB2_LIB.BASEBOARD_FAB2(SCH_1):PAGE211
 EU3P1   23 GND<1> PXE1110B_QFN-IC,H89187-001    I93 @BASEBOARD_FAB2_LIB.BASEBOARD_FAB2(SCH_1):PAGE211
 EU3P1   41  THPAD PXE1110B_QFN-IC,H89187-001    I93 @BASEBOARD_FAB2_LIB.BASEBOARD_FAB2(SCH_1):PAGE211
 C3N35    2      B CAPP_3018-470UF,2.5V,20%,ALUM,A    I18 @BASEBOARD_FAB2_LIB.BASEBOARD_FAB2(SCH_1):PAGE212
  C7C6    2      B CAP_A_0603V-22.0UF,4V,20%,X6S,A    I23 @BASEBOARD_FAB2_LIB.BASEBOARD_FAB2(SCH_1):PAGE212
 C7C18    2      B CAP_0402-0.22UF,16V,10%,X7R,A3A    I33 @BASEBOARD_FAB2_LIB.BASEBOARD_FAB2(SCH_1):PAGE212
 C7C17    2      B CAP_0402-1.0UF,16V,10%,X6S,D97A    I36 @BASEBOARD_FAB2_LIB.BASEBOARD_FAB2(SCH_1):PAGE212
 C7C11    2      B CAP_A_0402V-0.1UF,16V,10%,X7R,A    I38 @BASEBOARD_FAB2_LIB.BASEBOARD_FAB2(SCH_1):PAGE212
 C7C12    2      B CAP_0402-1.0UF,16V,10%,X6S,D97A    I39 @BASEBOARD_FAB2_LIB.BASEBOARD_FAB2(SCH_1):PAGE212
 C3N36    2      B CAP_0805-10UF,16V,10%,X6S,C953A    I40 @BASEBOARD_FAB2_LIB.BASEBOARD_FAB2(SCH_1):PAGE212
 C3N33    2      B CAP_0805-10UF,16V,10%,X6S,C953A    I41 @BASEBOARD_FAB2_LIB.BASEBOARD_FAB2(SCH_1):PAGE212
 C3N34    2      B CAP_0805-10UF,16V,10%,X6S,C953A    I43 @BASEBOARD_FAB2_LIB.BASEBOARD_FAB2(SCH_1):PAGE212
 R3N20    2      B RES_0402-100.0,1%,1/16W,CHIP,GA    I68 @BASEBOARD_FAB2_LIB.BASEBOARD_FAB2(SCH_1):PAGE212
 C7C10    2      B CAP_A_0603V-22.0UF,4V,20%,X6S,A    I77 @BASEBOARD_FAB2_LIB.BASEBOARD_FAB2(SCH_1):PAGE212
  R7C3    2      B RES_0402-51.1,1.0%,1/16W,CHIP,A    I78 @BASEBOARD_FAB2_LIB.BASEBOARD_FAB2(SCH_1):PAGE212
 EU7C1    2   LGND IR354XX_SM-IR35412,IC,H73684-0A   I101 @BASEBOARD_FAB2_LIB.BASEBOARD_FAB2(SCH_1):PAGE212
 EU7C1    5 PGND<0> IR354XX_SM-IR35412,IC,H73684-0A   I101 @BASEBOARD_FAB2_LIB.BASEBOARD_FAB2(SCH_1):PAGE212
 EU7C1    7 PGND<1> IR354XX_SM-IR35412,IC,H73684-0A   I101 @BASEBOARD_FAB2_LIB.BASEBOARD_FAB2(SCH_1):PAGE212
 EU7C1   40 PGND<2> IR354XX_SM-IR35412,IC,H73684-0A   I101 @BASEBOARD_FAB2_LIB.BASEBOARD_FAB2(SCH_1):PAGE212
 R7C25    2      B RES_0402-68.1K,1%,1/16W,EMPTY,A   I103 @BASEBOARD_FAB2_LIB.BASEBOARD_FAB2(SCH_1):PAGE212
 C4D31    2      B CAP_A_0402V-1.0UF,6.3V,10%,X6SA     I9 @BASEBOARD_FAB2_LIB.BASEBOARD_FAB2(SCH_1):PAGE213
 C4D32    2      B CAP_A_0402V-0.1UF,16V,10%,X7R,A    I11 @BASEBOARD_FAB2_LIB.BASEBOARD_FAB2(SCH_1):PAGE213
 C4D36    2      B CAP_A_0402V-1.0UF,6.3V,10%,X6SA    I17 @BASEBOARD_FAB2_LIB.BASEBOARD_FAB2(SCH_1):PAGE213
 R4D57    2      B RES_0402-1.5K,1%,1/16W,CHIP,G2A    I32 @BASEBOARD_FAB2_LIB.BASEBOARD_FAB2(SCH_1):PAGE213
 C4D38    2      B CAP_A_0402V-0.1UF,16V,10%,X7R,A    I35 @BASEBOARD_FAB2_LIB.BASEBOARD_FAB2(SCH_1):PAGE213
 C4D33    2      B CAP_0402LF-1000PF,50V,10%,X7R,A    I73 @BASEBOARD_FAB2_LIB.BASEBOARD_FAB2(SCH_1):PAGE213
 EU4D5   26 BISEN1 PXE1110B_QFN-IC,H89187-001    I96 @BASEBOARD_FAB2_LIB.BASEBOARD_FAB2(SCH_1):PAGE213
 EU4D5   27 GND<0> PXE1110B_QFN-IC,H89187-001    I96 @BASEBOARD_FAB2_LIB.BASEBOARD_FAB2(SCH_1):PAGE213
 EU4D5   23 GND<1> PXE1110B_QFN-IC,H89187-001    I96 @BASEBOARD_FAB2_LIB.BASEBOARD_FAB2(SCH_1):PAGE213
 EU4D5   41  THPAD PXE1110B_QFN-IC,H89187-001    I96 @BASEBOARD_FAB2_LIB.BASEBOARD_FAB2(SCH_1):PAGE213
  C6R5    2      B CAPP_3018-470UF,2.5V,20%,ALUM,A    I24 @BASEBOARD_FAB2_LIB.BASEBOARD_FAB2(SCH_1):PAGE214
  C7R1    2      B CAP_A_0603V-22.0UF,4V,20%,X6S,A    I65 @BASEBOARD_FAB2_LIB.BASEBOARD_FAB2(SCH_1):PAGE214
 C4E23    2      B CAP_0402-0.22UF,16V,10%,X7R,A3A    I73 @BASEBOARD_FAB2_LIB.BASEBOARD_FAB2(SCH_1):PAGE214
 C4E22    2      B CAP_0402-1.0UF,16V,10%,X6S,D97A    I76 @BASEBOARD_FAB2_LIB.BASEBOARD_FAB2(SCH_1):PAGE214
 C4E13    2      B CAP_A_0402V-0.1UF,16V,10%,X7R,A    I77 @BASEBOARD_FAB2_LIB.BASEBOARD_FAB2(SCH_1):PAGE214
 C4E15    2      B CAP_0402-1.0UF,16V,10%,X6S,D97A    I79 @BASEBOARD_FAB2_LIB.BASEBOARD_FAB2(SCH_1):PAGE214
 C6R14    2      B CAP_0805-10UF,16V,10%,X6S,C953A    I80 @BASEBOARD_FAB2_LIB.BASEBOARD_FAB2(SCH_1):PAGE214
 C6R10    2      B CAP_0805-10UF,16V,10%,X6S,C953A    I81 @BASEBOARD_FAB2_LIB.BASEBOARD_FAB2(SCH_1):PAGE214
  C6R8    2      B CAP_0805-10UF,16V,10%,X6S,C953A    I83 @BASEBOARD_FAB2_LIB.BASEBOARD_FAB2(SCH_1):PAGE214
 R3D28    2      B RES_0402-100.0,1%,1/16W,CHIP,GA   I101 @BASEBOARD_FAB2_LIB.BASEBOARD_FAB2(SCH_1):PAGE214
  C3E1    2      B CAP_A_0603V-22.0UF,4V,20%,X6S,A   I108 @BASEBOARD_FAB2_LIB.BASEBOARD_FAB2(SCH_1):PAGE214
  R7R1    2      B RES_0402-51.1,1.0%,1/16W,CHIP,A   I109 @BASEBOARD_FAB2_LIB.BASEBOARD_FAB2(SCH_1):PAGE214
 EU4E2    2   LGND IR354XX_SM-IR35412,IC,H73684-0A   I126 @BASEBOARD_FAB2_LIB.BASEBOARD_FAB2(SCH_1):PAGE214
 EU4E2    5 PGND<0> IR354XX_SM-IR35412,IC,H73684-0A   I126 @BASEBOARD_FAB2_LIB.BASEBOARD_FAB2(SCH_1):PAGE214
 EU4E2    7 PGND<1> IR354XX_SM-IR35412,IC,H73684-0A   I126 @BASEBOARD_FAB2_LIB.BASEBOARD_FAB2(SCH_1):PAGE214
 EU4E2   40 PGND<2> IR354XX_SM-IR35412,IC,H73684-0A   I126 @BASEBOARD_FAB2_LIB.BASEBOARD_FAB2(SCH_1):PAGE214
 R4E21    2      B RES_0402-68.1K,1%,1/16W,EMPTY,A   I127 @BASEBOARD_FAB2_LIB.BASEBOARD_FAB2(SCH_1):PAGE214
  C6G3    2      B CAP_0805LF-22UF,4V,20%,X6S,C95A     I6 @BASEBOARD_FAB2_LIB.BASEBOARD_FAB2(SCH_1):PAGE216
  C3U2    2      B CAP_0805-10UF,16V,10%,X6S,C953A    I45 @BASEBOARD_FAB2_LIB.BASEBOARD_FAB2(SCH_1):PAGE216
  C3U3    2      B CAP_0805-10UF,16V,10%,X6S,C953A    I46 @BASEBOARD_FAB2_LIB.BASEBOARD_FAB2(SCH_1):PAGE216
  C3U4    2      B CAP_0805-10UF,16V,10%,X6S,C953A    I47 @BASEBOARD_FAB2_LIB.BASEBOARD_FAB2(SCH_1):PAGE216
 C7G37    2      B CAP_0402-1.0UF,16V,10%,X6S,D97A    I48 @BASEBOARD_FAB2_LIB.BASEBOARD_FAB2(SCH_1):PAGE216
 C7G33    2      B CAP_0402-1.0UF,16V,10%,X6S,D97A    I50 @BASEBOARD_FAB2_LIB.BASEBOARD_FAB2(SCH_1):PAGE216
 C7G29    2      B CAP_A_0402V-0.1UF,16V,10%,X7R,A    I51 @BASEBOARD_FAB2_LIB.BASEBOARD_FAB2(SCH_1):PAGE216
 C7G34    2      B CAP_0402-0.22UF,16V,10%,X7R,A3A    I54 @BASEBOARD_FAB2_LIB.BASEBOARD_FAB2(SCH_1):PAGE216
 C7G27    2      B CAP_0805LF-22UF,4V,20%,X6S,C95A    I68 @BASEBOARD_FAB2_LIB.BASEBOARD_FAB2(SCH_1):PAGE216
 C7G41    2      B CAP_0402-0.22UF,16V,10%,X7R,A3A    I72 @BASEBOARD_FAB2_LIB.BASEBOARD_FAB2(SCH_1):PAGE216
 C7G40    2      B CAP_0402-1.0UF,16V,10%,X6S,D97A    I77 @BASEBOARD_FAB2_LIB.BASEBOARD_FAB2(SCH_1):PAGE216
 C7G36    2      B CAP_A_0402V-0.1UF,16V,10%,X7R,A    I78 @BASEBOARD_FAB2_LIB.BASEBOARD_FAB2(SCH_1):PAGE216
 C7G30    2      B CAP_0402-1.0UF,16V,10%,X6S,D97A    I79 @BASEBOARD_FAB2_LIB.BASEBOARD_FAB2(SCH_1):PAGE216
  C3U9    2      B CAP_0805-10UF,16V,10%,X6S,C953A    I80 @BASEBOARD_FAB2_LIB.BASEBOARD_FAB2(SCH_1):PAGE216
  C3U7    2      B CAP_0805-10UF,16V,10%,X6S,C953A    I81 @BASEBOARD_FAB2_LIB.BASEBOARD_FAB2(SCH_1):PAGE216
  C3U6    2      B CAP_0805-10UF,16V,10%,X6S,C953A    I84 @BASEBOARD_FAB2_LIB.BASEBOARD_FAB2(SCH_1):PAGE216
 EU7G2    2   LGND IR354XX_SM-IR35411,IC,H73688-0A   I102 @BASEBOARD_FAB2_LIB.BASEBOARD_FAB2(SCH_1):PAGE216
 EU7G2    5 PGND<0> IR354XX_SM-IR35411,IC,H73688-0A   I102 @BASEBOARD_FAB2_LIB.BASEBOARD_FAB2(SCH_1):PAGE216
 EU7G2    7 PGND<1> IR354XX_SM-IR35411,IC,H73688-0A   I102 @BASEBOARD_FAB2_LIB.BASEBOARD_FAB2(SCH_1):PAGE216
 EU7G2   40 PGND<2> IR354XX_SM-IR35411,IC,H73688-0A   I102 @BASEBOARD_FAB2_LIB.BASEBOARD_FAB2(SCH_1):PAGE216
 EU7G3    2   LGND IR354XX_SM-IR35411,IC,H73688-0A   I103 @BASEBOARD_FAB2_LIB.BASEBOARD_FAB2(SCH_1):PAGE216
 EU7G3    5 PGND<0> IR354XX_SM-IR35411,IC,H73688-0A   I103 @BASEBOARD_FAB2_LIB.BASEBOARD_FAB2(SCH_1):PAGE216
 EU7G3    7 PGND<1> IR354XX_SM-IR35411,IC,H73688-0A   I103 @BASEBOARD_FAB2_LIB.BASEBOARD_FAB2(SCH_1):PAGE216
 EU7G3   40 PGND<2> IR354XX_SM-IR35411,IC,H73688-0A   I103 @BASEBOARD_FAB2_LIB.BASEBOARD_FAB2(SCH_1):PAGE216
 R7G25    2      B RES_0402-68.1K,1%,1/16W,EMPTY,A   I104 @BASEBOARD_FAB2_LIB.BASEBOARD_FAB2(SCH_1):PAGE216
 R7G30    2      B RES_0402-68.1K,1%,1/16W,EMPTY,A   I106 @BASEBOARD_FAB2_LIB.BASEBOARD_FAB2(SCH_1):PAGE216
  R3U4    2      B RES_0603-120.0,1%,1/10W,CHIP,GA    I58 @BASEBOARD_FAB2_LIB.BASEBOARD_FAB2(SCH_1):PAGE217
 C7G28    2      B CAPP_3018-470UF,2.5V,20%,ALUM,A    I75 @BASEBOARD_FAB2_LIB.BASEBOARD_FAB2(SCH_1):PAGE217
  C3U1    2      B CAPP_3018-470UF,2.5V,20%,ALUM,A    I76 @BASEBOARD_FAB2_LIB.BASEBOARD_FAB2(SCH_1):PAGE217
  C3U5    2      B CAPP_3018-470UF,2.5V,20%,ALUM,A    I77 @BASEBOARD_FAB2_LIB.BASEBOARD_FAB2(SCH_1):PAGE217
  C3U8    2      B CAPP_3018-470UF,2.5V,20%,ALUM,A    I78 @BASEBOARD_FAB2_LIB.BASEBOARD_FAB2(SCH_1):PAGE217
  C7G2    2      B CAPP_2626-270UF,16V,20%,OSCON,A   I175 @BASEBOARD_FAB2_LIB.BASEBOARD_FAB2(SCH_1):PAGE217
  C5F2    2      B CAP_A_0603V-47UF,4V,20%,X5R,60A   I205 @BASEBOARD_FAB2_LIB.BASEBOARD_FAB2(SCH_1):PAGE217
  C5F1    2      B CAP_A_0603V-47UF,4V,20%,X5R,60A   I206 @BASEBOARD_FAB2_LIB.BASEBOARD_FAB2(SCH_1):PAGE217
 C5G10    2      B CAP_A_0603V-47UF,4V,20%,X5R,60A   I207 @BASEBOARD_FAB2_LIB.BASEBOARD_FAB2(SCH_1):PAGE217
  C5T2    2      B CAP_A_0603V-47UF,4V,20%,X5R,60A   I208 @BASEBOARD_FAB2_LIB.BASEBOARD_FAB2(SCH_1):PAGE217
 C5U11    2      B CAP_A_0603V-47UF,4V,20%,X5R,60A   I209 @BASEBOARD_FAB2_LIB.BASEBOARD_FAB2(SCH_1):PAGE217
 C5T13    2      B CAP_A_0603V-47UF,4V,20%,X5R,60A   I210 @BASEBOARD_FAB2_LIB.BASEBOARD_FAB2(SCH_1):PAGE217
  C5T4    2      B CAP_A_0603V-47UF,4V,20%,X5R,60A   I211 @BASEBOARD_FAB2_LIB.BASEBOARD_FAB2(SCH_1):PAGE217
  C5T1    2      B CAP_A_0603V-47UF,4V,20%,X5R,60A   I212 @BASEBOARD_FAB2_LIB.BASEBOARD_FAB2(SCH_1):PAGE217
 C5G19    2      B CAP_A_0603V-47UF,4V,20%,X5R,60A   I213 @BASEBOARD_FAB2_LIB.BASEBOARD_FAB2(SCH_1):PAGE217
 SH4U1    2      B SHUNT_SH0201-EMPTY,N_A   I259 @BASEBOARD_FAB2_LIB.BASEBOARD_FAB2(SCH_1):PAGE217
  C3L2    2      B CAP_0805-10UF,16V,10%,X6S,C953A    I45 @BASEBOARD_FAB2_LIB.BASEBOARD_FAB2(SCH_1):PAGE219
  C3L4    2      B CAP_0805-10UF,16V,10%,X6S,C953A    I46 @BASEBOARD_FAB2_LIB.BASEBOARD_FAB2(SCH_1):PAGE219
 C3L13    2      B CAP_0805-10UF,16V,10%,X6S,C953A    I47 @BASEBOARD_FAB2_LIB.BASEBOARD_FAB2(SCH_1):PAGE219
 C7A11    2      B CAP_0402-1.0UF,16V,10%,X6S,D97A    I48 @BASEBOARD_FAB2_LIB.BASEBOARD_FAB2(SCH_1):PAGE219
 C7A16    2      B CAP_0402-1.0UF,16V,10%,X6S,D97A    I50 @BASEBOARD_FAB2_LIB.BASEBOARD_FAB2(SCH_1):PAGE219
  C7A5    2      B CAP_A_0402V-0.1UF,16V,10%,X7R,A    I51 @BASEBOARD_FAB2_LIB.BASEBOARD_FAB2(SCH_1):PAGE219
 C7A17    2      B CAP_0402-0.22UF,16V,10%,X7R,A3A    I54 @BASEBOARD_FAB2_LIB.BASEBOARD_FAB2(SCH_1):PAGE219
  C6A4    2      B CAP_0805LF-22UF,4V,20%,X6S,C95A    I68 @BASEBOARD_FAB2_LIB.BASEBOARD_FAB2(SCH_1):PAGE219
 C7A25    2      B CAP_0402-0.22UF,16V,10%,X7R,A3A    I72 @BASEBOARD_FAB2_LIB.BASEBOARD_FAB2(SCH_1):PAGE219
 C7A24    2      B CAP_0402-1.0UF,16V,10%,X6S,D97A    I77 @BASEBOARD_FAB2_LIB.BASEBOARD_FAB2(SCH_1):PAGE219
 C7A20    2      B CAP_A_0402V-0.1UF,16V,10%,X7R,A    I78 @BASEBOARD_FAB2_LIB.BASEBOARD_FAB2(SCH_1):PAGE219
 C7A21    2      B CAP_0402-1.0UF,16V,10%,X6S,D97A    I79 @BASEBOARD_FAB2_LIB.BASEBOARD_FAB2(SCH_1):PAGE219
 C3L17    2      B CAP_0805-10UF,16V,10%,X6S,C953A    I80 @BASEBOARD_FAB2_LIB.BASEBOARD_FAB2(SCH_1):PAGE219
 C3L16    2      B CAP_0805-10UF,16V,10%,X6S,C953A    I81 @BASEBOARD_FAB2_LIB.BASEBOARD_FAB2(SCH_1):PAGE219
 C3L15    2      B CAP_0805-10UF,16V,10%,X6S,C953A    I84 @BASEBOARD_FAB2_LIB.BASEBOARD_FAB2(SCH_1):PAGE219
  C6A1    2      B CAP_0805LF-22UF,4V,20%,X6S,C95A    I87 @BASEBOARD_FAB2_LIB.BASEBOARD_FAB2(SCH_1):PAGE219
 EU7A1    2   LGND IR354XX_SM-IR35411,IC,H73688-0A   I106 @BASEBOARD_FAB2_LIB.BASEBOARD_FAB2(SCH_1):PAGE219
 EU7A1    5 PGND<0> IR354XX_SM-IR35411,IC,H73688-0A   I106 @BASEBOARD_FAB2_LIB.BASEBOARD_FAB2(SCH_1):PAGE219
 EU7A1    7 PGND<1> IR354XX_SM-IR35411,IC,H73688-0A   I106 @BASEBOARD_FAB2_LIB.BASEBOARD_FAB2(SCH_1):PAGE219
 EU7A1   40 PGND<2> IR354XX_SM-IR35411,IC,H73688-0A   I106 @BASEBOARD_FAB2_LIB.BASEBOARD_FAB2(SCH_1):PAGE219
 EU7A4    2   LGND IR354XX_SM-IR35411,IC,H73688-0A   I107 @BASEBOARD_FAB2_LIB.BASEBOARD_FAB2(SCH_1):PAGE219
 EU7A4    5 PGND<0> IR354XX_SM-IR35411,IC,H73688-0A   I107 @BASEBOARD_FAB2_LIB.BASEBOARD_FAB2(SCH_1):PAGE219
 EU7A4    7 PGND<1> IR354XX_SM-IR35411,IC,H73688-0A   I107 @BASEBOARD_FAB2_LIB.BASEBOARD_FAB2(SCH_1):PAGE219
 EU7A4   40 PGND<2> IR354XX_SM-IR35411,IC,H73688-0A   I107 @BASEBOARD_FAB2_LIB.BASEBOARD_FAB2(SCH_1):PAGE219
 R7A20    2      B RES_0402-68.1K,1%,1/16W,EMPTY,A   I108 @BASEBOARD_FAB2_LIB.BASEBOARD_FAB2(SCH_1):PAGE219
 R7A21    2      B RES_0402-68.1K,1%,1/16W,EMPTY,A   I110 @BASEBOARD_FAB2_LIB.BASEBOARD_FAB2(SCH_1):PAGE219
  R4L4    2      B RES_0603-120.0,1%,1/10W,CHIP,GA    I58 @BASEBOARD_FAB2_LIB.BASEBOARD_FAB2(SCH_1):PAGE220
  C3L6    2      B CAPP_3018-470UF,2.5V,20%,ALUM,A    I75 @BASEBOARD_FAB2_LIB.BASEBOARD_FAB2(SCH_1):PAGE220
 C3L14    2      B CAPP_3018-470UF,2.5V,20%,ALUM,A    I76 @BASEBOARD_FAB2_LIB.BASEBOARD_FAB2(SCH_1):PAGE220
  C6A5    2      B CAPP_3018-470UF,2.5V,20%,ALUM,A    I77 @BASEBOARD_FAB2_LIB.BASEBOARD_FAB2(SCH_1):PAGE220
  C4L5    2      B CAPP_3018-470UF,2.5V,20%,ALUM,A    I78 @BASEBOARD_FAB2_LIB.BASEBOARD_FAB2(SCH_1):PAGE220
 C5L15    2      B CAP_A_0603V-47UF,4V,20%,X5R,60A   I192 @BASEBOARD_FAB2_LIB.BASEBOARD_FAB2(SCH_1):PAGE220
  C5A5    2      B CAP_A_0603V-47UF,4V,20%,X5R,60A   I193 @BASEBOARD_FAB2_LIB.BASEBOARD_FAB2(SCH_1):PAGE220
  C5B1    2      B CAP_A_0603V-47UF,4V,20%,X5R,60A   I194 @BASEBOARD_FAB2_LIB.BASEBOARD_FAB2(SCH_1):PAGE220
  C5M9    2      B CAP_A_0603V-47UF,4V,20%,X5R,60A   I195 @BASEBOARD_FAB2_LIB.BASEBOARD_FAB2(SCH_1):PAGE220
  C4M5    2      B CAP_A_0603V-47UF,4V,20%,X5R,60A   I196 @BASEBOARD_FAB2_LIB.BASEBOARD_FAB2(SCH_1):PAGE220
  C5B2    2      B CAP_A_0603V-47UF,4V,20%,X5R,60A   I197 @BASEBOARD_FAB2_LIB.BASEBOARD_FAB2(SCH_1):PAGE220
 C5M10    2      B CAP_A_0603V-47UF,4V,20%,X5R,60A   I198 @BASEBOARD_FAB2_LIB.BASEBOARD_FAB2(SCH_1):PAGE220
  C5M3    2      B CAP_A_0603V-47UF,4V,20%,X5R,60A   I199 @BASEBOARD_FAB2_LIB.BASEBOARD_FAB2(SCH_1):PAGE220
 C5M11    2      B CAP_A_0603V-47UF,4V,20%,X5R,60A   I200 @BASEBOARD_FAB2_LIB.BASEBOARD_FAB2(SCH_1):PAGE220
 SH4L1    2      B SHUNT_SH0201-EMPTY,N_A   I240 @BASEBOARD_FAB2_LIB.BASEBOARD_FAB2(SCH_1):PAGE220
 C4G16    2      B CAP_0402-1.0UF,16V,10%,X6S,D97A    I22 @BASEBOARD_FAB2_LIB.BASEBOARD_FAB2(SCH_1):PAGE221
 C4G24    2      B CAP_0805LF-22UF,4V,20%,X6S,C95A    I24 @BASEBOARD_FAB2_LIB.BASEBOARD_FAB2(SCH_1):PAGE221
 C4A10    2      B CAP_0402-1.0UF,16V,10%,X6S,D97A    I12 @BASEBOARD_FAB2_LIB.BASEBOARD_FAB2(SCH_1):PAGE222
  C4A1    2      B CAP_0805LF-22UF,4V,20%,X6S,C95A    I28 @BASEBOARD_FAB2_LIB.BASEBOARD_FAB2(SCH_1):PAGE222
 C1G23    2      B CAP_A_0402V-1.0UF,6.3V,10%,X6SA    I44 @BASEBOARD_FAB2_LIB.BASEBOARD_FAB2(SCH_1):PAGE223
 C1G17    2      B CAP_0805LF-22UF,4V,20%,X6S,C95A     I6 @BASEBOARD_FAB2_LIB.BASEBOARD_FAB2(SCH_1):PAGE224
  C9U6    2      B CAP_0805-10UF,16V,10%,X6S,C953A    I45 @BASEBOARD_FAB2_LIB.BASEBOARD_FAB2(SCH_1):PAGE224
  C9U4    2      B CAP_0805-10UF,16V,10%,X6S,C953A    I46 @BASEBOARD_FAB2_LIB.BASEBOARD_FAB2(SCH_1):PAGE224
  C9T4    2      B CAP_0805-10UF,16V,10%,X6S,C953A    I47 @BASEBOARD_FAB2_LIB.BASEBOARD_FAB2(SCH_1):PAGE224
 C1F27    2      B CAP_0402-1.0UF,16V,10%,X6S,D97A    I48 @BASEBOARD_FAB2_LIB.BASEBOARD_FAB2(SCH_1):PAGE224
  C1G6    2      B CAP_0402-1.0UF,16V,10%,X6S,D97A    I50 @BASEBOARD_FAB2_LIB.BASEBOARD_FAB2(SCH_1):PAGE224
 C1G14    2      B CAP_A_0402V-0.1UF,16V,10%,X7R,A    I51 @BASEBOARD_FAB2_LIB.BASEBOARD_FAB2(SCH_1):PAGE224
  C1G5    2      B CAP_0402-0.22UF,16V,10%,X7R,A3A    I54 @BASEBOARD_FAB2_LIB.BASEBOARD_FAB2(SCH_1):PAGE224
 C1G20    2      B CAP_0805LF-22UF,4V,20%,X6S,C95A    I68 @BASEBOARD_FAB2_LIB.BASEBOARD_FAB2(SCH_1):PAGE224
 C1G29    2      B CAP_0402-0.22UF,16V,10%,X7R,A3A    I72 @BASEBOARD_FAB2_LIB.BASEBOARD_FAB2(SCH_1):PAGE224
 C1G28    2      B CAP_0402-1.0UF,16V,10%,X6S,D97A    I77 @BASEBOARD_FAB2_LIB.BASEBOARD_FAB2(SCH_1):PAGE224
 C1F28    2      B CAP_A_0402V-0.1UF,16V,10%,X7R,A    I78 @BASEBOARD_FAB2_LIB.BASEBOARD_FAB2(SCH_1):PAGE224
 C1G13    2      B CAP_0402-1.0UF,16V,10%,X6S,D97A    I79 @BASEBOARD_FAB2_LIB.BASEBOARD_FAB2(SCH_1):PAGE224
  C9U3    2      B CAP_0805-10UF,16V,10%,X6S,C953A    I80 @BASEBOARD_FAB2_LIB.BASEBOARD_FAB2(SCH_1):PAGE224
  C9T6    2      B CAP_0805-10UF,16V,10%,X6S,C953A    I81 @BASEBOARD_FAB2_LIB.BASEBOARD_FAB2(SCH_1):PAGE224
  C9T9    2      B CAP_0805-10UF,16V,10%,X6S,C953A    I84 @BASEBOARD_FAB2_LIB.BASEBOARD_FAB2(SCH_1):PAGE224
 EU1G1    2   LGND IR354XX_SM-IR35411,IC,H73688-0A   I110 @BASEBOARD_FAB2_LIB.BASEBOARD_FAB2(SCH_1):PAGE224
 EU1G1    5 PGND<0> IR354XX_SM-IR35411,IC,H73688-0A   I110 @BASEBOARD_FAB2_LIB.BASEBOARD_FAB2(SCH_1):PAGE224
 EU1G1    7 PGND<1> IR354XX_SM-IR35411,IC,H73688-0A   I110 @BASEBOARD_FAB2_LIB.BASEBOARD_FAB2(SCH_1):PAGE224
 EU1G1   40 PGND<2> IR354XX_SM-IR35411,IC,H73688-0A   I110 @BASEBOARD_FAB2_LIB.BASEBOARD_FAB2(SCH_1):PAGE224
 EU1F1    2   LGND IR354XX_SM-IR35411,IC,H73688-0A   I111 @BASEBOARD_FAB2_LIB.BASEBOARD_FAB2(SCH_1):PAGE224
 EU1F1    5 PGND<0> IR354XX_SM-IR35411,IC,H73688-0A   I111 @BASEBOARD_FAB2_LIB.BASEBOARD_FAB2(SCH_1):PAGE224
 EU1F1    7 PGND<1> IR354XX_SM-IR35411,IC,H73688-0A   I111 @BASEBOARD_FAB2_LIB.BASEBOARD_FAB2(SCH_1):PAGE224
 EU1F1   40 PGND<2> IR354XX_SM-IR35411,IC,H73688-0A   I111 @BASEBOARD_FAB2_LIB.BASEBOARD_FAB2(SCH_1):PAGE224
 R1G26    2      B RES_0402-68.1K,1%,1/16W,EMPTY,A   I112 @BASEBOARD_FAB2_LIB.BASEBOARD_FAB2(SCH_1):PAGE224
 R1G25    2      B RES_0402-68.1K,1%,1/16W,EMPTY,A   I114 @BASEBOARD_FAB2_LIB.BASEBOARD_FAB2(SCH_1):PAGE224
 R1G20    2      B RES_0603-120.0,1%,1/10W,CHIP,GA    I58 @BASEBOARD_FAB2_LIB.BASEBOARD_FAB2(SCH_1):PAGE225
  C9T5    2      B CAPP_3018-470UF,2.5V,20%,ALUM,A    I75 @BASEBOARD_FAB2_LIB.BASEBOARD_FAB2(SCH_1):PAGE225
  C9U2    2      B CAPP_3018-470UF,2.5V,20%,ALUM,A    I76 @BASEBOARD_FAB2_LIB.BASEBOARD_FAB2(SCH_1):PAGE225
  C9U9    2      B CAPP_3018-470UF,2.5V,20%,ALUM,A    I77 @BASEBOARD_FAB2_LIB.BASEBOARD_FAB2(SCH_1):PAGE225
  C9U5    2      B CAPP_3018-470UF,2.5V,20%,ALUM,A    I78 @BASEBOARD_FAB2_LIB.BASEBOARD_FAB2(SCH_1):PAGE225
  C8T4    2      B CAP_A_0603V-47UF,4V,20%,X5R,60A   I196 @BASEBOARD_FAB2_LIB.BASEBOARD_FAB2(SCH_1):PAGE225
  C2G8    2      B CAP_A_0603V-47UF,4V,20%,X5R,60A   I197 @BASEBOARD_FAB2_LIB.BASEBOARD_FAB2(SCH_1):PAGE225
  C8T2    2      B CAP_A_0603V-47UF,4V,20%,X5R,60A   I198 @BASEBOARD_FAB2_LIB.BASEBOARD_FAB2(SCH_1):PAGE225
 C8U13    2      B CAP_A_0603V-47UF,4V,20%,X5R,60A   I199 @BASEBOARD_FAB2_LIB.BASEBOARD_FAB2(SCH_1):PAGE225
 C2G15    2      B CAP_A_0603V-47UF,4V,20%,X5R,60A   I200 @BASEBOARD_FAB2_LIB.BASEBOARD_FAB2(SCH_1):PAGE225
  C2F1    2      B CAP_A_0603V-47UF,4V,20%,X5R,60A   I201 @BASEBOARD_FAB2_LIB.BASEBOARD_FAB2(SCH_1):PAGE225
  C8T1    2      B CAP_A_0603V-47UF,4V,20%,X5R,60A   I202 @BASEBOARD_FAB2_LIB.BASEBOARD_FAB2(SCH_1):PAGE225
  C8U9    2      B CAP_A_0603V-47UF,4V,20%,X5R,60A   I203 @BASEBOARD_FAB2_LIB.BASEBOARD_FAB2(SCH_1):PAGE225
 C8T11    2      B CAP_A_0603V-47UF,4V,20%,X5R,60A   I204 @BASEBOARD_FAB2_LIB.BASEBOARD_FAB2(SCH_1):PAGE225
 SH7U2    2      B SHUNT_SH0201-EMPTY,N_A   I244 @BASEBOARD_FAB2_LIB.BASEBOARD_FAB2(SCH_1):PAGE225
  C1B2    2      B CAP_A_0402V-0.1UF,16V,10%,X7R,A    I44 @BASEBOARD_FAB2_LIB.BASEBOARD_FAB2(SCH_1):PAGE226
 C1A12    2      B CAP_0805LF-22UF,4V,20%,X6S,C95A     I6 @BASEBOARD_FAB2_LIB.BASEBOARD_FAB2(SCH_1):PAGE227
 C9L11    2      B CAP_0805-10UF,16V,10%,X6S,C953A    I45 @BASEBOARD_FAB2_LIB.BASEBOARD_FAB2(SCH_1):PAGE227
 C9L10    2      B CAP_0805-10UF,16V,10%,X6S,C953A    I46 @BASEBOARD_FAB2_LIB.BASEBOARD_FAB2(SCH_1):PAGE227
  C9L6    2      B CAP_0805-10UF,16V,10%,X6S,C953A    I47 @BASEBOARD_FAB2_LIB.BASEBOARD_FAB2(SCH_1):PAGE227
 C1A19    2      B CAP_0402-1.0UF,16V,10%,X6S,D97A    I48 @BASEBOARD_FAB2_LIB.BASEBOARD_FAB2(SCH_1):PAGE227
 C1B20    2      B CAP_0402-1.0UF,16V,10%,X6S,D97A    I50 @BASEBOARD_FAB2_LIB.BASEBOARD_FAB2(SCH_1):PAGE227
 C1A10    2      B CAP_A_0402V-0.1UF,16V,10%,X7R,A    I51 @BASEBOARD_FAB2_LIB.BASEBOARD_FAB2(SCH_1):PAGE227
 C1B21    2      B CAP_0402-0.22UF,16V,10%,X7R,A3A    I54 @BASEBOARD_FAB2_LIB.BASEBOARD_FAB2(SCH_1):PAGE227
  C1A1    2      B CAP_0805LF-22UF,4V,20%,X6S,C95A    I68 @BASEBOARD_FAB2_LIB.BASEBOARD_FAB2(SCH_1):PAGE227
 C1A13    2      B CAP_0402-0.22UF,16V,10%,X7R,A3A    I72 @BASEBOARD_FAB2_LIB.BASEBOARD_FAB2(SCH_1):PAGE227
  C1A6    2      B CAP_0402-1.0UF,16V,10%,X6S,D97A    I77 @BASEBOARD_FAB2_LIB.BASEBOARD_FAB2(SCH_1):PAGE227
 C1A20    2      B CAP_A_0402V-0.1UF,16V,10%,X7R,A    I78 @BASEBOARD_FAB2_LIB.BASEBOARD_FAB2(SCH_1):PAGE227
  C1A9    2      B CAP_0402-1.0UF,16V,10%,X6S,D97A    I79 @BASEBOARD_FAB2_LIB.BASEBOARD_FAB2(SCH_1):PAGE227
  C9L5    2      B CAP_0805-10UF,16V,10%,X6S,C953A    I80 @BASEBOARD_FAB2_LIB.BASEBOARD_FAB2(SCH_1):PAGE227
 C9L13    2      B CAP_0805-10UF,16V,10%,X6S,C953A    I81 @BASEBOARD_FAB2_LIB.BASEBOARD_FAB2(SCH_1):PAGE227
 C9L14    2      B CAP_0805-10UF,16V,10%,X6S,C953A    I84 @BASEBOARD_FAB2_LIB.BASEBOARD_FAB2(SCH_1):PAGE227
 EU1A2    2   LGND IR354XX_SM-IR35411,IC,H73688-0A   I101 @BASEBOARD_FAB2_LIB.BASEBOARD_FAB2(SCH_1):PAGE227
 EU1A2    5 PGND<0> IR354XX_SM-IR35411,IC,H73688-0A   I101 @BASEBOARD_FAB2_LIB.BASEBOARD_FAB2(SCH_1):PAGE227
 EU1A2    7 PGND<1> IR354XX_SM-IR35411,IC,H73688-0A   I101 @BASEBOARD_FAB2_LIB.BASEBOARD_FAB2(SCH_1):PAGE227
 EU1A2   40 PGND<2> IR354XX_SM-IR35411,IC,H73688-0A   I101 @BASEBOARD_FAB2_LIB.BASEBOARD_FAB2(SCH_1):PAGE227
 EU1A1    2   LGND IR354XX_SM-IR35411,IC,H73688-0A   I102 @BASEBOARD_FAB2_LIB.BASEBOARD_FAB2(SCH_1):PAGE227
 EU1A1    5 PGND<0> IR354XX_SM-IR35411,IC,H73688-0A   I102 @BASEBOARD_FAB2_LIB.BASEBOARD_FAB2(SCH_1):PAGE227
 EU1A1    7 PGND<1> IR354XX_SM-IR35411,IC,H73688-0A   I102 @BASEBOARD_FAB2_LIB.BASEBOARD_FAB2(SCH_1):PAGE227
 EU1A1   40 PGND<2> IR354XX_SM-IR35411,IC,H73688-0A   I102 @BASEBOARD_FAB2_LIB.BASEBOARD_FAB2(SCH_1):PAGE227
  R1A3    2      B RES_0402-68.1K,1%,1/16W,EMPTY,A   I103 @BASEBOARD_FAB2_LIB.BASEBOARD_FAB2(SCH_1):PAGE227
  R1A2    2      B RES_0402-68.1K,1%,1/16W,EMPTY,A   I105 @BASEBOARD_FAB2_LIB.BASEBOARD_FAB2(SCH_1):PAGE227
  R1A1    2      B RES_0603-120.0,1%,1/10W,CHIP,GA    I58 @BASEBOARD_FAB2_LIB.BASEBOARD_FAB2(SCH_1):PAGE228
  C9L9    2      B CAPP_3018-470UF,2.5V,20%,ALUM,A    I75 @BASEBOARD_FAB2_LIB.BASEBOARD_FAB2(SCH_1):PAGE228
 C9L12    2      B CAPP_3018-470UF,2.5V,20%,ALUM,A    I76 @BASEBOARD_FAB2_LIB.BASEBOARD_FAB2(SCH_1):PAGE228
  C9L4    2      B CAPP_3018-470UF,2.5V,20%,ALUM,A    I77 @BASEBOARD_FAB2_LIB.BASEBOARD_FAB2(SCH_1):PAGE228
  C9L2    2      B CAPP_3018-470UF,2.5V,20%,ALUM,A    I78 @BASEBOARD_FAB2_LIB.BASEBOARD_FAB2(SCH_1):PAGE228
 C1B10    2      B CAPP_2626-270UF,16V,20%,OSCON,A   I175 @BASEBOARD_FAB2_LIB.BASEBOARD_FAB2(SCH_1):PAGE228
  C8M8    2      B CAP_A_0603V-47UF,4V,20%,X5R,60A   I198 @BASEBOARD_FAB2_LIB.BASEBOARD_FAB2(SCH_1):PAGE228
  C2A5    2      B CAP_A_0603V-47UF,4V,20%,X5R,60A   I199 @BASEBOARD_FAB2_LIB.BASEBOARD_FAB2(SCH_1):PAGE228
  C2B1    2      B CAP_A_0603V-47UF,4V,20%,X5R,60A   I200 @BASEBOARD_FAB2_LIB.BASEBOARD_FAB2(SCH_1):PAGE228
 C8L12    2      B CAP_A_0603V-47UF,4V,20%,X5R,60A   I201 @BASEBOARD_FAB2_LIB.BASEBOARD_FAB2(SCH_1):PAGE228
  C7M5    2      B CAP_A_0603V-47UF,4V,20%,X5R,60A   I202 @BASEBOARD_FAB2_LIB.BASEBOARD_FAB2(SCH_1):PAGE228
 C8M10    2      B CAP_A_0603V-47UF,4V,20%,X5R,60A   I203 @BASEBOARD_FAB2_LIB.BASEBOARD_FAB2(SCH_1):PAGE228
  C2B2    2      B CAP_A_0603V-47UF,4V,20%,X5R,60A   I204 @BASEBOARD_FAB2_LIB.BASEBOARD_FAB2(SCH_1):PAGE228
  C8M9    2      B CAP_A_0603V-47UF,4V,20%,X5R,60A   I205 @BASEBOARD_FAB2_LIB.BASEBOARD_FAB2(SCH_1):PAGE228
  C8M2    2      B CAP_A_0603V-47UF,4V,20%,X5R,60A   I206 @BASEBOARD_FAB2_LIB.BASEBOARD_FAB2(SCH_1):PAGE228
 SH7L1    2      B SHUNT_SH0201-EMPTY,N_A   I246 @BASEBOARD_FAB2_LIB.BASEBOARD_FAB2(SCH_1):PAGE228
 C4G21    2      B CAP_0402-1.0UF,16V,10%,X6S,D97A    I21 @BASEBOARD_FAB2_LIB.BASEBOARD_FAB2(SCH_1):PAGE229
  C6F6    2      B CAP_0603LF-10UF,4V,20%,X6S,E15A   I122 @BASEBOARD_FAB2_LIB.BASEBOARD_FAB2(SCH_1):PAGE231
  C4T6    2      B CAP_0603LF-10UF,4V,20%,X6S,E15A   I124 @BASEBOARD_FAB2_LIB.BASEBOARD_FAB2(SCH_1):PAGE231
  C4T5    2      B CAP_0603LF-10UF,4V,20%,X6S,E15A   I125 @BASEBOARD_FAB2_LIB.BASEBOARD_FAB2(SCH_1):PAGE231
  C6G1    2      B CAP_0603LF-10UF,4V,20%,X6S,E15A   I126 @BASEBOARD_FAB2_LIB.BASEBOARD_FAB2(SCH_1):PAGE231
  C6G2    2      B CAP_0603LF-10UF,4V,20%,X6S,E15A   I128 @BASEBOARD_FAB2_LIB.BASEBOARD_FAB2(SCH_1):PAGE231
  C4U2    2      B CAP_0603LF-10UF,4V,20%,X6S,E15A   I129 @BASEBOARD_FAB2_LIB.BASEBOARD_FAB2(SCH_1):PAGE231
  C4U1    2      B CAP_0603LF-10UF,4V,20%,X6S,E15A   I130 @BASEBOARD_FAB2_LIB.BASEBOARD_FAB2(SCH_1):PAGE231
  C6G4    2      B CAP_0603LF-10UF,4V,20%,X6S,E15A   I131 @BASEBOARD_FAB2_LIB.BASEBOARD_FAB2(SCH_1):PAGE231
 R7F14    2      B RES_0402-10.0K,1%,1/16W,CHIP,GA   I136 @BASEBOARD_FAB2_LIB.BASEBOARD_FAB2(SCH_1):PAGE231
 C7F11    2      B CAP_0402LF-1000PF,50V,10%,X7R,A   I142 @BASEBOARD_FAB2_LIB.BASEBOARD_FAB2(SCH_1):PAGE231
  C6G5    2      B CAP_0603LF-10UF,4V,20%,X6S,E15A   I145 @BASEBOARD_FAB2_LIB.BASEBOARD_FAB2(SCH_1):PAGE231
  C4U4    2      B CAP_0603LF-10UF,4V,20%,X6S,E15A   I146 @BASEBOARD_FAB2_LIB.BASEBOARD_FAB2(SCH_1):PAGE231
  C4U3    2      B CAP_0603LF-10UF,4V,20%,X6S,E15A   I148 @BASEBOARD_FAB2_LIB.BASEBOARD_FAB2(SCH_1):PAGE231
  C6F5    2      B CAP_0603LF-10UF,4V,20%,X6S,E15A   I149 @BASEBOARD_FAB2_LIB.BASEBOARD_FAB2(SCH_1):PAGE231
 C3T10    2      B CAP_0402-1.0UF,16V,10%,X6S,D97A   I161 @BASEBOARD_FAB2_LIB.BASEBOARD_FAB2(SCH_1):PAGE231
 R7F35    1      A RES_0402-0.0,5%,1/16W,CHIP,G21A   I170 @BASEBOARD_FAB2_LIB.BASEBOARD_FAB2(SCH_1):PAGE231
  R7F7    2      B RES_0402-2.2,5%,1/16W,EMPTY,G2A   I174 @BASEBOARD_FAB2_LIB.BASEBOARD_FAB2(SCH_1):PAGE231
 R7F10    2      B RES_0603-120.0,1%,1/10W,CHIP,GA   I177 @BASEBOARD_FAB2_LIB.BASEBOARD_FAB2(SCH_1):PAGE231
  C6F4    2      B CAPP_7343LF-330UF,6.3V,20%,POSA   I180 @BASEBOARD_FAB2_LIB.BASEBOARD_FAB2(SCH_1):PAGE231
  C3T7    2      B CAP_0805-47UF,4V,20%,X6S,C9533A   I184 @BASEBOARD_FAB2_LIB.BASEBOARD_FAB2(SCH_1):PAGE231
  C3T9    2      B CAP_0805-47UF,4V,20%,X6S,C9533A   I186 @BASEBOARD_FAB2_LIB.BASEBOARD_FAB2(SCH_1):PAGE231
 EU7F1   41    GND NCP3232L_SM-IC,H86355-001   I193 @BASEBOARD_FAB2_LIB.BASEBOARD_FAB2(SCH_1):PAGE231
 EU7F1   16 PGND<0> NCP3232L_SM-IC,H86355-001   I193 @BASEBOARD_FAB2_LIB.BASEBOARD_FAB2(SCH_1):PAGE231
 EU7F1   17 PGND<1> NCP3232L_SM-IC,H86355-001   I193 @BASEBOARD_FAB2_LIB.BASEBOARD_FAB2(SCH_1):PAGE231
 EU7F1   18 PGND<2> NCP3232L_SM-IC,H86355-001   I193 @BASEBOARD_FAB2_LIB.BASEBOARD_FAB2(SCH_1):PAGE231
 EU7F1   19 PGND<3> NCP3232L_SM-IC,H86355-001   I193 @BASEBOARD_FAB2_LIB.BASEBOARD_FAB2(SCH_1):PAGE231
 EU7F1   20 PGND<4> NCP3232L_SM-IC,H86355-001   I193 @BASEBOARD_FAB2_LIB.BASEBOARD_FAB2(SCH_1):PAGE231
 EU7F1   21 PGND<5> NCP3232L_SM-IC,H86355-001   I193 @BASEBOARD_FAB2_LIB.BASEBOARD_FAB2(SCH_1):PAGE231
 EU7F1   22 PGND<6> NCP3232L_SM-IC,H86355-001   I193 @BASEBOARD_FAB2_LIB.BASEBOARD_FAB2(SCH_1):PAGE231
 EU7F1   23 PGND<7> NCP3232L_SM-IC,H86355-001   I193 @BASEBOARD_FAB2_LIB.BASEBOARD_FAB2(SCH_1):PAGE231
 EU7F1   24 PGND<8> NCP3232L_SM-IC,H86355-001   I193 @BASEBOARD_FAB2_LIB.BASEBOARD_FAB2(SCH_1):PAGE231
 EU7F1   25 PGND<9> NCP3232L_SM-IC,H86355-001   I193 @BASEBOARD_FAB2_LIB.BASEBOARD_FAB2(SCH_1):PAGE231
 EU7F1   26 PGND<10> NCP3232L_SM-IC,H86355-001   I193 @BASEBOARD_FAB2_LIB.BASEBOARD_FAB2(SCH_1):PAGE231
 EU7F1   27 PGND<11> NCP3232L_SM-IC,H86355-001   I193 @BASEBOARD_FAB2_LIB.BASEBOARD_FAB2(SCH_1):PAGE231
 EU7F1   28 PGND<12> NCP3232L_SM-IC,H86355-001   I193 @BASEBOARD_FAB2_LIB.BASEBOARD_FAB2(SCH_1):PAGE231
 EU7F1   37 PGND<13> NCP3232L_SM-IC,H86355-001   I193 @BASEBOARD_FAB2_LIB.BASEBOARD_FAB2(SCH_1):PAGE231
  C7F6    2      B CAP_A_0402V-0.1UF,16V,10%,X7R,A   I205 @BASEBOARD_FAB2_LIB.BASEBOARD_FAB2(SCH_1):PAGE231
  C7F5    2      B CAP_0805-10UF,16V,10%,X6S,C953A   I209 @BASEBOARD_FAB2_LIB.BASEBOARD_FAB2(SCH_1):PAGE231
  C3T8    2      B CAP_0805-10UF,16V,10%,X6S,C953A   I210 @BASEBOARD_FAB2_LIB.BASEBOARD_FAB2(SCH_1):PAGE231
 C3T14    2      B CAP_0805-10UF,16V,10%,X6S,C953A   I211 @BASEBOARD_FAB2_LIB.BASEBOARD_FAB2(SCH_1):PAGE231
 C3T12    2      B CAP_0805-10UF,16V,10%,X6S,C953A   I215 @BASEBOARD_FAB2_LIB.BASEBOARD_FAB2(SCH_1):PAGE231
  C4T3    2      B CAPP_7343-220UF,4V,20%,POSCAP,A   I217 @BASEBOARD_FAB2_LIB.BASEBOARD_FAB2(SCH_1):PAGE231
  C4L2    2      B CAP_0603LF-10UF,4V,20%,X6S,E15A   I102 @BASEBOARD_FAB2_LIB.BASEBOARD_FAB2(SCH_1):PAGE232
  C6A3    2      B CAP_0603LF-10UF,4V,20%,X6S,E15A   I104 @BASEBOARD_FAB2_LIB.BASEBOARD_FAB2(SCH_1):PAGE232
  C6A2    2      B CAP_0603LF-10UF,4V,20%,X6S,E15A   I105 @BASEBOARD_FAB2_LIB.BASEBOARD_FAB2(SCH_1):PAGE232
  C4L3    2      B CAP_0603LF-10UF,4V,20%,X6S,E15A   I106 @BASEBOARD_FAB2_LIB.BASEBOARD_FAB2(SCH_1):PAGE232
  C4L4    2      B CAP_0603LF-10UF,4V,20%,X6S,E15A   I108 @BASEBOARD_FAB2_LIB.BASEBOARD_FAB2(SCH_1):PAGE232
  C6A7    2      B CAP_0603LF-10UF,4V,20%,X6S,E15A   I109 @BASEBOARD_FAB2_LIB.BASEBOARD_FAB2(SCH_1):PAGE232
  C6A6    2      B CAP_0603LF-10UF,4V,20%,X6S,E15A   I110 @BASEBOARD_FAB2_LIB.BASEBOARD_FAB2(SCH_1):PAGE232
  C4M3    2      B CAP_0603LF-10UF,4V,20%,X6S,E15A   I111 @BASEBOARD_FAB2_LIB.BASEBOARD_FAB2(SCH_1):PAGE232
  C4M4    2      B CAP_0603LF-10UF,4V,20%,X6S,E15A   I125 @BASEBOARD_FAB2_LIB.BASEBOARD_FAB2(SCH_1):PAGE232
  C6B2    2      B CAP_0603LF-10UF,4V,20%,X6S,E15A   I126 @BASEBOARD_FAB2_LIB.BASEBOARD_FAB2(SCH_1):PAGE232
  C6B1    2      B CAP_0603LF-10UF,4V,20%,X6S,E15A   I128 @BASEBOARD_FAB2_LIB.BASEBOARD_FAB2(SCH_1):PAGE232
  C4L1    2      B CAP_0603LF-10UF,4V,20%,X6S,E15A   I129 @BASEBOARD_FAB2_LIB.BASEBOARD_FAB2(SCH_1):PAGE232
 R7B20    1      A RES_0402-0.0,5%,1/16W,CHIP,G21A   I150 @BASEBOARD_FAB2_LIB.BASEBOARD_FAB2(SCH_1):PAGE232
  C3M9    2      B CAP_0402-1.0UF,16V,10%,X6S,D97A   I207 @BASEBOARD_FAB2_LIB.BASEBOARD_FAB2(SCH_1):PAGE232
 C7B12    2      B CAP_0402LF-1000PF,50V,10%,X7R,A   I209 @BASEBOARD_FAB2_LIB.BASEBOARD_FAB2(SCH_1):PAGE232
 EU7B1   41    GND NCP3232L_SM-IC,H86355-001   I214 @BASEBOARD_FAB2_LIB.BASEBOARD_FAB2(SCH_1):PAGE232
 EU7B1   16 PGND<0> NCP3232L_SM-IC,H86355-001   I214 @BASEBOARD_FAB2_LIB.BASEBOARD_FAB2(SCH_1):PAGE232
 EU7B1   17 PGND<1> NCP3232L_SM-IC,H86355-001   I214 @BASEBOARD_FAB2_LIB.BASEBOARD_FAB2(SCH_1):PAGE232
 EU7B1   18 PGND<2> NCP3232L_SM-IC,H86355-001   I214 @BASEBOARD_FAB2_LIB.BASEBOARD_FAB2(SCH_1):PAGE232
 EU7B1   19 PGND<3> NCP3232L_SM-IC,H86355-001   I214 @BASEBOARD_FAB2_LIB.BASEBOARD_FAB2(SCH_1):PAGE232
 EU7B1   20 PGND<4> NCP3232L_SM-IC,H86355-001   I214 @BASEBOARD_FAB2_LIB.BASEBOARD_FAB2(SCH_1):PAGE232
 EU7B1   21 PGND<5> NCP3232L_SM-IC,H86355-001   I214 @BASEBOARD_FAB2_LIB.BASEBOARD_FAB2(SCH_1):PAGE232
 EU7B1   22 PGND<6> NCP3232L_SM-IC,H86355-001   I214 @BASEBOARD_FAB2_LIB.BASEBOARD_FAB2(SCH_1):PAGE232
 EU7B1   23 PGND<7> NCP3232L_SM-IC,H86355-001   I214 @BASEBOARD_FAB2_LIB.BASEBOARD_FAB2(SCH_1):PAGE232
 EU7B1   24 PGND<8> NCP3232L_SM-IC,H86355-001   I214 @BASEBOARD_FAB2_LIB.BASEBOARD_FAB2(SCH_1):PAGE232
 EU7B1   25 PGND<9> NCP3232L_SM-IC,H86355-001   I214 @BASEBOARD_FAB2_LIB.BASEBOARD_FAB2(SCH_1):PAGE232
 EU7B1   26 PGND<10> NCP3232L_SM-IC,H86355-001   I214 @BASEBOARD_FAB2_LIB.BASEBOARD_FAB2(SCH_1):PAGE232
 EU7B1   27 PGND<11> NCP3232L_SM-IC,H86355-001   I214 @BASEBOARD_FAB2_LIB.BASEBOARD_FAB2(SCH_1):PAGE232
 EU7B1   28 PGND<12> NCP3232L_SM-IC,H86355-001   I214 @BASEBOARD_FAB2_LIB.BASEBOARD_FAB2(SCH_1):PAGE232
 EU7B1   37 PGND<13> NCP3232L_SM-IC,H86355-001   I214 @BASEBOARD_FAB2_LIB.BASEBOARD_FAB2(SCH_1):PAGE232
 R7A15    2      B RES_0402-2.2,5%,1/16W,EMPTY,G2A   I218 @BASEBOARD_FAB2_LIB.BASEBOARD_FAB2(SCH_1):PAGE232
 R7B10    2      B RES_0603-120.0,1%,1/10W,CHIP,GA   I227 @BASEBOARD_FAB2_LIB.BASEBOARD_FAB2(SCH_1):PAGE232
  C6B7    2      B CAPP_7343LF-330UF,6.3V,20%,POSA   I229 @BASEBOARD_FAB2_LIB.BASEBOARD_FAB2(SCH_1):PAGE232
  C6B3    2      B CAP_0805-47UF,4V,20%,X6S,C9533A   I236 @BASEBOARD_FAB2_LIB.BASEBOARD_FAB2(SCH_1):PAGE232
  C7B7    2      B CAP_0805-47UF,4V,20%,X6S,C9533A   I238 @BASEBOARD_FAB2_LIB.BASEBOARD_FAB2(SCH_1):PAGE232
  C7B6    2      B CAP_A_0402V-0.1UF,16V,10%,X7R,A   I252 @BASEBOARD_FAB2_LIB.BASEBOARD_FAB2(SCH_1):PAGE232
  C3M8    2      B CAP_0805-10UF,16V,10%,X6S,C953A   I259 @BASEBOARD_FAB2_LIB.BASEBOARD_FAB2(SCH_1):PAGE232
 C3M15    2      B CAP_0805-10UF,16V,10%,X6S,C953A   I260 @BASEBOARD_FAB2_LIB.BASEBOARD_FAB2(SCH_1):PAGE232
 C3M16    2      B CAP_0805-10UF,16V,10%,X6S,C953A   I261 @BASEBOARD_FAB2_LIB.BASEBOARD_FAB2(SCH_1):PAGE232
  C7B5    2      B CAP_0805-10UF,16V,10%,X6S,C953A   I262 @BASEBOARD_FAB2_LIB.BASEBOARD_FAB2(SCH_1):PAGE232
  C4M1    2      B CAPP_7343-220UF,4V,20%,POSCAP,A   I267 @BASEBOARD_FAB2_LIB.BASEBOARD_FAB2(SCH_1):PAGE232
  C7U4    2      B CAP_0603LF-10UF,4V,20%,X6S,E15A   I109 @BASEBOARD_FAB2_LIB.BASEBOARD_FAB2(SCH_1):PAGE233
  C7U5    2      B CAP_0603LF-10UF,4V,20%,X6S,E15A   I111 @BASEBOARD_FAB2_LIB.BASEBOARD_FAB2(SCH_1):PAGE233
  C7T2    2      B CAP_0603LF-10UF,4V,20%,X6S,E15A   I112 @BASEBOARD_FAB2_LIB.BASEBOARD_FAB2(SCH_1):PAGE233
  C7T3    2      B CAP_0603LF-10UF,4V,20%,X6S,E15A   I113 @BASEBOARD_FAB2_LIB.BASEBOARD_FAB2(SCH_1):PAGE233
  C7U6    2      B CAP_0603LF-10UF,4V,20%,X6S,E15A   I115 @BASEBOARD_FAB2_LIB.BASEBOARD_FAB2(SCH_1):PAGE233
  C3F3    2      B CAP_0603LF-10UF,4V,20%,X6S,E15A   I116 @BASEBOARD_FAB2_LIB.BASEBOARD_FAB2(SCH_1):PAGE233
  C3F4    2      B CAP_0603LF-10UF,4V,20%,X6S,E15A   I117 @BASEBOARD_FAB2_LIB.BASEBOARD_FAB2(SCH_1):PAGE233
  C3G3    2      B CAP_0603LF-10UF,4V,20%,X6S,E15A   I118 @BASEBOARD_FAB2_LIB.BASEBOARD_FAB2(SCH_1):PAGE233
  C3G7    2      B CAP_0603LF-10UF,4V,20%,X6S,E15A   I132 @BASEBOARD_FAB2_LIB.BASEBOARD_FAB2(SCH_1):PAGE233
  C3G4    2      B CAP_0603LF-10UF,4V,20%,X6S,E15A   I133 @BASEBOARD_FAB2_LIB.BASEBOARD_FAB2(SCH_1):PAGE233
  C3G8    2      B CAP_0603LF-10UF,4V,20%,X6S,E15A   I135 @BASEBOARD_FAB2_LIB.BASEBOARD_FAB2(SCH_1):PAGE233
  C7U3    2      B CAP_0603LF-10UF,4V,20%,X6S,E15A   I136 @BASEBOARD_FAB2_LIB.BASEBOARD_FAB2(SCH_1):PAGE233
 R4G25    1      A RES_0402-0.0,5%,1/16W,CHIP,G21A   I157 @BASEBOARD_FAB2_LIB.BASEBOARD_FAB2(SCH_1):PAGE233
  R4G5    2      B RES_0402-10.0K,1%,1/16W,CHIP,GA   I182 @BASEBOARD_FAB2_LIB.BASEBOARD_FAB2(SCH_1):PAGE233
  C4G4    2      B CAP_0402-1.0UF,16V,10%,X6S,D97A   I196 @BASEBOARD_FAB2_LIB.BASEBOARD_FAB2(SCH_1):PAGE233
  C4G9    2      B CAP_0402LF-1000PF,50V,10%,X7R,A   I201 @BASEBOARD_FAB2_LIB.BASEBOARD_FAB2(SCH_1):PAGE233
  R4F6    2      B RES_0402-2.2,5%,1/16W,EMPTY,G2A   I208 @BASEBOARD_FAB2_LIB.BASEBOARD_FAB2(SCH_1):PAGE233
  R4G6    2      B RES_0603-120.0,1%,1/10W,CHIP,GA   I211 @BASEBOARD_FAB2_LIB.BASEBOARD_FAB2(SCH_1):PAGE233
  C4F7    2      B CAPP_7343LF-330UF,6.3V,20%,POSA   I217 @BASEBOARD_FAB2_LIB.BASEBOARD_FAB2(SCH_1):PAGE233
  C6U3    2      B CAP_0805-47UF,4V,20%,X6S,C9533A   I221 @BASEBOARD_FAB2_LIB.BASEBOARD_FAB2(SCH_1):PAGE233
  C6U2    2      B CAP_0805-47UF,4V,20%,X6S,C9533A   I223 @BASEBOARD_FAB2_LIB.BASEBOARD_FAB2(SCH_1):PAGE233
 EU4G1   41    GND NCP3232L_SM-IC,H86355-001   I225 @BASEBOARD_FAB2_LIB.BASEBOARD_FAB2(SCH_1):PAGE233
 EU4G1   16 PGND<0> NCP3232L_SM-IC,H86355-001   I225 @BASEBOARD_FAB2_LIB.BASEBOARD_FAB2(SCH_1):PAGE233
 EU4G1   17 PGND<1> NCP3232L_SM-IC,H86355-001   I225 @BASEBOARD_FAB2_LIB.BASEBOARD_FAB2(SCH_1):PAGE233
 EU4G1   18 PGND<2> NCP3232L_SM-IC,H86355-001   I225 @BASEBOARD_FAB2_LIB.BASEBOARD_FAB2(SCH_1):PAGE233
 EU4G1   19 PGND<3> NCP3232L_SM-IC,H86355-001   I225 @BASEBOARD_FAB2_LIB.BASEBOARD_FAB2(SCH_1):PAGE233
 EU4G1   20 PGND<4> NCP3232L_SM-IC,H86355-001   I225 @BASEBOARD_FAB2_LIB.BASEBOARD_FAB2(SCH_1):PAGE233
 EU4G1   21 PGND<5> NCP3232L_SM-IC,H86355-001   I225 @BASEBOARD_FAB2_LIB.BASEBOARD_FAB2(SCH_1):PAGE233
 EU4G1   22 PGND<6> NCP3232L_SM-IC,H86355-001   I225 @BASEBOARD_FAB2_LIB.BASEBOARD_FAB2(SCH_1):PAGE233
 EU4G1   23 PGND<7> NCP3232L_SM-IC,H86355-001   I225 @BASEBOARD_FAB2_LIB.BASEBOARD_FAB2(SCH_1):PAGE233
 EU4G1   24 PGND<8> NCP3232L_SM-IC,H86355-001   I225 @BASEBOARD_FAB2_LIB.BASEBOARD_FAB2(SCH_1):PAGE233
 EU4G1   25 PGND<9> NCP3232L_SM-IC,H86355-001   I225 @BASEBOARD_FAB2_LIB.BASEBOARD_FAB2(SCH_1):PAGE233
 EU4G1   26 PGND<10> NCP3232L_SM-IC,H86355-001   I225 @BASEBOARD_FAB2_LIB.BASEBOARD_FAB2(SCH_1):PAGE233
 EU4G1   27 PGND<11> NCP3232L_SM-IC,H86355-001   I225 @BASEBOARD_FAB2_LIB.BASEBOARD_FAB2(SCH_1):PAGE233
 EU4G1   28 PGND<12> NCP3232L_SM-IC,H86355-001   I225 @BASEBOARD_FAB2_LIB.BASEBOARD_FAB2(SCH_1):PAGE233
 EU4G1   37 PGND<13> NCP3232L_SM-IC,H86355-001   I225 @BASEBOARD_FAB2_LIB.BASEBOARD_FAB2(SCH_1):PAGE233
  C6U5    2      B CAP_A_0402V-0.1UF,16V,10%,X7R,A   I242 @BASEBOARD_FAB2_LIB.BASEBOARD_FAB2(SCH_1):PAGE233
  C6U4    2      B CAP_0805-10UF,16V,10%,X6S,C953A   I248 @BASEBOARD_FAB2_LIB.BASEBOARD_FAB2(SCH_1):PAGE233
  C4G2    2      B CAP_0805-10UF,16V,10%,X6S,C953A   I253 @BASEBOARD_FAB2_LIB.BASEBOARD_FAB2(SCH_1):PAGE233
  C6U7    2      B CAP_0805-10UF,16V,10%,X6S,C953A   I254 @BASEBOARD_FAB2_LIB.BASEBOARD_FAB2(SCH_1):PAGE233
  C6U8    2      B CAP_0805-10UF,16V,10%,X6S,C953A   I255 @BASEBOARD_FAB2_LIB.BASEBOARD_FAB2(SCH_1):PAGE233
 C4F11    2      B CAPP_7343-220UF,4V,20%,POSCAP,A   I256 @BASEBOARD_FAB2_LIB.BASEBOARD_FAB2(SCH_1):PAGE233
 R4B14    1      A RES_0402-0.0,5%,1/16W,CHIP,G21A    I29 @BASEBOARD_FAB2_LIB.BASEBOARD_FAB2(SCH_1):PAGE234
  C3B2    2      B CAP_0603LF-10UF,4V,20%,X6S,E15A    I84 @BASEBOARD_FAB2_LIB.BASEBOARD_FAB2(SCH_1):PAGE234
  C3A8    2      B CAP_0603LF-10UF,4V,20%,X6S,E15A    I86 @BASEBOARD_FAB2_LIB.BASEBOARD_FAB2(SCH_1):PAGE234
  C7L3    2      B CAP_0603LF-10UF,4V,20%,X6S,E15A    I87 @BASEBOARD_FAB2_LIB.BASEBOARD_FAB2(SCH_1):PAGE234
  C7L2    2      B CAP_0603LF-10UF,4V,20%,X6S,E15A    I88 @BASEBOARD_FAB2_LIB.BASEBOARD_FAB2(SCH_1):PAGE234
  C7L7    2      B CAP_0603LF-10UF,4V,20%,X6S,E15A    I89 @BASEBOARD_FAB2_LIB.BASEBOARD_FAB2(SCH_1):PAGE234
  C7L6    2      B CAP_0603LF-10UF,4V,20%,X6S,E15A    I90 @BASEBOARD_FAB2_LIB.BASEBOARD_FAB2(SCH_1):PAGE234
  C7M4    2      B CAP_0603LF-10UF,4V,20%,X6S,E15A    I91 @BASEBOARD_FAB2_LIB.BASEBOARD_FAB2(SCH_1):PAGE234
  C7M3    2      B CAP_0603LF-10UF,4V,20%,X6S,E15A    I92 @BASEBOARD_FAB2_LIB.BASEBOARD_FAB2(SCH_1):PAGE234
  C3A4    2      B CAP_0603LF-10UF,4V,20%,X6S,E15A    I93 @BASEBOARD_FAB2_LIB.BASEBOARD_FAB2(SCH_1):PAGE234
  C3B1    2      B CAP_0603LF-10UF,4V,20%,X6S,E15A    I94 @BASEBOARD_FAB2_LIB.BASEBOARD_FAB2(SCH_1):PAGE234
  C3A7    2      B CAP_0603LF-10UF,4V,20%,X6S,E15A    I95 @BASEBOARD_FAB2_LIB.BASEBOARD_FAB2(SCH_1):PAGE234
  C3A3    2      B CAP_0603LF-10UF,4V,20%,X6S,E15A    I97 @BASEBOARD_FAB2_LIB.BASEBOARD_FAB2(SCH_1):PAGE234
  C4B8    2      B CAP_0402LF-1000PF,50V,10%,X7R,A   I139 @BASEBOARD_FAB2_LIB.BASEBOARD_FAB2(SCH_1):PAGE234
 C6L11    2      B CAP_0402-1.0UF,16V,10%,X6S,D97A   I152 @BASEBOARD_FAB2_LIB.BASEBOARD_FAB2(SCH_1):PAGE234
  R4A7    2      B RES_0402-2.2,5%,1/16W,EMPTY,G2A   I162 @BASEBOARD_FAB2_LIB.BASEBOARD_FAB2(SCH_1):PAGE234
  C3B3    2      B CAPP_7343LF-330UF,6.3V,20%,POSA   I167 @BASEBOARD_FAB2_LIB.BASEBOARD_FAB2(SCH_1):PAGE234
  C4B3    2      B CAP_0805-47UF,4V,20%,X6S,C9533A   I177 @BASEBOARD_FAB2_LIB.BASEBOARD_FAB2(SCH_1):PAGE234
  C4B2    2      B CAP_0805-47UF,4V,20%,X6S,C9533A   I180 @BASEBOARD_FAB2_LIB.BASEBOARD_FAB2(SCH_1):PAGE234
  R4B2    2      B RES_0603-120.0,1%,1/10W,CHIP,GA   I183 @BASEBOARD_FAB2_LIB.BASEBOARD_FAB2(SCH_1):PAGE234
 EU4A3   41    GND NCP3232L_SM-IC,H86355-001   I184 @BASEBOARD_FAB2_LIB.BASEBOARD_FAB2(SCH_1):PAGE234
 EU4A3   16 PGND<0> NCP3232L_SM-IC,H86355-001   I184 @BASEBOARD_FAB2_LIB.BASEBOARD_FAB2(SCH_1):PAGE234
 EU4A3   17 PGND<1> NCP3232L_SM-IC,H86355-001   I184 @BASEBOARD_FAB2_LIB.BASEBOARD_FAB2(SCH_1):PAGE234
 EU4A3   18 PGND<2> NCP3232L_SM-IC,H86355-001   I184 @BASEBOARD_FAB2_LIB.BASEBOARD_FAB2(SCH_1):PAGE234
 EU4A3   19 PGND<3> NCP3232L_SM-IC,H86355-001   I184 @BASEBOARD_FAB2_LIB.BASEBOARD_FAB2(SCH_1):PAGE234
 EU4A3   20 PGND<4> NCP3232L_SM-IC,H86355-001   I184 @BASEBOARD_FAB2_LIB.BASEBOARD_FAB2(SCH_1):PAGE234
 EU4A3   21 PGND<5> NCP3232L_SM-IC,H86355-001   I184 @BASEBOARD_FAB2_LIB.BASEBOARD_FAB2(SCH_1):PAGE234
 EU4A3   22 PGND<6> NCP3232L_SM-IC,H86355-001   I184 @BASEBOARD_FAB2_LIB.BASEBOARD_FAB2(SCH_1):PAGE234
 EU4A3   23 PGND<7> NCP3232L_SM-IC,H86355-001   I184 @BASEBOARD_FAB2_LIB.BASEBOARD_FAB2(SCH_1):PAGE234
 EU4A3   24 PGND<8> NCP3232L_SM-IC,H86355-001   I184 @BASEBOARD_FAB2_LIB.BASEBOARD_FAB2(SCH_1):PAGE234
 EU4A3   25 PGND<9> NCP3232L_SM-IC,H86355-001   I184 @BASEBOARD_FAB2_LIB.BASEBOARD_FAB2(SCH_1):PAGE234
 EU4A3   26 PGND<10> NCP3232L_SM-IC,H86355-001   I184 @BASEBOARD_FAB2_LIB.BASEBOARD_FAB2(SCH_1):PAGE234
 EU4A3   27 PGND<11> NCP3232L_SM-IC,H86355-001   I184 @BASEBOARD_FAB2_LIB.BASEBOARD_FAB2(SCH_1):PAGE234
 EU4A3   28 PGND<12> NCP3232L_SM-IC,H86355-001   I184 @BASEBOARD_FAB2_LIB.BASEBOARD_FAB2(SCH_1):PAGE234
 EU4A3   37 PGND<13> NCP3232L_SM-IC,H86355-001   I184 @BASEBOARD_FAB2_LIB.BASEBOARD_FAB2(SCH_1):PAGE234
 C4A20    2      B CAP_A_0402V-0.1UF,16V,10%,X7R,A   I199 @BASEBOARD_FAB2_LIB.BASEBOARD_FAB2(SCH_1):PAGE234
 C6L10    2      B CAP_0805-10UF,16V,10%,X6S,C953A   I202 @BASEBOARD_FAB2_LIB.BASEBOARD_FAB2(SCH_1):PAGE234
  C6M3    2      B CAP_0805-10UF,16V,10%,X6S,C953A   I203 @BASEBOARD_FAB2_LIB.BASEBOARD_FAB2(SCH_1):PAGE234
  C6M5    2      B CAP_0805-10UF,16V,10%,X6S,C953A   I204 @BASEBOARD_FAB2_LIB.BASEBOARD_FAB2(SCH_1):PAGE234
 C4A19    2      B CAP_0805-10UF,16V,10%,X6S,C953A   I205 @BASEBOARD_FAB2_LIB.BASEBOARD_FAB2(SCH_1):PAGE234
  C6L8    2      B CAPP_7343-220UF,4V,20%,POSCAP,A   I210 @BASEBOARD_FAB2_LIB.BASEBOARD_FAB2(SCH_1):PAGE234
  C8A7    2      B CAP_A_0402V-1.0UF,6.3V,10%,X6SA   I143 @BASEBOARD_FAB2_LIB.BASEBOARD_FAB2(SCH_1):PAGE235
  C8A8    2      B CAP_A_0402V-0.1UF,16V,10%,X7R,A   I145 @BASEBOARD_FAB2_LIB.BASEBOARD_FAB2(SCH_1):PAGE235
  C2L8    2      B CAP_A_0402V-1.0UF,6.3V,10%,X6SA   I151 @BASEBOARD_FAB2_LIB.BASEBOARD_FAB2(SCH_1):PAGE235
 R2L10    2      B RES_0402-1.5K,1%,1/16W,CHIP,G2A   I166 @BASEBOARD_FAB2_LIB.BASEBOARD_FAB2(SCH_1):PAGE235
 C2L11    2      B CAP_A_0402V-0.1UF,16V,10%,X7R,A   I169 @BASEBOARD_FAB2_LIB.BASEBOARD_FAB2(SCH_1):PAGE235
  R8A2    2      B RES_0402-2.67K,1%,1/16W,CHIP,GA   I217 @BASEBOARD_FAB2_LIB.BASEBOARD_FAB2(SCH_1):PAGE235
  C8A9    2      B CAP_0402LF-1000PF,50V,10%,X7R,A   I218 @BASEBOARD_FAB2_LIB.BASEBOARD_FAB2(SCH_1):PAGE235
 EU8A1   27 GND<0> PXE1110B_QFN-IC,H89187-001   I229 @BASEBOARD_FAB2_LIB.BASEBOARD_FAB2(SCH_1):PAGE235
 EU8A1   23 GND<1> PXE1110B_QFN-IC,H89187-001   I229 @BASEBOARD_FAB2_LIB.BASEBOARD_FAB2(SCH_1):PAGE235
 EU8A1   41  THPAD PXE1110B_QFN-IC,H89187-001   I229 @BASEBOARD_FAB2_LIB.BASEBOARD_FAB2(SCH_1):PAGE235
 C7A30    2      B CAP_0805LF-22UF,4V,20%,X6S,C95A     I9 @BASEBOARD_FAB2_LIB.BASEBOARD_FAB2(SCH_1):PAGE236
  C7A8    2      B CAP_0402-0.22UF,16V,10%,X7R,A3A    I16 @BASEBOARD_FAB2_LIB.BASEBOARD_FAB2(SCH_1):PAGE236
  C7A6    2      B CAP_0402-1.0UF,16V,10%,X6S,D97A    I19 @BASEBOARD_FAB2_LIB.BASEBOARD_FAB2(SCH_1):PAGE236
 C7A39    2      B CAP_A_0402V-0.1UF,16V,10%,X7R,A    I20 @BASEBOARD_FAB2_LIB.BASEBOARD_FAB2(SCH_1):PAGE236
  C7A7    2      B CAP_0402-1.0UF,16V,10%,X6S,D97A    I22 @BASEBOARD_FAB2_LIB.BASEBOARD_FAB2(SCH_1):PAGE236
 C3L12    2      B CAP_0805-10UF,16V,10%,X6S,C953A    I23 @BASEBOARD_FAB2_LIB.BASEBOARD_FAB2(SCH_1):PAGE236
 C3L11    2      B CAP_0805-10UF,16V,10%,X6S,C953A    I24 @BASEBOARD_FAB2_LIB.BASEBOARD_FAB2(SCH_1):PAGE236
  C3L8    2      B CAP_0805-10UF,16V,10%,X6S,C953A    I26 @BASEBOARD_FAB2_LIB.BASEBOARD_FAB2(SCH_1):PAGE236
  C3L9    2      B CAP_0805-10UF,16V,10%,X6S,C953A    I29 @BASEBOARD_FAB2_LIB.BASEBOARD_FAB2(SCH_1):PAGE236
  C3L7    2      B CAP_0805-10UF,16V,10%,X6S,C953A    I31 @BASEBOARD_FAB2_LIB.BASEBOARD_FAB2(SCH_1):PAGE236
 C3L10    2      B CAP_0805-10UF,16V,10%,X6S,C953A    I32 @BASEBOARD_FAB2_LIB.BASEBOARD_FAB2(SCH_1):PAGE236
  C7A9    2      B CAP_0402-1.0UF,16V,10%,X6S,D97A    I33 @BASEBOARD_FAB2_LIB.BASEBOARD_FAB2(SCH_1):PAGE236
 C7A40    2      B CAP_A_0402V-0.1UF,16V,10%,X7R,A    I35 @BASEBOARD_FAB2_LIB.BASEBOARD_FAB2(SCH_1):PAGE236
 C7A10    2      B CAP_0402-1.0UF,16V,10%,X6S,D97A    I36 @BASEBOARD_FAB2_LIB.BASEBOARD_FAB2(SCH_1):PAGE236
 C7A41    2      B CAP_0402-0.22UF,16V,10%,X7R,A3A    I39 @BASEBOARD_FAB2_LIB.BASEBOARD_FAB2(SCH_1):PAGE236
 C7A42    2      B CAP_0805LF-22UF,4V,20%,X6S,C95A    I46 @BASEBOARD_FAB2_LIB.BASEBOARD_FAB2(SCH_1):PAGE236
 R8B12    2      B RES_0402-0.0,5%,1/16W,CHIP,G21A    I59 @BASEBOARD_FAB2_LIB.BASEBOARD_FAB2(SCH_1):PAGE236
 C3L18    2      B CAPP_SM-470UF,2V,20%,ALUM,6990A    I71 @BASEBOARD_FAB2_LIB.BASEBOARD_FAB2(SCH_1):PAGE236
 C3L20    2      B CAPP_SM-470UF,2V,20%,ALUM,6990A    I73 @BASEBOARD_FAB2_LIB.BASEBOARD_FAB2(SCH_1):PAGE236
 C3L21    2      B CAPP_SM-470UF,2V,20%,ALUM,6990A    I74 @BASEBOARD_FAB2_LIB.BASEBOARD_FAB2(SCH_1):PAGE236
 C7A27    2      B CAPP_SM-470UF,2V,20%,ALUM,6990A    I75 @BASEBOARD_FAB2_LIB.BASEBOARD_FAB2(SCH_1):PAGE236
 C3L19    2      B CAPP_SM-470UF,2V,20%,ALUM,6990A    I76 @BASEBOARD_FAB2_LIB.BASEBOARD_FAB2(SCH_1):PAGE236
 C2L46    2      B CAPP_SM-470UF,2V,20%,ALUM,6990A    I77 @BASEBOARD_FAB2_LIB.BASEBOARD_FAB2(SCH_1):PAGE236
 C8A15    2      B CAPP_SM-470UF,2V,20%,ALUM,6990A    I78 @BASEBOARD_FAB2_LIB.BASEBOARD_FAB2(SCH_1):PAGE236
 C2L25    2      B CAPP_SM-470UF,2V,20%,ALUM,6990A    I79 @BASEBOARD_FAB2_LIB.BASEBOARD_FAB2(SCH_1):PAGE236
 R7A18    1      A RES_0402-0.0,5%,1/16W,CHIP,G21A    I92 @BASEBOARD_FAB2_LIB.BASEBOARD_FAB2(SCH_1):PAGE236
 EU7A3    2   LGND IR354XX_SM-IR35412,IC,H73684-0A   I116 @BASEBOARD_FAB2_LIB.BASEBOARD_FAB2(SCH_1):PAGE236
 EU7A3    5 PGND<0> IR354XX_SM-IR35412,IC,H73684-0A   I116 @BASEBOARD_FAB2_LIB.BASEBOARD_FAB2(SCH_1):PAGE236
 EU7A3    7 PGND<1> IR354XX_SM-IR35412,IC,H73684-0A   I116 @BASEBOARD_FAB2_LIB.BASEBOARD_FAB2(SCH_1):PAGE236
 EU7A3   40 PGND<2> IR354XX_SM-IR35412,IC,H73684-0A   I116 @BASEBOARD_FAB2_LIB.BASEBOARD_FAB2(SCH_1):PAGE236
 EU7A2    2   LGND IR354XX_SM-IR35412,IC,H73684-0A   I117 @BASEBOARD_FAB2_LIB.BASEBOARD_FAB2(SCH_1):PAGE236
 EU7A2    5 PGND<0> IR354XX_SM-IR35412,IC,H73684-0A   I117 @BASEBOARD_FAB2_LIB.BASEBOARD_FAB2(SCH_1):PAGE236
 EU7A2    7 PGND<1> IR354XX_SM-IR35412,IC,H73684-0A   I117 @BASEBOARD_FAB2_LIB.BASEBOARD_FAB2(SCH_1):PAGE236
 EU7A2   40 PGND<2> IR354XX_SM-IR35412,IC,H73684-0A   I117 @BASEBOARD_FAB2_LIB.BASEBOARD_FAB2(SCH_1):PAGE236
 R3L15    2      B RES_0402-68.1K,1%,1/16W,EMPTY,A   I118 @BASEBOARD_FAB2_LIB.BASEBOARD_FAB2(SCH_1):PAGE236
 R3L14    2      B RES_0402-68.1K,1%,1/16W,EMPTY,A   I120 @BASEBOARD_FAB2_LIB.BASEBOARD_FAB2(SCH_1):PAGE236
 C8A11    2      B CAP_0402LF-1000PF,50V,10%,X7R,A     I5 @BASEBOARD_FAB2_LIB.BASEBOARD_FAB2(SCH_1):PAGE237
 C2L45    2      B CAP_0805-22UF,6.3V,20%,X6S,C95A    I12 @BASEBOARD_FAB2_LIB.BASEBOARD_FAB2(SCH_1):PAGE237
 C8A14    2      B CAP_0805-22UF,6.3V,20%,X6S,C95A    I13 @BASEBOARD_FAB2_LIB.BASEBOARD_FAB2(SCH_1):PAGE237
 R8A12    2      B RES_0603-475.0,1%,1/10W,CHIP,GA    I15 @BASEBOARD_FAB2_LIB.BASEBOARD_FAB2(SCH_1):PAGE237
  C8A6    2      B CAP_0603-10UF,6.3V,20%,X6S,E15A    I29 @BASEBOARD_FAB2_LIB.BASEBOARD_FAB2(SCH_1):PAGE237
  C8A4    2      B CAP_0603LF-0.1UF,25V,10%,X7R,6A    I31 @BASEBOARD_FAB2_LIB.BASEBOARD_FAB2(SCH_1):PAGE237
 C8A10    2      B CAP_0402LF-1000PF,50V,10%,EMPTA    I55 @BASEBOARD_FAB2_LIB.BASEBOARD_FAB2(SCH_1):PAGE237
 C8A12    2      B CAP_0805-47UF,4V,20%,X6S,C9533A    I77 @BASEBOARD_FAB2_LIB.BASEBOARD_FAB2(SCH_1):PAGE237
 C2L32    2      B CAP_0805-47UF,4V,20%,X6S,C9533A    I79 @BASEBOARD_FAB2_LIB.BASEBOARD_FAB2(SCH_1):PAGE237
 R2L19    2      B RES_0402-49.9K,1%,1/16W,CHIP,GA    I80 @BASEBOARD_FAB2_LIB.BASEBOARD_FAB2(SCH_1):PAGE237
 EU8A2   11    GND RT9059_DFN-IC,H65765-001    I86 @BASEBOARD_FAB2_LIB.BASEBOARD_FAB2(SCH_1):PAGE237
  C9F9    2      B CAP_0402LF-1000PF,50V,10%,EMPTA     I5 @BASEBOARD_FAB2_LIB.BASEBOARD_FAB2(SCH_1):PAGE238
  C9F3    2      B CAP_0603-10UF,6.3V,20%,X6S,E15A     I7 @BASEBOARD_FAB2_LIB.BASEBOARD_FAB2(SCH_1):PAGE238
  R9F8    1      A RES_0402-10.0K,1%,1/16W,CHIP,GA    I14 @BASEBOARD_FAB2_LIB.BASEBOARD_FAB2(SCH_1):PAGE238
  C9F8    2      B CAP_0402LF-1000PF,50V,10%,X7R,A    I19 @BASEBOARD_FAB2_LIB.BASEBOARD_FAB2(SCH_1):PAGE238
 C9E10    2      B CAP_0603-10UF,6.3V,20%,X6S,E15A    I23 @BASEBOARD_FAB2_LIB.BASEBOARD_FAB2(SCH_1):PAGE238
  C9F4    2      B CAP_0805LF-22UF,4V,20%,X6S,C95A    I30 @BASEBOARD_FAB2_LIB.BASEBOARD_FAB2(SCH_1):PAGE238
 C9E11    2      B CAP_0402-1.0UF,16V,10%,X6S,D97A    I39 @BASEBOARD_FAB2_LIB.BASEBOARD_FAB2(SCH_1):PAGE238
 EU9F1   11    GND RT9059_DFN-IC,H65765-001    I40 @BASEBOARD_FAB2_LIB.BASEBOARD_FAB2(SCH_1):PAGE238
 C9F10    2      B CAP_0402LF-1000PF,50V,10%,X7R,A     I4 @BASEBOARD_FAB2_LIB.BASEBOARD_FAB2(SCH_1):PAGE239
 C9F13    2      B CAP_0805LF-22UF,4V,20%,X6S,C95A     I7 @BASEBOARD_FAB2_LIB.BASEBOARD_FAB2(SCH_1):PAGE239
 C1T15    2      B CAP_0603-10UF,6.3V,20%,X6S,E15A    I12 @BASEBOARD_FAB2_LIB.BASEBOARD_FAB2(SCH_1):PAGE239
  C1T7    2      B CAP_0603-10UF,6.3V,20%,X6S,E15A    I22 @BASEBOARD_FAB2_LIB.BASEBOARD_FAB2(SCH_1):PAGE239
  C9F6    2      B CAP_0402LF-1000PF,50V,10%,EMPTA    I30 @BASEBOARD_FAB2_LIB.BASEBOARD_FAB2(SCH_1):PAGE239
 EU9F2   11    GND RT9059_DFN-IC,H65765-001    I70 @BASEBOARD_FAB2_LIB.BASEBOARD_FAB2(SCH_1):PAGE239
  C9F5    2      B CAP_A_0402V-0.1UF,16V,10%,X7R,A    I71 @BASEBOARD_FAB2_LIB.BASEBOARD_FAB2(SCH_1):PAGE239
  R8F1    2      B RES_0402-10.0K,1%,1/16W,EMPTY,A   I111 @BASEBOARD_FAB2_LIB.BASEBOARD_FAB2(SCH_1):PAGE240
  C8F2    2      B CAP_0402LF-1000PF,50V,10%,X7R,A   I116 @BASEBOARD_FAB2_LIB.BASEBOARD_FAB2(SCH_1):PAGE240
 C8E10    2      B CAP_1206LF-22UF,16V,10%,X6S,D3A   I137 @BASEBOARD_FAB2_LIB.BASEBOARD_FAB2(SCH_1):PAGE240
 C8E14    2      B CAP_0402-1.0UF,16V,10%,X6S,D97A   I139 @BASEBOARD_FAB2_LIB.BASEBOARD_FAB2(SCH_1):PAGE240
 R8F11    1      A RES_0402-0.0,5%,1/16W,CHIP,G21A   I146 @BASEBOARD_FAB2_LIB.BASEBOARD_FAB2(SCH_1):PAGE240
  R8F3    2      B RES_0402-2.2,5%,1/16W,EMPTY,G2A   I148 @BASEBOARD_FAB2_LIB.BASEBOARD_FAB2(SCH_1):PAGE240
  R2T4    2      B RES_0402-1.0K,0.1%,1/16W,CHIP,A   I152 @BASEBOARD_FAB2_LIB.BASEBOARD_FAB2(SCH_1):PAGE240
  C2T7    2      B CAP_0805-22UF,6.3V,20%,X6S,C95A   I158 @BASEBOARD_FAB2_LIB.BASEBOARD_FAB2(SCH_1):PAGE240
  C2T6    2      B CAP_0805-22UF,6.3V,20%,X6S,C95A   I160 @BASEBOARD_FAB2_LIB.BASEBOARD_FAB2(SCH_1):PAGE240
 EU8E1    3   PGND CSD87384M_SM-IC,H66258-001   I170 @BASEBOARD_FAB2_LIB.BASEBOARD_FAB2(SCH_1):PAGE240
  C2T9    2      B CAP_0805-22UF,6.3V,20%,X6S,C95A   I174 @BASEBOARD_FAB2_LIB.BASEBOARD_FAB2(SCH_1):PAGE240
 R8E18    2      B RES_0402-1.0K,0.1%,1/16W,CHIP,A     I9 @BASEBOARD_FAB2_LIB.BASEBOARD_FAB2(SCH_1):PAGE241
 C7E10    2      B CAP_0402LF-1000PF,50V,10%,X7R,A    I14 @BASEBOARD_FAB2_LIB.BASEBOARD_FAB2(SCH_1):PAGE241
 C7E14    2      B CAP_0402-1.0UF,16V,10%,X6S,D97A    I30 @BASEBOARD_FAB2_LIB.BASEBOARD_FAB2(SCH_1):PAGE241
 C7E11    2      B CAP_1206LF-22UF,16V,10%,X6S,D3A    I39 @BASEBOARD_FAB2_LIB.BASEBOARD_FAB2(SCH_1):PAGE241
 R7E13    1      A RES_0402-0.0,5%,1/16W,CHIP,G21A    I58 @BASEBOARD_FAB2_LIB.BASEBOARD_FAB2(SCH_1):PAGE241
 EU7E2    2 GND<0> TPS54821_LCC-IC,H63269-001    I83 @BASEBOARD_FAB2_LIB.BASEBOARD_FAB2(SCH_1):PAGE241
 EU7E2    3 GND<1> TPS54821_LCC-IC,H63269-001    I83 @BASEBOARD_FAB2_LIB.BASEBOARD_FAB2(SCH_1):PAGE241
 EU7E2   15  THPAD TPS54821_LCC-IC,H63269-001    I83 @BASEBOARD_FAB2_LIB.BASEBOARD_FAB2(SCH_1):PAGE241
 C5G41    2      B CAP_A_0603V-22.0UF,4V,20%,X6S,A    I53 @BASEBOARD_FAB2_LIB.BASEBOARD_FAB2(SCH_1):PAGE242
 C5G42    2      B CAP_A_0603V-22.0UF,4V,20%,X6S,A    I54 @BASEBOARD_FAB2_LIB.BASEBOARD_FAB2(SCH_1):PAGE242
 C5G44    2      B CAP_A_0603V-22.0UF,4V,20%,X6S,A    I55 @BASEBOARD_FAB2_LIB.BASEBOARD_FAB2(SCH_1):PAGE242
 C5G43    2      B CAP_A_0603V-22.0UF,4V,20%,X6S,A    I56 @BASEBOARD_FAB2_LIB.BASEBOARD_FAB2(SCH_1):PAGE242
 C5G48    2      B CAP_A_0603V-22.0UF,4V,20%,X6S,A    I57 @BASEBOARD_FAB2_LIB.BASEBOARD_FAB2(SCH_1):PAGE242
 C5G47    2      B CAP_A_0603V-22.0UF,4V,20%,X6S,A    I58 @BASEBOARD_FAB2_LIB.BASEBOARD_FAB2(SCH_1):PAGE242
 C5G46    2      B CAP_A_0603V-22.0UF,4V,20%,X6S,A    I59 @BASEBOARD_FAB2_LIB.BASEBOARD_FAB2(SCH_1):PAGE242
 C5G45    2      B CAP_A_0603V-22.0UF,4V,20%,X6S,A    I60 @BASEBOARD_FAB2_LIB.BASEBOARD_FAB2(SCH_1):PAGE242
 C5G49    2      B CAP_A_0603V-22.0UF,4V,20%,X6S,A    I61 @BASEBOARD_FAB2_LIB.BASEBOARD_FAB2(SCH_1):PAGE242
 C5G54    2      B CAP_A_0603V-22.0UF,4V,20%,X6S,A    I62 @BASEBOARD_FAB2_LIB.BASEBOARD_FAB2(SCH_1):PAGE242
 C5G58    2      B CAP_A_0603V-22.0UF,4V,20%,X6S,A    I63 @BASEBOARD_FAB2_LIB.BASEBOARD_FAB2(SCH_1):PAGE242
 C5G57    2      B CAP_A_0603V-22.0UF,4V,20%,X6S,A    I64 @BASEBOARD_FAB2_LIB.BASEBOARD_FAB2(SCH_1):PAGE242
 C5G56    2      B CAP_A_0603V-22.0UF,4V,20%,X6S,A    I65 @BASEBOARD_FAB2_LIB.BASEBOARD_FAB2(SCH_1):PAGE242
 C5G55    2      B CAP_A_0603V-22.0UF,4V,20%,X6S,A    I66 @BASEBOARD_FAB2_LIB.BASEBOARD_FAB2(SCH_1):PAGE242
 C5G53    2      B CAP_A_0603V-22.0UF,4V,20%,X6S,A    I67 @BASEBOARD_FAB2_LIB.BASEBOARD_FAB2(SCH_1):PAGE242
 C5G52    2      B CAP_A_0603V-22.0UF,4V,20%,X6S,A    I68 @BASEBOARD_FAB2_LIB.BASEBOARD_FAB2(SCH_1):PAGE242
 C5G51    2      B CAP_A_0603V-22.0UF,4V,20%,X6S,A    I69 @BASEBOARD_FAB2_LIB.BASEBOARD_FAB2(SCH_1):PAGE242
 C5G50    2      B CAP_A_0603V-22.0UF,4V,20%,X6S,A    I70 @BASEBOARD_FAB2_LIB.BASEBOARD_FAB2(SCH_1):PAGE242
 C5G67    2      B CAP_A_0603V-22.0UF,4V,20%,X6S,A    I71 @BASEBOARD_FAB2_LIB.BASEBOARD_FAB2(SCH_1):PAGE242
 C5G66    2      B CAP_A_0603V-22.0UF,4V,20%,X6S,A    I72 @BASEBOARD_FAB2_LIB.BASEBOARD_FAB2(SCH_1):PAGE242
 C5G65    2      B CAP_A_0603V-22.0UF,4V,20%,X6S,A    I73 @BASEBOARD_FAB2_LIB.BASEBOARD_FAB2(SCH_1):PAGE242
 C5G64    2      B CAP_A_0603V-22.0UF,4V,20%,X6S,A    I74 @BASEBOARD_FAB2_LIB.BASEBOARD_FAB2(SCH_1):PAGE242
 C5G63    2      B CAP_A_0603V-22.0UF,4V,20%,X6S,A    I75 @BASEBOARD_FAB2_LIB.BASEBOARD_FAB2(SCH_1):PAGE242
 C5G62    2      B CAP_A_0603V-22.0UF,4V,20%,X6S,A    I76 @BASEBOARD_FAB2_LIB.BASEBOARD_FAB2(SCH_1):PAGE242
 C5G61    2      B CAP_A_0603V-22.0UF,4V,20%,X6S,A    I77 @BASEBOARD_FAB2_LIB.BASEBOARD_FAB2(SCH_1):PAGE242
 C5G60    2      B CAP_A_0603V-22.0UF,4V,20%,X6S,A    I78 @BASEBOARD_FAB2_LIB.BASEBOARD_FAB2(SCH_1):PAGE242
 C5G59    2      B CAP_A_0603V-22.0UF,4V,20%,X6S,A    I79 @BASEBOARD_FAB2_LIB.BASEBOARD_FAB2(SCH_1):PAGE242
 C5G76    2      B CAP_A_0603V-22.0UF,4V,20%,X6S,A    I80 @BASEBOARD_FAB2_LIB.BASEBOARD_FAB2(SCH_1):PAGE242
 C5G75    2      B CAP_A_0603V-22.0UF,4V,20%,X6S,A    I81 @BASEBOARD_FAB2_LIB.BASEBOARD_FAB2(SCH_1):PAGE242
 C5G74    2      B CAP_A_0603V-22.0UF,4V,20%,X6S,A    I82 @BASEBOARD_FAB2_LIB.BASEBOARD_FAB2(SCH_1):PAGE242
 C5G73    2      B CAP_A_0603V-22.0UF,4V,20%,X6S,A    I83 @BASEBOARD_FAB2_LIB.BASEBOARD_FAB2(SCH_1):PAGE242
 C5G72    2      B CAP_A_0603V-22.0UF,4V,20%,X6S,A    I84 @BASEBOARD_FAB2_LIB.BASEBOARD_FAB2(SCH_1):PAGE242
 C5G71    2      B CAP_A_0603V-22.0UF,4V,20%,X6S,A    I85 @BASEBOARD_FAB2_LIB.BASEBOARD_FAB2(SCH_1):PAGE242
 C5G70    2      B CAP_A_0603V-22.0UF,4V,20%,X6S,A    I86 @BASEBOARD_FAB2_LIB.BASEBOARD_FAB2(SCH_1):PAGE242
 C5G69    2      B CAP_A_0603V-22.0UF,4V,20%,X6S,A    I87 @BASEBOARD_FAB2_LIB.BASEBOARD_FAB2(SCH_1):PAGE242
 C5G68    2      B CAP_A_0603V-22.0UF,4V,20%,X6S,A    I88 @BASEBOARD_FAB2_LIB.BASEBOARD_FAB2(SCH_1):PAGE242
 C5G79    2      B CAP_A_0603V-22.0UF,4V,20%,X6S,A    I53 @BASEBOARD_FAB2_LIB.BASEBOARD_FAB2(SCH_1):PAGE243
 C5G87    2      B CAP_A_0603V-22.0UF,4V,20%,X6S,A    I54 @BASEBOARD_FAB2_LIB.BASEBOARD_FAB2(SCH_1):PAGE243
 C5G86    2      B CAP_A_0603V-22.0UF,4V,20%,X6S,A    I55 @BASEBOARD_FAB2_LIB.BASEBOARD_FAB2(SCH_1):PAGE243
 C5G85    2      B CAP_A_0603V-22.0UF,4V,20%,X6S,A    I56 @BASEBOARD_FAB2_LIB.BASEBOARD_FAB2(SCH_1):PAGE243
 C5G84    2      B CAP_A_0603V-22.0UF,4V,20%,X6S,A    I57 @BASEBOARD_FAB2_LIB.BASEBOARD_FAB2(SCH_1):PAGE243
 C5G83    2      B CAP_A_0603V-22.0UF,4V,20%,X6S,A    I58 @BASEBOARD_FAB2_LIB.BASEBOARD_FAB2(SCH_1):PAGE243
 C5G82    2      B CAP_A_0603V-22.0UF,4V,20%,X6S,A    I59 @BASEBOARD_FAB2_LIB.BASEBOARD_FAB2(SCH_1):PAGE243
 C5G81    2      B CAP_A_0603V-22.0UF,4V,20%,X6S,A    I60 @BASEBOARD_FAB2_LIB.BASEBOARD_FAB2(SCH_1):PAGE243
 C5G80    2      B CAP_A_0603V-22.0UF,4V,20%,X6S,A    I61 @BASEBOARD_FAB2_LIB.BASEBOARD_FAB2(SCH_1):PAGE243
 C5G96    2      B CAP_A_0603V-22.0UF,4V,20%,X6S,A    I62 @BASEBOARD_FAB2_LIB.BASEBOARD_FAB2(SCH_1):PAGE243
 C5G95    2      B CAP_A_0603V-22.0UF,4V,20%,X6S,A    I63 @BASEBOARD_FAB2_LIB.BASEBOARD_FAB2(SCH_1):PAGE243
 C5G94    2      B CAP_A_0603V-22.0UF,4V,20%,X6S,A    I64 @BASEBOARD_FAB2_LIB.BASEBOARD_FAB2(SCH_1):PAGE243
 C5G93    2      B CAP_A_0603V-22.0UF,4V,20%,X6S,A    I65 @BASEBOARD_FAB2_LIB.BASEBOARD_FAB2(SCH_1):PAGE243
 C5G92    2      B CAP_A_0603V-22.0UF,4V,20%,X6S,A    I66 @BASEBOARD_FAB2_LIB.BASEBOARD_FAB2(SCH_1):PAGE243
 C5G91    2      B CAP_A_0603V-22.0UF,4V,20%,X6S,A    I67 @BASEBOARD_FAB2_LIB.BASEBOARD_FAB2(SCH_1):PAGE243
 C5G90    2      B CAP_A_0603V-22.0UF,4V,20%,X6S,A    I68 @BASEBOARD_FAB2_LIB.BASEBOARD_FAB2(SCH_1):PAGE243
 C5G89    2      B CAP_A_0603V-22.0UF,4V,20%,X6S,A    I69 @BASEBOARD_FAB2_LIB.BASEBOARD_FAB2(SCH_1):PAGE243
 C5G88    2      B CAP_A_0603V-22.0UF,4V,20%,X6S,A    I70 @BASEBOARD_FAB2_LIB.BASEBOARD_FAB2(SCH_1):PAGE243
C5G103    2      B CAP_A_0603V-22.0UF,4V,20%,X6S,A    I71 @BASEBOARD_FAB2_LIB.BASEBOARD_FAB2(SCH_1):PAGE243
C5G104    2      B CAP_A_0603V-22.0UF,4V,20%,X6S,A    I72 @BASEBOARD_FAB2_LIB.BASEBOARD_FAB2(SCH_1):PAGE243
C5G105    2      B CAP_A_0603V-22.0UF,4V,20%,X6S,A    I73 @BASEBOARD_FAB2_LIB.BASEBOARD_FAB2(SCH_1):PAGE243
C5G102    2      B CAP_A_0603V-22.0UF,4V,20%,X6S,A    I74 @BASEBOARD_FAB2_LIB.BASEBOARD_FAB2(SCH_1):PAGE243
C5G101    2      B CAP_A_0603V-22.0UF,4V,20%,X6S,A    I75 @BASEBOARD_FAB2_LIB.BASEBOARD_FAB2(SCH_1):PAGE243
C5G100    2      B CAP_A_0603V-22.0UF,4V,20%,X6S,A    I76 @BASEBOARD_FAB2_LIB.BASEBOARD_FAB2(SCH_1):PAGE243
 C5G99    2      B CAP_A_0603V-22.0UF,4V,20%,X6S,A    I77 @BASEBOARD_FAB2_LIB.BASEBOARD_FAB2(SCH_1):PAGE243
 C5G98    2      B CAP_A_0603V-22.0UF,4V,20%,X6S,A    I78 @BASEBOARD_FAB2_LIB.BASEBOARD_FAB2(SCH_1):PAGE243
 C5G97    2      B CAP_A_0603V-22.0UF,4V,20%,X6S,A    I79 @BASEBOARD_FAB2_LIB.BASEBOARD_FAB2(SCH_1):PAGE243
C5G114    2      B CAP_A_0603V-22.0UF,4V,20%,X6S,A    I80 @BASEBOARD_FAB2_LIB.BASEBOARD_FAB2(SCH_1):PAGE243
C5G113    2      B CAP_A_0603V-22.0UF,4V,20%,X6S,A    I81 @BASEBOARD_FAB2_LIB.BASEBOARD_FAB2(SCH_1):PAGE243
C5G112    2      B CAP_A_0603V-22.0UF,4V,20%,X6S,A    I82 @BASEBOARD_FAB2_LIB.BASEBOARD_FAB2(SCH_1):PAGE243
C5G111    2      B CAP_A_0603V-22.0UF,4V,20%,X6S,A    I83 @BASEBOARD_FAB2_LIB.BASEBOARD_FAB2(SCH_1):PAGE243
C5G110    2      B CAP_A_0603V-22.0UF,4V,20%,X6S,A    I84 @BASEBOARD_FAB2_LIB.BASEBOARD_FAB2(SCH_1):PAGE243
C5G109    2      B CAP_A_0603V-22.0UF,4V,20%,X6S,A    I85 @BASEBOARD_FAB2_LIB.BASEBOARD_FAB2(SCH_1):PAGE243
C5G108    2      B CAP_A_0603V-22.0UF,4V,20%,X6S,A    I86 @BASEBOARD_FAB2_LIB.BASEBOARD_FAB2(SCH_1):PAGE243
C5G107    2      B CAP_A_0603V-22.0UF,4V,20%,X6S,A    I87 @BASEBOARD_FAB2_LIB.BASEBOARD_FAB2(SCH_1):PAGE243
C5G106    2      B CAP_A_0603V-22.0UF,4V,20%,X6S,A    I88 @BASEBOARD_FAB2_LIB.BASEBOARD_FAB2(SCH_1):PAGE243
   CT1    2      B CAP_A_0402V-0.1UF,16V,10%,X7R,A    I70 @BASEBOARD_FAB2_LIB.BASEBOARD_FAB2(SCH_1):PAGE202
   CT2    2      B CAP_0402LF-1000PF,50V,10%,X7R,A    I78 @BASEBOARD_FAB2_LIB.BASEBOARD_FAB2(SCH_1):PAGE202
   CT6    2      B CAP_A_0402V-0.1UF,16V,10%,X7R,A    I81 @BASEBOARD_FAB2_LIB.BASEBOARD_FAB2(SCH_1):PAGE202
   CT7    2      B CAP_A_0402V-0.1UF,16V,10%,X7R,A   I109 @BASEBOARD_FAB2_LIB.BASEBOARD_FAB2(SCH_1):PAGE227
   CT8    2      B CAP_0402LF-1000PF,50V,10%,X7R,A   I114 @BASEBOARD_FAB2_LIB.BASEBOARD_FAB2(SCH_1):PAGE227
  CT10    2      B CAP_0402LF-1000PF,50V,10%,X7R,A   I119 @BASEBOARD_FAB2_LIB.BASEBOARD_FAB2(SCH_1):PAGE227
  CT12    2      B CAP_A_0402V-0.1UF,16V,10%,X7R,A   I122 @BASEBOARD_FAB2_LIB.BASEBOARD_FAB2(SCH_1):PAGE227
  CT13    2      B CAP_A_0402V-0.1UF,16V,10%,X7R,A    I62 @BASEBOARD_FAB2_LIB.BASEBOARD_FAB2(SCH_1):PAGE209
  CT15    2      B CAP_0402LF-1000PF,50V,10%,X7R,A    I67 @BASEBOARD_FAB2_LIB.BASEBOARD_FAB2(SCH_1):PAGE209
  CT16    2      B CAP_A_0402V-0.1UF,16V,10%,X7R,A    I80 @BASEBOARD_FAB2_LIB.BASEBOARD_FAB2(SCH_1):PAGE208
  CTI7    2      B CAP_0402LF-1000PF,50V,10%,X7R,A    I82 @BASEBOARD_FAB2_LIB.BASEBOARD_FAB2(SCH_1):PAGE208
  CT21    2      B CAP_A_0402V-0.1UF,16V,10%,X7R,A    I87 @BASEBOARD_FAB2_LIB.BASEBOARD_FAB2(SCH_1):PAGE208
  CT19    2      B CAP_0402LF-1000PF,50V,10%,X7R,A    I90 @BASEBOARD_FAB2_LIB.BASEBOARD_FAB2(SCH_1):PAGE208
  CT24    2      B CAP_A_0402V-0.1UF,16V,10%,X7R,A    I71 @BASEBOARD_FAB2_LIB.BASEBOARD_FAB2(SCH_1):PAGE207
  CT22    2      B CAP_0402LF-1000PF,50V,10%,X7R,A    I74 @BASEBOARD_FAB2_LIB.BASEBOARD_FAB2(SCH_1):PAGE207
  CT30    2      B CAP_A_0402V-0.1UF,16V,10%,X7R,A   I117 @BASEBOARD_FAB2_LIB.BASEBOARD_FAB2(SCH_1):PAGE224
  CT28    2      B CAP_0402LF-1000PF,50V,10%,X7R,A   I122 @BASEBOARD_FAB2_LIB.BASEBOARD_FAB2(SCH_1):PAGE224
  CT31    2      B CAP_A_0402V-0.1UF,16V,10%,X7R,A   I124 @BASEBOARD_FAB2_LIB.BASEBOARD_FAB2(SCH_1):PAGE224
  CT32    2      B CAP_0402LF-1000PF,50V,10%,X7R,A   I130 @BASEBOARD_FAB2_LIB.BASEBOARD_FAB2(SCH_1):PAGE224
  CT36    2      B CAP_A_0402V-0.1UF,16V,10%,X7R,A    I85 @BASEBOARD_FAB2_LIB.BASEBOARD_FAB2(SCH_1):PAGE204
  CT34    2      B CAP_0402LF-1000PF,50V,10%,X7R,A    I88 @BASEBOARD_FAB2_LIB.BASEBOARD_FAB2(SCH_1):PAGE204
  CT40    2      B CAP_A_0402V-0.1UF,16V,10%,X7R,A    I93 @BASEBOARD_FAB2_LIB.BASEBOARD_FAB2(SCH_1):PAGE203
  CT39    2      B CAP_A_0402V-0.1UF,16V,10%,X7R,A    I96 @BASEBOARD_FAB2_LIB.BASEBOARD_FAB2(SCH_1):PAGE203
  CT37    2      B CAP_0402LF-1000PF,50V,10%,X7R,A    I99 @BASEBOARD_FAB2_LIB.BASEBOARD_FAB2(SCH_1):PAGE203
  CT42    2      B CAP_0402LF-1000PF,50V,10%,X7R,A   I108 @BASEBOARD_FAB2_LIB.BASEBOARD_FAB2(SCH_1):PAGE203
  CT46    2      B CAP_A_0402V-0.1UF,16V,10%,X7R,A   I113 @BASEBOARD_FAB2_LIB.BASEBOARD_FAB2(SCH_1):PAGE219
  CT45    2      B CAP_A_0402V-0.1UF,16V,10%,X7R,A   I116 @BASEBOARD_FAB2_LIB.BASEBOARD_FAB2(SCH_1):PAGE219
  CT48    2      B CAP_0402LF-1000PF,50V,10%,X7R,A   I119 @BASEBOARD_FAB2_LIB.BASEBOARD_FAB2(SCH_1):PAGE219
  CT43    2      B CAP_0402LF-1000PF,50V,10%,X7R,A   I124 @BASEBOARD_FAB2_LIB.BASEBOARD_FAB2(SCH_1):PAGE219
  CT51    2      B CAP_A_0402V-0.1UF,16V,10%,X7R,A   I108 @BASEBOARD_FAB2_LIB.BASEBOARD_FAB2(SCH_1):PAGE216
  CT52    2      B CAP_A_0402V-0.1UF,16V,10%,X7R,A   I111 @BASEBOARD_FAB2_LIB.BASEBOARD_FAB2(SCH_1):PAGE216
  CT49    2      B CAP_0402LF-1000PF,50V,10%,X7R,A   I118 @BASEBOARD_FAB2_LIB.BASEBOARD_FAB2(SCH_1):PAGE216
  CT54    2      B CAP_0402LF-1000PF,50V,10%,X7R,A   I121 @BASEBOARD_FAB2_LIB.BASEBOARD_FAB2(SCH_1):PAGE216
  CT57    2      B CAP_A_0402V-0.1UF,16V,10%,X7R,A    I55 @BASEBOARD_FAB2_LIB.BASEBOARD_FAB2(SCH_1):PAGE210
  CT55    2      B CAP_0402LF-1000PF,50V,10%,X7R,A    I60 @BASEBOARD_FAB2_LIB.BASEBOARD_FAB2(SCH_1):PAGE210
  CT58    2      B CAP_0402LF-1000PF,50V,10%,X7R,A    I65 @BASEBOARD_FAB2_LIB.BASEBOARD_FAB2(SCH_1):PAGE205
  CT60    2      B CAP_A_0402V-0.1UF,16V,10%,X7R,A    I69 @BASEBOARD_FAB2_LIB.BASEBOARD_FAB2(SCH_1):PAGE205
  CT61    2      B CAP_0402LF-1000PF,50V,10%,X7R,A   I134 @BASEBOARD_FAB2_LIB.BASEBOARD_FAB2(SCH_1):PAGE214
  CT63    2      B CAP_A_0402V-0.1UF,16V,10%,X7R,A   I137 @BASEBOARD_FAB2_LIB.BASEBOARD_FAB2(SCH_1):PAGE214
  CT67    2      B CAP_A_0402V-0.1UF,16V,10%,X7R,A   I124 @BASEBOARD_FAB2_LIB.BASEBOARD_FAB2(SCH_1):PAGE236
  CT66    2      B CAP_A_0402V-0.1UF,16V,10%,X7R,A   I127 @BASEBOARD_FAB2_LIB.BASEBOARD_FAB2(SCH_1):PAGE236
  CT69    2      B CAP_0402LF-1000PF,50V,10%,X7R,A   I134 @BASEBOARD_FAB2_LIB.BASEBOARD_FAB2(SCH_1):PAGE236
  CT64    2      B CAP_0402LF-1000PF,50V,10%,X7R,A   I136 @BASEBOARD_FAB2_LIB.BASEBOARD_FAB2(SCH_1):PAGE236
  CT70    2      B CAP_A_0402V-0.1UF,16V,10%,X7R,A   I106 @BASEBOARD_FAB2_LIB.BASEBOARD_FAB2(SCH_1):PAGE212
  CT71    2      B CAP_0402LF-1000PF,50V,10%,X7R,A   I109 @BASEBOARD_FAB2_LIB.BASEBOARD_FAB2(SCH_1):PAGE212
  CT25    2      B CAP_A_0402V-0.1UF,16V,10%,X7R,A    I81 @BASEBOARD_FAB2_LIB.BASEBOARD_FAB2(SCH_1):PAGE207
  CT26    2      B CAP_0402LF-1000PF,50V,10%,X7R,A    I82 @BASEBOARD_FAB2_LIB.BASEBOARD_FAB2(SCH_1):PAGE207
   CT4    2      B CAP_0402LF-1000PF,50V,10%,X7R,A    I87 @BASEBOARD_FAB2_LIB.BASEBOARD_FAB2(SCH_1):PAGE202
 CONX8    1      1 SMC-CONN60A-22-GP_CONN-G7-SMC-A    I48 @BASEBOARD_FAB2_LIB.BASEBOARD_FAB2(SCH_1):PAGE245
 CONX8    4      4 SMC-CONN60A-22-GP_CONN-G7-SMC-A    I48 @BASEBOARD_FAB2_LIB.BASEBOARD_FAB2(SCH_1):PAGE245
 CONX8    7      7 SMC-CONN60A-22-GP_CONN-G7-SMC-A    I48 @BASEBOARD_FAB2_LIB.BASEBOARD_FAB2(SCH_1):PAGE245
 CONX8   10     10 SMC-CONN60A-22-GP_CONN-G7-SMC-A    I48 @BASEBOARD_FAB2_LIB.BASEBOARD_FAB2(SCH_1):PAGE245
 CONX8   13     13 SMC-CONN60A-22-GP_CONN-G7-SMC-A    I48 @BASEBOARD_FAB2_LIB.BASEBOARD_FAB2(SCH_1):PAGE245
 CONX8   16     16 SMC-CONN60A-22-GP_CONN-G7-SMC-A    I48 @BASEBOARD_FAB2_LIB.BASEBOARD_FAB2(SCH_1):PAGE245
 CONX8   19     19 SMC-CONN60A-22-GP_CONN-G7-SMC-A    I48 @BASEBOARD_FAB2_LIB.BASEBOARD_FAB2(SCH_1):PAGE245
 CONX8   22     22 SMC-CONN60A-22-GP_CONN-G7-SMC-A    I48 @BASEBOARD_FAB2_LIB.BASEBOARD_FAB2(SCH_1):PAGE245
 CONX8   25     25 SMC-CONN60A-22-GP_CONN-G7-SMC-A    I48 @BASEBOARD_FAB2_LIB.BASEBOARD_FAB2(SCH_1):PAGE245
 CONX8   28     28 SMC-CONN60A-22-GP_CONN-G7-SMC-A    I48 @BASEBOARD_FAB2_LIB.BASEBOARD_FAB2(SCH_1):PAGE245
 CONX8   31     31 SMC-CONN60A-22-GP_CONN-G7-SMC-A    I48 @BASEBOARD_FAB2_LIB.BASEBOARD_FAB2(SCH_1):PAGE245
 CONX8   34     34 SMC-CONN60A-22-GP_CONN-G7-SMC-A    I48 @BASEBOARD_FAB2_LIB.BASEBOARD_FAB2(SCH_1):PAGE245
 CONX8   37     37 SMC-CONN60A-22-GP_CONN-G7-SMC-A    I48 @BASEBOARD_FAB2_LIB.BASEBOARD_FAB2(SCH_1):PAGE245
 CONX8   40     40 SMC-CONN60A-22-GP_CONN-G7-SMC-A    I48 @BASEBOARD_FAB2_LIB.BASEBOARD_FAB2(SCH_1):PAGE245
 CONX8   43     43 SMC-CONN60A-22-GP_CONN-G7-SMC-A    I48 @BASEBOARD_FAB2_LIB.BASEBOARD_FAB2(SCH_1):PAGE245
 CONX8   46     46 SMC-CONN60A-22-GP_CONN-G7-SMC-A    I48 @BASEBOARD_FAB2_LIB.BASEBOARD_FAB2(SCH_1):PAGE245
 CONX8   49     49 SMC-CONN60A-22-GP_CONN-G7-SMC-A    I48 @BASEBOARD_FAB2_LIB.BASEBOARD_FAB2(SCH_1):PAGE245
 CONX8   52     52 SMC-CONN60A-22-GP_CONN-G7-SMC-A    I48 @BASEBOARD_FAB2_LIB.BASEBOARD_FAB2(SCH_1):PAGE245
 CONX8   55     55 SMC-CONN60A-22-GP_CONN-G7-SMC-A    I48 @BASEBOARD_FAB2_LIB.BASEBOARD_FAB2(SCH_1):PAGE245
 CONX8   58     58 SMC-CONN60A-22-GP_CONN-G7-SMC-A    I48 @BASEBOARD_FAB2_LIB.BASEBOARD_FAB2(SCH_1):PAGE245
 CONX8 PTH1   PTH1 SMC-CONN60A-22-GP_CONN-G7-SMC-A    I48 @BASEBOARD_FAB2_LIB.BASEBOARD_FAB2(SCH_1):PAGE245
 CONX8 PTH2   PTH2 SMC-CONN60A-22-GP_CONN-G7-SMC-A    I48 @BASEBOARD_FAB2_LIB.BASEBOARD_FAB2(SCH_1):PAGE245
  J8G1  101  IO101 SCONN200_H68296001_SM-CONN,H68A    I78 @BASEBOARD_FAB2_LIB.BASEBOARD_FAB2(SCH_1):PAGE109
  J8G1  104  IO104 SCONN200_H68296001_SM-CONN,H68A    I78 @BASEBOARD_FAB2_LIB.BASEBOARD_FAB2(SCH_1):PAGE109
  J8G1  107  IO107 SCONN200_H68296001_SM-CONN,H68A    I78 @BASEBOARD_FAB2_LIB.BASEBOARD_FAB2(SCH_1):PAGE109
  J8G1  110  IO110 SCONN200_H68296001_SM-CONN,H68A    I78 @BASEBOARD_FAB2_LIB.BASEBOARD_FAB2(SCH_1):PAGE109
  J8G1  113  IO113 SCONN200_H68296001_SM-CONN,H68A    I78 @BASEBOARD_FAB2_LIB.BASEBOARD_FAB2(SCH_1):PAGE109
  J8G1  116  IO116 SCONN200_H68296001_SM-CONN,H68A    I78 @BASEBOARD_FAB2_LIB.BASEBOARD_FAB2(SCH_1):PAGE109
  J8G1  119  IO119 SCONN200_H68296001_SM-CONN,H68A    I78 @BASEBOARD_FAB2_LIB.BASEBOARD_FAB2(SCH_1):PAGE109
  J8G1  122  IO122 SCONN200_H68296001_SM-CONN,H68A    I78 @BASEBOARD_FAB2_LIB.BASEBOARD_FAB2(SCH_1):PAGE109
  J8G1  125  IO125 SCONN200_H68296001_SM-CONN,H68A    I78 @BASEBOARD_FAB2_LIB.BASEBOARD_FAB2(SCH_1):PAGE109
  J8G1  128  IO128 SCONN200_H68296001_SM-CONN,H68A    I78 @BASEBOARD_FAB2_LIB.BASEBOARD_FAB2(SCH_1):PAGE109
  J8G1  131  IO131 SCONN200_H68296001_SM-CONN,H68A    I78 @BASEBOARD_FAB2_LIB.BASEBOARD_FAB2(SCH_1):PAGE109
  J8G1  134  IO134 SCONN200_H68296001_SM-CONN,H68A    I78 @BASEBOARD_FAB2_LIB.BASEBOARD_FAB2(SCH_1):PAGE109
  J8G1  137  IO137 SCONN200_H68296001_SM-CONN,H68A    I78 @BASEBOARD_FAB2_LIB.BASEBOARD_FAB2(SCH_1):PAGE109
  J8G1  140  IO140 SCONN200_H68296001_SM-CONN,H68A    I78 @BASEBOARD_FAB2_LIB.BASEBOARD_FAB2(SCH_1):PAGE109
  J8G1  143  IO143 SCONN200_H68296001_SM-CONN,H68A    I78 @BASEBOARD_FAB2_LIB.BASEBOARD_FAB2(SCH_1):PAGE109
  J8G1  146  IO146 SCONN200_H68296001_SM-CONN,H68A    I78 @BASEBOARD_FAB2_LIB.BASEBOARD_FAB2(SCH_1):PAGE109
  J8G1  149  IO149 SCONN200_H68296001_SM-CONN,H68A    I78 @BASEBOARD_FAB2_LIB.BASEBOARD_FAB2(SCH_1):PAGE109
  J8G1  152  IO152 SCONN200_H68296001_SM-CONN,H68A    I78 @BASEBOARD_FAB2_LIB.BASEBOARD_FAB2(SCH_1):PAGE109
  J8G1  155  IO155 SCONN200_H68296001_SM-CONN,H68A    I78 @BASEBOARD_FAB2_LIB.BASEBOARD_FAB2(SCH_1):PAGE109
  J8G1  158  IO158 SCONN200_H68296001_SM-CONN,H68A    I78 @BASEBOARD_FAB2_LIB.BASEBOARD_FAB2(SCH_1):PAGE109
  J8G1  161  IO161 SCONN200_H68296001_SM-CONN,H68A    I78 @BASEBOARD_FAB2_LIB.BASEBOARD_FAB2(SCH_1):PAGE109
  J8G1  164  IO164 SCONN200_H68296001_SM-CONN,H68A    I78 @BASEBOARD_FAB2_LIB.BASEBOARD_FAB2(SCH_1):PAGE109
  J8G1  167  IO167 SCONN200_H68296001_SM-CONN,H68A    I78 @BASEBOARD_FAB2_LIB.BASEBOARD_FAB2(SCH_1):PAGE109
  J8G1  170  IO170 SCONN200_H68296001_SM-CONN,H68A    I78 @BASEBOARD_FAB2_LIB.BASEBOARD_FAB2(SCH_1):PAGE109
  J8G1  173  IO173 SCONN200_H68296001_SM-CONN,H68A    I78 @BASEBOARD_FAB2_LIB.BASEBOARD_FAB2(SCH_1):PAGE109
  J8G1  176  IO176 SCONN200_H68296001_SM-CONN,H68A    I78 @BASEBOARD_FAB2_LIB.BASEBOARD_FAB2(SCH_1):PAGE109
  J8G1  179  IO179 SCONN200_H68296001_SM-CONN,H68A    I78 @BASEBOARD_FAB2_LIB.BASEBOARD_FAB2(SCH_1):PAGE109
  J8G1  182  IO182 SCONN200_H68296001_SM-CONN,H68A    I78 @BASEBOARD_FAB2_LIB.BASEBOARD_FAB2(SCH_1):PAGE109
  J8G1  185  IO185 SCONN200_H68296001_SM-CONN,H68A    I78 @BASEBOARD_FAB2_LIB.BASEBOARD_FAB2(SCH_1):PAGE109
  J8G1  188  IO188 SCONN200_H68296001_SM-CONN,H68A    I78 @BASEBOARD_FAB2_LIB.BASEBOARD_FAB2(SCH_1):PAGE109
  J8G1  191  IO191 SCONN200_H68296001_SM-CONN,H68A    I78 @BASEBOARD_FAB2_LIB.BASEBOARD_FAB2(SCH_1):PAGE109
  J8G1  194  IO194 SCONN200_H68296001_SM-CONN,H68A    I78 @BASEBOARD_FAB2_LIB.BASEBOARD_FAB2(SCH_1):PAGE109
  J8G1  197  IO197 SCONN200_H68296001_SM-CONN,H68A    I78 @BASEBOARD_FAB2_LIB.BASEBOARD_FAB2(SCH_1):PAGE109
  J8G1  200  IO200 SCONN200_H68296001_SM-CONN,H68A    I78 @BASEBOARD_FAB2_LIB.BASEBOARD_FAB2(SCH_1):PAGE109
 UN8F2   10    GND W25Q256_XSOI-IC,H25002-001    I17 @BASEBOARD_FAB2_LIB.BASEBOARD_FAB2(SCH_1):PAGE246
  Q6W1    2    SRC FET_N_SOT23LF-2N7002,FET,C7925A   I225 @BASEBOARD_FAB2_LIB.BASEBOARD_FAB2(SCH_1):PAGE200
  R3W1    2      B RES_0402-1.00K,1%,1/16W,CHIP,GA     I2 @BASEBOARD_FAB2_LIB.BASEBOARD_FAB2(SCH_1):PAGE249
  R3W9    2      B RES_0402-10.0K,1%,1/16W,CHIP,GA     I7 @BASEBOARD_FAB2_LIB.BASEBOARD_FAB2(SCH_1):PAGE249
  Q9W4    2    GND LMV331IDCKRG4-GP_DISCRET-G-LMVA    I15 @BASEBOARD_FAB2_LIB.BASEBOARD_FAB2(SCH_1):PAGE249
  Q9W2    2      E NPN_SM-MMBT3904,IC,C52245-001    I29 @BASEBOARD_FAB2_LIB.BASEBOARD_FAB2(SCH_1):PAGE249
EU25F2   11    GND RT9059_DFN-IC,H65765-001    I73 @BASEBOARD_FAB2_LIB.BASEBOARD_FAB2(SCH_1):PAGE239
 C9W13    2      B CAP_0805LF-22UF,4V,20%,X6S,C95A    I81 @BASEBOARD_FAB2_LIB.BASEBOARD_FAB2(SCH_1):PAGE239
 C1W15    2      B CAP_0603-10UF,6.3V,20%,X6S,E15A    I83 @BASEBOARD_FAB2_LIB.BASEBOARD_FAB2(SCH_1):PAGE239
 C9W10    2      B CAP_0402LF-1000PF,50V,10%,X7R,A    I84 @BASEBOARD_FAB2_LIB.BASEBOARD_FAB2(SCH_1):PAGE239
  C9W5    2      B CAP_A_0402V-0.1UF,16V,10%,X7R,A    I90 @BASEBOARD_FAB2_LIB.BASEBOARD_FAB2(SCH_1):PAGE239
  C9W6    2      B CAP_0402LF-1000PF,50V,10%,EMPTA    I91 @BASEBOARD_FAB2_LIB.BASEBOARD_FAB2(SCH_1):PAGE239
  C1W7    2      B CAP_0603-10UF,6.3V,20%,X6S,E15A    I92 @BASEBOARD_FAB2_LIB.BASEBOARD_FAB2(SCH_1):PAGE239
  Q9W1    2    SRC FET_N_SOT23LF-2N7002,FET,C7925A    I30 @BASEBOARD_FAB2_LIB.BASEBOARD_FAB2(SCH_1):PAGE249
 R1T27    1      A RES_0402-240,1.0%,1/16W,CHIP,GA    I58 @BASEBOARD_FAB2_LIB.BASEBOARD_FAB2(SCH_1):PAGE143
  Y9F2    2    GND OSC_C_SM4-24MHZ,OSC,D34520-021     I8 @BASEBOARD_FAB2_LIB.BASEBOARD_FAB2(SCH_1):PAGE145
 C9F23    2      B CAP_A_0402V-0.1UF,16V,10%,X7R,A    I15 @BASEBOARD_FAB2_LIB.BASEBOARD_FAB2(SCH_1):PAGE145
 R9F20    2      B RES_0402-348,1%,1/16W,EMPTY,G2A    I22 @BASEBOARD_FAB2_LIB.BASEBOARD_FAB2(SCH_1):PAGE145
R25W61    2      B RES_0402-100.0K,1%,1/16W,CHIP,A    I30 @BASEBOARD_FAB2_LIB.BASEBOARD_FAB2(SCH_1):PAGE145
R25W62    2      B RES_0402-100.0K,1%,1/16W,CHIP,A    I31 @BASEBOARD_FAB2_LIB.BASEBOARD_FAB2(SCH_1):PAGE145
R25W60    2      B RES_0402-100.0K,1%,1/16W,CHIP,A    I34 @BASEBOARD_FAB2_LIB.BASEBOARD_FAB2(SCH_1):PAGE145
R25W64    2      B RES_0402-100.0K,1%,1/16W,CHIP,A    I36 @BASEBOARD_FAB2_LIB.BASEBOARD_FAB2(SCH_1):PAGE145
R25W65    2      B RES_0402-100.0K,1%,1/16W,CHIP,A    I38 @BASEBOARD_FAB2_LIB.BASEBOARD_FAB2(SCH_1):PAGE145
 R1T25    2      B RES_0402-8.2K,1%,1/16W,CHIP,G2A    I35 @BASEBOARD_FAB2_LIB.BASEBOARD_FAB2(SCH_1):PAGE146
 R1T26    2      B RES_0402-8.2K,1%,1/16W,CHIP,G2A    I37 @BASEBOARD_FAB2_LIB.BASEBOARD_FAB2(SCH_1):PAGE146
  R1U2    2      B RES_0402-100.0K,1%,1/16W,CHIP,A    I62 @BASEBOARD_FAB2_LIB.BASEBOARD_FAB2(SCH_1):PAGE147
R25W63    2      B RES_0402-100.0K,1%,1/16W,CHIP,A    I65 @BASEBOARD_FAB2_LIB.BASEBOARD_FAB2(SCH_1):PAGE146
R25W66    2      B RES_0402-100.0K,1%,1/16W,CHIP,A    I76 @BASEBOARD_FAB2_LIB.BASEBOARD_FAB2(SCH_1):PAGE146
  R1U7    1      A RES_0402-10.0K,1%,1/16W,CHIP,GA    I78 @BASEBOARD_FAB2_LIB.BASEBOARD_FAB2(SCH_1):PAGE146
  R1U4    2      B RES_0402-100.0K,1%,1/16W,CHIP,A    I65 @BASEBOARD_FAB2_LIB.BASEBOARD_FAB2(SCH_1):PAGE147
  R1U5    2      B RES_0402-100.0K,1%,1/16W,CHIP,A    I66 @BASEBOARD_FAB2_LIB.BASEBOARD_FAB2(SCH_1):PAGE147
  R1U1    2      B RES_0402-100.0K,1%,1/16W,CHIP,A    I61 @BASEBOARD_FAB2_LIB.BASEBOARD_FAB2(SCH_1):PAGE147
 C1T21    2      B CAP_A_0402V-1.0UF,6.3V,10%,X6SA    I20 @BASEBOARD_FAB2_LIB.BASEBOARD_FAB2(SCH_1):PAGE148
 R2N13    2      B RES_0402-10.0K,1%,1/16W,CHIP,GA    I75 @BASEBOARD_FAB2_LIB.BASEBOARD_FAB2(SCH_1):PAGE147
 R1T23    2      B RES_0402-0.0,5%,1/16W,EMPTY,G2A   I101 @BASEBOARD_FAB2_LIB.BASEBOARD_FAB2(SCH_1):PAGE145
  C6W3    2      B CAP_A_0402V-0.1UF,16V,10%,X7R,A    I85 @BASEBOARD_FAB2_LIB.BASEBOARD_FAB2(SCH_1):PAGE247
  U6W3    2     A1 AT24C64_SOICLF-IC,C47049-001-GA    I89 @BASEBOARD_FAB2_LIB.BASEBOARD_FAB2(SCH_1):PAGE247
  U6W3    3     A2 AT24C64_SOICLF-IC,C47049-001-GA    I89 @BASEBOARD_FAB2_LIB.BASEBOARD_FAB2(SCH_1):PAGE247
 R6W23    2      B RES_0402-1.00K,1%,1/16W,CHIP,GA    I92 @BASEBOARD_FAB2_LIB.BASEBOARD_FAB2(SCH_1):PAGE247
 U25W4   F2 ADC8_GPIX0 AST2520A1-GP-GP_ASIC2-GB1-AST2A   I106 @BASEBOARD_FAB2_LIB.BASEBOARD_FAB2(SCH_1):PAGE147
 U25W4   G3 ADC9_GPIX1 AST2520A1-GP-GP_ASIC2-GB1-AST2A   I106 @BASEBOARD_FAB2_LIB.BASEBOARD_FAB2(SCH_1):PAGE147
 U25W4   G2 ADC10_GPIX2 AST2520A1-GP-GP_ASIC2-GB1-AST2A   I106 @BASEBOARD_FAB2_LIB.BASEBOARD_FAB2(SCH_1):PAGE147
 U25W4   A1   GND0 AST2520A1-GP-GP_ASIC2-GB1-AST2A    I28 @BASEBOARD_FAB2_LIB.BASEBOARD_FAB2(SCH_1):PAGE148
 U25W4  A22   GND1 AST2520A1-GP-GP_ASIC2-GB1-AST2A    I28 @BASEBOARD_FAB2_LIB.BASEBOARD_FAB2(SCH_1):PAGE148
 U25W4 AA11   GND2 AST2520A1-GP-GP_ASIC2-GB1-AST2A    I28 @BASEBOARD_FAB2_LIB.BASEBOARD_FAB2(SCH_1):PAGE148
 U25W4 AA13   GND3 AST2520A1-GP-GP_ASIC2-GB1-AST2A    I28 @BASEBOARD_FAB2_LIB.BASEBOARD_FAB2(SCH_1):PAGE148
 U25W4 AA15   GND4 AST2520A1-GP-GP_ASIC2-GB1-AST2A    I28 @BASEBOARD_FAB2_LIB.BASEBOARD_FAB2(SCH_1):PAGE148
 U25W4  AA7   GND5 AST2520A1-GP-GP_ASIC2-GB1-AST2A    I28 @BASEBOARD_FAB2_LIB.BASEBOARD_FAB2(SCH_1):PAGE148
 U25W4  AA9   GND6 AST2520A1-GP-GP_ASIC2-GB1-AST2A    I28 @BASEBOARD_FAB2_LIB.BASEBOARD_FAB2(SCH_1):PAGE148
 U25W4  AB1   GND7 AST2520A1-GP-GP_ASIC2-GB1-AST2A    I28 @BASEBOARD_FAB2_LIB.BASEBOARD_FAB2(SCH_1):PAGE148
 U25W4 AB22   GND8 AST2520A1-GP-GP_ASIC2-GB1-AST2A    I28 @BASEBOARD_FAB2_LIB.BASEBOARD_FAB2(SCH_1):PAGE148
 U25W4   C6   GND9 AST2520A1-GP-GP_ASIC2-GB1-AST2A    I28 @BASEBOARD_FAB2_LIB.BASEBOARD_FAB2(SCH_1):PAGE148
 U25W4   E8  GND10 AST2520A1-GP-GP_ASIC2-GB1-AST2A    I28 @BASEBOARD_FAB2_LIB.BASEBOARD_FAB2(SCH_1):PAGE148
 U25W4  F16  GND11 AST2520A1-GP-GP_ASIC2-GB1-AST2A    I28 @BASEBOARD_FAB2_LIB.BASEBOARD_FAB2(SCH_1):PAGE148
 U25W4  G19  GND12 AST2520A1-GP-GP_ASIC2-GB1-AST2A    I28 @BASEBOARD_FAB2_LIB.BASEBOARD_FAB2(SCH_1):PAGE148
 U25W4   G6  GND13 AST2520A1-GP-GP_ASIC2-GB1-AST2A    I28 @BASEBOARD_FAB2_LIB.BASEBOARD_FAB2(SCH_1):PAGE148
 U25W4   H6  GND14 AST2520A1-GP-GP_ASIC2-GB1-AST2A    I28 @BASEBOARD_FAB2_LIB.BASEBOARD_FAB2(SCH_1):PAGE148
 U25W4  J10  GND15 AST2520A1-GP-GP_ASIC2-GB1-AST2A    I28 @BASEBOARD_FAB2_LIB.BASEBOARD_FAB2(SCH_1):PAGE148
 U25W4  J11  GND16 AST2520A1-GP-GP_ASIC2-GB1-AST2A    I28 @BASEBOARD_FAB2_LIB.BASEBOARD_FAB2(SCH_1):PAGE148
 U25W4  J12  GND17 AST2520A1-GP-GP_ASIC2-GB1-AST2A    I28 @BASEBOARD_FAB2_LIB.BASEBOARD_FAB2(SCH_1):PAGE148
 U25W4  J13  GND18 AST2520A1-GP-GP_ASIC2-GB1-AST2A    I28 @BASEBOARD_FAB2_LIB.BASEBOARD_FAB2(SCH_1):PAGE148
 U25W4  J14  GND19 AST2520A1-GP-GP_ASIC2-GB1-AST2A    I28 @BASEBOARD_FAB2_LIB.BASEBOARD_FAB2(SCH_1):PAGE148
 U25W4  J21  GND20 AST2520A1-GP-GP_ASIC2-GB1-AST2A    I28 @BASEBOARD_FAB2_LIB.BASEBOARD_FAB2(SCH_1):PAGE148
 U25W4  J22  GND21 AST2520A1-GP-GP_ASIC2-GB1-AST2A    I28 @BASEBOARD_FAB2_LIB.BASEBOARD_FAB2(SCH_1):PAGE148
 U25W4   J5  GND22 AST2520A1-GP-GP_ASIC2-GB1-AST2A    I28 @BASEBOARD_FAB2_LIB.BASEBOARD_FAB2(SCH_1):PAGE148
 U25W4   J9  GND23 AST2520A1-GP-GP_ASIC2-GB1-AST2A    I28 @BASEBOARD_FAB2_LIB.BASEBOARD_FAB2(SCH_1):PAGE148
 U25W4  K10  GND24 AST2520A1-GP-GP_ASIC2-GB1-AST2A    I28 @BASEBOARD_FAB2_LIB.BASEBOARD_FAB2(SCH_1):PAGE148
 U25W4  K11  GND25 AST2520A1-GP-GP_ASIC2-GB1-AST2A    I28 @BASEBOARD_FAB2_LIB.BASEBOARD_FAB2(SCH_1):PAGE148
 U25W4  K12  GND26 AST2520A1-GP-GP_ASIC2-GB1-AST2A    I28 @BASEBOARD_FAB2_LIB.BASEBOARD_FAB2(SCH_1):PAGE148
 U25W4  K13  GND27 AST2520A1-GP-GP_ASIC2-GB1-AST2A    I28 @BASEBOARD_FAB2_LIB.BASEBOARD_FAB2(SCH_1):PAGE148
 U25W4  K14  GND28 AST2520A1-GP-GP_ASIC2-GB1-AST2A    I28 @BASEBOARD_FAB2_LIB.BASEBOARD_FAB2(SCH_1):PAGE148
 U25W4  K16  GND29 AST2520A1-GP-GP_ASIC2-GB1-AST2A    I28 @BASEBOARD_FAB2_LIB.BASEBOARD_FAB2(SCH_1):PAGE148
 U25W4   K9  GND30 AST2520A1-GP-GP_ASIC2-GB1-AST2A    I28 @BASEBOARD_FAB2_LIB.BASEBOARD_FAB2(SCH_1):PAGE148
 U25W4  L10  GND31 AST2520A1-GP-GP_ASIC2-GB1-AST2A    I28 @BASEBOARD_FAB2_LIB.BASEBOARD_FAB2(SCH_1):PAGE148
 U25W4  L11  GND32 AST2520A1-GP-GP_ASIC2-GB1-AST2A    I28 @BASEBOARD_FAB2_LIB.BASEBOARD_FAB2(SCH_1):PAGE148
 U25W4  L12  GND33 AST2520A1-GP-GP_ASIC2-GB1-AST2A    I28 @BASEBOARD_FAB2_LIB.BASEBOARD_FAB2(SCH_1):PAGE148
 U25W4  L13  GND34 AST2520A1-GP-GP_ASIC2-GB1-AST2A    I28 @BASEBOARD_FAB2_LIB.BASEBOARD_FAB2(SCH_1):PAGE148
 U25W4  L14  GND35 AST2520A1-GP-GP_ASIC2-GB1-AST2A    I28 @BASEBOARD_FAB2_LIB.BASEBOARD_FAB2(SCH_1):PAGE148
 U25W4   L9  GND36 AST2520A1-GP-GP_ASIC2-GB1-AST2A    I28 @BASEBOARD_FAB2_LIB.BASEBOARD_FAB2(SCH_1):PAGE148
 U25W4   M1  GND37 AST2520A1-GP-GP_ASIC2-GB1-AST2A    I28 @BASEBOARD_FAB2_LIB.BASEBOARD_FAB2(SCH_1):PAGE148
 U25W4  M10  GND38 AST2520A1-GP-GP_ASIC2-GB1-AST2A    I28 @BASEBOARD_FAB2_LIB.BASEBOARD_FAB2(SCH_1):PAGE148
 U25W4  M11  GND39 AST2520A1-GP-GP_ASIC2-GB1-AST2A    I28 @BASEBOARD_FAB2_LIB.BASEBOARD_FAB2(SCH_1):PAGE148
 U25W4  M12  GND40 AST2520A1-GP-GP_ASIC2-GB1-AST2A    I28 @BASEBOARD_FAB2_LIB.BASEBOARD_FAB2(SCH_1):PAGE148
 U25W4  M13  GND41 AST2520A1-GP-GP_ASIC2-GB1-AST2A    I28 @BASEBOARD_FAB2_LIB.BASEBOARD_FAB2(SCH_1):PAGE148
 U25W4  M14  GND42 AST2520A1-GP-GP_ASIC2-GB1-AST2A    I28 @BASEBOARD_FAB2_LIB.BASEBOARD_FAB2(SCH_1):PAGE148
 U25W4  M16  GND43 AST2520A1-GP-GP_ASIC2-GB1-AST2A    I28 @BASEBOARD_FAB2_LIB.BASEBOARD_FAB2(SCH_1):PAGE148
 U25W4  M17  GND44 AST2520A1-GP-GP_ASIC2-GB1-AST2A    I28 @BASEBOARD_FAB2_LIB.BASEBOARD_FAB2(SCH_1):PAGE148
 U25W4   M2  GND45 AST2520A1-GP-GP_ASIC2-GB1-AST2A    I28 @BASEBOARD_FAB2_LIB.BASEBOARD_FAB2(SCH_1):PAGE148
 U25W4   M3  GND46 AST2520A1-GP-GP_ASIC2-GB1-AST2A    I28 @BASEBOARD_FAB2_LIB.BASEBOARD_FAB2(SCH_1):PAGE148
 U25W4   M4  GND47 AST2520A1-GP-GP_ASIC2-GB1-AST2A    I28 @BASEBOARD_FAB2_LIB.BASEBOARD_FAB2(SCH_1):PAGE148
 U25W4   M5  GND48 AST2520A1-GP-GP_ASIC2-GB1-AST2A    I28 @BASEBOARD_FAB2_LIB.BASEBOARD_FAB2(SCH_1):PAGE148
 U25W4   M6  GND49 AST2520A1-GP-GP_ASIC2-GB1-AST2A    I28 @BASEBOARD_FAB2_LIB.BASEBOARD_FAB2(SCH_1):PAGE148
 U25W4   M7  GND50 AST2520A1-GP-GP_ASIC2-GB1-AST2A    I28 @BASEBOARD_FAB2_LIB.BASEBOARD_FAB2(SCH_1):PAGE148
 U25W4   M9  GND51 AST2520A1-GP-GP_ASIC2-GB1-AST2A    I28 @BASEBOARD_FAB2_LIB.BASEBOARD_FAB2(SCH_1):PAGE148
 U25W4  N10  GND52 AST2520A1-GP-GP_ASIC2-GB1-AST2A    I28 @BASEBOARD_FAB2_LIB.BASEBOARD_FAB2(SCH_1):PAGE148
 U25W4  N11  GND53 AST2520A1-GP-GP_ASIC2-GB1-AST2A    I28 @BASEBOARD_FAB2_LIB.BASEBOARD_FAB2(SCH_1):PAGE148
 U25W4  N12  GND54 AST2520A1-GP-GP_ASIC2-GB1-AST2A    I28 @BASEBOARD_FAB2_LIB.BASEBOARD_FAB2(SCH_1):PAGE148
 U25W4  N13  GND55 AST2520A1-GP-GP_ASIC2-GB1-AST2A    I28 @BASEBOARD_FAB2_LIB.BASEBOARD_FAB2(SCH_1):PAGE148
 U25W4  N14  GND56 AST2520A1-GP-GP_ASIC2-GB1-AST2A    I28 @BASEBOARD_FAB2_LIB.BASEBOARD_FAB2(SCH_1):PAGE148
 U25W4   N9  GND57 AST2520A1-GP-GP_ASIC2-GB1-AST2A    I28 @BASEBOARD_FAB2_LIB.BASEBOARD_FAB2(SCH_1):PAGE148
 U25W4  T16  GND58 AST2520A1-GP-GP_ASIC2-GB1-AST2A    I28 @BASEBOARD_FAB2_LIB.BASEBOARD_FAB2(SCH_1):PAGE148
 U25W4   T6  GND59 AST2520A1-GP-GP_ASIC2-GB1-AST2A    I28 @BASEBOARD_FAB2_LIB.BASEBOARD_FAB2(SCH_1):PAGE148
 U25W4   T7  GND60 AST2520A1-GP-GP_ASIC2-GB1-AST2A    I28 @BASEBOARD_FAB2_LIB.BASEBOARD_FAB2(SCH_1):PAGE148
 U25W4  U11  GND61 AST2520A1-GP-GP_ASIC2-GB1-AST2A    I28 @BASEBOARD_FAB2_LIB.BASEBOARD_FAB2(SCH_1):PAGE148
 U25W4   U6  GND62 AST2520A1-GP-GP_ASIC2-GB1-AST2A    I28 @BASEBOARD_FAB2_LIB.BASEBOARD_FAB2(SCH_1):PAGE148
 U25W4  V10  GND63 AST2520A1-GP-GP_ASIC2-GB1-AST2A    I28 @BASEBOARD_FAB2_LIB.BASEBOARD_FAB2(SCH_1):PAGE148
 U25W4  V12  GND64 AST2520A1-GP-GP_ASIC2-GB1-AST2A    I28 @BASEBOARD_FAB2_LIB.BASEBOARD_FAB2(SCH_1):PAGE148
 U25W4  V14  GND65 AST2520A1-GP-GP_ASIC2-GB1-AST2A    I28 @BASEBOARD_FAB2_LIB.BASEBOARD_FAB2(SCH_1):PAGE148
 U25W4  V16  GND66 AST2520A1-GP-GP_ASIC2-GB1-AST2A    I28 @BASEBOARD_FAB2_LIB.BASEBOARD_FAB2(SCH_1):PAGE148
 U25W4   V8  GND67 AST2520A1-GP-GP_ASIC2-GB1-AST2A    I28 @BASEBOARD_FAB2_LIB.BASEBOARD_FAB2(SCH_1):PAGE148
 U25W4   E5  GND68 AST2520A1-GP-GP_ASIC2-GB1-AST2A    I28 @BASEBOARD_FAB2_LIB.BASEBOARD_FAB2(SCH_1):PAGE148
R25W67    2      2 200R2F-L1-GP_SMD-RG4-200R2F-L1A   I118 @BASEBOARD_FAB2_LIB.BASEBOARD_FAB2(SCH_1):PAGE145
  U3T1   10    GND W25Q256FVFIG-GP_MEMORY-G4-W25QA   I185 @BASEBOARD_FAB2_LIB.BASEBOARD_FAB2(SCH_1):PAGE153
 C14W1    2      B CAP_A_0402V-0.1UF,16V,10%,X7R,A    I13 @BASEBOARD_FAB2_LIB.BASEBOARD_FAB2(SCH_1):PAGE248
 C14W2    2      B CAP_A_0402V-0.1UF,16V,10%,X7R,A    I17 @BASEBOARD_FAB2_LIB.BASEBOARD_FAB2(SCH_1):PAGE248
  S9A2    1   PIN1 SWITCH_D37771002_SM-IC,D37771-A    I92 @BASEBOARD_FAB2_LIB.BASEBOARD_FAB2(SCH_1):PAGE175
  S9A2    2   PIN2 SWITCH_D37771002_SM-IC,D37771-A    I92 @BASEBOARD_FAB2_LIB.BASEBOARD_FAB2(SCH_1):PAGE175
C25W70    2      B CAP_0603-4.7UF,6.3V,10%,X6S,E1A     I5 @BASEBOARD_FAB2_LIB.BASEBOARD_FAB2(SCH_1):PAGE149
C25W69    2      B CAP_0603-4.7UF,6.3V,10%,X6S,E1A    I17 @BASEBOARD_FAB2_LIB.BASEBOARD_FAB2(SCH_1):PAGE149
C25W39    2      B CAP_0603-4.7UF,6.3V,10%,X6S,E1A    I25 @BASEBOARD_FAB2_LIB.BASEBOARD_FAB2(SCH_1):PAGE149
C25W50    2      B CAP_0603-4.7UF,6.3V,10%,X6S,E1A    I31 @BASEBOARD_FAB2_LIB.BASEBOARD_FAB2(SCH_1):PAGE149
C25W62    2      B CAP_0603-4.7UF,6.3V,10%,X6S,E1A    I40 @BASEBOARD_FAB2_LIB.BASEBOARD_FAB2(SCH_1):PAGE149
C25W36    2      B CAP_0603-4.7UF,6.3V,10%,X6S,E1A    I46 @BASEBOARD_FAB2_LIB.BASEBOARD_FAB2(SCH_1):PAGE149
C25W47    2      B CAP_0603-4.7UF,6.3V,10%,X6S,E1A    I50 @BASEBOARD_FAB2_LIB.BASEBOARD_FAB2(SCH_1):PAGE149
C25W46    2      B CAP_0805-10UF,16V,10%,X6S,C953A    I51 @BASEBOARD_FAB2_LIB.BASEBOARD_FAB2(SCH_1):PAGE149
C25W59    2      B CAP_0603-4.7UF,6.3V,10%,X6S,E1A    I79 @BASEBOARD_FAB2_LIB.BASEBOARD_FAB2(SCH_1):PAGE149
C25W30    2      B CAP_0603-4.7UF,6.3V,10%,X6S,E1A     I1 @BASEBOARD_FAB2_LIB.BASEBOARD_FAB2(SCH_1):PAGE149
 U25W5   N9    TEN H5AN4G6NAFR-TFC-GP_MEMORY-G2-HA    I49 @BASEBOARD_FAB2_LIB.BASEBOARD_FAB2(SCH_1):PAGE151
 U25W5   B2 VSS<0> H5AN4G6NAFR-TFC-GP_MEMORY-G2-HA    I49 @BASEBOARD_FAB2_LIB.BASEBOARD_FAB2(SCH_1):PAGE151
 U25W5   E1 VSS<1> H5AN4G6NAFR-TFC-GP_MEMORY-G2-HA    I49 @BASEBOARD_FAB2_LIB.BASEBOARD_FAB2(SCH_1):PAGE151
 U25W5   E9 VSS<2> H5AN4G6NAFR-TFC-GP_MEMORY-G2-HA    I49 @BASEBOARD_FAB2_LIB.BASEBOARD_FAB2(SCH_1):PAGE151
 U25W5   G8 VSS<3> H5AN4G6NAFR-TFC-GP_MEMORY-G2-HA    I49 @BASEBOARD_FAB2_LIB.BASEBOARD_FAB2(SCH_1):PAGE151
 U25W5   K1 VSS<4> H5AN4G6NAFR-TFC-GP_MEMORY-G2-HA    I49 @BASEBOARD_FAB2_LIB.BASEBOARD_FAB2(SCH_1):PAGE151
 U25W5   K9 VSS<5> H5AN4G6NAFR-TFC-GP_MEMORY-G2-HA    I49 @BASEBOARD_FAB2_LIB.BASEBOARD_FAB2(SCH_1):PAGE151
 U25W5   M9 VSS<6> H5AN4G6NAFR-TFC-GP_MEMORY-G2-HA    I49 @BASEBOARD_FAB2_LIB.BASEBOARD_FAB2(SCH_1):PAGE151
 U25W5   N1 VSS<7> H5AN4G6NAFR-TFC-GP_MEMORY-G2-HA    I49 @BASEBOARD_FAB2_LIB.BASEBOARD_FAB2(SCH_1):PAGE151
 U25W5   T1 VSS<8> H5AN4G6NAFR-TFC-GP_MEMORY-G2-HA    I49 @BASEBOARD_FAB2_LIB.BASEBOARD_FAB2(SCH_1):PAGE151
 U25W5   A2 VSSQ<0> H5AN4G6NAFR-TFC-GP_MEMORY-G2-HA    I49 @BASEBOARD_FAB2_LIB.BASEBOARD_FAB2(SCH_1):PAGE151
 U25W5   A8 VSSQ<1> H5AN4G6NAFR-TFC-GP_MEMORY-G2-HA    I49 @BASEBOARD_FAB2_LIB.BASEBOARD_FAB2(SCH_1):PAGE151
 U25W5   C9 VSSQ<2> H5AN4G6NAFR-TFC-GP_MEMORY-G2-HA    I49 @BASEBOARD_FAB2_LIB.BASEBOARD_FAB2(SCH_1):PAGE151
 U25W5   D2 VSSQ<3> H5AN4G6NAFR-TFC-GP_MEMORY-G2-HA    I49 @BASEBOARD_FAB2_LIB.BASEBOARD_FAB2(SCH_1):PAGE151
 U25W5   D8 VSSQ<4> H5AN4G6NAFR-TFC-GP_MEMORY-G2-HA    I49 @BASEBOARD_FAB2_LIB.BASEBOARD_FAB2(SCH_1):PAGE151
 U25W5   E3 VSSQ<5> H5AN4G6NAFR-TFC-GP_MEMORY-G2-HA    I49 @BASEBOARD_FAB2_LIB.BASEBOARD_FAB2(SCH_1):PAGE151
 U25W5   E8 VSSQ<6> H5AN4G6NAFR-TFC-GP_MEMORY-G2-HA    I49 @BASEBOARD_FAB2_LIB.BASEBOARD_FAB2(SCH_1):PAGE151
 U25W5   F1 VSSQ<7> H5AN4G6NAFR-TFC-GP_MEMORY-G2-HA    I49 @BASEBOARD_FAB2_LIB.BASEBOARD_FAB2(SCH_1):PAGE151
 U25W5   H1 VSSQ<8> H5AN4G6NAFR-TFC-GP_MEMORY-G2-HA    I49 @BASEBOARD_FAB2_LIB.BASEBOARD_FAB2(SCH_1):PAGE151
 U25W5   H9 VSSQ<9> H5AN4G6NAFR-TFC-GP_MEMORY-G2-HA    I49 @BASEBOARD_FAB2_LIB.BASEBOARD_FAB2(SCH_1):PAGE151
C25W16    2      B CAP_0402LF-100.0PF,50V,5%,COG,A    I58 @BASEBOARD_FAB2_LIB.BASEBOARD_FAB2(SCH_1):PAGE151
R25W117    2      B RES_0402-240,1.0%,1/16W,CHIP,GA   I101 @BASEBOARD_FAB2_LIB.BASEBOARD_FAB2(SCH_1):PAGE151
C25W17    2      2 SC1U16V3KX-2GP_SMD-BCG-SC1U16VA   I120 @BASEBOARD_FAB2_LIB.BASEBOARD_FAB2(SCH_1):PAGE151
C25W18    2      2 SC1U16V3KX-2GP_SMD-BCG-SC1U16VA   I121 @BASEBOARD_FAB2_LIB.BASEBOARD_FAB2(SCH_1):PAGE151
C25W19    2      B CAP_0603-4.7UF,6.3V,10%,X6S,E1A   I123 @BASEBOARD_FAB2_LIB.BASEBOARD_FAB2(SCH_1):PAGE151
 C25W1    2      B CAP_0402-1.0UF,16V,10%,X6S,D97A   I125 @BASEBOARD_FAB2_LIB.BASEBOARD_FAB2(SCH_1):PAGE151
 C25W2    2      B CAP_0402-1.0UF,16V,10%,X6S,D97A   I139 @BASEBOARD_FAB2_LIB.BASEBOARD_FAB2(SCH_1):PAGE151
 C25W3    2      B CAP_0402-1.0UF,16V,10%,X6S,D97A   I140 @BASEBOARD_FAB2_LIB.BASEBOARD_FAB2(SCH_1):PAGE151
 C25W4    2      B CAP_0402-1.0UF,16V,10%,X6S,D97A   I141 @BASEBOARD_FAB2_LIB.BASEBOARD_FAB2(SCH_1):PAGE151
 C25W5    2      B CAP_0402-1.0UF,16V,10%,X6S,D97A   I142 @BASEBOARD_FAB2_LIB.BASEBOARD_FAB2(SCH_1):PAGE151
 C25W6    2      B CAP_0402-1.0UF,16V,10%,X6S,D97A   I143 @BASEBOARD_FAB2_LIB.BASEBOARD_FAB2(SCH_1):PAGE151
  Q9E1    4 SOURCE<0> FET_N_DUAL_SMLF-NTJD4001N,FET,A   I145 @BASEBOARD_FAB2_LIB.BASEBOARD_FAB2(SCH_1):PAGE151
  Q9E1    1 SOURCE<0> FET_N_DUAL_SMLF-NTJD4001N,FET,A   I198 @BASEBOARD_FAB2_LIB.BASEBOARD_FAB2(SCH_1):PAGE151
 R1T29    2      B RES_0402-1.00K,1%,1/16W,CHIP,GA   I202 @BASEBOARD_FAB2_LIB.BASEBOARD_FAB2(SCH_1):PAGE151
  C6W4    2      B CAP_A_0402V-0.1UF,16V,10%,X7R,A   I105 @BASEBOARD_FAB2_LIB.BASEBOARD_FAB2(SCH_1):PAGE247
  C6W2    2      B CAP_A_0402V-0.1UF,16V,10%,X7R,A   I107 @BASEBOARD_FAB2_LIB.BASEBOARD_FAB2(SCH_1):PAGE247
  C9W8    2      B CAP_A_0402V-0.1UF,16V,10%,X7R,A    I30 @BASEBOARD_FAB2_LIB.BASEBOARD_FAB2(SCH_1):PAGE248
  C9W7    2      B CAP_A_0402V-0.1UF,16V,10%,X7R,A    I32 @BASEBOARD_FAB2_LIB.BASEBOARD_FAB2(SCH_1):PAGE248
 R1U16    2      B RES_0402-1.00K,1%,1/16W,CHIP,GA    I37 @BASEBOARD_FAB2_LIB.BASEBOARD_FAB2(SCH_1):PAGE164
 RN8F6    2      2 82KR2F-1-GP_SMD-RG-82KR2F-1-GPA    I19 @BASEBOARD_FAB2_LIB.BASEBOARD_FAB2(SCH_1):PAGE246
  Q1P2    2    SRC FET_N_SOT23LF-2N7002,FET,C7925A   I129 @BASEBOARD_FAB2_LIB.BASEBOARD_FAB2(SCH_1):PAGE196
  Q7D1    2    SRC FET_N_SOT23LF-2N7002,FET,C7925A    I14 @BASEBOARD_FAB2_LIB.BASEBOARD_FAB2(SCH_1):PAGE134
  Q7E4    2    SRC FET_N_SOT23LF-2N7002,FET,C7925A   I122 @BASEBOARD_FAB2_LIB.BASEBOARD_FAB2(SCH_1):PAGE95
  Q7E8    2    SRC FET_N_SOT23LF-2N7002,FET,C7925A   I123 @BASEBOARD_FAB2_LIB.BASEBOARD_FAB2(SCH_1):PAGE95
  Q1W4    1 SOURCE<0> FET_N_DUAL_SMLF-2N7002DW,FET,DA     I3 @BASEBOARD_FAB2_LIB.BASEBOARD_FAB2(SCH_1):PAGE250
  Q1W4    4 SOURCE<0> FET_N_DUAL_SMLF-2N7002DW,FET,DA     I8 @BASEBOARD_FAB2_LIB.BASEBOARD_FAB2(SCH_1):PAGE250
 R1U28    2      2 1K82R2F-1-GP_SMD-RG-1K82R2F-1-A   I169 @BASEBOARD_FAB2_LIB.BASEBOARD_FAB2(SCH_1):PAGE169
 R1U44    2      2 1K82R2F-1-GP_SMD-RG-1K82R2F-1-A   I170 @BASEBOARD_FAB2_LIB.BASEBOARD_FAB2(SCH_1):PAGE169
 R1U33    2      2 649R2F-GP_RCL_GP-649R2F-GP,64.A   I171 @BASEBOARD_FAB2_LIB.BASEBOARD_FAB2(SCH_1):PAGE169
 R1U38    2      B RES_0402-3.48K,1.0%,1/16W,CHIPA   I172 @BASEBOARD_FAB2_LIB.BASEBOARD_FAB2(SCH_1):PAGE169
 R1U27    2      B RES_0402-3.48K,1.0%,1/16W,CHIPA   I173 @BASEBOARD_FAB2_LIB.BASEBOARD_FAB2(SCH_1):PAGE169
 C5G77    2      B CAP_0805-47UF,4V,20%,X6S,C9533A    I89 @BASEBOARD_FAB2_LIB.BASEBOARD_FAB2(SCH_1):PAGE242
 C5G22    2      B CAP_0805-47UF,4V,20%,X6S,C9533A    I90 @BASEBOARD_FAB2_LIB.BASEBOARD_FAB2(SCH_1):PAGE242
 C5G78    2      B CAP_0805-47UF,4V,20%,X6S,C9533A    I91 @BASEBOARD_FAB2_LIB.BASEBOARD_FAB2(SCH_1):PAGE242
 C5G21    2      B CAP_0805-47UF,4V,20%,X6S,C9533A    I92 @BASEBOARD_FAB2_LIB.BASEBOARD_FAB2(SCH_1):PAGE242
C5G115    2      B CAP_0805-47UF,4V,20%,X6S,C9533A    I89 @BASEBOARD_FAB2_LIB.BASEBOARD_FAB2(SCH_1):PAGE243
C5G116    2      B CAP_0805-47UF,4V,20%,X6S,C9533A    I90 @BASEBOARD_FAB2_LIB.BASEBOARD_FAB2(SCH_1):PAGE243
C5G118    2      B CAP_0805-47UF,4V,20%,X6S,C9533A    I91 @BASEBOARD_FAB2_LIB.BASEBOARD_FAB2(SCH_1):PAGE243
C5G117    2      B CAP_0805-47UF,4V,20%,X6S,C9533A    I92 @BASEBOARD_FAB2_LIB.BASEBOARD_FAB2(SCH_1):PAGE243
R25W57    2      B RES_0402-49.9K,1%,1/16W,CHIP,GA   I151 @BASEBOARD_FAB2_LIB.BASEBOARD_FAB2(SCH_1):PAGE147
C25W53    2      B CAP_0402-1.0UF,16V,10%,X6S,D97A    I92 @BASEBOARD_FAB2_LIB.BASEBOARD_FAB2(SCH_1):PAGE149
C25W56    2      B CAP_0402-1.0UF,16V,10%,X6S,D97A    I93 @BASEBOARD_FAB2_LIB.BASEBOARD_FAB2(SCH_1):PAGE149
C25W54    2      B CAP_0402-1.0UF,16V,10%,X6S,D97A    I95 @BASEBOARD_FAB2_LIB.BASEBOARD_FAB2(SCH_1):PAGE149
C25W40    2      B CAP_0402-1.0UF,16V,10%,X6S,D97A    I96 @BASEBOARD_FAB2_LIB.BASEBOARD_FAB2(SCH_1):PAGE149
C25W41    2      B CAP_0402-1.0UF,16V,10%,X6S,D97A    I97 @BASEBOARD_FAB2_LIB.BASEBOARD_FAB2(SCH_1):PAGE149
C25W42    2      B CAP_0402-1.0UF,16V,10%,X6S,D97A    I98 @BASEBOARD_FAB2_LIB.BASEBOARD_FAB2(SCH_1):PAGE149
C25W32    2      B CAP_0402-1.0UF,16V,10%,X6S,D97A    I99 @BASEBOARD_FAB2_LIB.BASEBOARD_FAB2(SCH_1):PAGE149
C25W43    2      B CAP_0402-1.0UF,16V,10%,X6S,D97A   I100 @BASEBOARD_FAB2_LIB.BASEBOARD_FAB2(SCH_1):PAGE149
C25W44    2      B CAP_0402-1.0UF,16V,10%,X6S,D97A   I101 @BASEBOARD_FAB2_LIB.BASEBOARD_FAB2(SCH_1):PAGE149
C25W33    2      B CAP_0402-1.0UF,16V,10%,X6S,D97A   I102 @BASEBOARD_FAB2_LIB.BASEBOARD_FAB2(SCH_1):PAGE149
C25W23    2      B CAP_0402-1.0UF,16V,10%,X6S,D97A   I103 @BASEBOARD_FAB2_LIB.BASEBOARD_FAB2(SCH_1):PAGE149
C25W24    2      B CAP_0402-1.0UF,16V,10%,X6S,D97A   I104 @BASEBOARD_FAB2_LIB.BASEBOARD_FAB2(SCH_1):PAGE149
C25W25    2      B CAP_0402-1.0UF,16V,10%,X6S,D97A   I105 @BASEBOARD_FAB2_LIB.BASEBOARD_FAB2(SCH_1):PAGE149
C25W26    2      B CAP_0402-1.0UF,16V,10%,X6S,D97A   I106 @BASEBOARD_FAB2_LIB.BASEBOARD_FAB2(SCH_1):PAGE149
C25W27    2      B CAP_0402-1.0UF,16V,10%,X6S,D97A   I107 @BASEBOARD_FAB2_LIB.BASEBOARD_FAB2(SCH_1):PAGE149
C25W28    2      B CAP_0402-1.0UF,16V,10%,X6S,D97A   I108 @BASEBOARD_FAB2_LIB.BASEBOARD_FAB2(SCH_1):PAGE149
C25W60    2      B CAP_0402-1.0UF,16V,10%,X6S,D97A   I109 @BASEBOARD_FAB2_LIB.BASEBOARD_FAB2(SCH_1):PAGE149
C25W35    2      B CAP_0402-1.0UF,16V,10%,X6S,D97A   I110 @BASEBOARD_FAB2_LIB.BASEBOARD_FAB2(SCH_1):PAGE149
C25W48    2      B CAP_0402-1.0UF,16V,10%,X6S,D97A   I112 @BASEBOARD_FAB2_LIB.BASEBOARD_FAB2(SCH_1):PAGE149
C25W37    2      B CAP_0402-1.0UF,16V,10%,X6S,D97A   I113 @BASEBOARD_FAB2_LIB.BASEBOARD_FAB2(SCH_1):PAGE149
C25W51    2      B CAP_0402-1.0UF,16V,10%,X6S,D97A   I114 @BASEBOARD_FAB2_LIB.BASEBOARD_FAB2(SCH_1):PAGE149
C25W71    2      B CAP_0402-1.0UF,16V,10%,X6S,D97A   I115 @BASEBOARD_FAB2_LIB.BASEBOARD_FAB2(SCH_1):PAGE149
C25W66    2      B CAP_0402-1.0UF,16V,10%,X6S,D97A   I116 @BASEBOARD_FAB2_LIB.BASEBOARD_FAB2(SCH_1):PAGE149
C25W67    2      B CAP_0402-1.0UF,16V,10%,X6S,D97A   I117 @BASEBOARD_FAB2_LIB.BASEBOARD_FAB2(SCH_1):PAGE149
C25W52    2      B CAP_0402-1.0UF,16V,10%,X6S,D97A   I118 @BASEBOARD_FAB2_LIB.BASEBOARD_FAB2(SCH_1):PAGE149
  U2R1    2    GND TC7PZ14FU-GP_DISCRET-GA1-TC7PZA   I390 @BASEBOARD_FAB2_LIB.BASEBOARD_FAB2(SCH_1):PAGE157
  U9A3    2    GND TC7PZ14FU-GP_DISCRET-GA1-TC7PZA    I93 @BASEBOARD_FAB2_LIB.BASEBOARD_FAB2(SCH_1):PAGE175
  U9A4    2    GND TC7PZ14FU-GP_DISCRET-GA1-TC7PZA    I97 @BASEBOARD_FAB2_LIB.BASEBOARD_FAB2(SCH_1):PAGE175
 R1U18    2      B RES_0402-1.00K,1%,1/16W,CHIP,GA    I40 @BASEBOARD_FAB2_LIB.BASEBOARD_FAB2(SCH_1):PAGE164
  U8F3    2    GND SN74LVC2G07DCKR-GP_DISCRET-G4-A   I340 @BASEBOARD_FAB2_LIB.BASEBOARD_FAB2(SCH_1):PAGE156
  U8G1    2    GND SN74LVC2G07DCKR-GP_DISCRET-G4-A   I342 @BASEBOARD_FAB2_LIB.BASEBOARD_FAB2(SCH_1):PAGE156
 C10W2    2      B CAP_A_0402V-0.1UF,16V,10%,X7R,A     I1 @BASEBOARD_FAB2_LIB.BASEBOARD_FAB2(SCH_1):PAGE251
 C10W1    2      B CAP_0805-10UF,16V,10%,X6S,C953A     I3 @BASEBOARD_FAB2_LIB.BASEBOARD_FAB2(SCH_1):PAGE251
 C10W3    2      B CAP_A_0402V-0.01UF,25V,10%,X7RA    I16 @BASEBOARD_FAB2_LIB.BASEBOARD_FAB2(SCH_1):PAGE251
 C10W4    2      B CAP_A_0402V-0.1UF,16V,10%,X7R,A    I21 @BASEBOARD_FAB2_LIB.BASEBOARD_FAB2(SCH_1):PAGE251
  Q1W2    4 SOURCE<0> FET_N_DUAL_SMLF-2N7002DW,FET,DA    I12 @BASEBOARD_FAB2_LIB.BASEBOARD_FAB2(SCH_1):PAGE250
  Q1W2    1 SOURCE<0> FET_N_DUAL_SMLF-2N7002DW,FET,DA    I24 @BASEBOARD_FAB2_LIB.BASEBOARD_FAB2(SCH_1):PAGE250
R25W123    2      B RES_0402-150.0,1%,1/16W,CHIP,GA   I139 @BASEBOARD_FAB2_LIB.BASEBOARD_FAB2(SCH_1):PAGE144
R25W124    2      B RES_0402-150.0,1%,1/16W,CHIP,GA   I140 @BASEBOARD_FAB2_LIB.BASEBOARD_FAB2(SCH_1):PAGE144
R25W125    2      B RES_0402-150.0,1%,1/16W,CHIP,GA   I141 @BASEBOARD_FAB2_LIB.BASEBOARD_FAB2(SCH_1):PAGE144
C25W72    2      B CAP_0402LF-12.0PF,50V,5%,COG,AA     I7 @BASEBOARD_FAB2_LIB.BASEBOARD_FAB2(SCH_1):PAGE255
C25W73    2      B CAP_0402LF-12.0PF,50V,5%,COG,AA    I11 @BASEBOARD_FAB2_LIB.BASEBOARD_FAB2(SCH_1):PAGE255
C25W74    2      B CAP_0402LF-12.0PF,50V,5%,COG,AA    I12 @BASEBOARD_FAB2_LIB.BASEBOARD_FAB2(SCH_1):PAGE255
C25W77    2      B CAP_0402LF-12.0PF,50V,5%,COG,AA    I16 @BASEBOARD_FAB2_LIB.BASEBOARD_FAB2(SCH_1):PAGE255
C25W76    2      B CAP_0402LF-12.0PF,50V,5%,COG,AA    I18 @BASEBOARD_FAB2_LIB.BASEBOARD_FAB2(SCH_1):PAGE255
C25W75    2      B CAP_0402LF-12.0PF,50V,5%,COG,AA    I21 @BASEBOARD_FAB2_LIB.BASEBOARD_FAB2(SCH_1):PAGE255
R25W128    2      B RES_0402-150.0,1%,1/16W,CHIP,GA    I22 @BASEBOARD_FAB2_LIB.BASEBOARD_FAB2(SCH_1):PAGE255
R25W127    2      B RES_0402-150.0,1%,1/16W,CHIP,GA    I24 @BASEBOARD_FAB2_LIB.BASEBOARD_FAB2(SCH_1):PAGE255
R25W126    2      B RES_0402-150.0,1%,1/16W,CHIP,GA    I26 @BASEBOARD_FAB2_LIB.BASEBOARD_FAB2(SCH_1):PAGE255
C25W78    2      B CAP_0402LF-100.0PF,50V,5%,COG,A    I35 @BASEBOARD_FAB2_LIB.BASEBOARD_FAB2(SCH_1):PAGE255
C25W79    2      B CAP_0402LF-100.0PF,50V,5%,COG,A    I39 @BASEBOARD_FAB2_LIB.BASEBOARD_FAB2(SCH_1):PAGE255
R25W116    1      A RES_0402-3.32K,1%,1/16W,EMPTY,A   I189 @BASEBOARD_FAB2_LIB.BASEBOARD_FAB2(SCH_1):PAGE150
C25W81    2      B CAP_0402LF-10.0PF,50V,5%,COG,AA    I60 @BASEBOARD_FAB2_LIB.BASEBOARD_FAB2(SCH_1):PAGE255
C25W82    2      B CAP_0402LF-10.0PF,50V,5%,COG,AA    I62 @BASEBOARD_FAB2_LIB.BASEBOARD_FAB2(SCH_1):PAGE255
C25P83    2      B CAP_A_0402V-0.1UF,16V,10%,X7R,A    I74 @BASEBOARD_FAB2_LIB.BASEBOARD_FAB2(SCH_1):PAGE255
  U1B2    4    GND TCA9517DGKR-GP_DISCRET-G8-TCA9A    I28 @BASEBOARD_FAB2_LIB.BASEBOARD_FAB2(SCH_1):PAGE163
  U6W2    4    GND TCA9517DGKR-GP_DISCRET-G8-TCA9A   I118 @BASEBOARD_FAB2_LIB.BASEBOARD_FAB2(SCH_1):PAGE247
  U1W2    4    GND TCA9517DGKR-GP_DISCRET-G8-TCA9A    I49 @BASEBOARD_FAB2_LIB.BASEBOARD_FAB2(SCH_1):PAGE248
  R7D1    2      B RES_0402-1.00K,1%,1/16W,EMPTY,A    I86 @BASEBOARD_FAB2_LIB.BASEBOARD_FAB2(SCH_1):PAGE125
 C22W1    2      2 SC22U16V5MX-4-GP_SMD-BCG5-SC22A   I246 @BASEBOARD_FAB2_LIB.BASEBOARD_FAB2(SCH_1):PAGE225
 C22W2    2      2 SC22U16V5MX-4-GP_SMD-BCG5-SC22A   I247 @BASEBOARD_FAB2_LIB.BASEBOARD_FAB2(SCH_1):PAGE225
 C22W3    2      2 SC22U16V5MX-4-GP_SMD-BCG5-SC22A   I249 @BASEBOARD_FAB2_LIB.BASEBOARD_FAB2(SCH_1):PAGE225
  C1G2    2      2 SC22U16V5MX-4-GP_SMD-BCG5-SC22A   I250 @BASEBOARD_FAB2_LIB.BASEBOARD_FAB2(SCH_1):PAGE225
 C22W4    2      2 SC22U16V5MX-4-GP_SMD-BCG5-SC22A   I251 @BASEBOARD_FAB2_LIB.BASEBOARD_FAB2(SCH_1):PAGE225
 C22W5    2      2 SC22U16V5MX-4-GP_SMD-BCG5-SC22A   I222 @BASEBOARD_FAB2_LIB.BASEBOARD_FAB2(SCH_1):PAGE234
  C4B1    2      2 SC22U16V5MX-4-GP_SMD-BCG5-SC22A   I223 @BASEBOARD_FAB2_LIB.BASEBOARD_FAB2(SCH_1):PAGE234
 C22W6    2      2 SC22U16V5MX-4-GP_SMD-BCG5-SC22A   I278 @BASEBOARD_FAB2_LIB.BASEBOARD_FAB2(SCH_1):PAGE233
  C4G5    2      2 SC22U16V5MX-4-GP_SMD-BCG5-SC22A   I280 @BASEBOARD_FAB2_LIB.BASEBOARD_FAB2(SCH_1):PAGE233
  C7B8    2      2 SC22U16V5MX-4-GP_SMD-BCG5-SC22A   I309 @BASEBOARD_FAB2_LIB.BASEBOARD_FAB2(SCH_1):PAGE232
 C22W7    2      2 SC22U16V5MX-4-GP_SMD-BCG5-SC22A   I311 @BASEBOARD_FAB2_LIB.BASEBOARD_FAB2(SCH_1):PAGE232
 C7E13    2      2 SC22U16V5MX-4-GP_SMD-BCG5-SC22A    I92 @BASEBOARD_FAB2_LIB.BASEBOARD_FAB2(SCH_1):PAGE241
 C22W9    2      2 SC22U16V5MX-4-GP_SMD-BCG5-SC22A    I95 @BASEBOARD_FAB2_LIB.BASEBOARD_FAB2(SCH_1):PAGE241
 C22W8    2      2 SC22U16V5MX-4-GP_SMD-BCG5-SC22A    I96 @BASEBOARD_FAB2_LIB.BASEBOARD_FAB2(SCH_1):PAGE241
 C7E12    2      2 SC22U16V5MX-4-GP_SMD-BCG5-SC22A    I98 @BASEBOARD_FAB2_LIB.BASEBOARD_FAB2(SCH_1):PAGE241
C22W10    2      2 SC22U16V5MX-4-GP_SMD-BCG5-SC22A   I225 @BASEBOARD_FAB2_LIB.BASEBOARD_FAB2(SCH_1):PAGE231
  C7F7    2      2 SC22U16V5MX-4-GP_SMD-BCG5-SC22A   I226 @BASEBOARD_FAB2_LIB.BASEBOARD_FAB2(SCH_1):PAGE231
  C9F1    2      2 SC22U16V5MX-4-GP_SMD-BCG5-SC22A   I181 @BASEBOARD_FAB2_LIB.BASEBOARD_FAB2(SCH_1):PAGE240
C22W11    2      2 SC22U16V5MX-4-GP_SMD-BCG5-SC22A   I182 @BASEBOARD_FAB2_LIB.BASEBOARD_FAB2(SCH_1):PAGE240
 C8E11    2      2 SC22U16V5MX-4-GP_SMD-BCG5-SC22A   I183 @BASEBOARD_FAB2_LIB.BASEBOARD_FAB2(SCH_1):PAGE240
C22W12    2      2 SC22U16V5MX-4-GP_SMD-BCG5-SC22A   I186 @BASEBOARD_FAB2_LIB.BASEBOARD_FAB2(SCH_1):PAGE240
 C4E14    2      2 SC22U16V5MX-4-GP_SMD-BCG5-SC22A   I148 @BASEBOARD_FAB2_LIB.BASEBOARD_FAB2(SCH_1):PAGE214
C22W13    2      2 SC22U16V5MX-4-GP_SMD-BCG5-SC22A   I149 @BASEBOARD_FAB2_LIB.BASEBOARD_FAB2(SCH_1):PAGE214
C22W14    2      2 SC22U16V5MX-4-GP_SMD-BCG5-SC22A   I152 @BASEBOARD_FAB2_LIB.BASEBOARD_FAB2(SCH_1):PAGE214
C22W15    2      2 SC22U16V5MX-4-GP_SMD-BCG5-SC22A   I154 @BASEBOARD_FAB2_LIB.BASEBOARD_FAB2(SCH_1):PAGE214
C22W18    2      2 SC22U16V5MX-4-GP_SMD-BCG5-SC22A   I156 @BASEBOARD_FAB2_LIB.BASEBOARD_FAB2(SCH_1):PAGE214
C22W17    2      2 SC22U16V5MX-4-GP_SMD-BCG5-SC22A   I158 @BASEBOARD_FAB2_LIB.BASEBOARD_FAB2(SCH_1):PAGE214
C22W16    2      2 SC22U16V5MX-4-GP_SMD-BCG5-SC22A   I160 @BASEBOARD_FAB2_LIB.BASEBOARD_FAB2(SCH_1):PAGE214
  C4E8    2      2 SC22U16V5MX-4-GP_SMD-BCG5-SC22A   I161 @BASEBOARD_FAB2_LIB.BASEBOARD_FAB2(SCH_1):PAGE214
  C4E9    2      2 SC22U16V5MX-4-GP_SMD-BCG5-SC22A   I164 @BASEBOARD_FAB2_LIB.BASEBOARD_FAB2(SCH_1):PAGE214
C22W21    2      2 SC22U16V5MX-4-GP_SMD-BCG5-SC22A   I166 @BASEBOARD_FAB2_LIB.BASEBOARD_FAB2(SCH_1):PAGE214
C22W20    2      2 SC22U16V5MX-4-GP_SMD-BCG5-SC22A   I168 @BASEBOARD_FAB2_LIB.BASEBOARD_FAB2(SCH_1):PAGE214
C22W19    2      2 SC22U16V5MX-4-GP_SMD-BCG5-SC22A   I169 @BASEBOARD_FAB2_LIB.BASEBOARD_FAB2(SCH_1):PAGE214
C22W23    2      2 SC22U16V5MX-4-GP_SMD-BCG5-SC22A   I159 @BASEBOARD_FAB2_LIB.BASEBOARD_FAB2(SCH_1):PAGE236
C22W24    2      2 SC22U16V5MX-4-GP_SMD-BCG5-SC22A   I160 @BASEBOARD_FAB2_LIB.BASEBOARD_FAB2(SCH_1):PAGE236
 C7A13    2      2 SC22U16V5MX-4-GP_SMD-BCG5-SC22A   I161 @BASEBOARD_FAB2_LIB.BASEBOARD_FAB2(SCH_1):PAGE236
C22W25    2      2 SC22U16V5MX-4-GP_SMD-BCG5-SC22A   I162 @BASEBOARD_FAB2_LIB.BASEBOARD_FAB2(SCH_1):PAGE236
C22W27    2      2 SC22U16V5MX-4-GP_SMD-BCG5-SC22A   I163 @BASEBOARD_FAB2_LIB.BASEBOARD_FAB2(SCH_1):PAGE236
C22W26    2      2 SC22U16V5MX-4-GP_SMD-BCG5-SC22A   I165 @BASEBOARD_FAB2_LIB.BASEBOARD_FAB2(SCH_1):PAGE236
C22W22    2      2 SC22U16V5MX-4-GP_SMD-BCG5-SC22A   I171 @BASEBOARD_FAB2_LIB.BASEBOARD_FAB2(SCH_1):PAGE236
 C7A14    2      2 SC22U16V5MX-4-GP_SMD-BCG5-SC22A   I172 @BASEBOARD_FAB2_LIB.BASEBOARD_FAB2(SCH_1):PAGE236
C22W33    2      2 SC22U16V5MX-4-GP_SMD-BCG5-SC22A   I124 @BASEBOARD_FAB2_LIB.BASEBOARD_FAB2(SCH_1):PAGE212
C22W32    2      2 SC22U16V5MX-4-GP_SMD-BCG5-SC22A   I126 @BASEBOARD_FAB2_LIB.BASEBOARD_FAB2(SCH_1):PAGE212
C22W31    2      2 SC22U16V5MX-4-GP_SMD-BCG5-SC22A   I129 @BASEBOARD_FAB2_LIB.BASEBOARD_FAB2(SCH_1):PAGE212
  C7C8    2      2 SC22U16V5MX-4-GP_SMD-BCG5-SC22A   I130 @BASEBOARD_FAB2_LIB.BASEBOARD_FAB2(SCH_1):PAGE212
C22W30    2      2 SC22U16V5MX-4-GP_SMD-BCG5-SC22A   I132 @BASEBOARD_FAB2_LIB.BASEBOARD_FAB2(SCH_1):PAGE212
C22W29    2      2 SC22U16V5MX-4-GP_SMD-BCG5-SC22A   I134 @BASEBOARD_FAB2_LIB.BASEBOARD_FAB2(SCH_1):PAGE212
C22W28    2      2 SC22U16V5MX-4-GP_SMD-BCG5-SC22A   I136 @BASEBOARD_FAB2_LIB.BASEBOARD_FAB2(SCH_1):PAGE212
  C7C7    2      2 SC22U16V5MX-4-GP_SMD-BCG5-SC22A   I138 @BASEBOARD_FAB2_LIB.BASEBOARD_FAB2(SCH_1):PAGE212
C22W34    2      2 SC22U16V5MX-4-GP_SMD-BCG5-SC22A   I244 @BASEBOARD_FAB2_LIB.BASEBOARD_FAB2(SCH_1):PAGE139
  C9F2    2      2 SC22U16V5MX-4-GP_SMD-BCG5-SC22A   I245 @BASEBOARD_FAB2_LIB.BASEBOARD_FAB2(SCH_1):PAGE139
C22W35    2      2 SC22U16V5MX-4-GP_SMD-BCG5-SC22A   I246 @BASEBOARD_FAB2_LIB.BASEBOARD_FAB2(SCH_1):PAGE139
  C9E6    2      2 SC22U16V5MX-4-GP_SMD-BCG5-SC22A   I248 @BASEBOARD_FAB2_LIB.BASEBOARD_FAB2(SCH_1):PAGE139
  Q1W1    2    SRC FET_N_SOT23LF-2N7002,FET,C7925A    I29 @BASEBOARD_FAB2_LIB.BASEBOARD_FAB2(SCH_1):PAGE250
  Q1W5    2    SRC FET_N_SOT23LF-2N7002,FET,C7925A   I130 @BASEBOARD_FAB2_LIB.BASEBOARD_FAB2(SCH_1):PAGE199
  U6W1   12    GND TCA9555PWR-GP_DISCRET-GC1-TCA9A   I120 @BASEBOARD_FAB2_LIB.BASEBOARD_FAB2(SCH_1):PAGE247
CR30W1    3 GND<0> DIODEAC_DUAL_ARRAY_SM9-ESD3V3UA     I5 @BASEBOARD_FAB2_LIB.BASEBOARD_FAB2(SCH_1):PAGE253
 U25W7    3    GND U74AHCT1G125G-AL5-R-GP-U_TTL-GA   I111 @BASEBOARD_FAB2_LIB.BASEBOARD_FAB2(SCH_1):PAGE255
 U25W7    1    OE# U74AHCT1G125G-AL5-R-GP-U_TTL-GA   I111 @BASEBOARD_FAB2_LIB.BASEBOARD_FAB2(SCH_1):PAGE255
 U25W8    3    GND U74AHCT1G125G-AL5-R-GP-U_TTL-GA   I112 @BASEBOARD_FAB2_LIB.BASEBOARD_FAB2(SCH_1):PAGE255
 U25W8    1    OE# U74AHCT1G125G-AL5-R-GP-U_TTL-GA   I112 @BASEBOARD_FAB2_LIB.BASEBOARD_FAB2(SCH_1):PAGE255
C25W90    2      B CAP_A_0402V-0.1UF,16V,10%,X7R,A   I118 @BASEBOARD_FAB2_LIB.BASEBOARD_FAB2(SCH_1):PAGE255
CR25W1    3 GND<0> DIODEAC_DUAL_ARRAY_SM9-ESD3V3UA   I129 @BASEBOARD_FAB2_LIB.BASEBOARD_FAB2(SCH_1):PAGE255
CR25W2    3 GND<0> DIODEAC_DUAL_ARRAY_SM9-ESD3V3UA   I131 @BASEBOARD_FAB2_LIB.BASEBOARD_FAB2(SCH_1):PAGE255
C25P80    2      B CAP_A_0402V-0.1UF,16V,10%,X7R,A   I134 @BASEBOARD_FAB2_LIB.BASEBOARD_FAB2(SCH_1):PAGE255
 C1W16    2      B CAP_0402LF-1000PF,50V,10%,X7R,A   I132 @BASEBOARD_FAB2_LIB.BASEBOARD_FAB2(SCH_1):PAGE199
 R1W21    1      A RES_0402-0.0,5%,1/16W,CHIP,G21A   I135 @BASEBOARD_FAB2_LIB.BASEBOARD_FAB2(SCH_1):PAGE199
R25W142    2      B RES_0402-100.0K,1%,1/16W,CHIP,A   I156 @BASEBOARD_FAB2_LIB.BASEBOARD_FAB2(SCH_1):PAGE147
  J2W1   H1     H1 SKT-SATA7P-6P-165-GP-U1_SOCKETA    I67 @BASEBOARD_FAB2_LIB.BASEBOARD_FAB2(SCH_1):PAGE172
  J2W1   H2     H2 SKT-SATA7P-6P-165-GP-U1_SOCKETA    I67 @BASEBOARD_FAB2_LIB.BASEBOARD_FAB2(SCH_1):PAGE172
  J2W1   P3     P3 SKT-SATA7P-6P-165-GP-U1_SOCKETA    I67 @BASEBOARD_FAB2_LIB.BASEBOARD_FAB2(SCH_1):PAGE172
  J2W1   P4     P4 SKT-SATA7P-6P-165-GP-U1_SOCKETA    I67 @BASEBOARD_FAB2_LIB.BASEBOARD_FAB2(SCH_1):PAGE172
  J2W1   S1     S1 SKT-SATA7P-6P-165-GP-U1_SOCKETA    I67 @BASEBOARD_FAB2_LIB.BASEBOARD_FAB2(SCH_1):PAGE172
  J2W1   S4     S4 SKT-SATA7P-6P-165-GP-U1_SOCKETA    I67 @BASEBOARD_FAB2_LIB.BASEBOARD_FAB2(SCH_1):PAGE172
  J2W1   S7     S7 SKT-SATA7P-6P-165-GP-U1_SOCKETA    I67 @BASEBOARD_FAB2_LIB.BASEBOARD_FAB2(SCH_1):PAGE172
  J2W2   H1     H1 SKT-SATA7P-6P-165-GP-U1_SOCKETA    I68 @BASEBOARD_FAB2_LIB.BASEBOARD_FAB2(SCH_1):PAGE172
  J2W2   H2     H2 SKT-SATA7P-6P-165-GP-U1_SOCKETA    I68 @BASEBOARD_FAB2_LIB.BASEBOARD_FAB2(SCH_1):PAGE172
  J2W2   P3     P3 SKT-SATA7P-6P-165-GP-U1_SOCKETA    I68 @BASEBOARD_FAB2_LIB.BASEBOARD_FAB2(SCH_1):PAGE172
  J2W2   P4     P4 SKT-SATA7P-6P-165-GP-U1_SOCKETA    I68 @BASEBOARD_FAB2_LIB.BASEBOARD_FAB2(SCH_1):PAGE172
  J2W2   S1     S1 SKT-SATA7P-6P-165-GP-U1_SOCKETA    I68 @BASEBOARD_FAB2_LIB.BASEBOARD_FAB2(SCH_1):PAGE172
  J2W2   S4     S4 SKT-SATA7P-6P-165-GP-U1_SOCKETA    I68 @BASEBOARD_FAB2_LIB.BASEBOARD_FAB2(SCH_1):PAGE172
  J2W2   S7     S7 SKT-SATA7P-6P-165-GP-U1_SOCKETA    I68 @BASEBOARD_FAB2_LIB.BASEBOARD_FAB2(SCH_1):PAGE172
 JA9G1    1      1 SKT-RJ45-LED-XFOR-1-GP_SOCKET-A   I129 @BASEBOARD_FAB2_LIB.BASEBOARD_FAB2(SCH_1):PAGE141
 JA9G1    2      2 SKT-RJ45-LED-XFOR-1-GP_SOCKET-A   I129 @BASEBOARD_FAB2_LIB.BASEBOARD_FAB2(SCH_1):PAGE141
 JA9G1   R6     R6 SKT-RJ45-LED-XFOR-1-GP_SOCKET-A   I129 @BASEBOARD_FAB2_LIB.BASEBOARD_FAB2(SCH_1):PAGE141
  C9G3    2      B CAP_0402LF-470PF,50V,10%,X7R,AA   I138 @BASEBOARD_FAB2_LIB.BASEBOARD_FAB2(SCH_1):PAGE141
  C9G1    2      B CAP_0402LF-470PF,50V,10%,X7R,AA   I140 @BASEBOARD_FAB2_LIB.BASEBOARD_FAB2(SCH_1):PAGE141
  C9G2    2      B CAP_0402LF-470PF,50V,10%,X7R,AA   I152 @BASEBOARD_FAB2_LIB.BASEBOARD_FAB2(SCH_1):PAGE141
 C9F22    2      B CAP_0402LF-470PF,50V,10%,X7R,AA   I159 @BASEBOARD_FAB2_LIB.BASEBOARD_FAB2(SCH_1):PAGE141
  C3W1    2      B CAP_0402-1.0UF,6.3V,10%,EMPTY,A   I193 @BASEBOARD_FAB2_LIB.BASEBOARD_FAB2(SCH_1):PAGE114
 J25W1    2      2 SMC-CON13-GP_CONN-GC2-SMC-CON1A   I136 @BASEBOARD_FAB2_LIB.BASEBOARD_FAB2(SCH_1):PAGE255
 J25W1    4      4 SMC-CON13-GP_CONN-GC2-SMC-CON1A   I136 @BASEBOARD_FAB2_LIB.BASEBOARD_FAB2(SCH_1):PAGE255
 J25W1    6      6 SMC-CON13-GP_CONN-GC2-SMC-CON1A   I136 @BASEBOARD_FAB2_LIB.BASEBOARD_FAB2(SCH_1):PAGE255
 J25W1    8      8 SMC-CON13-GP_CONN-GC2-SMC-CON1A   I136 @BASEBOARD_FAB2_LIB.BASEBOARD_FAB2(SCH_1):PAGE255
 J25W1   10     10 SMC-CON13-GP_CONN-GC2-SMC-CON1A   I136 @BASEBOARD_FAB2_LIB.BASEBOARD_FAB2(SCH_1):PAGE255
 J25W1 PTH1   PTH1 SMC-CON13-GP_CONN-GC2-SMC-CON1A   I136 @BASEBOARD_FAB2_LIB.BASEBOARD_FAB2(SCH_1):PAGE255
 J25W1 PTH2   PTH2 SMC-CON13-GP_CONN-GC2-SMC-CON1A   I136 @BASEBOARD_FAB2_LIB.BASEBOARD_FAB2(SCH_1):PAGE255
 C8F14    2      2 ST470U6D3VDM-7-GP_SMD-TCG4-ST4A   I189 @BASEBOARD_FAB2_LIB.BASEBOARD_FAB2(SCH_1):PAGE240
  C8F8    2      2 ST470U6D3VDM-7-GP_SMD-TCG4-ST4A   I190 @BASEBOARD_FAB2_LIB.BASEBOARD_FAB2(SCH_1):PAGE240
  J8F1    1      1 SKT-MINI67P-41-GP_SOCKET-G4-SKA   I143 @BASEBOARD_FAB2_LIB.BASEBOARD_FAB2(SCH_1):PAGE185
  J8F1    3      3 SKT-MINI67P-41-GP_SOCKET-G4-SKA   I143 @BASEBOARD_FAB2_LIB.BASEBOARD_FAB2(SCH_1):PAGE185
  J8F1    9      9 SKT-MINI67P-41-GP_SOCKET-G4-SKA   I143 @BASEBOARD_FAB2_LIB.BASEBOARD_FAB2(SCH_1):PAGE185
  J8F1   15     15 SKT-MINI67P-41-GP_SOCKET-G4-SKA   I143 @BASEBOARD_FAB2_LIB.BASEBOARD_FAB2(SCH_1):PAGE185
  J8F1   21     21 SKT-MINI67P-41-GP_SOCKET-G4-SKA   I143 @BASEBOARD_FAB2_LIB.BASEBOARD_FAB2(SCH_1):PAGE185
  J8F1   27     27 SKT-MINI67P-41-GP_SOCKET-G4-SKA   I143 @BASEBOARD_FAB2_LIB.BASEBOARD_FAB2(SCH_1):PAGE185
  J8F1   33     33 SKT-MINI67P-41-GP_SOCKET-G4-SKA   I143 @BASEBOARD_FAB2_LIB.BASEBOARD_FAB2(SCH_1):PAGE185
  J8F1   39     39 SKT-MINI67P-41-GP_SOCKET-G4-SKA   I143 @BASEBOARD_FAB2_LIB.BASEBOARD_FAB2(SCH_1):PAGE185
  J8F1   45     45 SKT-MINI67P-41-GP_SOCKET-G4-SKA   I143 @BASEBOARD_FAB2_LIB.BASEBOARD_FAB2(SCH_1):PAGE185
  J8F1   51     51 SKT-MINI67P-41-GP_SOCKET-G4-SKA   I143 @BASEBOARD_FAB2_LIB.BASEBOARD_FAB2(SCH_1):PAGE185
  J8F1   57     57 SKT-MINI67P-41-GP_SOCKET-G4-SKA   I143 @BASEBOARD_FAB2_LIB.BASEBOARD_FAB2(SCH_1):PAGE185
  J8F1   71     71 SKT-MINI67P-41-GP_SOCKET-G4-SKA   I143 @BASEBOARD_FAB2_LIB.BASEBOARD_FAB2(SCH_1):PAGE185
  J8F1   73     73 SKT-MINI67P-41-GP_SOCKET-G4-SKA   I143 @BASEBOARD_FAB2_LIB.BASEBOARD_FAB2(SCH_1):PAGE185
  J8F1   75     75 SKT-MINI67P-41-GP_SOCKET-G4-SKA   I143 @BASEBOARD_FAB2_LIB.BASEBOARD_FAB2(SCH_1):PAGE185
  J8F1   76     76 SKT-MINI67P-41-GP_SOCKET-G4-SKA   I143 @BASEBOARD_FAB2_LIB.BASEBOARD_FAB2(SCH_1):PAGE185
  J8F1   77     77 SKT-MINI67P-41-GP_SOCKET-G4-SKA   I143 @BASEBOARD_FAB2_LIB.BASEBOARD_FAB2(SCH_1):PAGE185
 C1W17    2      B CAP_0805-10UF,16V,10%,EMPTY,C9A   I139 @BASEBOARD_FAB2_LIB.BASEBOARD_FAB2(SCH_1):PAGE101
 R1W25    2      B RES_0402-1.00K,1%,1/16W,CHIP,GA   I140 @BASEBOARD_FAB2_LIB.BASEBOARD_FAB2(SCH_1):PAGE101
 R1W26    2      B RES_0402-10.0K,1%,1/16W,EMPTY,A   I349 @BASEBOARD_FAB2_LIB.BASEBOARD_FAB2(SCH_1):PAGE190
  C4W1    2      B CAP_0402LF-220PF,50V,10%,X7R,AA    I97 @BASEBOARD_FAB2_LIB.BASEBOARD_FAB2(SCH_1):PAGE211
  C4W2    2      B CAP_0402LF-220PF,50V,10%,X7R,AA   I101 @BASEBOARD_FAB2_LIB.BASEBOARD_FAB2(SCH_1):PAGE213
  C4W3    2      B CAP_0402LF-220PF,50V,10%,X7R,AA   I244 @BASEBOARD_FAB2_LIB.BASEBOARD_FAB2(SCH_1):PAGE235
  C4W4    2      B CAP_0402LF-220PF,50V,10%,X7R,AA   I246 @BASEBOARD_FAB2_LIB.BASEBOARD_FAB2(SCH_1):PAGE235
R25W146    1      A RES_0402-4.75K,1%,1/16W,CHIP,GA   I199 @BASEBOARD_FAB2_LIB.BASEBOARD_FAB2(SCH_1):PAGE150
R25W148    1      A RES_0402-4.75K,1%,1/16W,CHIP,GA   I216 @BASEBOARD_FAB2_LIB.BASEBOARD_FAB2(SCH_1):PAGE150
R25W151    1      A RES_0402-4.75K,1%,1/16W,CHIP,GA   I232 @BASEBOARD_FAB2_LIB.BASEBOARD_FAB2(SCH_1):PAGE150
R25W149    1      A RES_0402-4.75K,1%,1/16W,CHIP,GA   I219 @BASEBOARD_FAB2_LIB.BASEBOARD_FAB2(SCH_1):PAGE150
R25W150    1      A RES_0402-4.75K,1%,1/16W,CHIP,GA   I229 @BASEBOARD_FAB2_LIB.BASEBOARD_FAB2(SCH_1):PAGE150
R25W152    1      A RES_0402-4.75K,1%,1/16W,CHIP,GA   I234 @BASEBOARD_FAB2_LIB.BASEBOARD_FAB2(SCH_1):PAGE150
R25W118    2      B RES_0402-0.0,5%,1/16W,CHIP,G21A   I211 @BASEBOARD_FAB2_LIB.BASEBOARD_FAB2(SCH_1):PAGE151
  J1E1  3_1    3_1 FCI-CONN12-2R-GP_CONN-G5-FCI-CA   I114 @BASEBOARD_FAB2_LIB.BASEBOARD_FAB2(SCH_1):PAGE195
  J1E1  3_2    3_2 FCI-CONN12-2R-GP_CONN-G5-FCI-CA   I114 @BASEBOARD_FAB2_LIB.BASEBOARD_FAB2(SCH_1):PAGE195
  J1E1  3_3    3_3 FCI-CONN12-2R-GP_CONN-G5-FCI-CA   I114 @BASEBOARD_FAB2_LIB.BASEBOARD_FAB2(SCH_1):PAGE195
  J1E1  4_1    4_1 FCI-CONN12-2R-GP_CONN-G5-FCI-CA   I114 @BASEBOARD_FAB2_LIB.BASEBOARD_FAB2(SCH_1):PAGE195
  J1E1  4_2    4_2 FCI-CONN12-2R-GP_CONN-G5-FCI-CA   I114 @BASEBOARD_FAB2_LIB.BASEBOARD_FAB2(SCH_1):PAGE195
  J1E1  4_3    4_3 FCI-CONN12-2R-GP_CONN-G5-FCI-CA   I114 @BASEBOARD_FAB2_LIB.BASEBOARD_FAB2(SCH_1):PAGE195
  J1D1  3_1    3_1 FCI-CONN12-2R-GP_CONN-G5-FCI-CA   I115 @BASEBOARD_FAB2_LIB.BASEBOARD_FAB2(SCH_1):PAGE195
  J1D1  3_2    3_2 FCI-CONN12-2R-GP_CONN-G5-FCI-CA   I115 @BASEBOARD_FAB2_LIB.BASEBOARD_FAB2(SCH_1):PAGE195
  J1D1  3_3    3_3 FCI-CONN12-2R-GP_CONN-G5-FCI-CA   I115 @BASEBOARD_FAB2_LIB.BASEBOARD_FAB2(SCH_1):PAGE195
  J1D1  4_1    4_1 FCI-CONN12-2R-GP_CONN-G5-FCI-CA   I115 @BASEBOARD_FAB2_LIB.BASEBOARD_FAB2(SCH_1):PAGE195
  J1D1  4_2    4_2 FCI-CONN12-2R-GP_CONN-G5-FCI-CA   I115 @BASEBOARD_FAB2_LIB.BASEBOARD_FAB2(SCH_1):PAGE195
  J1D1  4_3    4_3 FCI-CONN12-2R-GP_CONN-G5-FCI-CA   I115 @BASEBOARD_FAB2_LIB.BASEBOARD_FAB2(SCH_1):PAGE195
 J30W1   A1 GND<0> SKT-USB32-8-GP_SOCKET-G4-SKT-UA    I26 @BASEBOARD_FAB2_LIB.BASEBOARD_FAB2(SCH_1):PAGE253
 J30W1  A12 GND<1> SKT-USB32-8-GP_SOCKET-G4-SKT-UA    I26 @BASEBOARD_FAB2_LIB.BASEBOARD_FAB2(SCH_1):PAGE253
 J30W1   B1 GND<2> SKT-USB32-8-GP_SOCKET-G4-SKT-UA    I26 @BASEBOARD_FAB2_LIB.BASEBOARD_FAB2(SCH_1):PAGE253
 J30W1  B12 GND<3> SKT-USB32-8-GP_SOCKET-G4-SKT-UA    I26 @BASEBOARD_FAB2_LIB.BASEBOARD_FAB2(SCH_1):PAGE253
 J30W1 PTH1   PTH1 SKT-USB32-8-GP_SOCKET-G4-SKT-UA    I26 @BASEBOARD_FAB2_LIB.BASEBOARD_FAB2(SCH_1):PAGE253
 J30W1 PTH2   PTH2 SKT-USB32-8-GP_SOCKET-G4-SKT-UA    I26 @BASEBOARD_FAB2_LIB.BASEBOARD_FAB2(SCH_1):PAGE253
 J30W1 PTH3   PTH3 SKT-USB32-8-GP_SOCKET-G4-SKT-UA    I26 @BASEBOARD_FAB2_LIB.BASEBOARD_FAB2(SCH_1):PAGE253
 J30W1 PTH4   PTH4 SKT-USB32-8-GP_SOCKET-G4-SKT-UA    I26 @BASEBOARD_FAB2_LIB.BASEBOARD_FAB2(SCH_1):PAGE253
 J30W1 PTH5   PTH5 SKT-USB32-8-GP_SOCKET-G4-SKT-UA    I26 @BASEBOARD_FAB2_LIB.BASEBOARD_FAB2(SCH_1):PAGE253
 J30W1 PTH6   PTH6 SKT-USB32-8-GP_SOCKET-G4-SKT-UA    I26 @BASEBOARD_FAB2_LIB.BASEBOARD_FAB2(SCH_1):PAGE253
 J30W1 PTH7   PTH7 SKT-USB32-8-GP_SOCKET-G4-SKT-UA    I26 @BASEBOARD_FAB2_LIB.BASEBOARD_FAB2(SCH_1):PAGE253
 J30W1 PTH8   PTH8 SKT-USB32-8-GP_SOCKET-G4-SKT-UA    I26 @BASEBOARD_FAB2_LIB.BASEBOARD_FAB2(SCH_1):PAGE253
R25W94    1      A RES_0402-4.75K,1%,1/16W,CHIP,GA   I140 @BASEBOARD_FAB2_LIB.BASEBOARD_FAB2(SCH_1):PAGE137
  R6W2    2      B RES_0402-10.0K,1%,1/16W,CHIP,GA   I144 @BASEBOARD_FAB2_LIB.BASEBOARD_FAB2(SCH_1):PAGE137
  C7G3    2      B CAP_0402LF-220PF,50V,10%,X7R,AA    I22 @BASEBOARD_FAB2_LIB.BASEBOARD_FAB2(SCH_1):PAGE215
 C7F17    2      B CAP_A_0402V-0.1UF,16V,10%,X7R,A    I34 @BASEBOARD_FAB2_LIB.BASEBOARD_FAB2(SCH_1):PAGE215
 C7F18    2      B CAP_A_0402V-1.0UF,6.3V,10%,X6SA    I35 @BASEBOARD_FAB2_LIB.BASEBOARD_FAB2(SCH_1):PAGE215
 C7F15    2      B CAP_A_0402V-0.1UF,16V,10%,X7R,A    I38 @BASEBOARD_FAB2_LIB.BASEBOARD_FAB2(SCH_1):PAGE215
 C7F16    2      B CAP_A_0402V-1.0UF,6.3V,10%,X6SA    I40 @BASEBOARD_FAB2_LIB.BASEBOARD_FAB2(SCH_1):PAGE215
 C7F14    2      B CAP_0402LF-1000PF,50V,10%,X7R,A    I44 @BASEBOARD_FAB2_LIB.BASEBOARD_FAB2(SCH_1):PAGE215
 EU7G1   32 BISEN1 PXM1310B_QFN-IC,H89186-001    I69 @BASEBOARD_FAB2_LIB.BASEBOARD_FAB2(SCH_1):PAGE215
 EU7G1   27    GND PXM1310B_QFN-IC,H89186-001    I69 @BASEBOARD_FAB2_LIB.BASEBOARD_FAB2(SCH_1):PAGE215
 EU7G1   41  THPAD PXM1310B_QFN-IC,H89186-001    I69 @BASEBOARD_FAB2_LIB.BASEBOARD_FAB2(SCH_1):PAGE215
 C4G23    2      B CAP_0402LF-1000PF,50V,10%,EMPTA     I2 @BASEBOARD_FAB2_LIB.BASEBOARD_FAB2(SCH_1):PAGE221
 C6U12    2      B CAP_0603-4.7UF,6.3V,10%,X6S,E1A    I11 @BASEBOARD_FAB2_LIB.BASEBOARD_FAB2(SCH_1):PAGE221
 C4G15    2      B CAP_0402-1.0UF,16V,10%,X6S,D97A    I13 @BASEBOARD_FAB2_LIB.BASEBOARD_FAB2(SCH_1):PAGE221
 C6U15    2      B CAP_0603LF-10UF,4V,20%,X6S,E15A    I18 @BASEBOARD_FAB2_LIB.BASEBOARD_FAB2(SCH_1):PAGE221
 C6U16    2      B CAP_0603LF-10UF,4V,20%,X6S,E15A    I19 @BASEBOARD_FAB2_LIB.BASEBOARD_FAB2(SCH_1):PAGE221
 C4G14    2      B CAP_0402LF-1000PF,50V,10%,X7R,A    I30 @BASEBOARD_FAB2_LIB.BASEBOARD_FAB2(SCH_1):PAGE221
 EU4G3    3   AGND MIC5166_DFN-IC,H55101-001    I15 @BASEBOARD_FAB2_LIB.BASEBOARD_FAB2(SCH_1):PAGE221
 EU4G3    8   PGND MIC5166_DFN-IC,H55101-001    I15 @BASEBOARD_FAB2_LIB.BASEBOARD_FAB2(SCH_1):PAGE221
 EU4G3   11  THPAD MIC5166_DFN-IC,H55101-001    I15 @BASEBOARD_FAB2_LIB.BASEBOARD_FAB2(SCH_1):PAGE221
  C7B2    2      B CAP_A_0402V-0.1UF,16V,10%,X7R,A    I28 @BASEBOARD_FAB2_LIB.BASEBOARD_FAB2(SCH_1):PAGE218
  C7B1    2      B CAP_A_0402V-1.0UF,6.3V,10%,X6SA    I30 @BASEBOARD_FAB2_LIB.BASEBOARD_FAB2(SCH_1):PAGE218
 C7A38    2      B CAP_A_0402V-0.1UF,16V,10%,X7R,A    I38 @BASEBOARD_FAB2_LIB.BASEBOARD_FAB2(SCH_1):PAGE218
  C7B3    2      B CAP_0402LF-1000PF,50V,10%,X7R,A    I41 @BASEBOARD_FAB2_LIB.BASEBOARD_FAB2(SCH_1):PAGE218
 EU7A5   32 BISEN1 PXM1310B_QFN-IC,H89186-001    I69 @BASEBOARD_FAB2_LIB.BASEBOARD_FAB2(SCH_1):PAGE218
 EU7A5   27    GND PXM1310B_QFN-IC,H89186-001    I69 @BASEBOARD_FAB2_LIB.BASEBOARD_FAB2(SCH_1):PAGE218
 EU7A5   41  THPAD PXM1310B_QFN-IC,H89186-001    I69 @BASEBOARD_FAB2_LIB.BASEBOARD_FAB2(SCH_1):PAGE218
 C7A29    2      B CAP_0402LF-220PF,50V,10%,X7R,AA    I16 @BASEBOARD_FAB2_LIB.BASEBOARD_FAB2(SCH_1):PAGE218
 C7A37    2      B CAP_A_0402V-1.0UF,6.3V,10%,X6SA    I40 @BASEBOARD_FAB2_LIB.BASEBOARD_FAB2(SCH_1):PAGE218
  C4A2    2      B CAP_0402LF-1000PF,50V,10%,EMPTA     I2 @BASEBOARD_FAB2_LIB.BASEBOARD_FAB2(SCH_1):PAGE222
 C4A11    2      B CAP_0603-4.7UF,6.3V,10%,X6S,E1A     I9 @BASEBOARD_FAB2_LIB.BASEBOARD_FAB2(SCH_1):PAGE222
 EU4A1    3   AGND MIC5166_DFN-IC,H55101-001    I13 @BASEBOARD_FAB2_LIB.BASEBOARD_FAB2(SCH_1):PAGE222
 EU4A1    8   PGND MIC5166_DFN-IC,H55101-001    I13 @BASEBOARD_FAB2_LIB.BASEBOARD_FAB2(SCH_1):PAGE222
 EU4A1   11  THPAD MIC5166_DFN-IC,H55101-001    I13 @BASEBOARD_FAB2_LIB.BASEBOARD_FAB2(SCH_1):PAGE222
  C6L4    2      B CAP_0603LF-10UF,4V,20%,X6S,E15A    I15 @BASEBOARD_FAB2_LIB.BASEBOARD_FAB2(SCH_1):PAGE222
  C6L3    2      B CAP_0603LF-10UF,4V,20%,X6S,E15A    I17 @BASEBOARD_FAB2_LIB.BASEBOARD_FAB2(SCH_1):PAGE222
  C4A9    2      B CAP_0402-1.0UF,16V,10%,X6S,D97A    I20 @BASEBOARD_FAB2_LIB.BASEBOARD_FAB2(SCH_1):PAGE222
 C4A12    2      B CAP_0402LF-1000PF,50V,10%,X7R,A    I22 @BASEBOARD_FAB2_LIB.BASEBOARD_FAB2(SCH_1):PAGE222
 C1G25    2      B CAP_A_0402V-0.1UF,16V,10%,X7R,A    I35 @BASEBOARD_FAB2_LIB.BASEBOARD_FAB2(SCH_1):PAGE223
 C1G21    2      B CAP_0402LF-1000PF,50V,10%,X7R,A    I40 @BASEBOARD_FAB2_LIB.BASEBOARD_FAB2(SCH_1):PAGE223
 C1G22    2      B CAP_A_0402V-0.1UF,16V,10%,X7R,A    I43 @BASEBOARD_FAB2_LIB.BASEBOARD_FAB2(SCH_1):PAGE223
 EU1G2   32 BISEN1 PXM1310B_QFN-IC,H89186-001    I69 @BASEBOARD_FAB2_LIB.BASEBOARD_FAB2(SCH_1):PAGE223
 EU1G2   27    GND PXM1310B_QFN-IC,H89186-001    I69 @BASEBOARD_FAB2_LIB.BASEBOARD_FAB2(SCH_1):PAGE223
 EU1G2   41  THPAD PXM1310B_QFN-IC,H89186-001    I69 @BASEBOARD_FAB2_LIB.BASEBOARD_FAB2(SCH_1):PAGE223
 C1G24    2      B CAP_0402LF-220PF,50V,10%,X7R,AA    I27 @BASEBOARD_FAB2_LIB.BASEBOARD_FAB2(SCH_1):PAGE223
 C1G27    2      B CAP_A_0402V-1.0UF,6.3V,10%,X6SA    I36 @BASEBOARD_FAB2_LIB.BASEBOARD_FAB2(SCH_1):PAGE223
 C4G12    2      B CAP_0402LF-1000PF,50V,10%,EMPTA     I2 @BASEBOARD_FAB2_LIB.BASEBOARD_FAB2(SCH_1):PAGE229
 C6U13    2      B CAP_0603LF-10UF,4V,20%,X6S,E15A    I11 @BASEBOARD_FAB2_LIB.BASEBOARD_FAB2(SCH_1):PAGE229
 C4G18    2      B CAP_0402-1.0UF,16V,10%,X6S,D97A    I16 @BASEBOARD_FAB2_LIB.BASEBOARD_FAB2(SCH_1):PAGE229
 C6U14    2      B CAP_0603LF-10UF,4V,20%,X6S,E15A    I18 @BASEBOARD_FAB2_LIB.BASEBOARD_FAB2(SCH_1):PAGE229
 C4G20    2      B CAP_0805LF-22UF,4V,20%,X6S,C95A    I23 @BASEBOARD_FAB2_LIB.BASEBOARD_FAB2(SCH_1):PAGE229
 C4G13    2      B CAP_0402LF-1000PF,50V,10%,X7R,A    I26 @BASEBOARD_FAB2_LIB.BASEBOARD_FAB2(SCH_1):PAGE229
  C2F2    2      B CAP_A_0603V-47UF,4V,20%,X5R,60A    I28 @BASEBOARD_FAB2_LIB.BASEBOARD_FAB2(SCH_1):PAGE229
 EU4G2    3   AGND MIC5166_DFN-IC,H55101-001    I37 @BASEBOARD_FAB2_LIB.BASEBOARD_FAB2(SCH_1):PAGE229
 EU4G2    8   PGND MIC5166_DFN-IC,H55101-001    I37 @BASEBOARD_FAB2_LIB.BASEBOARD_FAB2(SCH_1):PAGE229
 EU4G2   11  THPAD MIC5166_DFN-IC,H55101-001    I37 @BASEBOARD_FAB2_LIB.BASEBOARD_FAB2(SCH_1):PAGE229
 C6U11    2      B CAP_0603-4.7UF,6.3V,10%,X6S,E1A    I14 @BASEBOARD_FAB2_LIB.BASEBOARD_FAB2(SCH_1):PAGE229
  C1B6    2      B CAP_A_0402V-1.0UF,6.3V,10%,X6SA    I38 @BASEBOARD_FAB2_LIB.BASEBOARD_FAB2(SCH_1):PAGE226
  C1B4    2      B CAP_0402LF-1000PF,50V,10%,X7R,A    I40 @BASEBOARD_FAB2_LIB.BASEBOARD_FAB2(SCH_1):PAGE226
  C1B3    2      B CAP_A_0402V-1.0UF,6.3V,10%,X6SA    I45 @BASEBOARD_FAB2_LIB.BASEBOARD_FAB2(SCH_1):PAGE226
 EU1B1   32 BISEN1 PXM1310B_QFN-IC,H89186-001    I69 @BASEBOARD_FAB2_LIB.BASEBOARD_FAB2(SCH_1):PAGE226
 EU1B1   27    GND PXM1310B_QFN-IC,H89186-001    I69 @BASEBOARD_FAB2_LIB.BASEBOARD_FAB2(SCH_1):PAGE226
 EU1B1   41  THPAD PXM1310B_QFN-IC,H89186-001    I69 @BASEBOARD_FAB2_LIB.BASEBOARD_FAB2(SCH_1):PAGE226
 C1B11    2      B CAP_0402LF-220PF,50V,10%,X7R,AA    I23 @BASEBOARD_FAB2_LIB.BASEBOARD_FAB2(SCH_1):PAGE226
  C1B5    2      B CAP_A_0402V-0.1UF,16V,10%,X7R,A    I32 @BASEBOARD_FAB2_LIB.BASEBOARD_FAB2(SCH_1):PAGE226
 Q12W2    5 SOURCE#5 BSL308C-H6327-GP_DISCRET-GB1-BA    I19 @BASEBOARD_FAB2_LIB.BASEBOARD_FAB2(SCH_1):PAGE197
 Q12W4    5 SOURCE#5 BSL308C-H6327-GP_DISCRET-GB1-BA    I35 @BASEBOARD_FAB2_LIB.BASEBOARD_FAB2(SCH_1):PAGE197
 Q12W1    5 SOURCE#5 BSL308C-H6327-GP_DISCRET-GB1-BA    I43 @BASEBOARD_FAB2_LIB.BASEBOARD_FAB2(SCH_1):PAGE197
  C9T8    2      B CAP_0805-10UF,16V,10%,X7R,G106A    I56 @BASEBOARD_FAB2_LIB.BASEBOARD_FAB2(SCH_1):PAGE197
  C1A4    2      B CAP_0805-10UF,16V,10%,X7R,G106A    I60 @BASEBOARD_FAB2_LIB.BASEBOARD_FAB2(SCH_1):PAGE197
 C9U11    2      B CAP_0805-10UF,16V,10%,X7R,G106A    I63 @BASEBOARD_FAB2_LIB.BASEBOARD_FAB2(SCH_1):PAGE197
  C9U8    2      B CAP_0805-10UF,16V,10%,X7R,G106A    I66 @BASEBOARD_FAB2_LIB.BASEBOARD_FAB2(SCH_1):PAGE197
 C6U18    2      B CAP_0805-10UF,16V,10%,X7R,G106A    I69 @BASEBOARD_FAB2_LIB.BASEBOARD_FAB2(SCH_1):PAGE197
  C6T2    2      B CAP_0805-10UF,16V,10%,X7R,G106A    I71 @BASEBOARD_FAB2_LIB.BASEBOARD_FAB2(SCH_1):PAGE197
  C1B7    2      B CAP_0805-10UF,16V,10%,X7R,G106A    I72 @BASEBOARD_FAB2_LIB.BASEBOARD_FAB2(SCH_1):PAGE197
 C1A16    2      B CAP_0805-10UF,16V,10%,X7R,G106A    I75 @BASEBOARD_FAB2_LIB.BASEBOARD_FAB2(SCH_1):PAGE197
 C4B11    2      B CAP_0805-10UF,16V,10%,X7R,G106A    I78 @BASEBOARD_FAB2_LIB.BASEBOARD_FAB2(SCH_1):PAGE197
  C4A4    2      B CAP_0805-10UF,16V,10%,X7R,G106A    I81 @BASEBOARD_FAB2_LIB.BASEBOARD_FAB2(SCH_1):PAGE197
 C6U10    2      B CAP_0805-10UF,16V,10%,X7R,G106A    I84 @BASEBOARD_FAB2_LIB.BASEBOARD_FAB2(SCH_1):PAGE197
 C4A17    2      B CAP_0805-10UF,16V,10%,X7R,G106A    I88 @BASEBOARD_FAB2_LIB.BASEBOARD_FAB2(SCH_1):PAGE197
 Q12W3    5 SOURCE#5 BSL308C-H6327-GP_DISCRET-GB1-BA    I91 @BASEBOARD_FAB2_LIB.BASEBOARD_FAB2(SCH_1):PAGE197
  C4A6    2      B CAP_0402LF-1000PF,50V,10%,EMPTA     I2 @BASEBOARD_FAB2_LIB.BASEBOARD_FAB2(SCH_1):PAGE230
  C4A7    2      B CAP_0603-4.7UF,6.3V,10%,X6S,E1A    I10 @BASEBOARD_FAB2_LIB.BASEBOARD_FAB2(SCH_1):PAGE230
  C4A8    2      B CAP_0402-1.0UF,16V,10%,X6S,D97A    I12 @BASEBOARD_FAB2_LIB.BASEBOARD_FAB2(SCH_1):PAGE230
 C4A13    2      B CAP_0805LF-22UF,4V,20%,X6S,C95A    I20 @BASEBOARD_FAB2_LIB.BASEBOARD_FAB2(SCH_1):PAGE230
  C4A3    2      B CAP_0402LF-1000PF,50V,10%,X7R,A    I23 @BASEBOARD_FAB2_LIB.BASEBOARD_FAB2(SCH_1):PAGE230
 C8M12    2      B CAP_A_0603V-47UF,4V,20%,X5R,60A    I24 @BASEBOARD_FAB2_LIB.BASEBOARD_FAB2(SCH_1):PAGE230
  C6L5    2      B CAP_0603LF-10UF,4V,20%,X6S,E15A    I35 @BASEBOARD_FAB2_LIB.BASEBOARD_FAB2(SCH_1):PAGE230
 C4A14    2      B CAP_0402-1.0UF,16V,10%,X6S,D97A    I36 @BASEBOARD_FAB2_LIB.BASEBOARD_FAB2(SCH_1):PAGE230
 C4A15    2      B CAP_0603LF-10UF,4V,20%,X6S,E15A    I17 @BASEBOARD_FAB2_LIB.BASEBOARD_FAB2(SCH_1):PAGE230
 EU4A2    3   AGND MIC5166_DFN-IC,H55101-001    I37 @BASEBOARD_FAB2_LIB.BASEBOARD_FAB2(SCH_1):PAGE230
 EU4A2    8   PGND MIC5166_DFN-IC,H55101-001    I37 @BASEBOARD_FAB2_LIB.BASEBOARD_FAB2(SCH_1):PAGE230
 EU4A2   11  THPAD MIC5166_DFN-IC,H55101-001    I37 @BASEBOARD_FAB2_LIB.BASEBOARD_FAB2(SCH_1):PAGE230
  C8E1    2      B CAP_A_0402V-0.1UF,16V,10%,X7R,A    I34 @BASEBOARD_FAB2_LIB.BASEBOARD_FAB2(SCH_1):PAGE181
  C2R6    2      B CAP_0402LF-470PF,50V,10%,EMPTYA    I40 @BASEBOARD_FAB2_LIB.BASEBOARD_FAB2(SCH_1):PAGE181
  Q9T1    2      E NPN_SM-MMBT3904,IC,C52245-001    I42 @BASEBOARD_FAB2_LIB.BASEBOARD_FAB2(SCH_1):PAGE181
  R9T3    2      B RES_0402-6.19K,1%,1/16W,CHIP,GA    I64 @BASEBOARD_FAB2_LIB.BASEBOARD_FAB2(SCH_1):PAGE181
  J1F3    8    IO8 CONN8_H62179001_PIP-CONN,H6217A   I106 @BASEBOARD_FAB2_LIB.BASEBOARD_FAB2(SCH_1):PAGE181
  C8E4    2      2 ST220U10VDM-LGP_SMD-TCG-ST220UA   I100 @BASEBOARD_FAB2_LIB.BASEBOARD_FAB2(SCH_1):PAGE241
  C9B9    2      2 SC1U10V2KX-4-GP_SMD-BCG6-SC1U1A   I357 @BASEBOARD_FAB2_LIB.BASEBOARD_FAB2(SCH_1):PAGE186
 C1C18    2      2 SC1U10V2KX-4-GP_SMD-BCG6-SC1U1A    I89 @BASEBOARD_FAB2_LIB.BASEBOARD_FAB2(SCH_1):PAGE209
 C1A11    2      2 SC1U10V2KX-4-GP_SMD-BCG6-SC1U1A   I147 @BASEBOARD_FAB2_LIB.BASEBOARD_FAB2(SCH_1):PAGE227
  C1A2    2      2 SC1U10V2KX-4-GP_SMD-BCG6-SC1U1A   I148 @BASEBOARD_FAB2_LIB.BASEBOARD_FAB2(SCH_1):PAGE227
  C1C3    2      2 SC1U10V2KX-4-GP_SMD-BCG6-SC1U1A    I73 @BASEBOARD_FAB2_LIB.BASEBOARD_FAB2(SCH_1):PAGE210
 C1D15    2      2 SC1U10V2KX-4-GP_SMD-BCG6-SC1U1A   I118 @BASEBOARD_FAB2_LIB.BASEBOARD_FAB2(SCH_1):PAGE208
  C1D5    2      2 SC1U10V2KX-4-GP_SMD-BCG6-SC1U1A   I119 @BASEBOARD_FAB2_LIB.BASEBOARD_FAB2(SCH_1):PAGE208
 C1E23    2      2 SC1U10V2KX-4-GP_SMD-BCG6-SC1U1A   I109 @BASEBOARD_FAB2_LIB.BASEBOARD_FAB2(SCH_1):PAGE207
  C1E6    2      2 SC1U10V2KX-4-GP_SMD-BCG6-SC1U1A   I110 @BASEBOARD_FAB2_LIB.BASEBOARD_FAB2(SCH_1):PAGE207
 C1F21    2      2 SC1U10V2KX-4-GP_SMD-BCG6-SC1U1A   I154 @BASEBOARD_FAB2_LIB.BASEBOARD_FAB2(SCH_1):PAGE224
  C1G4    2      2 SC1U10V2KX-4-GP_SMD-BCG6-SC1U1A   I155 @BASEBOARD_FAB2_LIB.BASEBOARD_FAB2(SCH_1):PAGE224
  C3L1    2      2 SC1U10V2KX-4-GP_SMD-BCG6-SC1U1A   I180 @BASEBOARD_FAB2_LIB.BASEBOARD_FAB2(SCH_1):PAGE236
 C3L29    2      2 SC1U10V2KX-4-GP_SMD-BCG6-SC1U1A   I181 @BASEBOARD_FAB2_LIB.BASEBOARD_FAB2(SCH_1):PAGE236
  C4C4    2      2 SC1U10V2KX-4-GP_SMD-BCG6-SC1U1A    I83 @BASEBOARD_FAB2_LIB.BASEBOARD_FAB2(SCH_1):PAGE205
 C4C14    2      2 SC1U10V2KX-4-GP_SMD-BCG6-SC1U1A   I113 @BASEBOARD_FAB2_LIB.BASEBOARD_FAB2(SCH_1):PAGE204
 C4D14    2      2 SC1U10V2KX-4-GP_SMD-BCG6-SC1U1A   I132 @BASEBOARD_FAB2_LIB.BASEBOARD_FAB2(SCH_1):PAGE203
  C4D6    2      2 SC1U10V2KX-4-GP_SMD-BCG6-SC1U1A   I133 @BASEBOARD_FAB2_LIB.BASEBOARD_FAB2(SCH_1):PAGE203
 C4E25    2      2 SC1U10V2KX-4-GP_SMD-BCG6-SC1U1A   I111 @BASEBOARD_FAB2_LIB.BASEBOARD_FAB2(SCH_1):PAGE202
  C4E6    2      2 SC1U10V2KX-4-GP_SMD-BCG6-SC1U1A   I112 @BASEBOARD_FAB2_LIB.BASEBOARD_FAB2(SCH_1):PAGE202
 C4E28    2      2 SC1U10V2KX-4-GP_SMD-BCG6-SC1U1A   I175 @BASEBOARD_FAB2_LIB.BASEBOARD_FAB2(SCH_1):PAGE214
 C7A18    2      2 SC1U10V2KX-4-GP_SMD-BCG6-SC1U1A   I151 @BASEBOARD_FAB2_LIB.BASEBOARD_FAB2(SCH_1):PAGE219
 C7A26    2      2 SC1U10V2KX-4-GP_SMD-BCG6-SC1U1A   I152 @BASEBOARD_FAB2_LIB.BASEBOARD_FAB2(SCH_1):PAGE219
 C7C20    2      2 SC1U10V2KX-4-GP_SMD-BCG6-SC1U1A   I143 @BASEBOARD_FAB2_LIB.BASEBOARD_FAB2(SCH_1):PAGE212
 C7G35    2      2 SC1U10V2KX-4-GP_SMD-BCG6-SC1U1A   I149 @BASEBOARD_FAB2_LIB.BASEBOARD_FAB2(SCH_1):PAGE216
 C7G42    2      2 SC1U10V2KX-4-GP_SMD-BCG6-SC1U1A   I150 @BASEBOARD_FAB2_LIB.BASEBOARD_FAB2(SCH_1):PAGE216
  J1F1   A2   GND1 DM-FCI-CONN76-8R-GP-U-01_CONN-A   I134 @BASEBOARD_FAB2_LIB.BASEBOARD_FAB2(SCH_1):PAGE181
  J1F1   A8   GND2 DM-FCI-CONN76-8R-GP-U-01_CONN-A   I134 @BASEBOARD_FAB2_LIB.BASEBOARD_FAB2(SCH_1):PAGE181
  J1F1   C1   GND3 DM-FCI-CONN76-8R-GP-U-01_CONN-A   I134 @BASEBOARD_FAB2_LIB.BASEBOARD_FAB2(SCH_1):PAGE181
  J1F1   C3   GND4 DM-FCI-CONN76-8R-GP-U-01_CONN-A   I134 @BASEBOARD_FAB2_LIB.BASEBOARD_FAB2(SCH_1):PAGE181
  J1F1   C5   GND5 DM-FCI-CONN76-8R-GP-U-01_CONN-A   I134 @BASEBOARD_FAB2_LIB.BASEBOARD_FAB2(SCH_1):PAGE181
  J1F1   C7   GND6 DM-FCI-CONN76-8R-GP-U-01_CONN-A   I134 @BASEBOARD_FAB2_LIB.BASEBOARD_FAB2(SCH_1):PAGE181
  J1F1   D2   GND7 DM-FCI-CONN76-8R-GP-U-01_CONN-A   I134 @BASEBOARD_FAB2_LIB.BASEBOARD_FAB2(SCH_1):PAGE181
  J1F1   D6   GND8 DM-FCI-CONN76-8R-GP-U-01_CONN-A   I134 @BASEBOARD_FAB2_LIB.BASEBOARD_FAB2(SCH_1):PAGE181
  J1F1   D8   GND9 DM-FCI-CONN76-8R-GP-U-01_CONN-A   I134 @BASEBOARD_FAB2_LIB.BASEBOARD_FAB2(SCH_1):PAGE181
  J1F1   F1  GND10 DM-FCI-CONN76-8R-GP-U-01_CONN-A   I134 @BASEBOARD_FAB2_LIB.BASEBOARD_FAB2(SCH_1):PAGE181
  J1F1   F3  GND11 DM-FCI-CONN76-8R-GP-U-01_CONN-A   I134 @BASEBOARD_FAB2_LIB.BASEBOARD_FAB2(SCH_1):PAGE181
  J1F1   F7  GND12 DM-FCI-CONN76-8R-GP-U-01_CONN-A   I134 @BASEBOARD_FAB2_LIB.BASEBOARD_FAB2(SCH_1):PAGE181
  J1F1   G2  GND13 DM-FCI-CONN76-8R-GP-U-01_CONN-A   I134 @BASEBOARD_FAB2_LIB.BASEBOARD_FAB2(SCH_1):PAGE181
  J1F1   G4  GND14 DM-FCI-CONN76-8R-GP-U-01_CONN-A   I134 @BASEBOARD_FAB2_LIB.BASEBOARD_FAB2(SCH_1):PAGE181
  J1F1   G6  GND15 DM-FCI-CONN76-8R-GP-U-01_CONN-A   I134 @BASEBOARD_FAB2_LIB.BASEBOARD_FAB2(SCH_1):PAGE181
  J1F1   G8  GND16 DM-FCI-CONN76-8R-GP-U-01_CONN-A   I134 @BASEBOARD_FAB2_LIB.BASEBOARD_FAB2(SCH_1):PAGE181
  J1F1   I1  GND17 DM-FCI-CONN76-8R-GP-U-01_CONN-A   I134 @BASEBOARD_FAB2_LIB.BASEBOARD_FAB2(SCH_1):PAGE181
  J1F1   I7  GND18 DM-FCI-CONN76-8R-GP-U-01_CONN-A   I134 @BASEBOARD_FAB2_LIB.BASEBOARD_FAB2(SCH_1):PAGE181
  J1F1   J2     J2 DM-FCI-CONN76-8R-GP-U-01_CONN-A   I134 @BASEBOARD_FAB2_LIB.BASEBOARD_FAB2(SCH_1):PAGE181
  J1F1   J4     J4 DM-FCI-CONN76-8R-GP-U-01_CONN-A   I134 @BASEBOARD_FAB2_LIB.BASEBOARD_FAB2(SCH_1):PAGE181
  J1F1   J6     J6 DM-FCI-CONN76-8R-GP-U-01_CONN-A   I134 @BASEBOARD_FAB2_LIB.BASEBOARD_FAB2(SCH_1):PAGE181
  J1F1   J8     J8 DM-FCI-CONN76-8R-GP-U-01_CONN-A   I134 @BASEBOARD_FAB2_LIB.BASEBOARD_FAB2(SCH_1):PAGE181
  J1C1   D4 FAN_TACH0 DM-FCI-CONN76-8R-GP-U-01_CONN-A    I79 @BASEBOARD_FAB2_LIB.BASEBOARD_FAB2(SCH_1):PAGE182
  J1C1   A4 FAN_TACH3 DM-FCI-CONN76-8R-GP-U-01_CONN-A    I79 @BASEBOARD_FAB2_LIB.BASEBOARD_FAB2(SCH_1):PAGE182
  J1C1   A2   GND1 DM-FCI-CONN76-8R-GP-U-01_CONN-A    I79 @BASEBOARD_FAB2_LIB.BASEBOARD_FAB2(SCH_1):PAGE182
  J1C1   A8   GND2 DM-FCI-CONN76-8R-GP-U-01_CONN-A    I79 @BASEBOARD_FAB2_LIB.BASEBOARD_FAB2(SCH_1):PAGE182
  J1C1   C1   GND3 DM-FCI-CONN76-8R-GP-U-01_CONN-A    I79 @BASEBOARD_FAB2_LIB.BASEBOARD_FAB2(SCH_1):PAGE182
  J1C1   C3   GND4 DM-FCI-CONN76-8R-GP-U-01_CONN-A    I79 @BASEBOARD_FAB2_LIB.BASEBOARD_FAB2(SCH_1):PAGE182
  J1C1   C5   GND5 DM-FCI-CONN76-8R-GP-U-01_CONN-A    I79 @BASEBOARD_FAB2_LIB.BASEBOARD_FAB2(SCH_1):PAGE182
  J1C1   C7   GND6 DM-FCI-CONN76-8R-GP-U-01_CONN-A    I79 @BASEBOARD_FAB2_LIB.BASEBOARD_FAB2(SCH_1):PAGE182
  J1C1   D2   GND7 DM-FCI-CONN76-8R-GP-U-01_CONN-A    I79 @BASEBOARD_FAB2_LIB.BASEBOARD_FAB2(SCH_1):PAGE182
  J1C1   D6   GND8 DM-FCI-CONN76-8R-GP-U-01_CONN-A    I79 @BASEBOARD_FAB2_LIB.BASEBOARD_FAB2(SCH_1):PAGE182
  J1C1   D8   GND9 DM-FCI-CONN76-8R-GP-U-01_CONN-A    I79 @BASEBOARD_FAB2_LIB.BASEBOARD_FAB2(SCH_1):PAGE182
  J1C1   F1  GND10 DM-FCI-CONN76-8R-GP-U-01_CONN-A    I79 @BASEBOARD_FAB2_LIB.BASEBOARD_FAB2(SCH_1):PAGE182
  J1C1   F3  GND11 DM-FCI-CONN76-8R-GP-U-01_CONN-A    I79 @BASEBOARD_FAB2_LIB.BASEBOARD_FAB2(SCH_1):PAGE182
  J1C1   F7  GND12 DM-FCI-CONN76-8R-GP-U-01_CONN-A    I79 @BASEBOARD_FAB2_LIB.BASEBOARD_FAB2(SCH_1):PAGE182
  J1C1   G2  GND13 DM-FCI-CONN76-8R-GP-U-01_CONN-A    I79 @BASEBOARD_FAB2_LIB.BASEBOARD_FAB2(SCH_1):PAGE182
  J1C1   G4  GND14 DM-FCI-CONN76-8R-GP-U-01_CONN-A    I79 @BASEBOARD_FAB2_LIB.BASEBOARD_FAB2(SCH_1):PAGE182
  J1C1   G6  GND15 DM-FCI-CONN76-8R-GP-U-01_CONN-A    I79 @BASEBOARD_FAB2_LIB.BASEBOARD_FAB2(SCH_1):PAGE182
  J1C1   G8  GND16 DM-FCI-CONN76-8R-GP-U-01_CONN-A    I79 @BASEBOARD_FAB2_LIB.BASEBOARD_FAB2(SCH_1):PAGE182
  J1C1   I1  GND17 DM-FCI-CONN76-8R-GP-U-01_CONN-A    I79 @BASEBOARD_FAB2_LIB.BASEBOARD_FAB2(SCH_1):PAGE182
  J1C1   I7  GND18 DM-FCI-CONN76-8R-GP-U-01_CONN-A    I79 @BASEBOARD_FAB2_LIB.BASEBOARD_FAB2(SCH_1):PAGE182
  J1C1   J2     J2 DM-FCI-CONN76-8R-GP-U-01_CONN-A    I79 @BASEBOARD_FAB2_LIB.BASEBOARD_FAB2(SCH_1):PAGE182
  J1C1   J4     J4 DM-FCI-CONN76-8R-GP-U-01_CONN-A    I79 @BASEBOARD_FAB2_LIB.BASEBOARD_FAB2(SCH_1):PAGE182
  J1C1   J6     J6 DM-FCI-CONN76-8R-GP-U-01_CONN-A    I79 @BASEBOARD_FAB2_LIB.BASEBOARD_FAB2(SCH_1):PAGE182
  J1C1   J8     J8 DM-FCI-CONN76-8R-GP-U-01_CONN-A    I79 @BASEBOARD_FAB2_LIB.BASEBOARD_FAB2(SCH_1):PAGE182
  J1C1   I3 MB_ON# DM-FCI-CONN76-8R-GP-U-01_CONN-A    I79 @BASEBOARD_FAB2_LIB.BASEBOARD_FAB2(SCH_1):PAGE182
  J1C1   F5 MB_SLOT_ID0 DM-FCI-CONN76-8R-GP-U-01_CONN-A    I79 @BASEBOARD_FAB2_LIB.BASEBOARD_FAB2(SCH_1):PAGE182
  J1C1   I5 PCIE_PERST# DM-FCI-CONN76-8R-GP-U-01_CONN-A    I79 @BASEBOARD_FAB2_LIB.BASEBOARD_FAB2(SCH_1):PAGE182
  J1C1   A6 PMBUS_ALERT# DM-FCI-CONN76-8R-GP-U-01_CONN-A    I79 @BASEBOARD_FAB2_LIB.BASEBOARD_FAB2(SCH_1):PAGE182
 CN8F1    2      B CAP_A_0402V-1.0UF,6.3V,10%,X6SA    I21 @BASEBOARD_FAB2_LIB.BASEBOARD_FAB2(SCH_1):PAGE246
C25W12    2      B CAP_A_0402V-1.0UF,6.3V,10%,X6SA   I212 @BASEBOARD_FAB2_LIB.BASEBOARD_FAB2(SCH_1):PAGE151
 CN8F2    2      B CAP_A_0402V-0.01UF,25V,10%,X7RA    I22 @BASEBOARD_FAB2_LIB.BASEBOARD_FAB2(SCH_1):PAGE246
C25W11    2      B CAP_A_0402V-0.01UF,25V,10%,X7RA   I214 @BASEBOARD_FAB2_LIB.BASEBOARD_FAB2(SCH_1):PAGE151
C25W14    2      B CAP_A_0402V-0.1UF,16V,10%,X7R,A   I215 @BASEBOARD_FAB2_LIB.BASEBOARD_FAB2(SCH_1):PAGE151
C25W15    2      B CAP_A_0402V-0.1UF,16V,10%,X7R,A   I216 @BASEBOARD_FAB2_LIB.BASEBOARD_FAB2(SCH_1):PAGE151
C25W31    2      B CAP_A_0402V-0.1UF,16V,10%,X7R,A   I119 @BASEBOARD_FAB2_LIB.BASEBOARD_FAB2(SCH_1):PAGE149
C25W34    2      B CAP_A_0402V-0.1UF,16V,10%,X7R,A   I120 @BASEBOARD_FAB2_LIB.BASEBOARD_FAB2(SCH_1):PAGE149
C25W38    2      B CAP_A_0402V-0.1UF,16V,10%,X7R,A   I121 @BASEBOARD_FAB2_LIB.BASEBOARD_FAB2(SCH_1):PAGE149
C25W45    2      B CAP_A_0402V-0.1UF,16V,10%,X7R,A   I122 @BASEBOARD_FAB2_LIB.BASEBOARD_FAB2(SCH_1):PAGE149
C25W49    2      B CAP_A_0402V-0.1UF,16V,10%,X7R,A   I123 @BASEBOARD_FAB2_LIB.BASEBOARD_FAB2(SCH_1):PAGE149
C25W55    2      B CAP_A_0402V-0.1UF,16V,10%,X7R,A   I124 @BASEBOARD_FAB2_LIB.BASEBOARD_FAB2(SCH_1):PAGE149
C25W58    2      B CAP_A_0402V-0.1UF,16V,10%,X7R,A   I125 @BASEBOARD_FAB2_LIB.BASEBOARD_FAB2(SCH_1):PAGE149
C25W61    2      B CAP_A_0402V-0.1UF,16V,10%,X7R,A   I126 @BASEBOARD_FAB2_LIB.BASEBOARD_FAB2(SCH_1):PAGE149
C25W22    2      B CAP_A_0402V-0.1UF,16V,10%,X7R,A    I67 @BASEBOARD_FAB2_LIB.BASEBOARD_FAB2(SCH_1):PAGE143
C25W68    2      B CAP_A_0402V-0.1UF,16V,10%,X7R,A   I128 @BASEBOARD_FAB2_LIB.BASEBOARD_FAB2(SCH_1):PAGE149
  C6W1    2      B CAP_A_0402V-0.1UF,16V,10%,X7R,A   I151 @BASEBOARD_FAB2_LIB.BASEBOARD_FAB2(SCH_1):PAGE247
 C6W10    2      B CAP_A_0402V-0.1UF,16V,10%,X7R,A   I139 @BASEBOARD_FAB2_LIB.BASEBOARD_FAB2(SCH_1):PAGE176
  C8W2    2      B CAP_A_0402V-0.1UF,16V,10%,X7R,A    I37 @BASEBOARD_FAB2_LIB.BASEBOARD_FAB2(SCH_1):PAGE249
C25W13    2      B CAP_A_0402V-0.1UF,16V,10%,X7R,A   I217 @BASEBOARD_FAB2_LIB.BASEBOARD_FAB2(SCH_1):PAGE151
  U7W1    2    GND PI5A3157BC6E-GP_DISCRET-GC2-PIA    I34 @BASEBOARD_FAB2_LIB.BASEBOARD_FAB2(SCH_1):PAGE166
  C7W1    2      B CAP_A_0402V-0.1UF,16V,10%,X7R,A    I36 @BASEBOARD_FAB2_LIB.BASEBOARD_FAB2(SCH_1):PAGE166
  R7W2    2      B RES_0402-10.0K,1%,1/16W,EMPTY,A    I42 @BASEBOARD_FAB2_LIB.BASEBOARD_FAB2(SCH_1):PAGE166
 C5D58    2      B CAP_A_0603V-22.0UF,4V,20%,X6S,A   I269 @BASEBOARD_FAB2_LIB.BASEBOARD_FAB2(SCH_1):PAGE217
 C5D61    2      B CAP_A_0603V-22.0UF,4V,20%,X6S,A   I270 @BASEBOARD_FAB2_LIB.BASEBOARD_FAB2(SCH_1):PAGE217
 C5D59    2      B CAP_A_0603V-22.0UF,4V,20%,X6S,A   I271 @BASEBOARD_FAB2_LIB.BASEBOARD_FAB2(SCH_1):PAGE217
 C5D60    2      B CAP_A_0603V-22.0UF,4V,20%,X6S,A   I272 @BASEBOARD_FAB2_LIB.BASEBOARD_FAB2(SCH_1):PAGE217
  C5D4    2      B CAP_A_0603V-22.0UF,4V,20%,X6S,A   I249 @BASEBOARD_FAB2_LIB.BASEBOARD_FAB2(SCH_1):PAGE220
  C5D3    2      B CAP_A_0603V-22.0UF,4V,20%,X6S,A   I250 @BASEBOARD_FAB2_LIB.BASEBOARD_FAB2(SCH_1):PAGE220
  C5D2    2      B CAP_A_0603V-22.0UF,4V,20%,X6S,A   I251 @BASEBOARD_FAB2_LIB.BASEBOARD_FAB2(SCH_1):PAGE220
  C5D1    2      B CAP_A_0603V-22.0UF,4V,20%,X6S,A   I252 @BASEBOARD_FAB2_LIB.BASEBOARD_FAB2(SCH_1):PAGE220
 C2D45    2      B CAP_A_0603V-22.0UF,4V,20%,X6S,A   I261 @BASEBOARD_FAB2_LIB.BASEBOARD_FAB2(SCH_1):PAGE225
 C3D25    2      B CAP_A_0603V-22.0UF,4V,20%,X6S,A   I262 @BASEBOARD_FAB2_LIB.BASEBOARD_FAB2(SCH_1):PAGE225
 C2D47    2      B CAP_A_0603V-22.0UF,4V,20%,X6S,A   I263 @BASEBOARD_FAB2_LIB.BASEBOARD_FAB2(SCH_1):PAGE225
 C2D46    2      B CAP_A_0603V-22.0UF,4V,20%,X6S,A   I264 @BASEBOARD_FAB2_LIB.BASEBOARD_FAB2(SCH_1):PAGE225
  C3D1    2      B CAP_A_0603V-22.0UF,4V,20%,X6S,A   I255 @BASEBOARD_FAB2_LIB.BASEBOARD_FAB2(SCH_1):PAGE228
  C2D3    2      B CAP_A_0603V-22.0UF,4V,20%,X6S,A   I256 @BASEBOARD_FAB2_LIB.BASEBOARD_FAB2(SCH_1):PAGE228
  C2D2    2      B CAP_A_0603V-22.0UF,4V,20%,X6S,A   I257 @BASEBOARD_FAB2_LIB.BASEBOARD_FAB2(SCH_1):PAGE228
  C2D1    2      B CAP_A_0603V-22.0UF,4V,20%,X6S,A   I258 @BASEBOARD_FAB2_LIB.BASEBOARD_FAB2(SCH_1):PAGE228
  C8W3    2      B CAP_0805-100UF,4V,20%,X5R,6024A   I211 @BASEBOARD_FAB2_LIB.BASEBOARD_FAB2(SCH_1):PAGE42
 RM1G1    1      1 STFT363B238R224H453-GP_DISCRETA   I117 @BASEBOARD_FAB2_LIB.BASEBOARD_FAB2(SCH_1):PAGE195
  Q4W2    2    SRC FET_N_SOT23LF-2N7002,FET,C7925A   I112 @BASEBOARD_FAB2_LIB.BASEBOARD_FAB2(SCH_1):PAGE102
 C5D54    2      B CAP_A_0603V-22.0UF,4V,20%,X6S,A   I279 @BASEBOARD_FAB2_LIB.BASEBOARD_FAB2(SCH_1):PAGE217
 C5D55    2      B CAP_A_0603V-22.0UF,4V,20%,X6S,A   I280 @BASEBOARD_FAB2_LIB.BASEBOARD_FAB2(SCH_1):PAGE217
 C5D56    2      B CAP_A_0603V-22.0UF,4V,20%,X6S,A   I281 @BASEBOARD_FAB2_LIB.BASEBOARD_FAB2(SCH_1):PAGE217
 C5D57    2      B CAP_A_0603V-22.0UF,4V,20%,X6S,A   I282 @BASEBOARD_FAB2_LIB.BASEBOARD_FAB2(SCH_1):PAGE217
  C5U2    2      B CAP_A_0603V-47UF,4V,20%,X5R,60A   I283 @BASEBOARD_FAB2_LIB.BASEBOARD_FAB2(SCH_1):PAGE217
  C5U3    2      B CAP_A_0603V-47UF,4V,20%,X5R,60A   I284 @BASEBOARD_FAB2_LIB.BASEBOARD_FAB2(SCH_1):PAGE217
  C5U4    2      B CAP_A_0603V-47UF,4V,20%,X5R,60A   I285 @BASEBOARD_FAB2_LIB.BASEBOARD_FAB2(SCH_1):PAGE217
  C5U5    2      B CAP_A_0603V-47UF,4V,20%,X5R,60A   I286 @BASEBOARD_FAB2_LIB.BASEBOARD_FAB2(SCH_1):PAGE217
  C5U6    2      B CAP_A_0603V-47UF,4V,20%,X5R,60A   I287 @BASEBOARD_FAB2_LIB.BASEBOARD_FAB2(SCH_1):PAGE217
  C5U7    2      B CAP_A_0603V-47UF,4V,20%,X5R,60A   I288 @BASEBOARD_FAB2_LIB.BASEBOARD_FAB2(SCH_1):PAGE217
  C5U8    2      B CAP_A_0603V-47UF,4V,20%,X5R,60A   I289 @BASEBOARD_FAB2_LIB.BASEBOARD_FAB2(SCH_1):PAGE217
  C5U9    2      B CAP_A_0603V-47UF,4V,20%,X5R,60A   I290 @BASEBOARD_FAB2_LIB.BASEBOARD_FAB2(SCH_1):PAGE217
 C5T12    2      B CAP_A_0603V-47UF,4V,20%,X5R,60A   I291 @BASEBOARD_FAB2_LIB.BASEBOARD_FAB2(SCH_1):PAGE217
 C5T11    2      B CAP_A_0603V-47UF,4V,20%,X5R,60A   I292 @BASEBOARD_FAB2_LIB.BASEBOARD_FAB2(SCH_1):PAGE217
 C5T10    2      B CAP_A_0603V-47UF,4V,20%,X5R,60A   I293 @BASEBOARD_FAB2_LIB.BASEBOARD_FAB2(SCH_1):PAGE217
  C5T9    2      B CAP_A_0603V-47UF,4V,20%,X5R,60A   I294 @BASEBOARD_FAB2_LIB.BASEBOARD_FAB2(SCH_1):PAGE217
  C5T8    2      B CAP_A_0603V-47UF,4V,20%,X5R,60A   I295 @BASEBOARD_FAB2_LIB.BASEBOARD_FAB2(SCH_1):PAGE217
  C5T7    2      B CAP_A_0603V-47UF,4V,20%,X5R,60A   I296 @BASEBOARD_FAB2_LIB.BASEBOARD_FAB2(SCH_1):PAGE217
  C5T6    2      B CAP_A_0603V-47UF,4V,20%,X5R,60A   I297 @BASEBOARD_FAB2_LIB.BASEBOARD_FAB2(SCH_1):PAGE217
  C5T5    2      B CAP_A_0603V-47UF,4V,20%,X5R,60A   I298 @BASEBOARD_FAB2_LIB.BASEBOARD_FAB2(SCH_1):PAGE217
 C5G11    2      B CAP_A_0603V-47UF,4V,20%,X5R,60A   I299 @BASEBOARD_FAB2_LIB.BASEBOARD_FAB2(SCH_1):PAGE217
 C5G12    2      B CAP_A_0603V-47UF,4V,20%,X5R,60A   I300 @BASEBOARD_FAB2_LIB.BASEBOARD_FAB2(SCH_1):PAGE217
  C5G2    2      B CAP_A_0603V-47UF,4V,20%,X5R,60A   I301 @BASEBOARD_FAB2_LIB.BASEBOARD_FAB2(SCH_1):PAGE217
  C5G4    2      B CAP_A_0603V-47UF,4V,20%,X5R,60A   I302 @BASEBOARD_FAB2_LIB.BASEBOARD_FAB2(SCH_1):PAGE217
 C5G13    2      B CAP_A_0603V-47UF,4V,20%,X5R,60A   I303 @BASEBOARD_FAB2_LIB.BASEBOARD_FAB2(SCH_1):PAGE217
  C5G6    2      B CAP_A_0603V-47UF,4V,20%,X5R,60A   I304 @BASEBOARD_FAB2_LIB.BASEBOARD_FAB2(SCH_1):PAGE217
  C5G5    2      B CAP_A_0603V-47UF,4V,20%,X5R,60A   I305 @BASEBOARD_FAB2_LIB.BASEBOARD_FAB2(SCH_1):PAGE217
  C5G7    2      B CAP_A_0603V-47UF,4V,20%,X5R,60A   I306 @BASEBOARD_FAB2_LIB.BASEBOARD_FAB2(SCH_1):PAGE217
  C5G1    2      B CAP_A_0603V-47UF,4V,20%,X5R,60A   I307 @BASEBOARD_FAB2_LIB.BASEBOARD_FAB2(SCH_1):PAGE217
  C5G8    2      B CAP_A_0603V-47UF,4V,20%,X5R,60A   I308 @BASEBOARD_FAB2_LIB.BASEBOARD_FAB2(SCH_1):PAGE217
 C5G18    2      B CAP_A_0603V-47UF,4V,20%,X5R,60A   I309 @BASEBOARD_FAB2_LIB.BASEBOARD_FAB2(SCH_1):PAGE217
 C5G17    2      B CAP_A_0603V-47UF,4V,20%,X5R,60A   I310 @BASEBOARD_FAB2_LIB.BASEBOARD_FAB2(SCH_1):PAGE217
 C5G14    2      B CAP_A_0603V-47UF,4V,20%,X5R,60A   I311 @BASEBOARD_FAB2_LIB.BASEBOARD_FAB2(SCH_1):PAGE217
 C5G16    2      B CAP_A_0603V-47UF,4V,20%,X5R,60A   I312 @BASEBOARD_FAB2_LIB.BASEBOARD_FAB2(SCH_1):PAGE217
 C5G15    2      B CAP_A_0603V-47UF,4V,20%,X5R,60A   I313 @BASEBOARD_FAB2_LIB.BASEBOARD_FAB2(SCH_1):PAGE217
  C5G3    2      B CAP_A_0603V-47UF,4V,20%,X5R,60A   I314 @BASEBOARD_FAB2_LIB.BASEBOARD_FAB2(SCH_1):PAGE217
  C5D9    2      B CAP_A_0603V-22.0UF,4V,20%,X6S,A   I258 @BASEBOARD_FAB2_LIB.BASEBOARD_FAB2(SCH_1):PAGE220
  C5D6    2      B CAP_A_0603V-22.0UF,4V,20%,X6S,A   I259 @BASEBOARD_FAB2_LIB.BASEBOARD_FAB2(SCH_1):PAGE220
  C5D7    2      B CAP_A_0603V-22.0UF,4V,20%,X6S,A   I260 @BASEBOARD_FAB2_LIB.BASEBOARD_FAB2(SCH_1):PAGE220
  C5D8    2      B CAP_A_0603V-22.0UF,4V,20%,X6S,A   I261 @BASEBOARD_FAB2_LIB.BASEBOARD_FAB2(SCH_1):PAGE220
  C5A1    2      B CAP_A_0603V-47UF,4V,20%,X5R,60A   I262 @BASEBOARD_FAB2_LIB.BASEBOARD_FAB2(SCH_1):PAGE220
 C5A15    2      B CAP_A_0603V-47UF,4V,20%,X5R,60A   I263 @BASEBOARD_FAB2_LIB.BASEBOARD_FAB2(SCH_1):PAGE220
 C5A12    2      B CAP_A_0603V-47UF,4V,20%,X5R,60A   I264 @BASEBOARD_FAB2_LIB.BASEBOARD_FAB2(SCH_1):PAGE220
 C5A13    2      B CAP_A_0603V-47UF,4V,20%,X5R,60A   I265 @BASEBOARD_FAB2_LIB.BASEBOARD_FAB2(SCH_1):PAGE220
  C5A2    2      B CAP_A_0603V-47UF,4V,20%,X5R,60A   I266 @BASEBOARD_FAB2_LIB.BASEBOARD_FAB2(SCH_1):PAGE220
 C5A14    2      B CAP_A_0603V-47UF,4V,20%,X5R,60A   I267 @BASEBOARD_FAB2_LIB.BASEBOARD_FAB2(SCH_1):PAGE220
  C5A6    2      B CAP_A_0603V-47UF,4V,20%,X5R,60A   I268 @BASEBOARD_FAB2_LIB.BASEBOARD_FAB2(SCH_1):PAGE220
  C5A7    2      B CAP_A_0603V-47UF,4V,20%,X5R,60A   I269 @BASEBOARD_FAB2_LIB.BASEBOARD_FAB2(SCH_1):PAGE220
  C5A3    2      B CAP_A_0603V-47UF,4V,20%,X5R,60A   I270 @BASEBOARD_FAB2_LIB.BASEBOARD_FAB2(SCH_1):PAGE220
  C5A8    2      B CAP_A_0603V-47UF,4V,20%,X5R,60A   I271 @BASEBOARD_FAB2_LIB.BASEBOARD_FAB2(SCH_1):PAGE220
  C5A9    2      B CAP_A_0603V-47UF,4V,20%,X5R,60A   I272 @BASEBOARD_FAB2_LIB.BASEBOARD_FAB2(SCH_1):PAGE220
 C5A16    2      B CAP_A_0603V-47UF,4V,20%,X5R,60A   I273 @BASEBOARD_FAB2_LIB.BASEBOARD_FAB2(SCH_1):PAGE220
  C5A4    2      B CAP_A_0603V-47UF,4V,20%,X5R,60A   I274 @BASEBOARD_FAB2_LIB.BASEBOARD_FAB2(SCH_1):PAGE220
 C5A17    2      B CAP_A_0603V-47UF,4V,20%,X5R,60A   I275 @BASEBOARD_FAB2_LIB.BASEBOARD_FAB2(SCH_1):PAGE220
 C5A18    2      B CAP_A_0603V-47UF,4V,20%,X5R,60A   I276 @BASEBOARD_FAB2_LIB.BASEBOARD_FAB2(SCH_1):PAGE220
 C5A19    2      B CAP_A_0603V-47UF,4V,20%,X5R,60A   I277 @BASEBOARD_FAB2_LIB.BASEBOARD_FAB2(SCH_1):PAGE220
  C5L6    2      B CAP_A_0603V-47UF,4V,20%,X5R,60A   I278 @BASEBOARD_FAB2_LIB.BASEBOARD_FAB2(SCH_1):PAGE220
  C5L7    2      B CAP_A_0603V-47UF,4V,20%,X5R,60A   I279 @BASEBOARD_FAB2_LIB.BASEBOARD_FAB2(SCH_1):PAGE220
  C5L8    2      B CAP_A_0603V-47UF,4V,20%,X5R,60A   I280 @BASEBOARD_FAB2_LIB.BASEBOARD_FAB2(SCH_1):PAGE220
  C5L9    2      B CAP_A_0603V-47UF,4V,20%,X5R,60A   I281 @BASEBOARD_FAB2_LIB.BASEBOARD_FAB2(SCH_1):PAGE220
 C5L10    2      B CAP_A_0603V-47UF,4V,20%,X5R,60A   I282 @BASEBOARD_FAB2_LIB.BASEBOARD_FAB2(SCH_1):PAGE220
 C5L11    2      B CAP_A_0603V-47UF,4V,20%,X5R,60A   I283 @BASEBOARD_FAB2_LIB.BASEBOARD_FAB2(SCH_1):PAGE220
 C5L12    2      B CAP_A_0603V-47UF,4V,20%,X5R,60A   I284 @BASEBOARD_FAB2_LIB.BASEBOARD_FAB2(SCH_1):PAGE220
 C5L13    2      B CAP_A_0603V-47UF,4V,20%,X5R,60A   I285 @BASEBOARD_FAB2_LIB.BASEBOARD_FAB2(SCH_1):PAGE220
  C5M7    2      B CAP_A_0603V-47UF,4V,20%,X5R,60A   I286 @BASEBOARD_FAB2_LIB.BASEBOARD_FAB2(SCH_1):PAGE220
  C5M6    2      B CAP_A_0603V-47UF,4V,20%,X5R,60A   I287 @BASEBOARD_FAB2_LIB.BASEBOARD_FAB2(SCH_1):PAGE220
  C5M5    2      B CAP_A_0603V-47UF,4V,20%,X5R,60A   I288 @BASEBOARD_FAB2_LIB.BASEBOARD_FAB2(SCH_1):PAGE220
  C5M4    2      B CAP_A_0603V-47UF,4V,20%,X5R,60A   I289 @BASEBOARD_FAB2_LIB.BASEBOARD_FAB2(SCH_1):PAGE220
  C5M2    2      B CAP_A_0603V-47UF,4V,20%,X5R,60A   I290 @BASEBOARD_FAB2_LIB.BASEBOARD_FAB2(SCH_1):PAGE220
  C5M1    2      B CAP_A_0603V-47UF,4V,20%,X5R,60A   I291 @BASEBOARD_FAB2_LIB.BASEBOARD_FAB2(SCH_1):PAGE220
  C4M2    2      B CAP_A_0603V-47UF,4V,20%,X5R,60A   I292 @BASEBOARD_FAB2_LIB.BASEBOARD_FAB2(SCH_1):PAGE220
 C5A11    2      B CAP_A_0603V-47UF,4V,20%,X5R,60A   I293 @BASEBOARD_FAB2_LIB.BASEBOARD_FAB2(SCH_1):PAGE220
 C2D43    2      B CAP_A_0603V-22.0UF,4V,20%,X6S,A   I270 @BASEBOARD_FAB2_LIB.BASEBOARD_FAB2(SCH_1):PAGE225
 C2D41    2      B CAP_A_0603V-22.0UF,4V,20%,X6S,A   I271 @BASEBOARD_FAB2_LIB.BASEBOARD_FAB2(SCH_1):PAGE225
 C2D44    2      B CAP_A_0603V-22.0UF,4V,20%,X6S,A   I272 @BASEBOARD_FAB2_LIB.BASEBOARD_FAB2(SCH_1):PAGE225
 C2D42    2      B CAP_A_0603V-22.0UF,4V,20%,X6S,A   I273 @BASEBOARD_FAB2_LIB.BASEBOARD_FAB2(SCH_1):PAGE225
 C2G10    2      B CAP_A_0603V-47UF,4V,20%,X5R,60A   I274 @BASEBOARD_FAB2_LIB.BASEBOARD_FAB2(SCH_1):PAGE225
 C2G11    2      B CAP_A_0603V-47UF,4V,20%,X5R,60A   I275 @BASEBOARD_FAB2_LIB.BASEBOARD_FAB2(SCH_1):PAGE225
 C2G12    2      B CAP_A_0603V-47UF,4V,20%,X5R,60A   I276 @BASEBOARD_FAB2_LIB.BASEBOARD_FAB2(SCH_1):PAGE225
  C2G1    2      B CAP_A_0603V-47UF,4V,20%,X5R,60A   I277 @BASEBOARD_FAB2_LIB.BASEBOARD_FAB2(SCH_1):PAGE225
  C2G9    2      B CAP_A_0603V-47UF,4V,20%,X5R,60A   I278 @BASEBOARD_FAB2_LIB.BASEBOARD_FAB2(SCH_1):PAGE225
  C2G2    2      B CAP_A_0603V-47UF,4V,20%,X5R,60A   I279 @BASEBOARD_FAB2_LIB.BASEBOARD_FAB2(SCH_1):PAGE225
  C2G3    2      B CAP_A_0603V-47UF,4V,20%,X5R,60A   I280 @BASEBOARD_FAB2_LIB.BASEBOARD_FAB2(SCH_1):PAGE225
  C2G4    2      B CAP_A_0603V-47UF,4V,20%,X5R,60A   I281 @BASEBOARD_FAB2_LIB.BASEBOARD_FAB2(SCH_1):PAGE225
  C2G5    2      B CAP_A_0603V-47UF,4V,20%,X5R,60A   I282 @BASEBOARD_FAB2_LIB.BASEBOARD_FAB2(SCH_1):PAGE225
  C2G6    2      B CAP_A_0603V-47UF,4V,20%,X5R,60A   I283 @BASEBOARD_FAB2_LIB.BASEBOARD_FAB2(SCH_1):PAGE225
  C3G1    2      B CAP_A_0603V-47UF,4V,20%,X5R,60A   I284 @BASEBOARD_FAB2_LIB.BASEBOARD_FAB2(SCH_1):PAGE225
  C3G2    2      B CAP_A_0603V-47UF,4V,20%,X5R,60A   I285 @BASEBOARD_FAB2_LIB.BASEBOARD_FAB2(SCH_1):PAGE225
 C2G13    2      B CAP_A_0603V-47UF,4V,20%,X5R,60A   I286 @BASEBOARD_FAB2_LIB.BASEBOARD_FAB2(SCH_1):PAGE225
 C2G14    2      B CAP_A_0603V-47UF,4V,20%,X5R,60A   I287 @BASEBOARD_FAB2_LIB.BASEBOARD_FAB2(SCH_1):PAGE225
  C3G5    2      B CAP_A_0603V-47UF,4V,20%,X5R,60A   I288 @BASEBOARD_FAB2_LIB.BASEBOARD_FAB2(SCH_1):PAGE225
  C3G6    2      B CAP_A_0603V-47UF,4V,20%,X5R,60A   I289 @BASEBOARD_FAB2_LIB.BASEBOARD_FAB2(SCH_1):PAGE225
  C8U7    2      B CAP_A_0603V-47UF,4V,20%,X5R,60A   I290 @BASEBOARD_FAB2_LIB.BASEBOARD_FAB2(SCH_1):PAGE225
  C8U2    2      B CAP_A_0603V-47UF,4V,20%,X5R,60A   I291 @BASEBOARD_FAB2_LIB.BASEBOARD_FAB2(SCH_1):PAGE225
  C7U2    2      B CAP_A_0603V-47UF,4V,20%,X5R,60A   I292 @BASEBOARD_FAB2_LIB.BASEBOARD_FAB2(SCH_1):PAGE225
  C7U1    2      B CAP_A_0603V-47UF,4V,20%,X5R,60A   I293 @BASEBOARD_FAB2_LIB.BASEBOARD_FAB2(SCH_1):PAGE225
  C8U3    2      B CAP_A_0603V-47UF,4V,20%,X5R,60A   I294 @BASEBOARD_FAB2_LIB.BASEBOARD_FAB2(SCH_1):PAGE225
  C7T4    2      B CAP_A_0603V-47UF,4V,20%,X5R,60A   I295 @BASEBOARD_FAB2_LIB.BASEBOARD_FAB2(SCH_1):PAGE225
  C7T5    2      B CAP_A_0603V-47UF,4V,20%,X5R,60A   I296 @BASEBOARD_FAB2_LIB.BASEBOARD_FAB2(SCH_1):PAGE225
  C8T5    2      B CAP_A_0603V-47UF,4V,20%,X5R,60A   I297 @BASEBOARD_FAB2_LIB.BASEBOARD_FAB2(SCH_1):PAGE225
  C8U6    2      B CAP_A_0603V-47UF,4V,20%,X5R,60A   I298 @BASEBOARD_FAB2_LIB.BASEBOARD_FAB2(SCH_1):PAGE225
  C8T6    2      B CAP_A_0603V-47UF,4V,20%,X5R,60A   I299 @BASEBOARD_FAB2_LIB.BASEBOARD_FAB2(SCH_1):PAGE225
  C8T7    2      B CAP_A_0603V-47UF,4V,20%,X5R,60A   I300 @BASEBOARD_FAB2_LIB.BASEBOARD_FAB2(SCH_1):PAGE225
  C8T8    2      B CAP_A_0603V-47UF,4V,20%,X5R,60A   I301 @BASEBOARD_FAB2_LIB.BASEBOARD_FAB2(SCH_1):PAGE225
  C8U5    2      B CAP_A_0603V-47UF,4V,20%,X5R,60A   I302 @BASEBOARD_FAB2_LIB.BASEBOARD_FAB2(SCH_1):PAGE225
  C8T9    2      B CAP_A_0603V-47UF,4V,20%,X5R,60A   I303 @BASEBOARD_FAB2_LIB.BASEBOARD_FAB2(SCH_1):PAGE225
 C8T10    2      B CAP_A_0603V-47UF,4V,20%,X5R,60A   I304 @BASEBOARD_FAB2_LIB.BASEBOARD_FAB2(SCH_1):PAGE225
  C8U4    2      B CAP_A_0603V-47UF,4V,20%,X5R,60A   I305 @BASEBOARD_FAB2_LIB.BASEBOARD_FAB2(SCH_1):PAGE225
  C2D7    2      B CAP_A_0603V-22.0UF,4V,20%,X6S,A   I264 @BASEBOARD_FAB2_LIB.BASEBOARD_FAB2(SCH_1):PAGE228
  C2D4    2      B CAP_A_0603V-22.0UF,4V,20%,X6S,A   I265 @BASEBOARD_FAB2_LIB.BASEBOARD_FAB2(SCH_1):PAGE228
  C2D5    2      B CAP_A_0603V-22.0UF,4V,20%,X6S,A   I266 @BASEBOARD_FAB2_LIB.BASEBOARD_FAB2(SCH_1):PAGE228
  C2D6    2      B CAP_A_0603V-22.0UF,4V,20%,X6S,A   I267 @BASEBOARD_FAB2_LIB.BASEBOARD_FAB2(SCH_1):PAGE228
  C7L5    2      B CAP_A_0603V-47UF,4V,20%,X5R,60A   I268 @BASEBOARD_FAB2_LIB.BASEBOARD_FAB2(SCH_1):PAGE228
  C3A6    2      B CAP_A_0603V-47UF,4V,20%,X5R,60A   I269 @BASEBOARD_FAB2_LIB.BASEBOARD_FAB2(SCH_1):PAGE228
  C3A5    2      B CAP_A_0603V-47UF,4V,20%,X5R,60A   I270 @BASEBOARD_FAB2_LIB.BASEBOARD_FAB2(SCH_1):PAGE228
 C2A15    2      B CAP_A_0603V-47UF,4V,20%,X5R,60A   I271 @BASEBOARD_FAB2_LIB.BASEBOARD_FAB2(SCH_1):PAGE228
 C2A14    2      B CAP_A_0603V-47UF,4V,20%,X5R,60A   I272 @BASEBOARD_FAB2_LIB.BASEBOARD_FAB2(SCH_1):PAGE228
  C2A6    2      B CAP_A_0603V-47UF,4V,20%,X5R,60A   I273 @BASEBOARD_FAB2_LIB.BASEBOARD_FAB2(SCH_1):PAGE228
  C2A7    2      B CAP_A_0603V-47UF,4V,20%,X5R,60A   I274 @BASEBOARD_FAB2_LIB.BASEBOARD_FAB2(SCH_1):PAGE228
  C3A1    2      B CAP_A_0603V-47UF,4V,20%,X5R,60A   I275 @BASEBOARD_FAB2_LIB.BASEBOARD_FAB2(SCH_1):PAGE228
  C3A2    2      B CAP_A_0603V-47UF,4V,20%,X5R,60A   I276 @BASEBOARD_FAB2_LIB.BASEBOARD_FAB2(SCH_1):PAGE228
  C2A9    2      B CAP_A_0603V-47UF,4V,20%,X5R,60A   I277 @BASEBOARD_FAB2_LIB.BASEBOARD_FAB2(SCH_1):PAGE228
 C2A10    2      B CAP_A_0603V-47UF,4V,20%,X5R,60A   I278 @BASEBOARD_FAB2_LIB.BASEBOARD_FAB2(SCH_1):PAGE228
 C2A11    2      B CAP_A_0603V-47UF,4V,20%,X5R,60A   I279 @BASEBOARD_FAB2_LIB.BASEBOARD_FAB2(SCH_1):PAGE228
 C2A13    2      B CAP_A_0603V-47UF,4V,20%,X5R,60A   I280 @BASEBOARD_FAB2_LIB.BASEBOARD_FAB2(SCH_1):PAGE228
 C2A12    2      B CAP_A_0603V-47UF,4V,20%,X5R,60A   I281 @BASEBOARD_FAB2_LIB.BASEBOARD_FAB2(SCH_1):PAGE228
  C2A1    2      B CAP_A_0603V-47UF,4V,20%,X5R,60A   I282 @BASEBOARD_FAB2_LIB.BASEBOARD_FAB2(SCH_1):PAGE228
  C2A2    2      B CAP_A_0603V-47UF,4V,20%,X5R,60A   I283 @BASEBOARD_FAB2_LIB.BASEBOARD_FAB2(SCH_1):PAGE228
  C8M1    2      B CAP_A_0603V-47UF,4V,20%,X5R,60A   I284 @BASEBOARD_FAB2_LIB.BASEBOARD_FAB2(SCH_1):PAGE228
  C8L5    2      B CAP_A_0603V-47UF,4V,20%,X5R,60A   I285 @BASEBOARD_FAB2_LIB.BASEBOARD_FAB2(SCH_1):PAGE228
  C8L6    2      B CAP_A_0603V-47UF,4V,20%,X5R,60A   I286 @BASEBOARD_FAB2_LIB.BASEBOARD_FAB2(SCH_1):PAGE228
  C8L7    2      B CAP_A_0603V-47UF,4V,20%,X5R,60A   I287 @BASEBOARD_FAB2_LIB.BASEBOARD_FAB2(SCH_1):PAGE228
  C7L4    2      B CAP_A_0603V-47UF,4V,20%,X5R,60A   I288 @BASEBOARD_FAB2_LIB.BASEBOARD_FAB2(SCH_1):PAGE228
  C8L8    2      B CAP_A_0603V-47UF,4V,20%,X5R,60A   I289 @BASEBOARD_FAB2_LIB.BASEBOARD_FAB2(SCH_1):PAGE228
  C8L9    2      B CAP_A_0603V-47UF,4V,20%,X5R,60A   I290 @BASEBOARD_FAB2_LIB.BASEBOARD_FAB2(SCH_1):PAGE228
  C8M6    2      B CAP_A_0603V-47UF,4V,20%,X5R,60A   I291 @BASEBOARD_FAB2_LIB.BASEBOARD_FAB2(SCH_1):PAGE228
  C2A4    2      B CAP_A_0603V-47UF,4V,20%,X5R,60A   I292 @BASEBOARD_FAB2_LIB.BASEBOARD_FAB2(SCH_1):PAGE228
  C8M4    2      B CAP_A_0603V-47UF,4V,20%,X5R,60A   I293 @BASEBOARD_FAB2_LIB.BASEBOARD_FAB2(SCH_1):PAGE228
  C7M2    2      B CAP_A_0603V-47UF,4V,20%,X5R,60A   I294 @BASEBOARD_FAB2_LIB.BASEBOARD_FAB2(SCH_1):PAGE228
  C7M1    2      B CAP_A_0603V-47UF,4V,20%,X5R,60A   I295 @BASEBOARD_FAB2_LIB.BASEBOARD_FAB2(SCH_1):PAGE228
  C2A3    2      B CAP_A_0603V-47UF,4V,20%,X5R,60A   I296 @BASEBOARD_FAB2_LIB.BASEBOARD_FAB2(SCH_1):PAGE228
 C8L10    2      B CAP_A_0603V-47UF,4V,20%,X5R,60A   I297 @BASEBOARD_FAB2_LIB.BASEBOARD_FAB2(SCH_1):PAGE228
  C8M5    2      B CAP_A_0603V-47UF,4V,20%,X5R,60A   I298 @BASEBOARD_FAB2_LIB.BASEBOARD_FAB2(SCH_1):PAGE228
  C8M3    2      B CAP_A_0603V-47UF,4V,20%,X5R,60A   I299 @BASEBOARD_FAB2_LIB.BASEBOARD_FAB2(SCH_1):PAGE228
  C7W5    2      2 SC22U16V5MX-4-GP_SMD-BCG5-SC22A   I298 @BASEBOARD_FAB2_LIB.BASEBOARD_FAB2(SCH_1):PAGE220
  C7W9    2      2 SC22U16V5MX-4-GP_SMD-BCG5-SC22A   I299 @BASEBOARD_FAB2_LIB.BASEBOARD_FAB2(SCH_1):PAGE220
  C7W8    2      2 SC22U16V5MX-4-GP_SMD-BCG5-SC22A   I300 @BASEBOARD_FAB2_LIB.BASEBOARD_FAB2(SCH_1):PAGE220
  C7W7    2      2 SC22U16V5MX-4-GP_SMD-BCG5-SC22A   I301 @BASEBOARD_FAB2_LIB.BASEBOARD_FAB2(SCH_1):PAGE220
  C7W6    2      2 SC22U16V5MX-4-GP_SMD-BCG5-SC22A   I302 @BASEBOARD_FAB2_LIB.BASEBOARD_FAB2(SCH_1):PAGE220
 C7W13    2      2 SC22U16V5MX-4-GP_SMD-BCG5-SC22A   I303 @BASEBOARD_FAB2_LIB.BASEBOARD_FAB2(SCH_1):PAGE220
 C7W12    2      2 SC22U16V5MX-4-GP_SMD-BCG5-SC22A   I304 @BASEBOARD_FAB2_LIB.BASEBOARD_FAB2(SCH_1):PAGE220
 C7W11    2      2 SC22U16V5MX-4-GP_SMD-BCG5-SC22A   I305 @BASEBOARD_FAB2_LIB.BASEBOARD_FAB2(SCH_1):PAGE220
 C7W10    2      2 SC22U16V5MX-4-GP_SMD-BCG5-SC22A   I306 @BASEBOARD_FAB2_LIB.BASEBOARD_FAB2(SCH_1):PAGE220
  J8D4    2      2 PIN-CON3-27-GP_CONN-G7-PIN-CONA   I191 @BASEBOARD_FAB2_LIB.BASEBOARD_FAB2(SCH_1):PAGE201
 C25W8    2      B CAP_A_0402V-0.1UF,16V,10%,X7R,A   I162 @BASEBOARD_FAB2_LIB.BASEBOARD_FAB2(SCH_1):PAGE147
  C8E7    2      2 SC22U16V5MX-4-GP_SMD-BCG5-SC22A   I103 @BASEBOARD_FAB2_LIB.BASEBOARD_FAB2(SCH_1):PAGE241
  C8E9    2      2 SC22U16V5MX-4-GP_SMD-BCG5-SC22A   I104 @BASEBOARD_FAB2_LIB.BASEBOARD_FAB2(SCH_1):PAGE241
  Q8D1    1   E<0> NPN_DUAL_SSOPLF-MBT3904,XSTR,CA    I46 @BASEBOARD_FAB2_LIB.BASEBOARD_FAB2(SCH_1):PAGE89
  Q8W1    1   E<0> NPN_DUAL_SSOPLF-MBT3904,XSTR,CA    I51 @BASEBOARD_FAB2_LIB.BASEBOARD_FAB2(SCH_1):PAGE89
  Q8W1    4   E<0> NPN_DUAL_SSOPLF-MBT3904,XSTR,CA    I52 @BASEBOARD_FAB2_LIB.BASEBOARD_FAB2(SCH_1):PAGE89
  Q1F1    2      E NPN_SM-MMBT3904,IC,C52245-001    I53 @BASEBOARD_FAB2_LIB.BASEBOARD_FAB2(SCH_1):PAGE89
  Q1W6    2      E NPN_SM-MMBT3904,IC,C52245-001    I55 @BASEBOARD_FAB2_LIB.BASEBOARD_FAB2(SCH_1):PAGE89
 C30W3    2      2 SC22U16V5MX-4-GP_SMD-BCG5-SC22A    I35 @BASEBOARD_FAB2_LIB.BASEBOARD_FAB2(SCH_1):PAGE253
 C30W4    2      2 SC22U16V5MX-4-GP_SMD-BCG5-SC22A    I36 @BASEBOARD_FAB2_LIB.BASEBOARD_FAB2(SCH_1):PAGE253
 C30W6    2      2 SC22U16V5MX-4-GP_SMD-BCG5-SC22A    I37 @BASEBOARD_FAB2_LIB.BASEBOARD_FAB2(SCH_1):PAGE253
 C30W5    2      2 SC22U16V5MX-4-GP_SMD-BCG5-SC22A    I38 @BASEBOARD_FAB2_LIB.BASEBOARD_FAB2(SCH_1):PAGE253
 C30W9    2      2 SC22U16V5MX-4-GP_SMD-BCG5-SC22A    I40 @BASEBOARD_FAB2_LIB.BASEBOARD_FAB2(SCH_1):PAGE253
 C30W8    2      2 SC22U16V5MX-4-GP_SMD-BCG5-SC22A    I41 @BASEBOARD_FAB2_LIB.BASEBOARD_FAB2(SCH_1):PAGE253
 C30W7    2      2 SC22U16V5MX-4-GP_SMD-BCG5-SC22A    I42 @BASEBOARD_FAB2_LIB.BASEBOARD_FAB2(SCH_1):PAGE253
  R4P1    1      A RES_0402-240,1.0%,1/16W,EMPTY,A    I98 @BASEBOARD_FAB2_LIB.BASEBOARD_FAB2(SCH_1):PAGE90
 R3D13    1      A RES_0402-240,1.0%,1/16W,EMPTY,A    I99 @BASEBOARD_FAB2_LIB.BASEBOARD_FAB2(SCH_1):PAGE90
 R7P14    1      A RES_0402-240,1.0%,1/16W,CHIP,GA   I100 @BASEBOARD_FAB2_LIB.BASEBOARD_FAB2(SCH_1):PAGE90
 R1U15    2      B RES_0402-1.00K,1%,1/16W,CHIP,GA    I48 @BASEBOARD_FAB2_LIB.BASEBOARD_FAB2(SCH_1):PAGE164
  R6D6    1      A RES_0402-240,1.0%,1/16W,EMPTY,A   I101 @BASEBOARD_FAB2_LIB.BASEBOARD_FAB2(SCH_1):PAGE90
 R3D12    1      A RES_0402-240,1.0%,1/16W,EMPTY,A   I102 @BASEBOARD_FAB2_LIB.BASEBOARD_FAB2(SCH_1):PAGE90
  R2T1    2      B RES_0402-1.00K,1%,1/16W,EMPTY,A    I89 @BASEBOARD_FAB2_LIB.BASEBOARD_FAB2(SCH_1):PAGE125
 R9F32    2      B RES_0402-10.0K,1%,1/16W,CHIP,GA   I100 @BASEBOARD_FAB2_LIB.BASEBOARD_FAB2(SCH_1):PAGE239
 R9W32    2      B RES_0402-10.0K,1%,1/16W,CHIP,GA   I101 @BASEBOARD_FAB2_LIB.BASEBOARD_FAB2(SCH_1):PAGE239
  R7G8    2      B RES_0402-2.26K,1.0%,1/16W,CHIPA    I72 @BASEBOARD_FAB2_LIB.BASEBOARD_FAB2(SCH_1):PAGE215
 R1B12    2      B RES_0402-16K,1.0%,1/16W,CHIP,GA    I72 @BASEBOARD_FAB2_LIB.BASEBOARD_FAB2(SCH_1):PAGE226
  Q6W4    2    SRC FET_N_SOT23LF-2N7002,FET,C7925A    I43 @BASEBOARD_FAB2_LIB.BASEBOARD_FAB2(SCH_1):PAGE168
 R6W38    2      B RES_0402-20.0K,1%,1/16W,CHIP,GA   I156 @BASEBOARD_FAB2_LIB.BASEBOARD_FAB2(SCH_1):PAGE176
 C5M13    2      B CAP_A_0603V-47UF,4V,20%,X5R,60A    I41 @BASEBOARD_FAB2_LIB.BASEBOARD_FAB2(SCH_1):PAGE222
  C5T3    2      B CAP_A_0603V-47UF,4V,20%,X5R,60A    I40 @BASEBOARD_FAB2_LIB.BASEBOARD_FAB2(SCH_1):PAGE221
 C1W18    2      B CAP_A_0402V-0.1UF,16V,10%,X7R,A   I163 @BASEBOARD_FAB2_LIB.BASEBOARD_FAB2(SCH_1):PAGE176
 C1W19    2      B CAP_A_0402V-0.1UF,16V,10%,X7R,A   I166 @BASEBOARD_FAB2_LIB.BASEBOARD_FAB2(SCH_1):PAGE176
 C1W20    2      B CAP_0402-0.22UF,16V,10%,X7R,A3A   I220 @BASEBOARD_FAB2_LIB.BASEBOARD_FAB2(SCH_1):PAGE151
 C1W21    2      B CAP_0603LF-0.033UF,50V,10%,X7RA   I160 @BASEBOARD_FAB2_LIB.BASEBOARD_FAB2(SCH_1):PAGE146
 R1T12    2      B RES_0402-1.00K,1%,1/16W,CHIP,GA    I53 @BASEBOARD_FAB2_LIB.BASEBOARD_FAB2(SCH_1):PAGE164
 R3N22    2      B RES_0402-4.02K,1%,1/16W,CHIP,GA   I102 @BASEBOARD_FAB2_LIB.BASEBOARD_FAB2(SCH_1):PAGE211
  R4E2    2      B RES_0402-3.16K,1%,1/16W,CHIP,GA   I103 @BASEBOARD_FAB2_LIB.BASEBOARD_FAB2(SCH_1):PAGE213
 R4D64    2      B RES_0402-3.16K,1%,1/16W,CHIP,GA   I104 @BASEBOARD_FAB2_LIB.BASEBOARD_FAB2(SCH_1):PAGE213
 R7G10    2      B RES_0402-2.26K,1.0%,1/16W,CHIPA    I73 @BASEBOARD_FAB2_LIB.BASEBOARD_FAB2(SCH_1):PAGE215
 R7A10    2      B RES_0402-16K,1.0%,1/16W,CHIP,GA    I73 @BASEBOARD_FAB2_LIB.BASEBOARD_FAB2(SCH_1):PAGE218
  R7A8    2      B RES_0402-2.26K,1.0%,1/16W,CHIPA    I74 @BASEBOARD_FAB2_LIB.BASEBOARD_FAB2(SCH_1):PAGE218
 R1G23    2      B RES_0402-5.36K,1.0%,1/16W,CHIPA    I73 @BASEBOARD_FAB2_LIB.BASEBOARD_FAB2(SCH_1):PAGE223
 R1G22    2      B RES_0402-3.16K,1%,1/16W,CHIP,GA    I74 @BASEBOARD_FAB2_LIB.BASEBOARD_FAB2(SCH_1):PAGE223
  R2L9    2      B RES_0402-4.02K,1%,1/16W,CHIP,GA   I254 @BASEBOARD_FAB2_LIB.BASEBOARD_FAB2(SCH_1):PAGE235
R25W58    2      2 18KR2F-GP_RCL_GP-18KR2F-GP,64.A   I150 @BASEBOARD_FAB2_LIB.BASEBOARD_FAB2(SCH_1):PAGE144
 R25W1    1      1 120R2F-GP_RCL_GP-120R2F-GP,64.A   I248 @BASEBOARD_FAB2_LIB.BASEBOARD_FAB2(SCH_1):PAGE151
 R25W2    1      1 120R2F-GP_RCL_GP-120R2F-GP,64.A   I249 @BASEBOARD_FAB2_LIB.BASEBOARD_FAB2(SCH_1):PAGE151
 R25W3    1      1 120R2F-GP_RCL_GP-120R2F-GP,64.A   I250 @BASEBOARD_FAB2_LIB.BASEBOARD_FAB2(SCH_1):PAGE151
 R25W4    1      1 120R2F-GP_RCL_GP-120R2F-GP,64.A   I251 @BASEBOARD_FAB2_LIB.BASEBOARD_FAB2(SCH_1):PAGE151
 R25W5    1      1 120R2F-GP_RCL_GP-120R2F-GP,64.A   I252 @BASEBOARD_FAB2_LIB.BASEBOARD_FAB2(SCH_1):PAGE151
 R25W6    1      1 120R2F-GP_RCL_GP-120R2F-GP,64.A   I253 @BASEBOARD_FAB2_LIB.BASEBOARD_FAB2(SCH_1):PAGE151
 R25W7    1      1 120R2F-GP_RCL_GP-120R2F-GP,64.A   I254 @BASEBOARD_FAB2_LIB.BASEBOARD_FAB2(SCH_1):PAGE151
 R25W8    1      1 120R2F-GP_RCL_GP-120R2F-GP,64.A   I255 @BASEBOARD_FAB2_LIB.BASEBOARD_FAB2(SCH_1):PAGE151
R25W12    1      1 120R2F-GP_RCL_GP-120R2F-GP,64.A   I256 @BASEBOARD_FAB2_LIB.BASEBOARD_FAB2(SCH_1):PAGE151
R25W11    1      1 120R2F-GP_RCL_GP-120R2F-GP,64.A   I257 @BASEBOARD_FAB2_LIB.BASEBOARD_FAB2(SCH_1):PAGE151
 R25W9    1      1 120R2F-GP_RCL_GP-120R2F-GP,64.A   I258 @BASEBOARD_FAB2_LIB.BASEBOARD_FAB2(SCH_1):PAGE151
R25W10    1      1 120R2F-GP_RCL_GP-120R2F-GP,64.A   I259 @BASEBOARD_FAB2_LIB.BASEBOARD_FAB2(SCH_1):PAGE151
R25W13    1      1 120R2F-GP_RCL_GP-120R2F-GP,64.A   I260 @BASEBOARD_FAB2_LIB.BASEBOARD_FAB2(SCH_1):PAGE151
R25W16    1      1 120R2F-GP_RCL_GP-120R2F-GP,64.A   I261 @BASEBOARD_FAB2_LIB.BASEBOARD_FAB2(SCH_1):PAGE151
R25W15    1      1 120R2F-GP_RCL_GP-120R2F-GP,64.A   I262 @BASEBOARD_FAB2_LIB.BASEBOARD_FAB2(SCH_1):PAGE151
R25W14    1      1 120R2F-GP_RCL_GP-120R2F-GP,64.A   I263 @BASEBOARD_FAB2_LIB.BASEBOARD_FAB2(SCH_1):PAGE151
R25W17    1      1 120R2F-GP_RCL_GP-120R2F-GP,64.A   I264 @BASEBOARD_FAB2_LIB.BASEBOARD_FAB2(SCH_1):PAGE151
R25W18    1      1 120R2F-GP_RCL_GP-120R2F-GP,64.A   I265 @BASEBOARD_FAB2_LIB.BASEBOARD_FAB2(SCH_1):PAGE151
R25W20    1      1 120R2F-GP_RCL_GP-120R2F-GP,64.A   I266 @BASEBOARD_FAB2_LIB.BASEBOARD_FAB2(SCH_1):PAGE151
R25W19    1      1 120R2F-GP_RCL_GP-120R2F-GP,64.A   I267 @BASEBOARD_FAB2_LIB.BASEBOARD_FAB2(SCH_1):PAGE151
R25W24    1      1 120R2F-GP_RCL_GP-120R2F-GP,64.A   I268 @BASEBOARD_FAB2_LIB.BASEBOARD_FAB2(SCH_1):PAGE151
R25W23    1      1 120R2F-GP_RCL_GP-120R2F-GP,64.A   I269 @BASEBOARD_FAB2_LIB.BASEBOARD_FAB2(SCH_1):PAGE151
R25W22    1      1 120R2F-GP_RCL_GP-120R2F-GP,64.A   I270 @BASEBOARD_FAB2_LIB.BASEBOARD_FAB2(SCH_1):PAGE151
R25W21    1      1 120R2F-GP_RCL_GP-120R2F-GP,64.A   I271 @BASEBOARD_FAB2_LIB.BASEBOARD_FAB2(SCH_1):PAGE151
R25W26    1      1 120R2F-GP_RCL_GP-120R2F-GP,64.A   I274 @BASEBOARD_FAB2_LIB.BASEBOARD_FAB2(SCH_1):PAGE151
R25W25    1      1 120R2F-GP_RCL_GP-120R2F-GP,64.A   I275 @BASEBOARD_FAB2_LIB.BASEBOARD_FAB2(SCH_1):PAGE151
  R9B7    2      2 887R2F-L-GP_SMD-RG-887R2F-L-GPA   I358 @BASEBOARD_FAB2_LIB.BASEBOARD_FAB2(SCH_1):PAGE186
  R2R8    2      2 887R2F-L-GP_SMD-RG-887R2F-L-GPA   I175 @BASEBOARD_FAB2_LIB.BASEBOARD_FAB2(SCH_1):PAGE187
   RT2    2      2 1R3F-GP_RCL_GP-1R3F-GP,64.1R00A   I114 @BASEBOARD_FAB2_LIB.BASEBOARD_FAB2(SCH_1):PAGE202
   RT4    2      2 1R3F-GP_RCL_GP-1R3F-GP,64.1R00A   I115 @BASEBOARD_FAB2_LIB.BASEBOARD_FAB2(SCH_1):PAGE202
  RT26    2      2 1R3F-GP_RCL_GP-1R3F-GP,64.1R00A   I134 @BASEBOARD_FAB2_LIB.BASEBOARD_FAB2(SCH_1):PAGE203
  RT27    2      2 1R3F-GP_RCL_GP-1R3F-GP,64.1R00A   I135 @BASEBOARD_FAB2_LIB.BASEBOARD_FAB2(SCH_1):PAGE203
  RT39    2      2 1R3F-GP_RCL_GP-1R3F-GP,64.1R00A    I84 @BASEBOARD_FAB2_LIB.BASEBOARD_FAB2(SCH_1):PAGE205
  RT16    2      2 1R3F-GP_RCL_GP-1R3F-GP,64.1R00A   I111 @BASEBOARD_FAB2_LIB.BASEBOARD_FAB2(SCH_1):PAGE207
  RT18    2      2 1R3F-GP_RCL_GP-1R3F-GP,64.1R00A   I112 @BASEBOARD_FAB2_LIB.BASEBOARD_FAB2(SCH_1):PAGE207
  RT24    2      2 1R3F-GP_RCL_GP-1R3F-GP,64.1R00A   I114 @BASEBOARD_FAB2_LIB.BASEBOARD_FAB2(SCH_1):PAGE204
  RT12    2      2 1R3F-GP_RCL_GP-1R3F-GP,64.1R00A   I120 @BASEBOARD_FAB2_LIB.BASEBOARD_FAB2(SCH_1):PAGE208
  RT13    2      2 1R3F-GP_RCL_GP-1R3F-GP,64.1R00A   I121 @BASEBOARD_FAB2_LIB.BASEBOARD_FAB2(SCH_1):PAGE208
  RT10    2      2 1R3F-GP_RCL_GP-1R3F-GP,64.1R00A    I90 @BASEBOARD_FAB2_LIB.BASEBOARD_FAB2(SCH_1):PAGE209
  RT38    2      2 1R3F-GP_RCL_GP-1R3F-GP,64.1R00A    I74 @BASEBOARD_FAB2_LIB.BASEBOARD_FAB2(SCH_1):PAGE210
  RT48    2      2 1R3F-GP_RCL_GP-1R3F-GP,64.1R00A   I144 @BASEBOARD_FAB2_LIB.BASEBOARD_FAB2(SCH_1):PAGE212
  RT42    2      2 1R3F-GP_RCL_GP-1R3F-GP,64.1R00A   I176 @BASEBOARD_FAB2_LIB.BASEBOARD_FAB2(SCH_1):PAGE214
  RT34    2      2 1R3F-GP_RCL_GP-1R3F-GP,64.1R00A   I151 @BASEBOARD_FAB2_LIB.BASEBOARD_FAB2(SCH_1):PAGE216
  RT35    2      2 1R3F-GP_RCL_GP-1R3F-GP,64.1R00A   I152 @BASEBOARD_FAB2_LIB.BASEBOARD_FAB2(SCH_1):PAGE216
  RT29    2      2 1R3F-GP_RCL_GP-1R3F-GP,64.1R00A   I153 @BASEBOARD_FAB2_LIB.BASEBOARD_FAB2(SCH_1):PAGE219
  RT32    2      2 1R3F-GP_RCL_GP-1R3F-GP,64.1R00A   I154 @BASEBOARD_FAB2_LIB.BASEBOARD_FAB2(SCH_1):PAGE219
  RT20    2      2 1R3F-GP_RCL_GP-1R3F-GP,64.1R00A   I156 @BASEBOARD_FAB2_LIB.BASEBOARD_FAB2(SCH_1):PAGE224
  RT22    2      2 1R3F-GP_RCL_GP-1R3F-GP,64.1R00A   I157 @BASEBOARD_FAB2_LIB.BASEBOARD_FAB2(SCH_1):PAGE224
  RT43    2      2 1R3F-GP_RCL_GP-1R3F-GP,64.1R00A   I182 @BASEBOARD_FAB2_LIB.BASEBOARD_FAB2(SCH_1):PAGE236
  RT45    2      2 1R3F-GP_RCL_GP-1R3F-GP,64.1R00A   I183 @BASEBOARD_FAB2_LIB.BASEBOARD_FAB2(SCH_1):PAGE236
   RT6    2      2 1R3F-GP_RCL_GP-1R3F-GP,64.1R00A   I149 @BASEBOARD_FAB2_LIB.BASEBOARD_FAB2(SCH_1):PAGE227
   RT7    2      2 1R3F-GP_RCL_GP-1R3F-GP,64.1R00A   I150 @BASEBOARD_FAB2_LIB.BASEBOARD_FAB2(SCH_1):PAGE227
 R1B15    2      B RES_0402-3.16K,1%,1/16W,CHIP,GA    I73 @BASEBOARD_FAB2_LIB.BASEBOARD_FAB2(SCH_1):PAGE226
  R6W9    2      B RES_0402-4.75K,1%,1/16W,EMPTY,A   I162 @BASEBOARD_FAB2_LIB.BASEBOARD_FAB2(SCH_1):PAGE247
  R6W8    2      B RES_0402-4.75K,1%,1/16W,EMPTY,A   I163 @BASEBOARD_FAB2_LIB.BASEBOARD_FAB2(SCH_1):PAGE247
  R6W7    2      B RES_0402-4.75K,1%,1/16W,EMPTY,A   I164 @BASEBOARD_FAB2_LIB.BASEBOARD_FAB2(SCH_1):PAGE247
  J1B2    1    IO1 CONN6_C74770005_PIP-HDR,C74770A    I25 @BASEBOARD_FAB2_LIB.BASEBOARD_FAB2(SCH_1):PAGE251
 C10W5    2      B CAP_A_0402V-0.01UF,25V,10%,X7RA    I29 @BASEBOARD_FAB2_LIB.BASEBOARD_FAB2(SCH_1):PAGE251
 C8F19    2      B CAP_0402LF-15.0PF,50V,5%,COG,AA   I146 @BASEBOARD_FAB2_LIB.BASEBOARD_FAB2(SCH_1):PAGE101
 C8F18    2      B CAP_0402LF-15.0PF,50V,5%,COG,AA   I147 @BASEBOARD_FAB2_LIB.BASEBOARD_FAB2(SCH_1):PAGE101
  J1F2    1      1 LOTES-CON4-S1-GP_CONN-G7-LOTESA   I139 @BASEBOARD_FAB2_LIB.BASEBOARD_FAB2(SCH_1):PAGE161
 J10W1    1      1 LOTES-CON4-S1-GP_CONN-G7-LOTESA   I140 @BASEBOARD_FAB2_LIB.BASEBOARD_FAB2(SCH_1):PAGE161
  C8W4    2      B CAP_0805-100UF,4V,20%,X5R,6024A   I245 @BASEBOARD_FAB2_LIB.BASEBOARD_FAB2(SCH_1):PAGE76
  C5U1    2      B CAP_0805-100UF,4V,20%,X5R,6024A   I316 @BASEBOARD_FAB2_LIB.BASEBOARD_FAB2(SCH_1):PAGE217
 C5U10    2      B CAP_0805-100UF,4V,20%,X5R,6024A   I317 @BASEBOARD_FAB2_LIB.BASEBOARD_FAB2(SCH_1):PAGE217
  C5G9    2      B CAP_0805-100UF,4V,20%,X5R,6024A   I318 @BASEBOARD_FAB2_LIB.BASEBOARD_FAB2(SCH_1):PAGE217
  C4T4    2      B CAP_0805-100UF,4V,20%,X5R,6024A   I319 @BASEBOARD_FAB2_LIB.BASEBOARD_FAB2(SCH_1):PAGE217
 C5U15    2      B CAP_0805-100UF,4V,20%,X5R,6024A   I320 @BASEBOARD_FAB2_LIB.BASEBOARD_FAB2(SCH_1):PAGE217
 C5U13    2      B CAP_0805-100UF,4V,20%,X5R,6024A   I321 @BASEBOARD_FAB2_LIB.BASEBOARD_FAB2(SCH_1):PAGE217
 C5U14    2      B CAP_0805-100UF,4V,20%,X5R,6024A   I322 @BASEBOARD_FAB2_LIB.BASEBOARD_FAB2(SCH_1):PAGE217
 C5P41    2      B CAP_0805-100UF,4V,20%,X5R,6024A   I323 @BASEBOARD_FAB2_LIB.BASEBOARD_FAB2(SCH_1):PAGE217
 C5P44    2      B CAP_0805-100UF,4V,20%,X5R,6024A   I324 @BASEBOARD_FAB2_LIB.BASEBOARD_FAB2(SCH_1):PAGE217
 C5P42    2      B CAP_0805-100UF,4V,20%,X5R,6024A   I325 @BASEBOARD_FAB2_LIB.BASEBOARD_FAB2(SCH_1):PAGE217
 C5P43    2      B CAP_0805-100UF,4V,20%,X5R,6024A   I326 @BASEBOARD_FAB2_LIB.BASEBOARD_FAB2(SCH_1):PAGE217
 C5P38    2      B CAP_0805-100UF,4V,20%,X5R,6024A   I327 @BASEBOARD_FAB2_LIB.BASEBOARD_FAB2(SCH_1):PAGE217
 C5P39    2      B CAP_0805-100UF,4V,20%,X5R,6024A   I328 @BASEBOARD_FAB2_LIB.BASEBOARD_FAB2(SCH_1):PAGE217
 C5G20    2      B CAP_0805-100UF,4V,20%,X5R,6024A   I329 @BASEBOARD_FAB2_LIB.BASEBOARD_FAB2(SCH_1):PAGE217
 C5A20    2      B CAP_0805-100UF,4V,20%,X5R,6024A   I308 @BASEBOARD_FAB2_LIB.BASEBOARD_FAB2(SCH_1):PAGE220
  C5L1    2      B CAP_0805-100UF,4V,20%,X5R,6024A   I309 @BASEBOARD_FAB2_LIB.BASEBOARD_FAB2(SCH_1):PAGE220
  C5L3    2      B CAP_0805-100UF,4V,20%,X5R,6024A   I310 @BASEBOARD_FAB2_LIB.BASEBOARD_FAB2(SCH_1):PAGE220
  C5L2    2      B CAP_0805-100UF,4V,20%,X5R,6024A   I311 @BASEBOARD_FAB2_LIB.BASEBOARD_FAB2(SCH_1):PAGE220
 C5M12    2      B CAP_0805-100UF,4V,20%,X5R,6024A   I312 @BASEBOARD_FAB2_LIB.BASEBOARD_FAB2(SCH_1):PAGE220
 C5L14    2      B CAP_0805-100UF,4V,20%,X5R,6024A   I313 @BASEBOARD_FAB2_LIB.BASEBOARD_FAB2(SCH_1):PAGE220
  C5M8    2      B CAP_0805-100UF,4V,20%,X5R,6024A   I314 @BASEBOARD_FAB2_LIB.BASEBOARD_FAB2(SCH_1):PAGE220
  C5P3    2      B CAP_0805-100UF,4V,20%,X5R,6024A   I315 @BASEBOARD_FAB2_LIB.BASEBOARD_FAB2(SCH_1):PAGE220
  C5P6    2      B CAP_0805-100UF,4V,20%,X5R,6024A   I316 @BASEBOARD_FAB2_LIB.BASEBOARD_FAB2(SCH_1):PAGE220
  C5P5    2      B CAP_0805-100UF,4V,20%,X5R,6024A   I317 @BASEBOARD_FAB2_LIB.BASEBOARD_FAB2(SCH_1):PAGE220
  C5P4    2      B CAP_0805-100UF,4V,20%,X5R,6024A   I318 @BASEBOARD_FAB2_LIB.BASEBOARD_FAB2(SCH_1):PAGE220
  C5P2    2      B CAP_0805-100UF,4V,20%,X5R,6024A   I319 @BASEBOARD_FAB2_LIB.BASEBOARD_FAB2(SCH_1):PAGE220
  C5P1    2      B CAP_0805-100UF,4V,20%,X5R,6024A   I320 @BASEBOARD_FAB2_LIB.BASEBOARD_FAB2(SCH_1):PAGE220
 C5A10    2      B CAP_0805-100UF,4V,20%,X5R,6024A   I321 @BASEBOARD_FAB2_LIB.BASEBOARD_FAB2(SCH_1):PAGE220
 C6W11    2      B CAP_0805-100UF,4V,20%,X5R,6024A    I44 @BASEBOARD_FAB2_LIB.BASEBOARD_FAB2(SCH_1):PAGE221
 C5U12    2      B CAP_0805-100UF,4V,20%,X5R,6024A    I45 @BASEBOARD_FAB2_LIB.BASEBOARD_FAB2(SCH_1):PAGE221
 C5U16    2      B CAP_0805-100UF,4V,20%,X5R,6024A    I46 @BASEBOARD_FAB2_LIB.BASEBOARD_FAB2(SCH_1):PAGE221
  C5L5    2      B CAP_0805-100UF,4V,20%,X5R,6024A    I44 @BASEBOARD_FAB2_LIB.BASEBOARD_FAB2(SCH_1):PAGE222
  C5L4    2      B CAP_0805-100UF,4V,20%,X5R,6024A    I45 @BASEBOARD_FAB2_LIB.BASEBOARD_FAB2(SCH_1):PAGE222
  C4W5    2      B CAP_0805-100UF,4V,20%,X5R,6024A    I46 @BASEBOARD_FAB2_LIB.BASEBOARD_FAB2(SCH_1):PAGE222
 C8U11    2      B CAP_0805-100UF,4V,20%,X5R,6024A   I307 @BASEBOARD_FAB2_LIB.BASEBOARD_FAB2(SCH_1):PAGE225
  C7U7    2      B CAP_0805-100UF,4V,20%,X5R,6024A   I308 @BASEBOARD_FAB2_LIB.BASEBOARD_FAB2(SCH_1):PAGE225
  C7T1    2      B CAP_0805-100UF,4V,20%,X5R,6024A   I309 @BASEBOARD_FAB2_LIB.BASEBOARD_FAB2(SCH_1):PAGE225
 C8U12    2      B CAP_0805-100UF,4V,20%,X5R,6024A   I310 @BASEBOARD_FAB2_LIB.BASEBOARD_FAB2(SCH_1):PAGE225
 C2G16    2      B CAP_0805-100UF,4V,20%,X5R,6024A   I311 @BASEBOARD_FAB2_LIB.BASEBOARD_FAB2(SCH_1):PAGE225
  C2G7    2      B CAP_0805-100UF,4V,20%,X5R,6024A   I312 @BASEBOARD_FAB2_LIB.BASEBOARD_FAB2(SCH_1):PAGE225
 C8P30    2      B CAP_0805-100UF,4V,20%,X5R,6024A   I313 @BASEBOARD_FAB2_LIB.BASEBOARD_FAB2(SCH_1):PAGE225
 C8P31    2      B CAP_0805-100UF,4V,20%,X5R,6024A   I314 @BASEBOARD_FAB2_LIB.BASEBOARD_FAB2(SCH_1):PAGE225
 C8P34    2      B CAP_0805-100UF,4V,20%,X5R,6024A   I315 @BASEBOARD_FAB2_LIB.BASEBOARD_FAB2(SCH_1):PAGE225
 C8P33    2      B CAP_0805-100UF,4V,20%,X5R,6024A   I316 @BASEBOARD_FAB2_LIB.BASEBOARD_FAB2(SCH_1):PAGE225
 C8P32    2      B CAP_0805-100UF,4V,20%,X5R,6024A   I317 @BASEBOARD_FAB2_LIB.BASEBOARD_FAB2(SCH_1):PAGE225
 C7P20    2      B CAP_0805-100UF,4V,20%,X5R,6024A   I318 @BASEBOARD_FAB2_LIB.BASEBOARD_FAB2(SCH_1):PAGE225
  C8U1    2      B CAP_0805-100UF,4V,20%,X5R,6024A   I319 @BASEBOARD_FAB2_LIB.BASEBOARD_FAB2(SCH_1):PAGE225
  C8U8    2      B CAP_0805-100UF,4V,20%,X5R,6024A   I320 @BASEBOARD_FAB2_LIB.BASEBOARD_FAB2(SCH_1):PAGE225
  C8L1    2      B CAP_0805-100UF,4V,20%,X5R,6024A   I301 @BASEBOARD_FAB2_LIB.BASEBOARD_FAB2(SCH_1):PAGE228
 C8L11    2      B CAP_0805-100UF,4V,20%,X5R,6024A   I302 @BASEBOARD_FAB2_LIB.BASEBOARD_FAB2(SCH_1):PAGE228
  C8P2    2      B CAP_0805-100UF,4V,20%,X5R,6024A   I303 @BASEBOARD_FAB2_LIB.BASEBOARD_FAB2(SCH_1):PAGE228
  C8P1    2      B CAP_0805-100UF,4V,20%,X5R,6024A   I304 @BASEBOARD_FAB2_LIB.BASEBOARD_FAB2(SCH_1):PAGE228
  C7P2    2      B CAP_0805-100UF,4V,20%,X5R,6024A   I305 @BASEBOARD_FAB2_LIB.BASEBOARD_FAB2(SCH_1):PAGE228
  C8P3    2      B CAP_0805-100UF,4V,20%,X5R,6024A   I306 @BASEBOARD_FAB2_LIB.BASEBOARD_FAB2(SCH_1):PAGE228
  C8P4    2      B CAP_0805-100UF,4V,20%,X5R,6024A   I307 @BASEBOARD_FAB2_LIB.BASEBOARD_FAB2(SCH_1):PAGE228
  C7P1    2      B CAP_0805-100UF,4V,20%,X5R,6024A   I308 @BASEBOARD_FAB2_LIB.BASEBOARD_FAB2(SCH_1):PAGE228
  C2A8    2      B CAP_0805-100UF,4V,20%,X5R,6024A   I309 @BASEBOARD_FAB2_LIB.BASEBOARD_FAB2(SCH_1):PAGE228
  C8L2    2      B CAP_0805-100UF,4V,20%,X5R,6024A   I310 @BASEBOARD_FAB2_LIB.BASEBOARD_FAB2(SCH_1):PAGE228
 C8M11    2      B CAP_0805-100UF,4V,20%,X5R,6024A   I311 @BASEBOARD_FAB2_LIB.BASEBOARD_FAB2(SCH_1):PAGE228
  C8M7    2      B CAP_0805-100UF,4V,20%,X5R,6024A   I312 @BASEBOARD_FAB2_LIB.BASEBOARD_FAB2(SCH_1):PAGE228
 C2A16    2      B CAP_0805-100UF,4V,20%,X5R,6024A   I313 @BASEBOARD_FAB2_LIB.BASEBOARD_FAB2(SCH_1):PAGE228
  C7L1    2      B CAP_0805-100UF,4V,20%,X5R,6024A   I314 @BASEBOARD_FAB2_LIB.BASEBOARD_FAB2(SCH_1):PAGE228
  C8T3    2      B CAP_0805-100UF,4V,20%,X5R,6024A    I41 @BASEBOARD_FAB2_LIB.BASEBOARD_FAB2(SCH_1):PAGE229
 C8U10    2      B CAP_0805-100UF,4V,20%,X5R,6024A    I42 @BASEBOARD_FAB2_LIB.BASEBOARD_FAB2(SCH_1):PAGE229
 C6W12    2      B CAP_0805-100UF,4V,20%,X5R,6024A    I43 @BASEBOARD_FAB2_LIB.BASEBOARD_FAB2(SCH_1):PAGE229
  C8L3    2      B CAP_0805-100UF,4V,20%,X5R,6024A    I41 @BASEBOARD_FAB2_LIB.BASEBOARD_FAB2(SCH_1):PAGE230
  C8L4    2      B CAP_0805-100UF,4V,20%,X5R,6024A    I42 @BASEBOARD_FAB2_LIB.BASEBOARD_FAB2(SCH_1):PAGE230
 C6W13    2      B CAP_0805-100UF,4V,20%,X5R,6024A    I43 @BASEBOARD_FAB2_LIB.BASEBOARD_FAB2(SCH_1):PAGE230
 C7C13    2      B CAP_0402LF-15.0PF,50V,5%,COG,AA   I195 @BASEBOARD_FAB2_LIB.BASEBOARD_FAB2(SCH_1):PAGE114
 C7C15    2      B CAP_0402LF-15.0PF,50V,5%,COG,AA   I196 @BASEBOARD_FAB2_LIB.BASEBOARD_FAB2(SCH_1):PAGE114
 C3N26    2      B CAPP_3018-470UF,2.5V,20%,ALUM,A   I145 @BASEBOARD_FAB2_LIB.BASEBOARD_FAB2(SCH_1):PAGE212
 C3N38    2      B CAPP_3018-470UF,2.5V,20%,ALUM,A   I146 @BASEBOARD_FAB2_LIB.BASEBOARD_FAB2(SCH_1):PAGE212
 C6R12    2      B CAPP_3018-470UF,2.5V,20%,ALUM,A   I177 @BASEBOARD_FAB2_LIB.BASEBOARD_FAB2(SCH_1):PAGE214
  C4E7    2      B CAPP_3018-470UF,2.5V,20%,ALUM,A   I178 @BASEBOARD_FAB2_LIB.BASEBOARD_FAB2(SCH_1):PAGE214
  C5P8    2      B CAP_0805LF-22UF,4V,20%,X6S,C95A   I214 @BASEBOARD_FAB2_LIB.BASEBOARD_FAB2(SCH_1):PAGE42
  C5P9    2      B CAP_0805LF-22UF,4V,20%,X6S,C95A   I215 @BASEBOARD_FAB2_LIB.BASEBOARD_FAB2(SCH_1):PAGE42
  C8P5    2      B CAP_0805LF-22UF,4V,20%,X6S,C95A   I246 @BASEBOARD_FAB2_LIB.BASEBOARD_FAB2(SCH_1):PAGE76
  C8P6    2      B CAP_0805LF-22UF,4V,20%,X6S,C95A   I247 @BASEBOARD_FAB2_LIB.BASEBOARD_FAB2(SCH_1):PAGE76
  C8P7    2      B CAP_0805LF-22UF,4V,20%,X6S,C95A   I248 @BASEBOARD_FAB2_LIB.BASEBOARD_FAB2(SCH_1):PAGE76
 C8P21    2      B CAP_0805-47UF,4V,20%,X6S,C9533A   I249 @BASEBOARD_FAB2_LIB.BASEBOARD_FAB2(SCH_1):PAGE76
 C8P27    2      B CAP_0805-47UF,4V,20%,X6S,C9533A   I250 @BASEBOARD_FAB2_LIB.BASEBOARD_FAB2(SCH_1):PAGE76
 C8P25    2      B CAP_0805-47UF,4V,20%,X6S,C9533A   I251 @BASEBOARD_FAB2_LIB.BASEBOARD_FAB2(SCH_1):PAGE76
 C8P17    2      B CAP_0805-47UF,4V,20%,X6S,C9533A   I252 @BASEBOARD_FAB2_LIB.BASEBOARD_FAB2(SCH_1):PAGE76
R25W157    2      B RES_0402-100.0K,1%,1/16W,CHIP,A   I164 @BASEBOARD_FAB2_LIB.BASEBOARD_FAB2(SCH_1):PAGE147
 C32W1    2      B CAP_A_0402V-0.1UF,16V,10%,X7R,A   I188 @BASEBOARD_FAB2_LIB.BASEBOARD_FAB2(SCH_1):PAGE185
 C32W3    2      B CAP_A_0402V-0.1UF,16V,10%,X7R,A   I190 @BASEBOARD_FAB2_LIB.BASEBOARD_FAB2(SCH_1):PAGE185
 U32W1    4    GND TCA9517DGKR-GP_DISCRET-G8-TCA9A   I191 @BASEBOARD_FAB2_LIB.BASEBOARD_FAB2(SCH_1):PAGE185
 C32W2    2      B CAP_A_0402V-0.1UF,16V,10%,X7R,A   I193 @BASEBOARD_FAB2_LIB.BASEBOARD_FAB2(SCH_1):PAGE185
 C32W4    2      B CAP_A_0402V-0.1UF,16V,10%,X7R,A   I196 @BASEBOARD_FAB2_LIB.BASEBOARD_FAB2(SCH_1):PAGE185
 R32W9    2      B RES_0402-10.0K,1%,1/16W,CHIP,GA   I200 @BASEBOARD_FAB2_LIB.BASEBOARD_FAB2(SCH_1):PAGE185
 U32W2    4    GND TCA9517DGKR-GP_DISCRET-G8-TCA9A   I204 @BASEBOARD_FAB2_LIB.BASEBOARD_FAB2(SCH_1):PAGE185
 R32W3    2      B RES_0402-3.3K,5%,1/16W,CHIP,G2A   I206 @BASEBOARD_FAB2_LIB.BASEBOARD_FAB2(SCH_1):PAGE185
 R32W4    2      B RES_0402-49.9K,1%,1/16W,CHIP,GA   I211 @BASEBOARD_FAB2_LIB.BASEBOARD_FAB2(SCH_1):PAGE185
VR32W1    3  ANODE LMV431AIMFX-GP_DISCRET-G5-LMV4A   I213 @BASEBOARD_FAB2_LIB.BASEBOARD_FAB2(SCH_1):PAGE185
  C9E9    2      B CAP_0402LF-15.0PF,50V,5%,COG,AA   I249 @BASEBOARD_FAB2_LIB.BASEBOARD_FAB2(SCH_1):PAGE139
  C9E8    2      B CAP_0402LF-15.0PF,50V,5%,COG,AA   I250 @BASEBOARD_FAB2_LIB.BASEBOARD_FAB2(SCH_1):PAGE139
 C32W5    2      B CAP_0402-1.0UF,16V,10%,X6S,D97A   I217 @BASEBOARD_FAB2_LIB.BASEBOARD_FAB2(SCH_1):PAGE185
  Q9W3    2      E NPN_SM-MMBT3904,IC,C52245-001    I49 @BASEBOARD_FAB2_LIB.BASEBOARD_FAB2(SCH_1):PAGE249
 C4D20    2      B CAP_A_0402V-0.1UF,16V,10%,X7R,A   I192 @BASEBOARD_FAB2_LIB.BASEBOARD_FAB2(SCH_1):PAGE201
  C1C8    2      B CAP_A_0402V-0.1UF,16V,10%,X7R,A   I156 @BASEBOARD_FAB2_LIB.BASEBOARD_FAB2(SCH_1):PAGE206
  C3P2    2      B CAP_A_0402V-0.1UF,16V,10%,X7R,A   I103 @BASEBOARD_FAB2_LIB.BASEBOARD_FAB2(SCH_1):PAGE211
 C4D40    2      B CAP_A_0402V-0.1UF,16V,10%,X7R,A   I105 @BASEBOARD_FAB2_LIB.BASEBOARD_FAB2(SCH_1):PAGE213
  C8A3    2      B CAP_A_0402V-0.1UF,16V,10%,X7R,A   I255 @BASEBOARD_FAB2_LIB.BASEBOARD_FAB2(SCH_1):PAGE235
  R3W2    2      B RES_0402-100.0K,1%,1/16W,CHIP,A    I56 @BASEBOARD_FAB2_LIB.BASEBOARD_FAB2(SCH_1):PAGE249
  C3W2    2      B CAP_A_0402V-0.1UF,16V,10%,X7R,A    I57 @BASEBOARD_FAB2_LIB.BASEBOARD_FAB2(SCH_1):PAGE249
  C5W1    2      B CAP_A_0603V-22.0UF,4V,20%,X6S,A   I217 @BASEBOARD_FAB2_LIB.BASEBOARD_FAB2(SCH_1):PAGE42
  C5W2    2      B CAP_A_0603V-22.0UF,4V,20%,X6S,A   I218 @BASEBOARD_FAB2_LIB.BASEBOARD_FAB2(SCH_1):PAGE42
  C3W4    2      B CAP_A_0603V-22.0UF,4V,20%,X6S,A   I254 @BASEBOARD_FAB2_LIB.BASEBOARD_FAB2(SCH_1):PAGE76
  C3W3    2      B CAP_A_0603V-22.0UF,4V,20%,X6S,A   I256 @BASEBOARD_FAB2_LIB.BASEBOARD_FAB2(SCH_1):PAGE76
 C6W14    2      B CAP_A_0402V-0.1UF,16V,10%,X7R,A    I66 @BASEBOARD_FAB2_LIB.BASEBOARD_FAB2(SCH_1):PAGE164
 R6W47    2      B RES_0402-4.75K,1%,1/16W,EMPTY,A    I76 @BASEBOARD_FAB2_LIB.BASEBOARD_FAB2(SCH_1):PAGE164
R25W167    2      B RES_0402-1.00K,1%,1/16W,CHIP,GA    I10 @BASEBOARD_FAB2_LIB.BASEBOARD_FAB2(SCH_1):PAGE269
R25W168    2      B RES_0402-1.00K,1%,1/16W,CHIP,GA    I11 @BASEBOARD_FAB2_LIB.BASEBOARD_FAB2(SCH_1):PAGE269
R25W169    2      B RES_0402-1.00K,1%,1/16W,CHIP,GA    I12 @BASEBOARD_FAB2_LIB.BASEBOARD_FAB2(SCH_1):PAGE269
R25W170    2      B RES_0402-1.00K,1%,1/16W,CHIP,GA    I13 @BASEBOARD_FAB2_LIB.BASEBOARD_FAB2(SCH_1):PAGE269
R25W159    1      A RES_0402-1.00K,1%,1/16W,CHIP,GA    I24 @BASEBOARD_FAB2_LIB.BASEBOARD_FAB2(SCH_1):PAGE269
C25W91    2      B CAP_A_0402V-1.0UF,6.3V,10%,X6SA    I26 @BASEBOARD_FAB2_LIB.BASEBOARD_FAB2(SCH_1):PAGE269
C25W94    2      B CAP_0402-1.0UF,16V,10%,X6S,D97A    I32 @BASEBOARD_FAB2_LIB.BASEBOARD_FAB2(SCH_1):PAGE269
U25W10    7 GND<0> GTL2014_SM-IC,D66151-001    I49 @BASEBOARD_FAB2_LIB.BASEBOARD_FAB2(SCH_1):PAGE269
U25W10    8 GND<1> GTL2014_SM-IC,D66151-001    I49 @BASEBOARD_FAB2_LIB.BASEBOARD_FAB2(SCH_1):PAGE269
U25W10   11 GND<2> GTL2014_SM-IC,D66151-001    I49 @BASEBOARD_FAB2_LIB.BASEBOARD_FAB2(SCH_1):PAGE269
C25W97    2      B CAP_A_0402V-0.1UF,16V,10%,X7R,A     I4 @BASEBOARD_FAB2_LIB.BASEBOARD_FAB2(SCH_1):PAGE268
C25W96    2      B CAP_A_0402V-0.1UF,16V,10%,X7R,A     I9 @BASEBOARD_FAB2_LIB.BASEBOARD_FAB2(SCH_1):PAGE268
R25W176    2      B RES_0402-1.00K,1%,1/16W,CHIP,GA    I14 @BASEBOARD_FAB2_LIB.BASEBOARD_FAB2(SCH_1):PAGE268
R25W175    2      B RES_0402-1.00K,1%,1/16W,CHIP,GA    I17 @BASEBOARD_FAB2_LIB.BASEBOARD_FAB2(SCH_1):PAGE268
C25W92    2      B CAP_0402-1.0UF,16V,10%,X6S,D97A    I23 @BASEBOARD_FAB2_LIB.BASEBOARD_FAB2(SCH_1):PAGE268
R25W166    2      B RES_0402-1.00K,1%,1/16W,CHIP,GA    I26 @BASEBOARD_FAB2_LIB.BASEBOARD_FAB2(SCH_1):PAGE268
C25W93    2      B CAP_A_0402V-0.1UF,16V,10%,X7R,A    I27 @BASEBOARD_FAB2_LIB.BASEBOARD_FAB2(SCH_1):PAGE268
R25W165    2      B RES_0402-100.0,1%,1/16W,CHIP,GA    I28 @BASEBOARD_FAB2_LIB.BASEBOARD_FAB2(SCH_1):PAGE268
U25W11    7 GND<0> GTL2014_SM-IC,D66151-001    I33 @BASEBOARD_FAB2_LIB.BASEBOARD_FAB2(SCH_1):PAGE268
U25W11    8 GND<1> GTL2014_SM-IC,D66151-001    I33 @BASEBOARD_FAB2_LIB.BASEBOARD_FAB2(SCH_1):PAGE268
U25W11   11 GND<2> GTL2014_SM-IC,D66151-001    I33 @BASEBOARD_FAB2_LIB.BASEBOARD_FAB2(SCH_1):PAGE268
U25W13    5    GND MAX4564EKA-GP_SCRET-GC1-MAX456A    I53 @BASEBOARD_FAB2_LIB.BASEBOARD_FAB2(SCH_1):PAGE269
U25W13    6     V- MAX4564EKA-GP_SCRET-GC1-MAX456A    I53 @BASEBOARD_FAB2_LIB.BASEBOARD_FAB2(SCH_1):PAGE269
C25W95    2      B CAP_A_0402V-0.1UF,16V,10%,X7R,A    I56 @BASEBOARD_FAB2_LIB.BASEBOARD_FAB2(SCH_1):PAGE269
 R6W46    2      B RES_0402-4.75K,1%,1/16W,CHIP,GA    I93 @BASEBOARD_FAB2_LIB.BASEBOARD_FAB2(SCH_1):PAGE164
 R6W45    2      B RES_0402-4.75K,1%,1/16W,CHIP,GA    I94 @BASEBOARD_FAB2_LIB.BASEBOARD_FAB2(SCH_1):PAGE164
C25W29    2      B CAP_0603LF-10UF,4V,20%,X6S,E15A   I129 @BASEBOARD_FAB2_LIB.BASEBOARD_FAB2(SCH_1):PAGE149
C25W57    2      B CAP_0402LF-100.0PF,50V,5%,COG,A   I130 @BASEBOARD_FAB2_LIB.BASEBOARD_FAB2(SCH_1):PAGE149
  Q6W2    2      E NPN_SM-MMBT3904,IC,C52245-001    I47 @BASEBOARD_FAB2_LIB.BASEBOARD_FAB2(SCH_1):PAGE168
 U6W11    8    GND PCA9554PWR-GP_DISCRET-G1-PCA95A    I97 @BASEBOARD_FAB2_LIB.BASEBOARD_FAB2(SCH_1):PAGE164
C1L119    2      B CAP_0402-1.0UF,16V,10%,X6S,D97A    I69 @BASEBOARD_FAB2_LIB.BASEBOARD_FAB2(SCH_1):PAGE189
 C4E29    2      B CAPP_3018-470UF,2.5V,20%,ALUM,A   I175 @BASEBOARD_FAB2_LIB.BASEBOARD_FAB2(SCH_1):PAGE193
 C5P29    2      B CAP_0805-100UF,4V,20%,X5R,6024A   I220 @BASEBOARD_FAB2_LIB.BASEBOARD_FAB2(SCH_1):PAGE42
 C5P30    2      B CAP_0805-100UF,4V,20%,X5R,6024A   I221 @BASEBOARD_FAB2_LIB.BASEBOARD_FAB2(SCH_1):PAGE42
 C5P19    2      B CAP_0805-100UF,4V,20%,X5R,6024A   I222 @BASEBOARD_FAB2_LIB.BASEBOARD_FAB2(SCH_1):PAGE42
  C4P4    2      B CAP_0805-100UF,4V,20%,X5R,6024A   I223 @BASEBOARD_FAB2_LIB.BASEBOARD_FAB2(SCH_1):PAGE42
  C4P7    2      B CAP_0805-100UF,4V,20%,X5R,6024A   I224 @BASEBOARD_FAB2_LIB.BASEBOARD_FAB2(SCH_1):PAGE42
  C4P3    2      B CAP_0805-100UF,4V,20%,X5R,6024A   I225 @BASEBOARD_FAB2_LIB.BASEBOARD_FAB2(SCH_1):PAGE42
 C5P10    2      B CAP_0805-100UF,4V,20%,X5R,6024A   I226 @BASEBOARD_FAB2_LIB.BASEBOARD_FAB2(SCH_1):PAGE42
 C5P11    2      B CAP_0805-100UF,4V,20%,X5R,6024A   I227 @BASEBOARD_FAB2_LIB.BASEBOARD_FAB2(SCH_1):PAGE42
 C5P18    2      B CAP_0805-100UF,4V,20%,X5R,6024A   I228 @BASEBOARD_FAB2_LIB.BASEBOARD_FAB2(SCH_1):PAGE42
 C5P28    2      B CAP_0805-100UF,4V,20%,X5R,6024A   I229 @BASEBOARD_FAB2_LIB.BASEBOARD_FAB2(SCH_1):PAGE42
  C4P2    2      B CAP_0805-100UF,4V,20%,X5R,6024A   I230 @BASEBOARD_FAB2_LIB.BASEBOARD_FAB2(SCH_1):PAGE42
 C5P31    2      B CAP_0805-100UF,4V,20%,X5R,6024A   I231 @BASEBOARD_FAB2_LIB.BASEBOARD_FAB2(SCH_1):PAGE42
 C5P13    2      B CAP_0805-100UF,4V,20%,X5R,6024A   I232 @BASEBOARD_FAB2_LIB.BASEBOARD_FAB2(SCH_1):PAGE42
  C4P5    2      B CAP_0805-100UF,4V,20%,X5R,6024A   I233 @BASEBOARD_FAB2_LIB.BASEBOARD_FAB2(SCH_1):PAGE42
 C5P20    2      B CAP_0805-100UF,4V,20%,X5R,6024A   I234 @BASEBOARD_FAB2_LIB.BASEBOARD_FAB2(SCH_1):PAGE42
 C5P21    2      B CAP_0805-100UF,4V,20%,X5R,6024A   I235 @BASEBOARD_FAB2_LIB.BASEBOARD_FAB2(SCH_1):PAGE42
 C5P12    2      B CAP_0805-100UF,4V,20%,X5R,6024A   I236 @BASEBOARD_FAB2_LIB.BASEBOARD_FAB2(SCH_1):PAGE42
  C7P9    2      B CAP_0805-100UF,4V,20%,X5R,6024A   I258 @BASEBOARD_FAB2_LIB.BASEBOARD_FAB2(SCH_1):PAGE76
  C7P5    2      B CAP_0805-100UF,4V,20%,X5R,6024A   I259 @BASEBOARD_FAB2_LIB.BASEBOARD_FAB2(SCH_1):PAGE76
 C8P23    2      B CAP_0805-100UF,4V,20%,X5R,6024A   I260 @BASEBOARD_FAB2_LIB.BASEBOARD_FAB2(SCH_1):PAGE76
 C7P14    2      B CAP_0805-100UF,4V,20%,X5R,6024A   I261 @BASEBOARD_FAB2_LIB.BASEBOARD_FAB2(SCH_1):PAGE76
 C7P11    2      B CAP_0805-100UF,4V,20%,X5R,6024A   I262 @BASEBOARD_FAB2_LIB.BASEBOARD_FAB2(SCH_1):PAGE76
 C7P15    2      B CAP_0805-100UF,4V,20%,X5R,6024A   I263 @BASEBOARD_FAB2_LIB.BASEBOARD_FAB2(SCH_1):PAGE76
 C8P22    2      B CAP_0805-100UF,4V,20%,X5R,6024A   I264 @BASEBOARD_FAB2_LIB.BASEBOARD_FAB2(SCH_1):PAGE76
  C7P8    2      B CAP_0805-100UF,4V,20%,X5R,6024A   I265 @BASEBOARD_FAB2_LIB.BASEBOARD_FAB2(SCH_1):PAGE76
 C7P10    2      B CAP_0805-100UF,4V,20%,X5R,6024A   I266 @BASEBOARD_FAB2_LIB.BASEBOARD_FAB2(SCH_1):PAGE76
  C7P7    2      B CAP_0805-100UF,4V,20%,X5R,6024A   I267 @BASEBOARD_FAB2_LIB.BASEBOARD_FAB2(SCH_1):PAGE76
  C7P6    2      B CAP_0805-100UF,4V,20%,X5R,6024A   I268 @BASEBOARD_FAB2_LIB.BASEBOARD_FAB2(SCH_1):PAGE76
 C7P13    2      B CAP_0805-100UF,4V,20%,X5R,6024A   I269 @BASEBOARD_FAB2_LIB.BASEBOARD_FAB2(SCH_1):PAGE76
 C8P15    2      B CAP_0805-100UF,4V,20%,X5R,6024A   I270 @BASEBOARD_FAB2_LIB.BASEBOARD_FAB2(SCH_1):PAGE76
  C7P4    2      B CAP_0805-100UF,4V,20%,X5R,6024A   I271 @BASEBOARD_FAB2_LIB.BASEBOARD_FAB2(SCH_1):PAGE76
 C8P14    2      B CAP_0805-100UF,4V,20%,X5R,6024A   I272 @BASEBOARD_FAB2_LIB.BASEBOARD_FAB2(SCH_1):PAGE76
  C8P9    2      B CAP_0805-100UF,4V,20%,X5R,6024A   I273 @BASEBOARD_FAB2_LIB.BASEBOARD_FAB2(SCH_1):PAGE76
  C8P8    2      B CAP_0805-100UF,4V,20%,X5R,6024A   I274 @BASEBOARD_FAB2_LIB.BASEBOARD_FAB2(SCH_1):PAGE76
C25W98    2      B CAP_0402-1.0UF,16V,10%,X6S,D97A    I40 @BASEBOARD_FAB2_LIB.BASEBOARD_FAB2(SCH_1):PAGE268
 Q25W5    2    SRC FET_N_SOT23LF-2N7002,FET,C7925A    I51 @BASEBOARD_FAB2_LIB.BASEBOARD_FAB2(SCH_1):PAGE268
 EU1D4    2   LGND IR354XX_SM-IR35411,IC,H73688-0A   I113 @BASEBOARD_FAB2_LIB.BASEBOARD_FAB2(SCH_1):PAGE207
 EU1D4    5 PGND<0> IR354XX_SM-IR35411,IC,H73688-0A   I113 @BASEBOARD_FAB2_LIB.BASEBOARD_FAB2(SCH_1):PAGE207
 EU1D4    7 PGND<1> IR354XX_SM-IR35411,IC,H73688-0A   I113 @BASEBOARD_FAB2_LIB.BASEBOARD_FAB2(SCH_1):PAGE207
 EU1D4   40 PGND<2> IR354XX_SM-IR35411,IC,H73688-0A   I113 @BASEBOARD_FAB2_LIB.BASEBOARD_FAB2(SCH_1):PAGE207
C25W99    2      B CAP_A_0402V-0.1UF,16V,10%,X7R,A    I62 @BASEBOARD_FAB2_LIB.BASEBOARD_FAB2(SCH_1):PAGE269
C25W100    2      B CAP_A_0402V-0.1UF,16V,10%,X7R,A    I60 @BASEBOARD_FAB2_LIB.BASEBOARD_FAB2(SCH_1):PAGE268
 C9W14    2      B CAP_0603-10UF,6.3V,20%,X6S,E15A    I46 @BASEBOARD_FAB2_LIB.BASEBOARD_FAB2(SCH_1):PAGE238
 C9W17    2      B CAP_0603-10UF,6.3V,20%,X6S,E15A   I104 @BASEBOARD_FAB2_LIB.BASEBOARD_FAB2(SCH_1):PAGE239
 C9W16    2      B CAP_A_0603V-22.0UF,4V,20%,X6S,A    I50 @BASEBOARD_FAB2_LIB.BASEBOARD_FAB2(SCH_1):PAGE238
 C9W19    2      B CAP_A_0603V-22.0UF,4V,20%,X6S,A   I111 @BASEBOARD_FAB2_LIB.BASEBOARD_FAB2(SCH_1):PAGE239
  S9W1    3      3 SW-SLIDE75-GP_DISCRET-G6-SW-SLA    I63 @BASEBOARD_FAB2_LIB.BASEBOARD_FAB2(SCH_1):PAGE268
  S9W1    4      4 SW-SLIDE75-GP_DISCRET-G6-SW-SLA    I63 @BASEBOARD_FAB2_LIB.BASEBOARD_FAB2(SCH_1):PAGE268
  S9W1    5      5 SW-SLIDE75-GP_DISCRET-G6-SW-SLA    I63 @BASEBOARD_FAB2_LIB.BASEBOARD_FAB2(SCH_1):PAGE268
  S9W1    6      6 SW-SLIDE75-GP_DISCRET-G6-SW-SLA    I63 @BASEBOARD_FAB2_LIB.BASEBOARD_FAB2(SCH_1):PAGE268
  S9W1    7      7 SW-SLIDE75-GP_DISCRET-G6-SW-SLA    I63 @BASEBOARD_FAB2_LIB.BASEBOARD_FAB2(SCH_1):PAGE268
 C1G15    2      2 ST270U2D5VBM-GP_SMD-TCG2-ST270A   I327 @BASEBOARD_FAB2_LIB.BASEBOARD_FAB2(SCH_1):PAGE225
 C1G12    2      2 ST270U2D5VBM-GP_SMD-TCG2-ST270A   I328 @BASEBOARD_FAB2_LIB.BASEBOARD_FAB2(SCH_1):PAGE225
  C1G7    2      2 ST270U2D5VBM-GP_SMD-TCG2-ST270A   I329 @BASEBOARD_FAB2_LIB.BASEBOARD_FAB2(SCH_1):PAGE225
  C7W2    2      2 SE100U16VM-48-GP_SMD-TCG2-SE10A   I324 @BASEBOARD_FAB2_LIB.BASEBOARD_FAB2(SCH_1):PAGE220
  T1P1 GND1   GND1 TPAD-DIFF-4P-GP_DISCRET-GB3-TPA     I3 @BASEBOARD_FAB2_LIB.BASEBOARD_FAB2(SCH_1):PAGE271
  T1P1 GND2   GND2 TPAD-DIFF-4P-GP_DISCRET-GB3-TPA     I3 @BASEBOARD_FAB2_LIB.BASEBOARD_FAB2(SCH_1):PAGE271
  T1D1    3 GND<0> TEST-PAD-12P-1-GP-U_DISCRET-GBA     I1 @BASEBOARD_FAB2_LIB.BASEBOARD_FAB2(SCH_1):PAGE270
  T1D1    4 GND<1> TEST-PAD-12P-1-GP-U_DISCRET-GBA     I1 @BASEBOARD_FAB2_LIB.BASEBOARD_FAB2(SCH_1):PAGE270
  T1D1    5 GND<2> TEST-PAD-12P-1-GP-U_DISCRET-GBA     I1 @BASEBOARD_FAB2_LIB.BASEBOARD_FAB2(SCH_1):PAGE270
  T1D1    6 GND<3> TEST-PAD-12P-1-GP-U_DISCRET-GBA     I1 @BASEBOARD_FAB2_LIB.BASEBOARD_FAB2(SCH_1):PAGE270
  T1D1    7 GND<4> TEST-PAD-12P-1-GP-U_DISCRET-GBA     I1 @BASEBOARD_FAB2_LIB.BASEBOARD_FAB2(SCH_1):PAGE270
  T1D1    8 GND<5> TEST-PAD-12P-1-GP-U_DISCRET-GBA     I1 @BASEBOARD_FAB2_LIB.BASEBOARD_FAB2(SCH_1):PAGE270
  T1D1    9 GND<6> TEST-PAD-12P-1-GP-U_DISCRET-GBA     I1 @BASEBOARD_FAB2_LIB.BASEBOARD_FAB2(SCH_1):PAGE270
  T1D1   10 GND<7> TEST-PAD-12P-1-GP-U_DISCRET-GBA     I1 @BASEBOARD_FAB2_LIB.BASEBOARD_FAB2(SCH_1):PAGE270
  T1D1   11 GND<8> TEST-PAD-12P-1-GP-U_DISCRET-GBA     I1 @BASEBOARD_FAB2_LIB.BASEBOARD_FAB2(SCH_1):PAGE270
  T1D1   12 GND<9> TEST-PAD-12P-1-GP-U_DISCRET-GBA     I1 @BASEBOARD_FAB2_LIB.BASEBOARD_FAB2(SCH_1):PAGE270
  T1D2    3 GND<0> TEST-PAD-12P-1-GP-U_DISCRET-GBA     I3 @BASEBOARD_FAB2_LIB.BASEBOARD_FAB2(SCH_1):PAGE270
  T1D2    4 GND<1> TEST-PAD-12P-1-GP-U_DISCRET-GBA     I3 @BASEBOARD_FAB2_LIB.BASEBOARD_FAB2(SCH_1):PAGE270
  T1D2    5 GND<2> TEST-PAD-12P-1-GP-U_DISCRET-GBA     I3 @BASEBOARD_FAB2_LIB.BASEBOARD_FAB2(SCH_1):PAGE270
  T1D2    6 GND<3> TEST-PAD-12P-1-GP-U_DISCRET-GBA     I3 @BASEBOARD_FAB2_LIB.BASEBOARD_FAB2(SCH_1):PAGE270
  T1D2    7 GND<4> TEST-PAD-12P-1-GP-U_DISCRET-GBA     I3 @BASEBOARD_FAB2_LIB.BASEBOARD_FAB2(SCH_1):PAGE270
  T1D2    8 GND<5> TEST-PAD-12P-1-GP-U_DISCRET-GBA     I3 @BASEBOARD_FAB2_LIB.BASEBOARD_FAB2(SCH_1):PAGE270
  T1D2    9 GND<6> TEST-PAD-12P-1-GP-U_DISCRET-GBA     I3 @BASEBOARD_FAB2_LIB.BASEBOARD_FAB2(SCH_1):PAGE270
  T1D2   10 GND<7> TEST-PAD-12P-1-GP-U_DISCRET-GBA     I3 @BASEBOARD_FAB2_LIB.BASEBOARD_FAB2(SCH_1):PAGE270
  T1D2   11 GND<8> TEST-PAD-12P-1-GP-U_DISCRET-GBA     I3 @BASEBOARD_FAB2_LIB.BASEBOARD_FAB2(SCH_1):PAGE270
  T1D2   12 GND<9> TEST-PAD-12P-1-GP-U_DISCRET-GBA     I3 @BASEBOARD_FAB2_LIB.BASEBOARD_FAB2(SCH_1):PAGE270
  T1D3    3 GND<0> TEST-PAD-12P-1-GP-U_DISCRET-GBA     I5 @BASEBOARD_FAB2_LIB.BASEBOARD_FAB2(SCH_1):PAGE270
  T1D3    4 GND<1> TEST-PAD-12P-1-GP-U_DISCRET-GBA     I5 @BASEBOARD_FAB2_LIB.BASEBOARD_FAB2(SCH_1):PAGE270
  T1D3    5 GND<2> TEST-PAD-12P-1-GP-U_DISCRET-GBA     I5 @BASEBOARD_FAB2_LIB.BASEBOARD_FAB2(SCH_1):PAGE270
  T1D3    6 GND<3> TEST-PAD-12P-1-GP-U_DISCRET-GBA     I5 @BASEBOARD_FAB2_LIB.BASEBOARD_FAB2(SCH_1):PAGE270
  T1D3    7 GND<4> TEST-PAD-12P-1-GP-U_DISCRET-GBA     I5 @BASEBOARD_FAB2_LIB.BASEBOARD_FAB2(SCH_1):PAGE270
  T1D3    8 GND<5> TEST-PAD-12P-1-GP-U_DISCRET-GBA     I5 @BASEBOARD_FAB2_LIB.BASEBOARD_FAB2(SCH_1):PAGE270
  T1D3    9 GND<6> TEST-PAD-12P-1-GP-U_DISCRET-GBA     I5 @BASEBOARD_FAB2_LIB.BASEBOARD_FAB2(SCH_1):PAGE270
  T1D3   10 GND<7> TEST-PAD-12P-1-GP-U_DISCRET-GBA     I5 @BASEBOARD_FAB2_LIB.BASEBOARD_FAB2(SCH_1):PAGE270
  T1D3   11 GND<8> TEST-PAD-12P-1-GP-U_DISCRET-GBA     I5 @BASEBOARD_FAB2_LIB.BASEBOARD_FAB2(SCH_1):PAGE270
  T1D3   12 GND<9> TEST-PAD-12P-1-GP-U_DISCRET-GBA     I5 @BASEBOARD_FAB2_LIB.BASEBOARD_FAB2(SCH_1):PAGE270
  T1D4    3 GND<0> TEST-PAD-12P-1-GP-U_DISCRET-GBA     I6 @BASEBOARD_FAB2_LIB.BASEBOARD_FAB2(SCH_1):PAGE270
  T1D4    4 GND<1> TEST-PAD-12P-1-GP-U_DISCRET-GBA     I6 @BASEBOARD_FAB2_LIB.BASEBOARD_FAB2(SCH_1):PAGE270
  T1D4    5 GND<2> TEST-PAD-12P-1-GP-U_DISCRET-GBA     I6 @BASEBOARD_FAB2_LIB.BASEBOARD_FAB2(SCH_1):PAGE270
  T1D4    6 GND<3> TEST-PAD-12P-1-GP-U_DISCRET-GBA     I6 @BASEBOARD_FAB2_LIB.BASEBOARD_FAB2(SCH_1):PAGE270
  T1D4    7 GND<4> TEST-PAD-12P-1-GP-U_DISCRET-GBA     I6 @BASEBOARD_FAB2_LIB.BASEBOARD_FAB2(SCH_1):PAGE270
  T1D4    8 GND<5> TEST-PAD-12P-1-GP-U_DISCRET-GBA     I6 @BASEBOARD_FAB2_LIB.BASEBOARD_FAB2(SCH_1):PAGE270
  T1D4    9 GND<6> TEST-PAD-12P-1-GP-U_DISCRET-GBA     I6 @BASEBOARD_FAB2_LIB.BASEBOARD_FAB2(SCH_1):PAGE270
  T1D4   10 GND<7> TEST-PAD-12P-1-GP-U_DISCRET-GBA     I6 @BASEBOARD_FAB2_LIB.BASEBOARD_FAB2(SCH_1):PAGE270
  T1D4   11 GND<8> TEST-PAD-12P-1-GP-U_DISCRET-GBA     I6 @BASEBOARD_FAB2_LIB.BASEBOARD_FAB2(SCH_1):PAGE270
  T1D4   12 GND<9> TEST-PAD-12P-1-GP-U_DISCRET-GBA     I6 @BASEBOARD_FAB2_LIB.BASEBOARD_FAB2(SCH_1):PAGE270
  T1D6    3 GND<0> TEST-PAD-12P-1-GP-U_DISCRET-GBA     I9 @BASEBOARD_FAB2_LIB.BASEBOARD_FAB2(SCH_1):PAGE270
  T1D6    4 GND<1> TEST-PAD-12P-1-GP-U_DISCRET-GBA     I9 @BASEBOARD_FAB2_LIB.BASEBOARD_FAB2(SCH_1):PAGE270
  T1D6    5 GND<2> TEST-PAD-12P-1-GP-U_DISCRET-GBA     I9 @BASEBOARD_FAB2_LIB.BASEBOARD_FAB2(SCH_1):PAGE270
  T1D6    6 GND<3> TEST-PAD-12P-1-GP-U_DISCRET-GBA     I9 @BASEBOARD_FAB2_LIB.BASEBOARD_FAB2(SCH_1):PAGE270
  T1D6    7 GND<4> TEST-PAD-12P-1-GP-U_DISCRET-GBA     I9 @BASEBOARD_FAB2_LIB.BASEBOARD_FAB2(SCH_1):PAGE270
  T1D6    8 GND<5> TEST-PAD-12P-1-GP-U_DISCRET-GBA     I9 @BASEBOARD_FAB2_LIB.BASEBOARD_FAB2(SCH_1):PAGE270
  T1D6    9 GND<6> TEST-PAD-12P-1-GP-U_DISCRET-GBA     I9 @BASEBOARD_FAB2_LIB.BASEBOARD_FAB2(SCH_1):PAGE270
  T1D6   10 GND<7> TEST-PAD-12P-1-GP-U_DISCRET-GBA     I9 @BASEBOARD_FAB2_LIB.BASEBOARD_FAB2(SCH_1):PAGE270
  T1D6   11 GND<8> TEST-PAD-12P-1-GP-U_DISCRET-GBA     I9 @BASEBOARD_FAB2_LIB.BASEBOARD_FAB2(SCH_1):PAGE270
  T1D6   12 GND<9> TEST-PAD-12P-1-GP-U_DISCRET-GBA     I9 @BASEBOARD_FAB2_LIB.BASEBOARD_FAB2(SCH_1):PAGE270
  T1D5    3 GND<0> TEST-PAD-12P-1-GP-U_DISCRET-GBA    I12 @BASEBOARD_FAB2_LIB.BASEBOARD_FAB2(SCH_1):PAGE270
  T1D5    4 GND<1> TEST-PAD-12P-1-GP-U_DISCRET-GBA    I12 @BASEBOARD_FAB2_LIB.BASEBOARD_FAB2(SCH_1):PAGE270
  T1D5    5 GND<2> TEST-PAD-12P-1-GP-U_DISCRET-GBA    I12 @BASEBOARD_FAB2_LIB.BASEBOARD_FAB2(SCH_1):PAGE270
  T1D5    6 GND<3> TEST-PAD-12P-1-GP-U_DISCRET-GBA    I12 @BASEBOARD_FAB2_LIB.BASEBOARD_FAB2(SCH_1):PAGE270
  T1D5    7 GND<4> TEST-PAD-12P-1-GP-U_DISCRET-GBA    I12 @BASEBOARD_FAB2_LIB.BASEBOARD_FAB2(SCH_1):PAGE270
  T1D5    8 GND<5> TEST-PAD-12P-1-GP-U_DISCRET-GBA    I12 @BASEBOARD_FAB2_LIB.BASEBOARD_FAB2(SCH_1):PAGE270
  T1D5    9 GND<6> TEST-PAD-12P-1-GP-U_DISCRET-GBA    I12 @BASEBOARD_FAB2_LIB.BASEBOARD_FAB2(SCH_1):PAGE270
  T1D5   10 GND<7> TEST-PAD-12P-1-GP-U_DISCRET-GBA    I12 @BASEBOARD_FAB2_LIB.BASEBOARD_FAB2(SCH_1):PAGE270
  T1D5   11 GND<8> TEST-PAD-12P-1-GP-U_DISCRET-GBA    I12 @BASEBOARD_FAB2_LIB.BASEBOARD_FAB2(SCH_1):PAGE270
  T1D5   12 GND<9> TEST-PAD-12P-1-GP-U_DISCRET-GBA    I12 @BASEBOARD_FAB2_LIB.BASEBOARD_FAB2(SCH_1):PAGE270
  T1D8    3 GND<0> TEST-PAD-12P-1-GP-U_DISCRET-GBA    I13 @BASEBOARD_FAB2_LIB.BASEBOARD_FAB2(SCH_1):PAGE270
  T1D8    4 GND<1> TEST-PAD-12P-1-GP-U_DISCRET-GBA    I13 @BASEBOARD_FAB2_LIB.BASEBOARD_FAB2(SCH_1):PAGE270
  T1D8    5 GND<2> TEST-PAD-12P-1-GP-U_DISCRET-GBA    I13 @BASEBOARD_FAB2_LIB.BASEBOARD_FAB2(SCH_1):PAGE270
  T1D8    6 GND<3> TEST-PAD-12P-1-GP-U_DISCRET-GBA    I13 @BASEBOARD_FAB2_LIB.BASEBOARD_FAB2(SCH_1):PAGE270
  T1D8    7 GND<4> TEST-PAD-12P-1-GP-U_DISCRET-GBA    I13 @BASEBOARD_FAB2_LIB.BASEBOARD_FAB2(SCH_1):PAGE270
  T1D8    8 GND<5> TEST-PAD-12P-1-GP-U_DISCRET-GBA    I13 @BASEBOARD_FAB2_LIB.BASEBOARD_FAB2(SCH_1):PAGE270
  T1D8    9 GND<6> TEST-PAD-12P-1-GP-U_DISCRET-GBA    I13 @BASEBOARD_FAB2_LIB.BASEBOARD_FAB2(SCH_1):PAGE270
  T1D8   10 GND<7> TEST-PAD-12P-1-GP-U_DISCRET-GBA    I13 @BASEBOARD_FAB2_LIB.BASEBOARD_FAB2(SCH_1):PAGE270
  T1D8   11 GND<8> TEST-PAD-12P-1-GP-U_DISCRET-GBA    I13 @BASEBOARD_FAB2_LIB.BASEBOARD_FAB2(SCH_1):PAGE270
  T1D8   12 GND<9> TEST-PAD-12P-1-GP-U_DISCRET-GBA    I13 @BASEBOARD_FAB2_LIB.BASEBOARD_FAB2(SCH_1):PAGE270
  T1D7    3 GND<0> TEST-PAD-12P-1-GP-U_DISCRET-GBA    I16 @BASEBOARD_FAB2_LIB.BASEBOARD_FAB2(SCH_1):PAGE270
  T1D7    4 GND<1> TEST-PAD-12P-1-GP-U_DISCRET-GBA    I16 @BASEBOARD_FAB2_LIB.BASEBOARD_FAB2(SCH_1):PAGE270
  T1D7    5 GND<2> TEST-PAD-12P-1-GP-U_DISCRET-GBA    I16 @BASEBOARD_FAB2_LIB.BASEBOARD_FAB2(SCH_1):PAGE270
  T1D7    6 GND<3> TEST-PAD-12P-1-GP-U_DISCRET-GBA    I16 @BASEBOARD_FAB2_LIB.BASEBOARD_FAB2(SCH_1):PAGE270
  T1D7    7 GND<4> TEST-PAD-12P-1-GP-U_DISCRET-GBA    I16 @BASEBOARD_FAB2_LIB.BASEBOARD_FAB2(SCH_1):PAGE270
  T1D7    8 GND<5> TEST-PAD-12P-1-GP-U_DISCRET-GBA    I16 @BASEBOARD_FAB2_LIB.BASEBOARD_FAB2(SCH_1):PAGE270
  T1D7    9 GND<6> TEST-PAD-12P-1-GP-U_DISCRET-GBA    I16 @BASEBOARD_FAB2_LIB.BASEBOARD_FAB2(SCH_1):PAGE270
  T1D7   10 GND<7> TEST-PAD-12P-1-GP-U_DISCRET-GBA    I16 @BASEBOARD_FAB2_LIB.BASEBOARD_FAB2(SCH_1):PAGE270
  T1D7   11 GND<8> TEST-PAD-12P-1-GP-U_DISCRET-GBA    I16 @BASEBOARD_FAB2_LIB.BASEBOARD_FAB2(SCH_1):PAGE270
  T1D7   12 GND<9> TEST-PAD-12P-1-GP-U_DISCRET-GBA    I16 @BASEBOARD_FAB2_LIB.BASEBOARD_FAB2(SCH_1):PAGE270
 T1D10    3 GND<0> TEST-PAD-12P-1-GP-U_DISCRET-GBA    I17 @BASEBOARD_FAB2_LIB.BASEBOARD_FAB2(SCH_1):PAGE270
 T1D10    4 GND<1> TEST-PAD-12P-1-GP-U_DISCRET-GBA    I17 @BASEBOARD_FAB2_LIB.BASEBOARD_FAB2(SCH_1):PAGE270
 T1D10    5 GND<2> TEST-PAD-12P-1-GP-U_DISCRET-GBA    I17 @BASEBOARD_FAB2_LIB.BASEBOARD_FAB2(SCH_1):PAGE270
 T1D10    6 GND<3> TEST-PAD-12P-1-GP-U_DISCRET-GBA    I17 @BASEBOARD_FAB2_LIB.BASEBOARD_FAB2(SCH_1):PAGE270
 T1D10    7 GND<4> TEST-PAD-12P-1-GP-U_DISCRET-GBA    I17 @BASEBOARD_FAB2_LIB.BASEBOARD_FAB2(SCH_1):PAGE270
 T1D10    8 GND<5> TEST-PAD-12P-1-GP-U_DISCRET-GBA    I17 @BASEBOARD_FAB2_LIB.BASEBOARD_FAB2(SCH_1):PAGE270
 T1D10    9 GND<6> TEST-PAD-12P-1-GP-U_DISCRET-GBA    I17 @BASEBOARD_FAB2_LIB.BASEBOARD_FAB2(SCH_1):PAGE270
 T1D10   10 GND<7> TEST-PAD-12P-1-GP-U_DISCRET-GBA    I17 @BASEBOARD_FAB2_LIB.BASEBOARD_FAB2(SCH_1):PAGE270
 T1D10   11 GND<8> TEST-PAD-12P-1-GP-U_DISCRET-GBA    I17 @BASEBOARD_FAB2_LIB.BASEBOARD_FAB2(SCH_1):PAGE270
 T1D10   12 GND<9> TEST-PAD-12P-1-GP-U_DISCRET-GBA    I17 @BASEBOARD_FAB2_LIB.BASEBOARD_FAB2(SCH_1):PAGE270
  T1D9    3 GND<0> TEST-PAD-12P-1-GP-U_DISCRET-GBA    I18 @BASEBOARD_FAB2_LIB.BASEBOARD_FAB2(SCH_1):PAGE270
  T1D9    4 GND<1> TEST-PAD-12P-1-GP-U_DISCRET-GBA    I18 @BASEBOARD_FAB2_LIB.BASEBOARD_FAB2(SCH_1):PAGE270
  T1D9    5 GND<2> TEST-PAD-12P-1-GP-U_DISCRET-GBA    I18 @BASEBOARD_FAB2_LIB.BASEBOARD_FAB2(SCH_1):PAGE270
  T1D9    6 GND<3> TEST-PAD-12P-1-GP-U_DISCRET-GBA    I18 @BASEBOARD_FAB2_LIB.BASEBOARD_FAB2(SCH_1):PAGE270
  T1D9    7 GND<4> TEST-PAD-12P-1-GP-U_DISCRET-GBA    I18 @BASEBOARD_FAB2_LIB.BASEBOARD_FAB2(SCH_1):PAGE270
  T1D9    8 GND<5> TEST-PAD-12P-1-GP-U_DISCRET-GBA    I18 @BASEBOARD_FAB2_LIB.BASEBOARD_FAB2(SCH_1):PAGE270
  T1D9    9 GND<6> TEST-PAD-12P-1-GP-U_DISCRET-GBA    I18 @BASEBOARD_FAB2_LIB.BASEBOARD_FAB2(SCH_1):PAGE270
  T1D9   10 GND<7> TEST-PAD-12P-1-GP-U_DISCRET-GBA    I18 @BASEBOARD_FAB2_LIB.BASEBOARD_FAB2(SCH_1):PAGE270
  T1D9   11 GND<8> TEST-PAD-12P-1-GP-U_DISCRET-GBA    I18 @BASEBOARD_FAB2_LIB.BASEBOARD_FAB2(SCH_1):PAGE270
  T1D9   12 GND<9> TEST-PAD-12P-1-GP-U_DISCRET-GBA    I18 @BASEBOARD_FAB2_LIB.BASEBOARD_FAB2(SCH_1):PAGE270
 T1D12    3 GND<0> TEST-PAD-12P-1-GP-U_DISCRET-GBA    I21 @BASEBOARD_FAB2_LIB.BASEBOARD_FAB2(SCH_1):PAGE270
 T1D12    4 GND<1> TEST-PAD-12P-1-GP-U_DISCRET-GBA    I21 @BASEBOARD_FAB2_LIB.BASEBOARD_FAB2(SCH_1):PAGE270
 T1D12    5 GND<2> TEST-PAD-12P-1-GP-U_DISCRET-GBA    I21 @BASEBOARD_FAB2_LIB.BASEBOARD_FAB2(SCH_1):PAGE270
 T1D12    6 GND<3> TEST-PAD-12P-1-GP-U_DISCRET-GBA    I21 @BASEBOARD_FAB2_LIB.BASEBOARD_FAB2(SCH_1):PAGE270
 T1D12    7 GND<4> TEST-PAD-12P-1-GP-U_DISCRET-GBA    I21 @BASEBOARD_FAB2_LIB.BASEBOARD_FAB2(SCH_1):PAGE270
 T1D12    8 GND<5> TEST-PAD-12P-1-GP-U_DISCRET-GBA    I21 @BASEBOARD_FAB2_LIB.BASEBOARD_FAB2(SCH_1):PAGE270
 T1D12    9 GND<6> TEST-PAD-12P-1-GP-U_DISCRET-GBA    I21 @BASEBOARD_FAB2_LIB.BASEBOARD_FAB2(SCH_1):PAGE270
 T1D12   10 GND<7> TEST-PAD-12P-1-GP-U_DISCRET-GBA    I21 @BASEBOARD_FAB2_LIB.BASEBOARD_FAB2(SCH_1):PAGE270
 T1D12   11 GND<8> TEST-PAD-12P-1-GP-U_DISCRET-GBA    I21 @BASEBOARD_FAB2_LIB.BASEBOARD_FAB2(SCH_1):PAGE270
 T1D12   12 GND<9> TEST-PAD-12P-1-GP-U_DISCRET-GBA    I21 @BASEBOARD_FAB2_LIB.BASEBOARD_FAB2(SCH_1):PAGE270
 T1D11    3 GND<0> TEST-PAD-12P-1-GP-U_DISCRET-GBA    I24 @BASEBOARD_FAB2_LIB.BASEBOARD_FAB2(SCH_1):PAGE270
 T1D11    4 GND<1> TEST-PAD-12P-1-GP-U_DISCRET-GBA    I24 @BASEBOARD_FAB2_LIB.BASEBOARD_FAB2(SCH_1):PAGE270
 T1D11    5 GND<2> TEST-PAD-12P-1-GP-U_DISCRET-GBA    I24 @BASEBOARD_FAB2_LIB.BASEBOARD_FAB2(SCH_1):PAGE270
 T1D11    6 GND<3> TEST-PAD-12P-1-GP-U_DISCRET-GBA    I24 @BASEBOARD_FAB2_LIB.BASEBOARD_FAB2(SCH_1):PAGE270
 T1D11    7 GND<4> TEST-PAD-12P-1-GP-U_DISCRET-GBA    I24 @BASEBOARD_FAB2_LIB.BASEBOARD_FAB2(SCH_1):PAGE270
 T1D11    8 GND<5> TEST-PAD-12P-1-GP-U_DISCRET-GBA    I24 @BASEBOARD_FAB2_LIB.BASEBOARD_FAB2(SCH_1):PAGE270
 T1D11    9 GND<6> TEST-PAD-12P-1-GP-U_DISCRET-GBA    I24 @BASEBOARD_FAB2_LIB.BASEBOARD_FAB2(SCH_1):PAGE270
 T1D11   10 GND<7> TEST-PAD-12P-1-GP-U_DISCRET-GBA    I24 @BASEBOARD_FAB2_LIB.BASEBOARD_FAB2(SCH_1):PAGE270
 T1D11   11 GND<8> TEST-PAD-12P-1-GP-U_DISCRET-GBA    I24 @BASEBOARD_FAB2_LIB.BASEBOARD_FAB2(SCH_1):PAGE270
 T1D11   12 GND<9> TEST-PAD-12P-1-GP-U_DISCRET-GBA    I24 @BASEBOARD_FAB2_LIB.BASEBOARD_FAB2(SCH_1):PAGE270
 T1D17    3 GND<0> TEST-PAD-12P-1-GP-U_DISCRET-GBA     I1 @BASEBOARD_FAB2_LIB.BASEBOARD_FAB2(SCH_1):PAGE272
 T1D17    4 GND<1> TEST-PAD-12P-1-GP-U_DISCRET-GBA     I1 @BASEBOARD_FAB2_LIB.BASEBOARD_FAB2(SCH_1):PAGE272
 T1D17    5 GND<2> TEST-PAD-12P-1-GP-U_DISCRET-GBA     I1 @BASEBOARD_FAB2_LIB.BASEBOARD_FAB2(SCH_1):PAGE272
 T1D17    6 GND<3> TEST-PAD-12P-1-GP-U_DISCRET-GBA     I1 @BASEBOARD_FAB2_LIB.BASEBOARD_FAB2(SCH_1):PAGE272
 T1D17    7 GND<4> TEST-PAD-12P-1-GP-U_DISCRET-GBA     I1 @BASEBOARD_FAB2_LIB.BASEBOARD_FAB2(SCH_1):PAGE272
 T1D17    8 GND<5> TEST-PAD-12P-1-GP-U_DISCRET-GBA     I1 @BASEBOARD_FAB2_LIB.BASEBOARD_FAB2(SCH_1):PAGE272
 T1D17    9 GND<6> TEST-PAD-12P-1-GP-U_DISCRET-GBA     I1 @BASEBOARD_FAB2_LIB.BASEBOARD_FAB2(SCH_1):PAGE272
 T1D17   10 GND<7> TEST-PAD-12P-1-GP-U_DISCRET-GBA     I1 @BASEBOARD_FAB2_LIB.BASEBOARD_FAB2(SCH_1):PAGE272
 T1D17   11 GND<8> TEST-PAD-12P-1-GP-U_DISCRET-GBA     I1 @BASEBOARD_FAB2_LIB.BASEBOARD_FAB2(SCH_1):PAGE272
 T1D17   12 GND<9> TEST-PAD-12P-1-GP-U_DISCRET-GBA     I1 @BASEBOARD_FAB2_LIB.BASEBOARD_FAB2(SCH_1):PAGE272
 T1D15    3 GND<0> TEST-PAD-12P-1-GP-U_DISCRET-GBA     I3 @BASEBOARD_FAB2_LIB.BASEBOARD_FAB2(SCH_1):PAGE272
 T1D15    4 GND<1> TEST-PAD-12P-1-GP-U_DISCRET-GBA     I3 @BASEBOARD_FAB2_LIB.BASEBOARD_FAB2(SCH_1):PAGE272
 T1D15    5 GND<2> TEST-PAD-12P-1-GP-U_DISCRET-GBA     I3 @BASEBOARD_FAB2_LIB.BASEBOARD_FAB2(SCH_1):PAGE272
 T1D15    6 GND<3> TEST-PAD-12P-1-GP-U_DISCRET-GBA     I3 @BASEBOARD_FAB2_LIB.BASEBOARD_FAB2(SCH_1):PAGE272
 T1D15    7 GND<4> TEST-PAD-12P-1-GP-U_DISCRET-GBA     I3 @BASEBOARD_FAB2_LIB.BASEBOARD_FAB2(SCH_1):PAGE272
 T1D15    8 GND<5> TEST-PAD-12P-1-GP-U_DISCRET-GBA     I3 @BASEBOARD_FAB2_LIB.BASEBOARD_FAB2(SCH_1):PAGE272
 T1D15    9 GND<6> TEST-PAD-12P-1-GP-U_DISCRET-GBA     I3 @BASEBOARD_FAB2_LIB.BASEBOARD_FAB2(SCH_1):PAGE272
 T1D15   10 GND<7> TEST-PAD-12P-1-GP-U_DISCRET-GBA     I3 @BASEBOARD_FAB2_LIB.BASEBOARD_FAB2(SCH_1):PAGE272
 T1D15   11 GND<8> TEST-PAD-12P-1-GP-U_DISCRET-GBA     I3 @BASEBOARD_FAB2_LIB.BASEBOARD_FAB2(SCH_1):PAGE272
 T1D15   12 GND<9> TEST-PAD-12P-1-GP-U_DISCRET-GBA     I3 @BASEBOARD_FAB2_LIB.BASEBOARD_FAB2(SCH_1):PAGE272
 T1D13    3 GND<0> TEST-PAD-12P-1-GP-U_DISCRET-GBA     I5 @BASEBOARD_FAB2_LIB.BASEBOARD_FAB2(SCH_1):PAGE272
 T1D13    4 GND<1> TEST-PAD-12P-1-GP-U_DISCRET-GBA     I5 @BASEBOARD_FAB2_LIB.BASEBOARD_FAB2(SCH_1):PAGE272
 T1D13    5 GND<2> TEST-PAD-12P-1-GP-U_DISCRET-GBA     I5 @BASEBOARD_FAB2_LIB.BASEBOARD_FAB2(SCH_1):PAGE272
 T1D13    6 GND<3> TEST-PAD-12P-1-GP-U_DISCRET-GBA     I5 @BASEBOARD_FAB2_LIB.BASEBOARD_FAB2(SCH_1):PAGE272
 T1D13    7 GND<4> TEST-PAD-12P-1-GP-U_DISCRET-GBA     I5 @BASEBOARD_FAB2_LIB.BASEBOARD_FAB2(SCH_1):PAGE272
 T1D13    8 GND<5> TEST-PAD-12P-1-GP-U_DISCRET-GBA     I5 @BASEBOARD_FAB2_LIB.BASEBOARD_FAB2(SCH_1):PAGE272
 T1D13    9 GND<6> TEST-PAD-12P-1-GP-U_DISCRET-GBA     I5 @BASEBOARD_FAB2_LIB.BASEBOARD_FAB2(SCH_1):PAGE272
 T1D13   10 GND<7> TEST-PAD-12P-1-GP-U_DISCRET-GBA     I5 @BASEBOARD_FAB2_LIB.BASEBOARD_FAB2(SCH_1):PAGE272
 T1D13   11 GND<8> TEST-PAD-12P-1-GP-U_DISCRET-GBA     I5 @BASEBOARD_FAB2_LIB.BASEBOARD_FAB2(SCH_1):PAGE272
 T1D13   12 GND<9> TEST-PAD-12P-1-GP-U_DISCRET-GBA     I5 @BASEBOARD_FAB2_LIB.BASEBOARD_FAB2(SCH_1):PAGE272
 T1D18    3 GND<0> TEST-PAD-12P-1-GP-U_DISCRET-GBA     I8 @BASEBOARD_FAB2_LIB.BASEBOARD_FAB2(SCH_1):PAGE272
 T1D18    4 GND<1> TEST-PAD-12P-1-GP-U_DISCRET-GBA     I8 @BASEBOARD_FAB2_LIB.BASEBOARD_FAB2(SCH_1):PAGE272
 T1D18    5 GND<2> TEST-PAD-12P-1-GP-U_DISCRET-GBA     I8 @BASEBOARD_FAB2_LIB.BASEBOARD_FAB2(SCH_1):PAGE272
 T1D18    6 GND<3> TEST-PAD-12P-1-GP-U_DISCRET-GBA     I8 @BASEBOARD_FAB2_LIB.BASEBOARD_FAB2(SCH_1):PAGE272
 T1D18    7 GND<4> TEST-PAD-12P-1-GP-U_DISCRET-GBA     I8 @BASEBOARD_FAB2_LIB.BASEBOARD_FAB2(SCH_1):PAGE272
 T1D18    8 GND<5> TEST-PAD-12P-1-GP-U_DISCRET-GBA     I8 @BASEBOARD_FAB2_LIB.BASEBOARD_FAB2(SCH_1):PAGE272
 T1D18    9 GND<6> TEST-PAD-12P-1-GP-U_DISCRET-GBA     I8 @BASEBOARD_FAB2_LIB.BASEBOARD_FAB2(SCH_1):PAGE272
 T1D18   10 GND<7> TEST-PAD-12P-1-GP-U_DISCRET-GBA     I8 @BASEBOARD_FAB2_LIB.BASEBOARD_FAB2(SCH_1):PAGE272
 T1D18   11 GND<8> TEST-PAD-12P-1-GP-U_DISCRET-GBA     I8 @BASEBOARD_FAB2_LIB.BASEBOARD_FAB2(SCH_1):PAGE272
 T1D18   12 GND<9> TEST-PAD-12P-1-GP-U_DISCRET-GBA     I8 @BASEBOARD_FAB2_LIB.BASEBOARD_FAB2(SCH_1):PAGE272
 T1D23    3 GND<0> TEST-PAD-12P-1-GP-U_DISCRET-GBA     I9 @BASEBOARD_FAB2_LIB.BASEBOARD_FAB2(SCH_1):PAGE272
 T1D23    4 GND<1> TEST-PAD-12P-1-GP-U_DISCRET-GBA     I9 @BASEBOARD_FAB2_LIB.BASEBOARD_FAB2(SCH_1):PAGE272
 T1D23    5 GND<2> TEST-PAD-12P-1-GP-U_DISCRET-GBA     I9 @BASEBOARD_FAB2_LIB.BASEBOARD_FAB2(SCH_1):PAGE272
 T1D23    6 GND<3> TEST-PAD-12P-1-GP-U_DISCRET-GBA     I9 @BASEBOARD_FAB2_LIB.BASEBOARD_FAB2(SCH_1):PAGE272
 T1D23    7 GND<4> TEST-PAD-12P-1-GP-U_DISCRET-GBA     I9 @BASEBOARD_FAB2_LIB.BASEBOARD_FAB2(SCH_1):PAGE272
 T1D23    8 GND<5> TEST-PAD-12P-1-GP-U_DISCRET-GBA     I9 @BASEBOARD_FAB2_LIB.BASEBOARD_FAB2(SCH_1):PAGE272
 T1D23    9 GND<6> TEST-PAD-12P-1-GP-U_DISCRET-GBA     I9 @BASEBOARD_FAB2_LIB.BASEBOARD_FAB2(SCH_1):PAGE272
 T1D23   10 GND<7> TEST-PAD-12P-1-GP-U_DISCRET-GBA     I9 @BASEBOARD_FAB2_LIB.BASEBOARD_FAB2(SCH_1):PAGE272
 T1D23   11 GND<8> TEST-PAD-12P-1-GP-U_DISCRET-GBA     I9 @BASEBOARD_FAB2_LIB.BASEBOARD_FAB2(SCH_1):PAGE272
 T1D23   12 GND<9> TEST-PAD-12P-1-GP-U_DISCRET-GBA     I9 @BASEBOARD_FAB2_LIB.BASEBOARD_FAB2(SCH_1):PAGE272
 T1D24    3 GND<0> TEST-PAD-12P-1-GP-U_DISCRET-GBA    I12 @BASEBOARD_FAB2_LIB.BASEBOARD_FAB2(SCH_1):PAGE272
 T1D24    4 GND<1> TEST-PAD-12P-1-GP-U_DISCRET-GBA    I12 @BASEBOARD_FAB2_LIB.BASEBOARD_FAB2(SCH_1):PAGE272
 T1D24    5 GND<2> TEST-PAD-12P-1-GP-U_DISCRET-GBA    I12 @BASEBOARD_FAB2_LIB.BASEBOARD_FAB2(SCH_1):PAGE272
 T1D24    6 GND<3> TEST-PAD-12P-1-GP-U_DISCRET-GBA    I12 @BASEBOARD_FAB2_LIB.BASEBOARD_FAB2(SCH_1):PAGE272
 T1D24    7 GND<4> TEST-PAD-12P-1-GP-U_DISCRET-GBA    I12 @BASEBOARD_FAB2_LIB.BASEBOARD_FAB2(SCH_1):PAGE272
 T1D24    8 GND<5> TEST-PAD-12P-1-GP-U_DISCRET-GBA    I12 @BASEBOARD_FAB2_LIB.BASEBOARD_FAB2(SCH_1):PAGE272
 T1D24    9 GND<6> TEST-PAD-12P-1-GP-U_DISCRET-GBA    I12 @BASEBOARD_FAB2_LIB.BASEBOARD_FAB2(SCH_1):PAGE272
 T1D24   10 GND<7> TEST-PAD-12P-1-GP-U_DISCRET-GBA    I12 @BASEBOARD_FAB2_LIB.BASEBOARD_FAB2(SCH_1):PAGE272
 T1D24   11 GND<8> TEST-PAD-12P-1-GP-U_DISCRET-GBA    I12 @BASEBOARD_FAB2_LIB.BASEBOARD_FAB2(SCH_1):PAGE272
 T1D24   12 GND<9> TEST-PAD-12P-1-GP-U_DISCRET-GBA    I12 @BASEBOARD_FAB2_LIB.BASEBOARD_FAB2(SCH_1):PAGE272
 T1D16    3 GND<0> TEST-PAD-12P-1-GP-U_DISCRET-GBA    I14 @BASEBOARD_FAB2_LIB.BASEBOARD_FAB2(SCH_1):PAGE272
 T1D16    4 GND<1> TEST-PAD-12P-1-GP-U_DISCRET-GBA    I14 @BASEBOARD_FAB2_LIB.BASEBOARD_FAB2(SCH_1):PAGE272
 T1D16    5 GND<2> TEST-PAD-12P-1-GP-U_DISCRET-GBA    I14 @BASEBOARD_FAB2_LIB.BASEBOARD_FAB2(SCH_1):PAGE272
 T1D16    6 GND<3> TEST-PAD-12P-1-GP-U_DISCRET-GBA    I14 @BASEBOARD_FAB2_LIB.BASEBOARD_FAB2(SCH_1):PAGE272
 T1D16    7 GND<4> TEST-PAD-12P-1-GP-U_DISCRET-GBA    I14 @BASEBOARD_FAB2_LIB.BASEBOARD_FAB2(SCH_1):PAGE272
 T1D16    8 GND<5> TEST-PAD-12P-1-GP-U_DISCRET-GBA    I14 @BASEBOARD_FAB2_LIB.BASEBOARD_FAB2(SCH_1):PAGE272
 T1D16    9 GND<6> TEST-PAD-12P-1-GP-U_DISCRET-GBA    I14 @BASEBOARD_FAB2_LIB.BASEBOARD_FAB2(SCH_1):PAGE272
 T1D16   10 GND<7> TEST-PAD-12P-1-GP-U_DISCRET-GBA    I14 @BASEBOARD_FAB2_LIB.BASEBOARD_FAB2(SCH_1):PAGE272
 T1D16   11 GND<8> TEST-PAD-12P-1-GP-U_DISCRET-GBA    I14 @BASEBOARD_FAB2_LIB.BASEBOARD_FAB2(SCH_1):PAGE272
 T1D16   12 GND<9> TEST-PAD-12P-1-GP-U_DISCRET-GBA    I14 @BASEBOARD_FAB2_LIB.BASEBOARD_FAB2(SCH_1):PAGE272
 T1D21    3 GND<0> TEST-PAD-12P-1-GP-U_DISCRET-GBA    I16 @BASEBOARD_FAB2_LIB.BASEBOARD_FAB2(SCH_1):PAGE272
 T1D21    4 GND<1> TEST-PAD-12P-1-GP-U_DISCRET-GBA    I16 @BASEBOARD_FAB2_LIB.BASEBOARD_FAB2(SCH_1):PAGE272
 T1D21    5 GND<2> TEST-PAD-12P-1-GP-U_DISCRET-GBA    I16 @BASEBOARD_FAB2_LIB.BASEBOARD_FAB2(SCH_1):PAGE272
 T1D21    6 GND<3> TEST-PAD-12P-1-GP-U_DISCRET-GBA    I16 @BASEBOARD_FAB2_LIB.BASEBOARD_FAB2(SCH_1):PAGE272
 T1D21    7 GND<4> TEST-PAD-12P-1-GP-U_DISCRET-GBA    I16 @BASEBOARD_FAB2_LIB.BASEBOARD_FAB2(SCH_1):PAGE272
 T1D21    8 GND<5> TEST-PAD-12P-1-GP-U_DISCRET-GBA    I16 @BASEBOARD_FAB2_LIB.BASEBOARD_FAB2(SCH_1):PAGE272
 T1D21    9 GND<6> TEST-PAD-12P-1-GP-U_DISCRET-GBA    I16 @BASEBOARD_FAB2_LIB.BASEBOARD_FAB2(SCH_1):PAGE272
 T1D21   10 GND<7> TEST-PAD-12P-1-GP-U_DISCRET-GBA    I16 @BASEBOARD_FAB2_LIB.BASEBOARD_FAB2(SCH_1):PAGE272
 T1D21   11 GND<8> TEST-PAD-12P-1-GP-U_DISCRET-GBA    I16 @BASEBOARD_FAB2_LIB.BASEBOARD_FAB2(SCH_1):PAGE272
 T1D21   12 GND<9> TEST-PAD-12P-1-GP-U_DISCRET-GBA    I16 @BASEBOARD_FAB2_LIB.BASEBOARD_FAB2(SCH_1):PAGE272
 T1D22    3 GND<0> TEST-PAD-12P-1-GP-U_DISCRET-GBA    I21 @BASEBOARD_FAB2_LIB.BASEBOARD_FAB2(SCH_1):PAGE272
 T1D22    4 GND<1> TEST-PAD-12P-1-GP-U_DISCRET-GBA    I21 @BASEBOARD_FAB2_LIB.BASEBOARD_FAB2(SCH_1):PAGE272
 T1D22    5 GND<2> TEST-PAD-12P-1-GP-U_DISCRET-GBA    I21 @BASEBOARD_FAB2_LIB.BASEBOARD_FAB2(SCH_1):PAGE272
 T1D22    6 GND<3> TEST-PAD-12P-1-GP-U_DISCRET-GBA    I21 @BASEBOARD_FAB2_LIB.BASEBOARD_FAB2(SCH_1):PAGE272
 T1D22    7 GND<4> TEST-PAD-12P-1-GP-U_DISCRET-GBA    I21 @BASEBOARD_FAB2_LIB.BASEBOARD_FAB2(SCH_1):PAGE272
 T1D22    8 GND<5> TEST-PAD-12P-1-GP-U_DISCRET-GBA    I21 @BASEBOARD_FAB2_LIB.BASEBOARD_FAB2(SCH_1):PAGE272
 T1D22    9 GND<6> TEST-PAD-12P-1-GP-U_DISCRET-GBA    I21 @BASEBOARD_FAB2_LIB.BASEBOARD_FAB2(SCH_1):PAGE272
 T1D22   10 GND<7> TEST-PAD-12P-1-GP-U_DISCRET-GBA    I21 @BASEBOARD_FAB2_LIB.BASEBOARD_FAB2(SCH_1):PAGE272
 T1D22   11 GND<8> TEST-PAD-12P-1-GP-U_DISCRET-GBA    I21 @BASEBOARD_FAB2_LIB.BASEBOARD_FAB2(SCH_1):PAGE272
 T1D22   12 GND<9> TEST-PAD-12P-1-GP-U_DISCRET-GBA    I21 @BASEBOARD_FAB2_LIB.BASEBOARD_FAB2(SCH_1):PAGE272
 T1D14    3 GND<0> TEST-PAD-12P-1-GP-U_DISCRET-GBA    I22 @BASEBOARD_FAB2_LIB.BASEBOARD_FAB2(SCH_1):PAGE272
 T1D14    4 GND<1> TEST-PAD-12P-1-GP-U_DISCRET-GBA    I22 @BASEBOARD_FAB2_LIB.BASEBOARD_FAB2(SCH_1):PAGE272
 T1D14    5 GND<2> TEST-PAD-12P-1-GP-U_DISCRET-GBA    I22 @BASEBOARD_FAB2_LIB.BASEBOARD_FAB2(SCH_1):PAGE272
 T1D14    6 GND<3> TEST-PAD-12P-1-GP-U_DISCRET-GBA    I22 @BASEBOARD_FAB2_LIB.BASEBOARD_FAB2(SCH_1):PAGE272
 T1D14    7 GND<4> TEST-PAD-12P-1-GP-U_DISCRET-GBA    I22 @BASEBOARD_FAB2_LIB.BASEBOARD_FAB2(SCH_1):PAGE272
 T1D14    8 GND<5> TEST-PAD-12P-1-GP-U_DISCRET-GBA    I22 @BASEBOARD_FAB2_LIB.BASEBOARD_FAB2(SCH_1):PAGE272
 T1D14    9 GND<6> TEST-PAD-12P-1-GP-U_DISCRET-GBA    I22 @BASEBOARD_FAB2_LIB.BASEBOARD_FAB2(SCH_1):PAGE272
 T1D14   10 GND<7> TEST-PAD-12P-1-GP-U_DISCRET-GBA    I22 @BASEBOARD_FAB2_LIB.BASEBOARD_FAB2(SCH_1):PAGE272
 T1D14   11 GND<8> TEST-PAD-12P-1-GP-U_DISCRET-GBA    I22 @BASEBOARD_FAB2_LIB.BASEBOARD_FAB2(SCH_1):PAGE272
 T1D14   12 GND<9> TEST-PAD-12P-1-GP-U_DISCRET-GBA    I22 @BASEBOARD_FAB2_LIB.BASEBOARD_FAB2(SCH_1):PAGE272
 T1D19    3 GND<0> TEST-PAD-12P-1-GP-U_DISCRET-GBA    I23 @BASEBOARD_FAB2_LIB.BASEBOARD_FAB2(SCH_1):PAGE272
 T1D19    4 GND<1> TEST-PAD-12P-1-GP-U_DISCRET-GBA    I23 @BASEBOARD_FAB2_LIB.BASEBOARD_FAB2(SCH_1):PAGE272
 T1D19    5 GND<2> TEST-PAD-12P-1-GP-U_DISCRET-GBA    I23 @BASEBOARD_FAB2_LIB.BASEBOARD_FAB2(SCH_1):PAGE272
 T1D19    6 GND<3> TEST-PAD-12P-1-GP-U_DISCRET-GBA    I23 @BASEBOARD_FAB2_LIB.BASEBOARD_FAB2(SCH_1):PAGE272
 T1D19    7 GND<4> TEST-PAD-12P-1-GP-U_DISCRET-GBA    I23 @BASEBOARD_FAB2_LIB.BASEBOARD_FAB2(SCH_1):PAGE272
 T1D19    8 GND<5> TEST-PAD-12P-1-GP-U_DISCRET-GBA    I23 @BASEBOARD_FAB2_LIB.BASEBOARD_FAB2(SCH_1):PAGE272
 T1D19    9 GND<6> TEST-PAD-12P-1-GP-U_DISCRET-GBA    I23 @BASEBOARD_FAB2_LIB.BASEBOARD_FAB2(SCH_1):PAGE272
 T1D19   10 GND<7> TEST-PAD-12P-1-GP-U_DISCRET-GBA    I23 @BASEBOARD_FAB2_LIB.BASEBOARD_FAB2(SCH_1):PAGE272
 T1D19   11 GND<8> TEST-PAD-12P-1-GP-U_DISCRET-GBA    I23 @BASEBOARD_FAB2_LIB.BASEBOARD_FAB2(SCH_1):PAGE272
 T1D19   12 GND<9> TEST-PAD-12P-1-GP-U_DISCRET-GBA    I23 @BASEBOARD_FAB2_LIB.BASEBOARD_FAB2(SCH_1):PAGE272
 T1D20    3 GND<0> TEST-PAD-12P-1-GP-U_DISCRET-GBA    I24 @BASEBOARD_FAB2_LIB.BASEBOARD_FAB2(SCH_1):PAGE272
 T1D20    4 GND<1> TEST-PAD-12P-1-GP-U_DISCRET-GBA    I24 @BASEBOARD_FAB2_LIB.BASEBOARD_FAB2(SCH_1):PAGE272
 T1D20    5 GND<2> TEST-PAD-12P-1-GP-U_DISCRET-GBA    I24 @BASEBOARD_FAB2_LIB.BASEBOARD_FAB2(SCH_1):PAGE272
 T1D20    6 GND<3> TEST-PAD-12P-1-GP-U_DISCRET-GBA    I24 @BASEBOARD_FAB2_LIB.BASEBOARD_FAB2(SCH_1):PAGE272
 T1D20    7 GND<4> TEST-PAD-12P-1-GP-U_DISCRET-GBA    I24 @BASEBOARD_FAB2_LIB.BASEBOARD_FAB2(SCH_1):PAGE272
 T1D20    8 GND<5> TEST-PAD-12P-1-GP-U_DISCRET-GBA    I24 @BASEBOARD_FAB2_LIB.BASEBOARD_FAB2(SCH_1):PAGE272
 T1D20    9 GND<6> TEST-PAD-12P-1-GP-U_DISCRET-GBA    I24 @BASEBOARD_FAB2_LIB.BASEBOARD_FAB2(SCH_1):PAGE272
 T1D20   10 GND<7> TEST-PAD-12P-1-GP-U_DISCRET-GBA    I24 @BASEBOARD_FAB2_LIB.BASEBOARD_FAB2(SCH_1):PAGE272
 T1D20   11 GND<8> TEST-PAD-12P-1-GP-U_DISCRET-GBA    I24 @BASEBOARD_FAB2_LIB.BASEBOARD_FAB2(SCH_1):PAGE272
 T1D20   12 GND<9> TEST-PAD-12P-1-GP-U_DISCRET-GBA    I24 @BASEBOARD_FAB2_LIB.BASEBOARD_FAB2(SCH_1):PAGE272
  T1P2 GND1   GND1 TPAD-DIFF-4P-GP_DISCRET-GB3-TPA     I5 @BASEBOARD_FAB2_LIB.BASEBOARD_FAB2(SCH_1):PAGE271
  T1P2 GND2   GND2 TPAD-DIFF-4P-GP_DISCRET-GB3-TPA     I5 @BASEBOARD_FAB2_LIB.BASEBOARD_FAB2(SCH_1):PAGE271
  T1P4 GND1   GND1 TPAD-DIFF-4P-GP_DISCRET-GB3-TPA     I7 @BASEBOARD_FAB2_LIB.BASEBOARD_FAB2(SCH_1):PAGE271
  T1P4 GND2   GND2 TPAD-DIFF-4P-GP_DISCRET-GB3-TPA     I7 @BASEBOARD_FAB2_LIB.BASEBOARD_FAB2(SCH_1):PAGE271
  T1P3 GND1   GND1 TPAD-DIFF-4P-GP_DISCRET-GB3-TPA     I8 @BASEBOARD_FAB2_LIB.BASEBOARD_FAB2(SCH_1):PAGE271
  T1P3 GND2   GND2 TPAD-DIFF-4P-GP_DISCRET-GB3-TPA     I8 @BASEBOARD_FAB2_LIB.BASEBOARD_FAB2(SCH_1):PAGE271
  T1P5 GND1   GND1 TPAD-DIFF-4P-GP_DISCRET-GB3-TPA    I11 @BASEBOARD_FAB2_LIB.BASEBOARD_FAB2(SCH_1):PAGE271
  T1P5 GND2   GND2 TPAD-DIFF-4P-GP_DISCRET-GB3-TPA    I11 @BASEBOARD_FAB2_LIB.BASEBOARD_FAB2(SCH_1):PAGE271
  T1P6 GND1   GND1 TPAD-DIFF-4P-GP_DISCRET-GB3-TPA    I13 @BASEBOARD_FAB2_LIB.BASEBOARD_FAB2(SCH_1):PAGE271
  T1P6 GND2   GND2 TPAD-DIFF-4P-GP_DISCRET-GB3-TPA    I13 @BASEBOARD_FAB2_LIB.BASEBOARD_FAB2(SCH_1):PAGE271
 T1P10 GND1   GND1 TPAD-DIFF-4P-GP_DISCRET-GB3-TPA    I15 @BASEBOARD_FAB2_LIB.BASEBOARD_FAB2(SCH_1):PAGE271
 T1P10 GND2   GND2 TPAD-DIFF-4P-GP_DISCRET-GB3-TPA    I15 @BASEBOARD_FAB2_LIB.BASEBOARD_FAB2(SCH_1):PAGE271
  T1P8 GND1   GND1 TPAD-DIFF-4P-GP_DISCRET-GB3-TPA    I16 @BASEBOARD_FAB2_LIB.BASEBOARD_FAB2(SCH_1):PAGE271
  T1P8 GND2   GND2 TPAD-DIFF-4P-GP_DISCRET-GB3-TPA    I16 @BASEBOARD_FAB2_LIB.BASEBOARD_FAB2(SCH_1):PAGE271
  T1P7 GND1   GND1 TPAD-DIFF-4P-GP_DISCRET-GB3-TPA    I17 @BASEBOARD_FAB2_LIB.BASEBOARD_FAB2(SCH_1):PAGE271
  T1P7 GND2   GND2 TPAD-DIFF-4P-GP_DISCRET-GB3-TPA    I17 @BASEBOARD_FAB2_LIB.BASEBOARD_FAB2(SCH_1):PAGE271
  T1P9 GND1   GND1 TPAD-DIFF-4P-GP_DISCRET-GB3-TPA    I19 @BASEBOARD_FAB2_LIB.BASEBOARD_FAB2(SCH_1):PAGE271
  T1P9 GND2   GND2 TPAD-DIFF-4P-GP_DISCRET-GB3-TPA    I19 @BASEBOARD_FAB2_LIB.BASEBOARD_FAB2(SCH_1):PAGE271
 T1P11 GND1   GND1 TPAD-DIFF-4P-GP_DISCRET-GB3-TPA    I23 @BASEBOARD_FAB2_LIB.BASEBOARD_FAB2(SCH_1):PAGE271
 T1P11 GND2   GND2 TPAD-DIFF-4P-GP_DISCRET-GB3-TPA    I23 @BASEBOARD_FAB2_LIB.BASEBOARD_FAB2(SCH_1):PAGE271
 T1P12 GND1   GND1 TPAD-DIFF-4P-GP_DISCRET-GB3-TPA    I24 @BASEBOARD_FAB2_LIB.BASEBOARD_FAB2(SCH_1):PAGE271
 T1P12 GND2   GND2 TPAD-DIFF-4P-GP_DISCRET-GB3-TPA    I24 @BASEBOARD_FAB2_LIB.BASEBOARD_FAB2(SCH_1):PAGE271
 T1P14 GND1   GND1 TPAD-DIFF-4P-GP_DISCRET-GB3-TPA    I30 @BASEBOARD_FAB2_LIB.BASEBOARD_FAB2(SCH_1):PAGE271
 T1P14 GND2   GND2 TPAD-DIFF-4P-GP_DISCRET-GB3-TPA    I30 @BASEBOARD_FAB2_LIB.BASEBOARD_FAB2(SCH_1):PAGE271
 T1P17 GND1   GND1 TPAD-DIFF-4P-GP_DISCRET-GB3-TPA    I36 @BASEBOARD_FAB2_LIB.BASEBOARD_FAB2(SCH_1):PAGE271
 T1P17 GND2   GND2 TPAD-DIFF-4P-GP_DISCRET-GB3-TPA    I36 @BASEBOARD_FAB2_LIB.BASEBOARD_FAB2(SCH_1):PAGE271
 T1P24 GND1   GND1 TPAD-DIFF-4P-GP_DISCRET-GB3-TPA    I38 @BASEBOARD_FAB2_LIB.BASEBOARD_FAB2(SCH_1):PAGE271
 T1P24 GND2   GND2 TPAD-DIFF-4P-GP_DISCRET-GB3-TPA    I38 @BASEBOARD_FAB2_LIB.BASEBOARD_FAB2(SCH_1):PAGE271
 T1P19 GND1   GND1 TPAD-DIFF-4P-GP_DISCRET-GB3-TPA    I39 @BASEBOARD_FAB2_LIB.BASEBOARD_FAB2(SCH_1):PAGE271
 T1P19 GND2   GND2 TPAD-DIFF-4P-GP_DISCRET-GB3-TPA    I39 @BASEBOARD_FAB2_LIB.BASEBOARD_FAB2(SCH_1):PAGE271
 T1P22 GND1   GND1 TPAD-DIFF-4P-GP_DISCRET-GB3-TPA    I45 @BASEBOARD_FAB2_LIB.BASEBOARD_FAB2(SCH_1):PAGE271
 T1P22 GND2   GND2 TPAD-DIFF-4P-GP_DISCRET-GB3-TPA    I45 @BASEBOARD_FAB2_LIB.BASEBOARD_FAB2(SCH_1):PAGE271
 T1P23 GND1   GND1 TPAD-DIFF-4P-GP_DISCRET-GB3-TPA    I47 @BASEBOARD_FAB2_LIB.BASEBOARD_FAB2(SCH_1):PAGE271
 T1P23 GND2   GND2 TPAD-DIFF-4P-GP_DISCRET-GB3-TPA    I47 @BASEBOARD_FAB2_LIB.BASEBOARD_FAB2(SCH_1):PAGE271
 T1P25 GND1   GND1 TPAD-SE-2P-GP_DISCRET-GA1-TPADA    I50 @BASEBOARD_FAB2_LIB.BASEBOARD_FAB2(SCH_1):PAGE271
 T1P26 GND1   GND1 TPAD-SE-2P-GP_DISCRET-GA1-TPADA    I52 @BASEBOARD_FAB2_LIB.BASEBOARD_FAB2(SCH_1):PAGE271
 T1P27 GND1   GND1 TPAD-SE-2P-GP_DISCRET-GA1-TPADA    I54 @BASEBOARD_FAB2_LIB.BASEBOARD_FAB2(SCH_1):PAGE271
 T1P29 GND1   GND1 TPAD-SE-2P-GP_DISCRET-GA1-TPADA    I56 @BASEBOARD_FAB2_LIB.BASEBOARD_FAB2(SCH_1):PAGE271
 T1P28 GND1   GND1 TPAD-SE-2P-GP_DISCRET-GA1-TPADA    I60 @BASEBOARD_FAB2_LIB.BASEBOARD_FAB2(SCH_1):PAGE271
 T1P30 GND1   GND1 TPAD-SE-2P-GP_DISCRET-GA1-TPADA    I61 @BASEBOARD_FAB2_LIB.BASEBOARD_FAB2(SCH_1):PAGE271
 T1P34 GND1   GND1 TPAD-SE-2P-GP_DISCRET-GA1-TPADA    I62 @BASEBOARD_FAB2_LIB.BASEBOARD_FAB2(SCH_1):PAGE271
 T1P36 GND1   GND1 TPAD-SE-2P-GP_DISCRET-GA1-TPADA    I63 @BASEBOARD_FAB2_LIB.BASEBOARD_FAB2(SCH_1):PAGE271
 T1P35 GND1   GND1 TPAD-SE-2P-GP_DISCRET-GA1-TPADA    I67 @BASEBOARD_FAB2_LIB.BASEBOARD_FAB2(SCH_1):PAGE271
 T1P31 GND1   GND1 TPAD-SE-2P-GP_DISCRET-GA1-TPADA    I71 @BASEBOARD_FAB2_LIB.BASEBOARD_FAB2(SCH_1):PAGE271
 T1P32 GND1   GND1 TPAD-SE-2P-GP_DISCRET-GA1-TPADA    I72 @BASEBOARD_FAB2_LIB.BASEBOARD_FAB2(SCH_1):PAGE271
 T1P33 GND1   GND1 TPAD-SE-2P-GP_DISCRET-GA1-TPADA    I73 @BASEBOARD_FAB2_LIB.BASEBOARD_FAB2(SCH_1):PAGE271
 R1W41    1      A RES_0402-4.75K,1%,1/16W,CHIP,GA   I129 @BASEBOARD_FAB2_LIB.BASEBOARD_FAB2(SCH_1):PAGE188
 R8C21    2      B RES_0402-100.0,1%,1/16W,CHIP,GA   I275 @BASEBOARD_FAB2_LIB.BASEBOARD_FAB2(SCH_1):PAGE120
 R8D40    2      B RES_0402-20.0K,1%,1/16W,CHIP,GA   I130 @BASEBOARD_FAB2_LIB.BASEBOARD_FAB2(SCH_1):PAGE196
  C8C1    2      B CAP_0402LF-33.0PF,50V,5%,COG,AA   I178 @BASEBOARD_FAB2_LIB.BASEBOARD_FAB2(SCH_1):PAGE118
  C8C2    2      B CAP_0402LF-33.0PF,50V,5%,COG,AA   I179 @BASEBOARD_FAB2_LIB.BASEBOARD_FAB2(SCH_1):PAGE118
  R9T8    2      B RES_0402-0.0,5%,1/16W,CHIP,G21A   I137 @BASEBOARD_FAB2_LIB.BASEBOARD_FAB2(SCH_1):PAGE181
C25W101    2      B CAP_A_0402V-0.1UF,16V,10%,X7R,A    I79 @BASEBOARD_FAB2_LIB.BASEBOARD_FAB2(SCH_1):PAGE269
  U8W2    2    GND NC7SB3157_SMLF-IC,C99406-001    I66 @BASEBOARD_FAB2_LIB.BASEBOARD_FAB2(SCH_1):PAGE245
  C8W6    2      B CAP_A_0402V-0.01UF,25V,10%,X7RA    I71 @BASEBOARD_FAB2_LIB.BASEBOARD_FAB2(SCH_1):PAGE245
  C8W5    2      B CAP_A_0402V-1.0UF,6.3V,10%,X6SA    I74 @BASEBOARD_FAB2_LIB.BASEBOARD_FAB2(SCH_1):PAGE245
 R1T10    2      B RES_0402-1.00K,1%,1/16W,CHIP,GA   I101 @BASEBOARD_FAB2_LIB.BASEBOARD_FAB2(SCH_1):PAGE164
 U6W12    2    GND NC7SB3157_SMLF-IC,C99406-001   I182 @BASEBOARD_FAB2_LIB.BASEBOARD_FAB2(SCH_1):PAGE176

GND_LAN_TRCT1234_C @BASEBOARD_FAB2_LIB.BASEBOARD_FAB2(SCH_1):GND_LAN_TRCT1234_C
  C9G4    1      A CAP_A_0402V-0.1UF,16V,10%,X7R,A    I46 @BASEBOARD_FAB2_LIB.BASEBOARD_FAB2(SCH_1):PAGE141
  C9G6    1      A CAP_A_0402V-0.1UF,16V,10%,X7R,A    I47 @BASEBOARD_FAB2_LIB.BASEBOARD_FAB2(SCH_1):PAGE141
  C9G5    1      A CAP_0402-1.0UF,16V,10%,X7S,G71A    I48 @BASEBOARD_FAB2_LIB.BASEBOARD_FAB2(SCH_1):PAGE141
 JA9G1   R1     R1 SKT-RJ45-LED-XFOR-1-GP_SOCKET-A   I129 @BASEBOARD_FAB2_LIB.BASEBOARD_FAB2(SCH_1):PAGE141
 JA9G1  R11    R11 SKT-RJ45-LED-XFOR-1-GP_SOCKET-A   I129 @BASEBOARD_FAB2_LIB.BASEBOARD_FAB2(SCH_1):PAGE141

GPIOS7 @BASEBOARD_FAB2_LIB.BASEBOARD_FAB2(SCH_1):GPIOS7
 U25W4 AA20 GPIOS7_VPOB9 AST2520A1-GP-GP_ASIC2-GB1-AST2A   I104 @BASEBOARD_FAB2_LIB.BASEBOARD_FAB2(SCH_1):PAGE146
R25W100    2      B RES_0402-4.75K,1%,1/16W,CHIP,GA   I211 @BASEBOARD_FAB2_LIB.BASEBOARD_FAB2(SCH_1):PAGE150

HSC_SMBUS_SWITCH_EN @BASEBOARD_FAB2_LIB.BASEBOARD_FAB2(SCH_1):HSC_SMBUS_SWITCH_EN
 U25W4  P18 GPIOS3_VPOB5_SALT6 AST2520A1-GP-GP_ASIC2-GB1-AST2A   I104 @BASEBOARD_FAB2_LIB.BASEBOARD_FAB2(SCH_1):PAGE146
 R6W28    2      B RES_0402-4.75K,1%,1/16W,CHIP,GA   I112 @BASEBOARD_FAB2_LIB.BASEBOARD_FAB2(SCH_1):PAGE247
  U6W2    5     EN TCA9517DGKR-GP_DISCRET-G8-TCA9A   I118 @BASEBOARD_FAB2_LIB.BASEBOARD_FAB2(SCH_1):PAGE247

H_CPU0_ABC_MEMHOT_LVT3_R_N @BASEBOARD_FAB2_LIB.BASEBOARD_FAB2(SCH_1):H_CPU0_ABC_MEMHOT_LVT3_R_N
  U9G1    9     A3 GTL2014_SM-IC,D66151-001     I1 @BASEBOARD_FAB2_LIB.BASEBOARD_FAB2(SCH_1):PAGE152
 R1U59    1      A RES_0402-0.0,5%,1/16W,CHIP,G21A    I74 @BASEBOARD_FAB2_LIB.BASEBOARD_FAB2(SCH_1):PAGE152

H_CPU0_BMCINIT @BASEBOARD_FAB2_LIB.BASEBOARD_FAB2(SCH_1):H_CPU0_BMCINIT
  U5D1 BD23 BMCINIT SKX_EXT_B_BGA1-IC,TBD   I259 @BASEBOARD_FAB2_LIB.BASEBOARD_FAB2(SCH_1):PAGE21
  R6D7    2      B RES_0402-240,1.0%,1/16W,EMPTY,A    I31 @BASEBOARD_FAB2_LIB.BASEBOARD_FAB2(SCH_1):PAGE90
 R6D16    2      B RES_0402-0.0,5%,1/16W,EMPTY,G2A   I299 @BASEBOARD_FAB2_LIB.BASEBOARD_FAB2(SCH_1):PAGE156

H_CPU0_CATERR_G_N @BASEBOARD_FAB2_LIB.BASEBOARD_FAB2(SCH_1):H_CPU0_CATERR_G_N
  U5D1 AL14 CATERR_N SKX_EXT_B_BGA1-IC,TBD   I259 @BASEBOARD_FAB2_LIB.BASEBOARD_FAB2(SCH_1):PAGE21
 R3P59    1      A RES_0402-0.0,5%,1/16W,CHIP,G21A    I97 @BASEBOARD_FAB2_LIB.BASEBOARD_FAB2(SCH_1):PAGE92
  R4R2    2      B RES_0402-150.0,1%,1/16W,CHIP,GA   I101 @BASEBOARD_FAB2_LIB.BASEBOARD_FAB2(SCH_1):PAGE92

H_CPU0_DEF_MEMHOT_LVT3_R_N @BASEBOARD_FAB2_LIB.BASEBOARD_FAB2(SCH_1):H_CPU0_DEF_MEMHOT_LVT3_R_N
  U9G1   10     A2 GTL2014_SM-IC,D66151-001     I1 @BASEBOARD_FAB2_LIB.BASEBOARD_FAB2(SCH_1):PAGE152
 R9G33    1      A RES_0402-0.0,5%,1/16W,CHIP,G21A    I73 @BASEBOARD_FAB2_LIB.BASEBOARD_FAB2(SCH_1):PAGE152

H_CPU0_ERR0_G_N @BASEBOARD_FAB2_LIB.BASEBOARD_FAB2(SCH_1):H_CPU0_ERR0_G_N
  U5D1 AJ12 ERROR_N<0> SKX_EXT_B_BGA1-IC,TBD   I259 @BASEBOARD_FAB2_LIB.BASEBOARD_FAB2(SCH_1):PAGE21
 R2T17    1      A RES_0402-0.0,5%,1/16W,CHIP,G21A    I23 @BASEBOARD_FAB2_LIB.BASEBOARD_FAB2(SCH_1):PAGE93

H_CPU0_ERR1_G_N @BASEBOARD_FAB2_LIB.BASEBOARD_FAB2(SCH_1):H_CPU0_ERR1_G_N
  U5D1 AK11 ERROR_N<1> SKX_EXT_B_BGA1-IC,TBD   I259 @BASEBOARD_FAB2_LIB.BASEBOARD_FAB2(SCH_1):PAGE21
 R2T32    1      A RES_0402-0.0,5%,1/16W,CHIP,G21A    I15 @BASEBOARD_FAB2_LIB.BASEBOARD_FAB2(SCH_1):PAGE93

H_CPU0_ERR2_G_N @BASEBOARD_FAB2_LIB.BASEBOARD_FAB2(SCH_1):H_CPU0_ERR2_G_N
  U5D1 AL12 ERROR_N<2> SKX_EXT_B_BGA1-IC,TBD   I259 @BASEBOARD_FAB2_LIB.BASEBOARD_FAB2(SCH_1):PAGE21
 R2T40    1      A RES_0402-0.0,5%,1/16W,CHIP,G21A    I93 @BASEBOARD_FAB2_LIB.BASEBOARD_FAB2(SCH_1):PAGE92

H_CPU0_FAST_WAKE @BASEBOARD_FAB2_LIB.BASEBOARD_FAB2(SCH_1):H_CPU0_FAST_WAKE
  R2T5    2      B RES_0402-1.00K,1%,1/16W,CHIP,GA   I326 @BASEBOARD_FAB2_LIB.BASEBOARD_FAB2(SCH_1):PAGE157
  Q2T1    3      C NPN_SM-MMBT3904,IC,C52245-001   I330 @BASEBOARD_FAB2_LIB.BASEBOARD_FAB2(SCH_1):PAGE157
  Q2T2    1   GATE FET_N_SOT23LF-2N7002,FET,C7925A   I340 @BASEBOARD_FAB2_LIB.BASEBOARD_FAB2(SCH_1):PAGE157

H_CPU0_FAST_WAKE_B_N @BASEBOARD_FAB2_LIB.BASEBOARD_FAB2(SCH_1):H_CPU0_FAST_WAKE_B_N
  Q2T1    1      B NPN_SM-MMBT3904,IC,C52245-001   I330 @BASEBOARD_FAB2_LIB.BASEBOARD_FAB2(SCH_1):PAGE157
  R4R1    2      B RES_0402-1.00K,1%,1/16W,CHIP,GA   I368 @BASEBOARD_FAB2_LIB.BASEBOARD_FAB2(SCH_1):PAGE157

H_CPU0_FAST_WAKE_LVT3_N @BASEBOARD_FAB2_LIB.BASEBOARD_FAB2(SCH_1):H_CPU0_FAST_WAKE_LVT3_N
  U7C1 BV47 GPP_D10_SSATA_DEVSLP4 LBG_CORE_QAT_EXT_D_BGA1-IC,H91A   I115 @BASEBOARD_FAB2_LIB.BASEBOARD_FAB2(SCH_1):PAGE119
  R2T7    2      B RES_0402-1.00K,1%,1/16W,CHIP,GA   I327 @BASEBOARD_FAB2_LIB.BASEBOARD_FAB2(SCH_1):PAGE157
  Q2T2    3    DRN FET_N_SOT23LF-2N7002,FET,C7925A   I340 @BASEBOARD_FAB2_LIB.BASEBOARD_FAB2(SCH_1):PAGE157
 U25W4  K18 GPIOB3 AST2520A1-GP-GP_ASIC2-GB1-AST2A    I95 @BASEBOARD_FAB2_LIB.BASEBOARD_FAB2(SCH_1):PAGE144

H_CPU0_FAST_WAKE_N @BASEBOARD_FAB2_LIB.BASEBOARD_FAB2(SCH_1):H_CPU0_FAST_WAKE_N
  U5D1 AF15 PM_FAST_WAKE_N SKX_EXT_B_BGA1-IC,TBD   I259 @BASEBOARD_FAB2_LIB.BASEBOARD_FAB2(SCH_1):PAGE21
 R3D18    1      A RES_0402-0.0,5%,1/16W,CHIP,G21A    I33 @BASEBOARD_FAB2_LIB.BASEBOARD_FAB2(SCH_1):PAGE97
  R4R4    2      B RES_0402-150.0,1%,1/16W,CHIP,GA    I42 @BASEBOARD_FAB2_LIB.BASEBOARD_FAB2(SCH_1):PAGE97
  R4R1    1      A RES_0402-1.00K,1%,1/16W,CHIP,GA   I368 @BASEBOARD_FAB2_LIB.BASEBOARD_FAB2(SCH_1):PAGE157

H_CPU0_FIVR_FAULT_G @BASEBOARD_FAB2_LIB.BASEBOARD_FAB2(SCH_1):H_CPU0_FIVR_FAULT_G
  U5D1 AU14 FIVR_FAULT SKX_EXT_B_BGA1-IC,TBD   I204 @BASEBOARD_FAB2_LIB.BASEBOARD_FAB2(SCH_1):PAGE22
  U7D2    3     B1 GTL2014_SM-IC,D66151-001    I32 @BASEBOARD_FAB2_LIB.BASEBOARD_FAB2(SCH_1):PAGE92

H_CPU0_MEMABC_MEMHOT @BASEBOARD_FAB2_LIB.BASEBOARD_FAB2(SCH_1):H_CPU0_MEMABC_MEMHOT
  Q3U1    6 DRAIN<0> FET_N_DUAL_SMLF-NTJD4001N,FET,A    I49 @BASEBOARD_FAB2_LIB.BASEBOARD_FAB2(SCH_1):PAGE94
  R7G7    2      B RES_0402-4.75K,1%,1/16W,CHIP,GA    I51 @BASEBOARD_FAB2_LIB.BASEBOARD_FAB2(SCH_1):PAGE94
  Q3U1    5 GATE<0> FET_N_DUAL_SMLF-NTJD4001N,FET,A    I89 @BASEBOARD_FAB2_LIB.BASEBOARD_FAB2(SCH_1):PAGE94

H_CPU0_MEMABC_MEMHOT_G_N @BASEBOARD_FAB2_LIB.BASEBOARD_FAB2(SCH_1):H_CPU0_MEMABC_MEMHOT_G_N
  U5D1 AH13 MEM_HOT_C012_N SKX_EXT_B_BGA1-IC,TBD   I259 @BASEBOARD_FAB2_LIB.BASEBOARD_FAB2(SCH_1):PAGE21
  Q3U1    3 DRAIN<0> FET_N_DUAL_SMLF-NTJD4001N,FET,A    I89 @BASEBOARD_FAB2_LIB.BASEBOARD_FAB2(SCH_1):PAGE94
  Q2U1    6 DRAIN<0> FET_N_DUAL_SMLF-NTJD4001N,FET,A    I28 @BASEBOARD_FAB2_LIB.BASEBOARD_FAB2(SCH_1):PAGE95
 R9G34    1      A RES_0402-0.0,5%,1/16W,CHIP,G21A    I45 @BASEBOARD_FAB2_LIB.BASEBOARD_FAB2(SCH_1):PAGE152
 R2U51    2      B RES_0402-0.0,5%,1/16W,EMPTY,G2A    I51 @BASEBOARD_FAB2_LIB.BASEBOARD_FAB2(SCH_1):PAGE152
 R2U40    2      B RES_0402-150.0,1%,1/16W,CHIP,GA    I53 @BASEBOARD_FAB2_LIB.BASEBOARD_FAB2(SCH_1):PAGE152
 R4P17    1      A RES_0402-150.0,1%,1/16W,CHIP,GA    I58 @BASEBOARD_FAB2_LIB.BASEBOARD_FAB2(SCH_1):PAGE152

H_CPU0_MEMABC_MEMHOT_G_PCH_N @BASEBOARD_FAB2_LIB.BASEBOARD_FAB2(SCH_1):H_CPU0_MEMABC_MEMHOT_G_PCH_N
 R2U51    1      A RES_0402-0.0,5%,1/16W,EMPTY,G2A    I51 @BASEBOARD_FAB2_LIB.BASEBOARD_FAB2(SCH_1):PAGE152
 R2U49    1      A RES_0402-0.0,5%,1/16W,EMPTY,G2A    I66 @BASEBOARD_FAB2_LIB.BASEBOARD_FAB2(SCH_1):PAGE152

H_CPU0_MEMABC_MEMHOT_G_R_N @BASEBOARD_FAB2_LIB.BASEBOARD_FAB2(SCH_1):H_CPU0_MEMABC_MEMHOT_G_R_N
  U9G1    6     B3 GTL2014_SM-IC,D66151-001     I1 @BASEBOARD_FAB2_LIB.BASEBOARD_FAB2(SCH_1):PAGE152
 R9G34    2      B RES_0402-0.0,5%,1/16W,CHIP,G21A    I45 @BASEBOARD_FAB2_LIB.BASEBOARD_FAB2(SCH_1):PAGE152

H_CPU0_MEMABC_MEMHOT_LVT3_BMC_N @BASEBOARD_FAB2_LIB.BASEBOARD_FAB2(SCH_1):H_CPU0_MEMABC_MEMHOT_LVT3_BMC_N
 R2U47    2      B RES_0402-0.0,5%,1/16W,CHIP,G21A    I79 @BASEBOARD_FAB2_LIB.BASEBOARD_FAB2(SCH_1):PAGE152
 U25W4   H5 ADC12_GPIX4 AST2520A1-GP-GP_ASIC2-GB1-AST2A   I106 @BASEBOARD_FAB2_LIB.BASEBOARD_FAB2(SCH_1):PAGE147

H_CPU0_MEMABC_MEMHOT_LVT3_K_N @BASEBOARD_FAB2_LIB.BASEBOARD_FAB2(SCH_1):H_CPU0_MEMABC_MEMHOT_LVT3_K_N
 R1U46    1      A RES_0402-33.2,1%,1/16W,CHIP,G2A     I6 @BASEBOARD_FAB2_LIB.BASEBOARD_FAB2(SCH_1):PAGE152
 R2U49    2      B RES_0402-0.0,5%,1/16W,EMPTY,G2A    I66 @BASEBOARD_FAB2_LIB.BASEBOARD_FAB2(SCH_1):PAGE152
 R1U59    2      B RES_0402-0.0,5%,1/16W,CHIP,G21A    I74 @BASEBOARD_FAB2_LIB.BASEBOARD_FAB2(SCH_1):PAGE152

H_CPU0_MEMABC_MEMHOT_LVT3_N @BASEBOARD_FAB2_LIB.BASEBOARD_FAB2(SCH_1):H_CPU0_MEMABC_MEMHOT_LVT3_N
 R1U46    2      B RES_0402-33.2,1%,1/16W,CHIP,G2A     I6 @BASEBOARD_FAB2_LIB.BASEBOARD_FAB2(SCH_1):PAGE152
 R2U47    1      A RES_0402-0.0,5%,1/16W,CHIP,G21A    I79 @BASEBOARD_FAB2_LIB.BASEBOARD_FAB2(SCH_1):PAGE152
 R3N30    1      A RES_0402-0.0,5%,1/16W,EMPTY,G2A    I95 @BASEBOARD_FAB2_LIB.BASEBOARD_FAB2(SCH_1):PAGE152

H_CPU0_MEMABC_MEMHOT_PCH_N @BASEBOARD_FAB2_LIB.BASEBOARD_FAB2(SCH_1):H_CPU0_MEMABC_MEMHOT_PCH_N
  U7C1  Y15 GPP_L12_TESTCH1_D1 LBG_CORE_QAT_EXT_D_BGA1-IC,H91A    I34 @BASEBOARD_FAB2_LIB.BASEBOARD_FAB2(SCH_1):PAGE121
 R3N30    2      B RES_0402-0.0,5%,1/16W,EMPTY,G2A    I95 @BASEBOARD_FAB2_LIB.BASEBOARD_FAB2(SCH_1):PAGE152

H_CPU0_MEMDEF_MEMHOT @BASEBOARD_FAB2_LIB.BASEBOARD_FAB2(SCH_1):H_CPU0_MEMDEF_MEMHOT
  Q7E1    6 DRAIN<0> FET_N_DUAL_SMLF-NTJD4001N,FET,A    I60 @BASEBOARD_FAB2_LIB.BASEBOARD_FAB2(SCH_1):PAGE94
  Q7E1    5 GATE<0> FET_N_DUAL_SMLF-NTJD4001N,FET,A    I64 @BASEBOARD_FAB2_LIB.BASEBOARD_FAB2(SCH_1):PAGE94
  R3R4    2      B RES_0402-4.75K,1%,1/16W,CHIP,GA    I66 @BASEBOARD_FAB2_LIB.BASEBOARD_FAB2(SCH_1):PAGE94

H_CPU0_MEMDEF_MEMHOT_G_N @BASEBOARD_FAB2_LIB.BASEBOARD_FAB2(SCH_1):H_CPU0_MEMDEF_MEMHOT_G_N
  U5D1 AF13 MEM_HOT_C345_N SKX_EXT_B_BGA1-IC,TBD   I259 @BASEBOARD_FAB2_LIB.BASEBOARD_FAB2(SCH_1):PAGE21
  Q7E1    3 DRAIN<0> FET_N_DUAL_SMLF-NTJD4001N,FET,A    I64 @BASEBOARD_FAB2_LIB.BASEBOARD_FAB2(SCH_1):PAGE94
  Q2U1    3 DRAIN<0> FET_N_DUAL_SMLF-NTJD4001N,FET,A   I113 @BASEBOARD_FAB2_LIB.BASEBOARD_FAB2(SCH_1):PAGE95
 R1U58    1      A RES_0402-0.0,5%,1/16W,CHIP,G21A    I49 @BASEBOARD_FAB2_LIB.BASEBOARD_FAB2(SCH_1):PAGE152
 R1U56    2      B RES_0402-0.0,5%,1/16W,EMPTY,G2A    I50 @BASEBOARD_FAB2_LIB.BASEBOARD_FAB2(SCH_1):PAGE152
 R2U41    2      B RES_0402-150.0,1%,1/16W,CHIP,GA    I54 @BASEBOARD_FAB2_LIB.BASEBOARD_FAB2(SCH_1):PAGE152
 R4P20    1      A RES_0402-150.0,1%,1/16W,CHIP,GA    I59 @BASEBOARD_FAB2_LIB.BASEBOARD_FAB2(SCH_1):PAGE152

H_CPU0_MEMDEF_MEMHOT_G_PCH_N @BASEBOARD_FAB2_LIB.BASEBOARD_FAB2(SCH_1):H_CPU0_MEMDEF_MEMHOT_G_PCH_N
 R9G27    1      A RES_0402-0.0,5%,1/16W,EMPTY,G2A    I47 @BASEBOARD_FAB2_LIB.BASEBOARD_FAB2(SCH_1):PAGE152
 R1U56    1      A RES_0402-0.0,5%,1/16W,EMPTY,G2A    I50 @BASEBOARD_FAB2_LIB.BASEBOARD_FAB2(SCH_1):PAGE152

H_CPU0_MEMDEF_MEMHOT_G_R_N @BASEBOARD_FAB2_LIB.BASEBOARD_FAB2(SCH_1):H_CPU0_MEMDEF_MEMHOT_G_R_N
  U9G1    5     B2 GTL2014_SM-IC,D66151-001     I1 @BASEBOARD_FAB2_LIB.BASEBOARD_FAB2(SCH_1):PAGE152
 R1U58    2      B RES_0402-0.0,5%,1/16W,CHIP,G21A    I49 @BASEBOARD_FAB2_LIB.BASEBOARD_FAB2(SCH_1):PAGE152

H_CPU0_MEMDEF_MEMHOT_LVT3_BMC_N @BASEBOARD_FAB2_LIB.BASEBOARD_FAB2(SCH_1):H_CPU0_MEMDEF_MEMHOT_LVT3_BMC_N
 R9G29    2      B RES_0402-0.0,5%,1/16W,CHIP,G21A    I92 @BASEBOARD_FAB2_LIB.BASEBOARD_FAB2(SCH_1):PAGE152
 U25W4   G1 ADC13_GPIX5 AST2520A1-GP-GP_ASIC2-GB1-AST2A   I106 @BASEBOARD_FAB2_LIB.BASEBOARD_FAB2(SCH_1):PAGE147

H_CPU0_MEMDEF_MEMHOT_LVT3_K_N @BASEBOARD_FAB2_LIB.BASEBOARD_FAB2(SCH_1):H_CPU0_MEMDEF_MEMHOT_LVT3_K_N
 R9G31    1      A RES_0402-33.2,1%,1/16W,CHIP,G2A    I14 @BASEBOARD_FAB2_LIB.BASEBOARD_FAB2(SCH_1):PAGE152
 R9G27    2      B RES_0402-0.0,5%,1/16W,EMPTY,G2A    I47 @BASEBOARD_FAB2_LIB.BASEBOARD_FAB2(SCH_1):PAGE152
 R9G33    2      B RES_0402-0.0,5%,1/16W,CHIP,G21A    I73 @BASEBOARD_FAB2_LIB.BASEBOARD_FAB2(SCH_1):PAGE152

H_CPU0_MEMDEF_MEMHOT_LVT3_N @BASEBOARD_FAB2_LIB.BASEBOARD_FAB2(SCH_1):H_CPU0_MEMDEF_MEMHOT_LVT3_N
 R9G31    2      B RES_0402-33.2,1%,1/16W,CHIP,G2A    I14 @BASEBOARD_FAB2_LIB.BASEBOARD_FAB2(SCH_1):PAGE152
 R9G29    1      A RES_0402-0.0,5%,1/16W,CHIP,G21A    I92 @BASEBOARD_FAB2_LIB.BASEBOARD_FAB2(SCH_1):PAGE152
 R9G30    1      A RES_0402-0.0,5%,1/16W,EMPTY,G2A    I98 @BASEBOARD_FAB2_LIB.BASEBOARD_FAB2(SCH_1):PAGE152

H_CPU0_MEMDEF_MEMHOT_PCH_N @BASEBOARD_FAB2_LIB.BASEBOARD_FAB2(SCH_1):H_CPU0_MEMDEF_MEMHOT_PCH_N
  U7C1 AD13 GPP_L13_TESTCH1_D2 LBG_CORE_QAT_EXT_D_BGA1-IC,H91A    I34 @BASEBOARD_FAB2_LIB.BASEBOARD_FAB2(SCH_1):PAGE121
 R9G30    2      B RES_0402-0.0,5%,1/16W,EMPTY,G2A    I98 @BASEBOARD_FAB2_LIB.BASEBOARD_FAB2(SCH_1):PAGE152

H_CPU0_MSMI_G_N @BASEBOARD_FAB2_LIB.BASEBOARD_FAB2(SCH_1):H_CPU0_MSMI_G_N
  U5D1 AN20 MSMI_N SKX_EXT_B_BGA1-IC,TBD   I259 @BASEBOARD_FAB2_LIB.BASEBOARD_FAB2(SCH_1):PAGE21
  R6D9    2      B RES_0402-150.0,1%,1/16W,CHIP,GA    I64 @BASEBOARD_FAB2_LIB.BASEBOARD_FAB2(SCH_1):PAGE92
 R7D27    1      A RES_0402-0.0,5%,1/16W,CHIP,G21A    I68 @BASEBOARD_FAB2_LIB.BASEBOARD_FAB2(SCH_1):PAGE92

H_CPU0_PROCHOT_G_N @BASEBOARD_FAB2_LIB.BASEBOARD_FAB2(SCH_1):H_CPU0_PROCHOT_G_N
  U5D1 AC16 PROCHOT_N SKX_EXT_B_BGA1-IC,TBD   I259 @BASEBOARD_FAB2_LIB.BASEBOARD_FAB2(SCH_1):PAGE21
  R4R3    2      B RES_0402-150.0,1%,1/16W,CHIP,GA    I79 @BASEBOARD_FAB2_LIB.BASEBOARD_FAB2(SCH_1):PAGE93
 R2T60    1      A RES_0402-0.0,5%,1/16W,CHIP,G21A   I103 @BASEBOARD_FAB2_LIB.BASEBOARD_FAB2(SCH_1):PAGE93
 R2T59    1      A RES_0402-0.0,5%,1/16W,EMPTY,G2A   I107 @BASEBOARD_FAB2_LIB.BASEBOARD_FAB2(SCH_1):PAGE93
 R2T72    2      B RES_0402-150.0,1%,1/16W,CHIP,GA   I143 @BASEBOARD_FAB2_LIB.BASEBOARD_FAB2(SCH_1):PAGE93
  Q7E3    6 DRAIN<0> FET_N_DUAL_SMLF-NTJD4001N,FET,A    I52 @BASEBOARD_FAB2_LIB.BASEBOARD_FAB2(SCH_1):PAGE95
  Q7E5    3 DRAIN<0> FET_N_DUAL_SMLF-NTJD4001N,FET,A    I59 @BASEBOARD_FAB2_LIB.BASEBOARD_FAB2(SCH_1):PAGE95

H_CPU0_PROCHOT_G_PCH_N @BASEBOARD_FAB2_LIB.BASEBOARD_FAB2(SCH_1):H_CPU0_PROCHOT_G_PCH_N
 R2T59    2      B RES_0402-0.0,5%,1/16W,EMPTY,G2A   I107 @BASEBOARD_FAB2_LIB.BASEBOARD_FAB2(SCH_1):PAGE93
 R2T71    2      B RES_0402-0.0,5%,1/16W,EMPTY,G2A   I109 @BASEBOARD_FAB2_LIB.BASEBOARD_FAB2(SCH_1):PAGE93

H_CPU0_PROCHOT_G_R_N @BASEBOARD_FAB2_LIB.BASEBOARD_FAB2(SCH_1):H_CPU0_PROCHOT_G_R_N
  U2T4    3     B1 GTL2014_SM-IC,D66151-001    I30 @BASEBOARD_FAB2_LIB.BASEBOARD_FAB2(SCH_1):PAGE93
 R2T60    2      B RES_0402-0.0,5%,1/16W,CHIP,G21A   I103 @BASEBOARD_FAB2_LIB.BASEBOARD_FAB2(SCH_1):PAGE93

H_CPU0_THERMTRIP_G_N @BASEBOARD_FAB2_LIB.BASEBOARD_FAB2(SCH_1):H_CPU0_THERMTRIP_G_N
  U5D1 AB15 THERMTRIP_N SKX_EXT_B_BGA1-IC,TBD   I259 @BASEBOARD_FAB2_LIB.BASEBOARD_FAB2(SCH_1):PAGE21
  R7E2    2      B RES_0402-75,1.0%,1/16W,CHIP,G2A    I19 @BASEBOARD_FAB2_LIB.BASEBOARD_FAB2(SCH_1):PAGE92
  U7D2    6     B3 GTL2014_SM-IC,D66151-001    I32 @BASEBOARD_FAB2_LIB.BASEBOARD_FAB2(SCH_1):PAGE92

H_CPU1_BMCINIT @BASEBOARD_FAB2_LIB.BASEBOARD_FAB2(SCH_1):H_CPU1_BMCINIT
  U2D1 BD23 BMCINIT SKX_EXT_B_BGA1-IC,TBD   I172 @BASEBOARD_FAB2_LIB.BASEBOARD_FAB2(SCH_1):PAGE55
 R3D16    2      B RES_0402-240,1.0%,1/16W,EMPTY,A    I24 @BASEBOARD_FAB2_LIB.BASEBOARD_FAB2(SCH_1):PAGE90
 R3D31    2      B RES_0402-0.0,5%,1/16W,EMPTY,G2A   I300 @BASEBOARD_FAB2_LIB.BASEBOARD_FAB2(SCH_1):PAGE156

H_CPU1_CATERR_G_N @BASEBOARD_FAB2_LIB.BASEBOARD_FAB2(SCH_1):H_CPU1_CATERR_G_N
  U2D1 AL14 CATERR_N SKX_EXT_B_BGA1-IC,TBD   I172 @BASEBOARD_FAB2_LIB.BASEBOARD_FAB2(SCH_1):PAGE55
 R3P58    1      A RES_0402-0.0,5%,1/16W,CHIP,G21A    I98 @BASEBOARD_FAB2_LIB.BASEBOARD_FAB2(SCH_1):PAGE92
 R7P18    2      B RES_0402-150.0,1%,1/16W,CHIP,GA   I100 @BASEBOARD_FAB2_LIB.BASEBOARD_FAB2(SCH_1):PAGE92

H_CPU1_ERR0_G_N @BASEBOARD_FAB2_LIB.BASEBOARD_FAB2(SCH_1):H_CPU1_ERR0_G_N
  U2D1 AJ12 ERROR_N<0> SKX_EXT_B_BGA1-IC,TBD   I172 @BASEBOARD_FAB2_LIB.BASEBOARD_FAB2(SCH_1):PAGE55
 R2T20    1      A RES_0402-0.0,5%,1/16W,CHIP,G21A    I16 @BASEBOARD_FAB2_LIB.BASEBOARD_FAB2(SCH_1):PAGE93

H_CPU1_ERR1_G_N @BASEBOARD_FAB2_LIB.BASEBOARD_FAB2(SCH_1):H_CPU1_ERR1_G_N
  U2D1 AK11 ERROR_N<1> SKX_EXT_B_BGA1-IC,TBD   I172 @BASEBOARD_FAB2_LIB.BASEBOARD_FAB2(SCH_1):PAGE55
 R2T27    1      A RES_0402-0.0,5%,1/16W,CHIP,G21A    I13 @BASEBOARD_FAB2_LIB.BASEBOARD_FAB2(SCH_1):PAGE93

H_CPU1_ERR2_G_N @BASEBOARD_FAB2_LIB.BASEBOARD_FAB2(SCH_1):H_CPU1_ERR2_G_N
  U2D1 AL12 ERROR_N<2> SKX_EXT_B_BGA1-IC,TBD   I172 @BASEBOARD_FAB2_LIB.BASEBOARD_FAB2(SCH_1):PAGE55
 R2T44    1      A RES_0402-0.0,5%,1/16W,CHIP,G21A    I92 @BASEBOARD_FAB2_LIB.BASEBOARD_FAB2(SCH_1):PAGE92

H_CPU1_FAST_WAKE_N @BASEBOARD_FAB2_LIB.BASEBOARD_FAB2(SCH_1):H_CPU1_FAST_WAKE_N
  U2D1 AF15 PM_FAST_WAKE_N SKX_EXT_B_BGA1-IC,TBD   I172 @BASEBOARD_FAB2_LIB.BASEBOARD_FAB2(SCH_1):PAGE55
 R3D18    2      B RES_0402-0.0,5%,1/16W,CHIP,G21A    I33 @BASEBOARD_FAB2_LIB.BASEBOARD_FAB2(SCH_1):PAGE97
 R7P20    2      B RES_0402-150.0,1%,1/16W,CHIP,GA    I44 @BASEBOARD_FAB2_LIB.BASEBOARD_FAB2(SCH_1):PAGE97

H_CPU1_FIVR_FAULT_G @BASEBOARD_FAB2_LIB.BASEBOARD_FAB2(SCH_1):H_CPU1_FIVR_FAULT_G
  U2D1 AU14 FIVR_FAULT SKX_EXT_B_BGA1-IC,TBD   I169 @BASEBOARD_FAB2_LIB.BASEBOARD_FAB2(SCH_1):PAGE56
  U3P2    3     B1 GTL2014_SM-IC,D66151-001     I1 @BASEBOARD_FAB2_LIB.BASEBOARD_FAB2(SCH_1):PAGE92
  R3R2    1      A RES_0402-1.00K,1%,1/16W,CHIP,GA    I75 @BASEBOARD_FAB2_LIB.BASEBOARD_FAB2(SCH_1):PAGE92

H_CPU1_GHJ_MEMHOT_LVT3_R_N @BASEBOARD_FAB2_LIB.BASEBOARD_FAB2(SCH_1):H_CPU1_GHJ_MEMHOT_LVT3_R_N
  U9G1   12     A1 GTL2014_SM-IC,D66151-001     I1 @BASEBOARD_FAB2_LIB.BASEBOARD_FAB2(SCH_1):PAGE152
 R9G32    1      A RES_0402-0.0,5%,1/16W,CHIP,G21A    I72 @BASEBOARD_FAB2_LIB.BASEBOARD_FAB2(SCH_1):PAGE152

H_CPU1_KLM_MEMHOT_LVT3_R_N @BASEBOARD_FAB2_LIB.BASEBOARD_FAB2(SCH_1):H_CPU1_KLM_MEMHOT_LVT3_R_N
  U9G1   13     A0 GTL2014_SM-IC,D66151-001     I1 @BASEBOARD_FAB2_LIB.BASEBOARD_FAB2(SCH_1):PAGE152
 R9G28    1      A RES_0402-0.0,5%,1/16W,CHIP,G21A    I71 @BASEBOARD_FAB2_LIB.BASEBOARD_FAB2(SCH_1):PAGE152

H_CPU1_MEMGHJ_MEMHOT @BASEBOARD_FAB2_LIB.BASEBOARD_FAB2(SCH_1):H_CPU1_MEMGHJ_MEMHOT
  Q7E2    6 DRAIN<0> FET_N_DUAL_SMLF-NTJD4001N,FET,A    I69 @BASEBOARD_FAB2_LIB.BASEBOARD_FAB2(SCH_1):PAGE94
  Q7E2    5 GATE<0> FET_N_DUAL_SMLF-NTJD4001N,FET,A    I75 @BASEBOARD_FAB2_LIB.BASEBOARD_FAB2(SCH_1):PAGE94
 R3R10    2      B RES_0402-4.75K,1%,1/16W,CHIP,GA    I79 @BASEBOARD_FAB2_LIB.BASEBOARD_FAB2(SCH_1):PAGE94

H_CPU1_MEMGHJ_MEMHOT_G_N @BASEBOARD_FAB2_LIB.BASEBOARD_FAB2(SCH_1):H_CPU1_MEMGHJ_MEMHOT_G_N
  U2D1 AH13 MEM_HOT_C012_N SKX_EXT_B_BGA1-IC,TBD   I172 @BASEBOARD_FAB2_LIB.BASEBOARD_FAB2(SCH_1):PAGE55
  Q7E2    3 DRAIN<0> FET_N_DUAL_SMLF-NTJD4001N,FET,A    I75 @BASEBOARD_FAB2_LIB.BASEBOARD_FAB2(SCH_1):PAGE94
  Q4B2    6 DRAIN<0> FET_N_DUAL_SMLF-NTJD4001N,FET,A    I32 @BASEBOARD_FAB2_LIB.BASEBOARD_FAB2(SCH_1):PAGE95
 R1U41    2      B RES_0402-150.0,1%,1/16W,CHIP,GA    I56 @BASEBOARD_FAB2_LIB.BASEBOARD_FAB2(SCH_1):PAGE152
  R7P5    1      A RES_0402-150.0,1%,1/16W,CHIP,GA    I61 @BASEBOARD_FAB2_LIB.BASEBOARD_FAB2(SCH_1):PAGE152
 R1U53    1      A RES_0402-0.0,5%,1/16W,CHIP,G21A    I64 @BASEBOARD_FAB2_LIB.BASEBOARD_FAB2(SCH_1):PAGE152
 R1U55    1      A RES_0402-0.0,5%,1/16W,EMPTY,G2A    I67 @BASEBOARD_FAB2_LIB.BASEBOARD_FAB2(SCH_1):PAGE152

H_CPU1_MEMGHJ_MEMHOT_G_PCH_N @BASEBOARD_FAB2_LIB.BASEBOARD_FAB2(SCH_1):H_CPU1_MEMGHJ_MEMHOT_G_PCH_N
 R1U55    2      B RES_0402-0.0,5%,1/16W,EMPTY,G2A    I67 @BASEBOARD_FAB2_LIB.BASEBOARD_FAB2(SCH_1):PAGE152
 R1U57    2      B RES_0402-0.0,5%,1/16W,EMPTY,G2A    I69 @BASEBOARD_FAB2_LIB.BASEBOARD_FAB2(SCH_1):PAGE152

H_CPU1_MEMGHJ_MEMHOT_G_R_N @BASEBOARD_FAB2_LIB.BASEBOARD_FAB2(SCH_1):H_CPU1_MEMGHJ_MEMHOT_G_R_N
  U9G1    3     B1 GTL2014_SM-IC,D66151-001     I1 @BASEBOARD_FAB2_LIB.BASEBOARD_FAB2(SCH_1):PAGE152
 R1U53    2      B RES_0402-0.0,5%,1/16W,CHIP,G21A    I64 @BASEBOARD_FAB2_LIB.BASEBOARD_FAB2(SCH_1):PAGE152

H_CPU1_MEMGHJ_MEMHOT_LVT3_BMC_N @BASEBOARD_FAB2_LIB.BASEBOARD_FAB2(SCH_1):H_CPU1_MEMGHJ_MEMHOT_LVT3_BMC_N
 R1U54    2      B RES_0402-0.0,5%,1/16W,CHIP,G21A    I93 @BASEBOARD_FAB2_LIB.BASEBOARD_FAB2(SCH_1):PAGE152
 U25W4   H3 ADC14_GPIX6 AST2520A1-GP-GP_ASIC2-GB1-AST2A   I106 @BASEBOARD_FAB2_LIB.BASEBOARD_FAB2(SCH_1):PAGE147

H_CPU1_MEMGHJ_MEMHOT_LVT3_K_N @BASEBOARD_FAB2_LIB.BASEBOARD_FAB2(SCH_1):H_CPU1_MEMGHJ_MEMHOT_LVT3_K_N
 R1U36    1      A RES_0402-33.2,1%,1/16W,CHIP,G2A    I15 @BASEBOARD_FAB2_LIB.BASEBOARD_FAB2(SCH_1):PAGE152
 R1U57    1      A RES_0402-0.0,5%,1/16W,EMPTY,G2A    I69 @BASEBOARD_FAB2_LIB.BASEBOARD_FAB2(SCH_1):PAGE152
 R9G32    2      B RES_0402-0.0,5%,1/16W,CHIP,G21A    I72 @BASEBOARD_FAB2_LIB.BASEBOARD_FAB2(SCH_1):PAGE152

H_CPU1_MEMGHJ_MEMHOT_LVT3_N @BASEBOARD_FAB2_LIB.BASEBOARD_FAB2(SCH_1):H_CPU1_MEMGHJ_MEMHOT_LVT3_N
 R1U36    2      B RES_0402-33.2,1%,1/16W,CHIP,G2A    I15 @BASEBOARD_FAB2_LIB.BASEBOARD_FAB2(SCH_1):PAGE152
 R1U54    1      A RES_0402-0.0,5%,1/16W,CHIP,G21A    I93 @BASEBOARD_FAB2_LIB.BASEBOARD_FAB2(SCH_1):PAGE152
 R3P63    1      A RES_0402-0.0,5%,1/16W,EMPTY,G2A   I100 @BASEBOARD_FAB2_LIB.BASEBOARD_FAB2(SCH_1):PAGE152

H_CPU1_MEMGHJ_MEMHOT_PCH_N @BASEBOARD_FAB2_LIB.BASEBOARD_FAB2(SCH_1):H_CPU1_MEMGHJ_MEMHOT_PCH_N
  U7C1 AA13 GPP_L14_TESTCH1_D3 LBG_CORE_QAT_EXT_D_BGA1-IC,H91A    I34 @BASEBOARD_FAB2_LIB.BASEBOARD_FAB2(SCH_1):PAGE121
 R3P63    2      B RES_0402-0.0,5%,1/16W,EMPTY,G2A   I100 @BASEBOARD_FAB2_LIB.BASEBOARD_FAB2(SCH_1):PAGE152

H_CPU1_MEMKLM_MEMHOT @BASEBOARD_FAB2_LIB.BASEBOARD_FAB2(SCH_1):H_CPU1_MEMKLM_MEMHOT
  Q4B1    5 GATE<0> FET_N_DUAL_SMLF-NTJD4001N,FET,A    I77 @BASEBOARD_FAB2_LIB.BASEBOARD_FAB2(SCH_1):PAGE94
  R6M4    2      B RES_0402-4.75K,1%,1/16W,CHIP,GA    I82 @BASEBOARD_FAB2_LIB.BASEBOARD_FAB2(SCH_1):PAGE94
  Q4B1    6 DRAIN<0> FET_N_DUAL_SMLF-NTJD4001N,FET,A    I84 @BASEBOARD_FAB2_LIB.BASEBOARD_FAB2(SCH_1):PAGE94

H_CPU1_MEMKLM_MEMHOT_G_N @BASEBOARD_FAB2_LIB.BASEBOARD_FAB2(SCH_1):H_CPU1_MEMKLM_MEMHOT_G_N
  U2D1 AF13 MEM_HOT_C345_N SKX_EXT_B_BGA1-IC,TBD   I172 @BASEBOARD_FAB2_LIB.BASEBOARD_FAB2(SCH_1):PAGE55
  Q4B1    3 DRAIN<0> FET_N_DUAL_SMLF-NTJD4001N,FET,A    I77 @BASEBOARD_FAB2_LIB.BASEBOARD_FAB2(SCH_1):PAGE94
  Q4B2    3 DRAIN<0> FET_N_DUAL_SMLF-NTJD4001N,FET,A    I33 @BASEBOARD_FAB2_LIB.BASEBOARD_FAB2(SCH_1):PAGE95
 R1U35    2      B RES_0402-150.0,1%,1/16W,CHIP,GA    I57 @BASEBOARD_FAB2_LIB.BASEBOARD_FAB2(SCH_1):PAGE152
 R7P21    1      A RES_0402-150.0,1%,1/16W,CHIP,GA    I62 @BASEBOARD_FAB2_LIB.BASEBOARD_FAB2(SCH_1):PAGE152
 R1U60    1      A RES_0402-0.0,5%,1/16W,CHIP,G21A    I65 @BASEBOARD_FAB2_LIB.BASEBOARD_FAB2(SCH_1):PAGE152
 R1U62    1      A RES_0402-0.0,5%,1/16W,EMPTY,G2A    I68 @BASEBOARD_FAB2_LIB.BASEBOARD_FAB2(SCH_1):PAGE152

H_CPU1_MEMKLM_MEMHOT_G_PCH_N @BASEBOARD_FAB2_LIB.BASEBOARD_FAB2(SCH_1):H_CPU1_MEMKLM_MEMHOT_G_PCH_N
 R1U62    2      B RES_0402-0.0,5%,1/16W,EMPTY,G2A    I68 @BASEBOARD_FAB2_LIB.BASEBOARD_FAB2(SCH_1):PAGE152
 R1U61    2      B RES_0402-0.0,5%,1/16W,EMPTY,G2A    I70 @BASEBOARD_FAB2_LIB.BASEBOARD_FAB2(SCH_1):PAGE152

H_CPU1_MEMKLM_MEMHOT_G_R_N @BASEBOARD_FAB2_LIB.BASEBOARD_FAB2(SCH_1):H_CPU1_MEMKLM_MEMHOT_G_R_N
  U9G1    2     B0 GTL2014_SM-IC,D66151-001     I1 @BASEBOARD_FAB2_LIB.BASEBOARD_FAB2(SCH_1):PAGE152
 R1U60    2      B RES_0402-0.0,5%,1/16W,CHIP,G21A    I65 @BASEBOARD_FAB2_LIB.BASEBOARD_FAB2(SCH_1):PAGE152

H_CPU1_MEMKLM_MEMHOT_LVT3_BMC_N @BASEBOARD_FAB2_LIB.BASEBOARD_FAB2(SCH_1):H_CPU1_MEMKLM_MEMHOT_LVT3_BMC_N
 R2U46    2      B RES_0402-0.0,5%,1/16W,CHIP,G21A    I94 @BASEBOARD_FAB2_LIB.BASEBOARD_FAB2(SCH_1):PAGE152
 U25W4   H4 ADC15_GPIX7 AST2520A1-GP-GP_ASIC2-GB1-AST2A   I106 @BASEBOARD_FAB2_LIB.BASEBOARD_FAB2(SCH_1):PAGE147

H_CPU1_MEMKLM_MEMHOT_LVT3_K_N @BASEBOARD_FAB2_LIB.BASEBOARD_FAB2(SCH_1):H_CPU1_MEMKLM_MEMHOT_LVT3_K_N
 R1U34    1      A RES_0402-33.2,1%,1/16W,CHIP,G2A    I16 @BASEBOARD_FAB2_LIB.BASEBOARD_FAB2(SCH_1):PAGE152
 R1U61    1      A RES_0402-0.0,5%,1/16W,EMPTY,G2A    I70 @BASEBOARD_FAB2_LIB.BASEBOARD_FAB2(SCH_1):PAGE152
 R9G28    2      B RES_0402-0.0,5%,1/16W,CHIP,G21A    I71 @BASEBOARD_FAB2_LIB.BASEBOARD_FAB2(SCH_1):PAGE152

H_CPU1_MEMKLM_MEMHOT_LVT3_N @BASEBOARD_FAB2_LIB.BASEBOARD_FAB2(SCH_1):H_CPU1_MEMKLM_MEMHOT_LVT3_N
 R1U34    2      B RES_0402-33.2,1%,1/16W,CHIP,G2A    I16 @BASEBOARD_FAB2_LIB.BASEBOARD_FAB2(SCH_1):PAGE152
 R2U46    1      A RES_0402-0.0,5%,1/16W,CHIP,G21A    I94 @BASEBOARD_FAB2_LIB.BASEBOARD_FAB2(SCH_1):PAGE152
 R2U45    1      A RES_0402-0.0,5%,1/16W,EMPTY,G2A   I102 @BASEBOARD_FAB2_LIB.BASEBOARD_FAB2(SCH_1):PAGE152

H_CPU1_MEMKLM_MEMHOT_PCH_N @BASEBOARD_FAB2_LIB.BASEBOARD_FAB2(SCH_1):H_CPU1_MEMKLM_MEMHOT_PCH_N
  U7C1  Y11 GPP_L15_TESTCH1_D4 LBG_CORE_QAT_EXT_D_BGA1-IC,H91A    I34 @BASEBOARD_FAB2_LIB.BASEBOARD_FAB2(SCH_1):PAGE121
 R2U45    2      B RES_0402-0.0,5%,1/16W,EMPTY,G2A   I102 @BASEBOARD_FAB2_LIB.BASEBOARD_FAB2(SCH_1):PAGE152

H_CPU1_MSMI_G_N @BASEBOARD_FAB2_LIB.BASEBOARD_FAB2(SCH_1):H_CPU1_MSMI_G_N
  U2D1 AN20 MSMI_N SKX_EXT_B_BGA1-IC,TBD   I172 @BASEBOARD_FAB2_LIB.BASEBOARD_FAB2(SCH_1):PAGE55
 R7P27    2      B RES_0402-150.0,1%,1/16W,CHIP,GA    I65 @BASEBOARD_FAB2_LIB.BASEBOARD_FAB2(SCH_1):PAGE92
 R7D28    1      A RES_0402-0.0,5%,1/16W,CHIP,G21A    I67 @BASEBOARD_FAB2_LIB.BASEBOARD_FAB2(SCH_1):PAGE92

H_CPU1_PROCHOT_G_N @BASEBOARD_FAB2_LIB.BASEBOARD_FAB2(SCH_1):H_CPU1_PROCHOT_G_N
  U2D1 AC16 PROCHOT_N SKX_EXT_B_BGA1-IC,TBD   I172 @BASEBOARD_FAB2_LIB.BASEBOARD_FAB2(SCH_1):PAGE55
 R2T68    1      A RES_0402-0.0,5%,1/16W,CHIP,G21A   I102 @BASEBOARD_FAB2_LIB.BASEBOARD_FAB2(SCH_1):PAGE93
 R7P28    2      B RES_0402-150.0,1%,1/16W,CHIP,GA   I106 @BASEBOARD_FAB2_LIB.BASEBOARD_FAB2(SCH_1):PAGE93
 R2T69    1      A RES_0402-0.0,5%,1/16W,EMPTY,G2A   I108 @BASEBOARD_FAB2_LIB.BASEBOARD_FAB2(SCH_1):PAGE93
 R2T73    2      B RES_0402-150.0,1%,1/16W,CHIP,GA   I144 @BASEBOARD_FAB2_LIB.BASEBOARD_FAB2(SCH_1):PAGE93
  Q7E3    3 DRAIN<0> FET_N_DUAL_SMLF-NTJD4001N,FET,A    I51 @BASEBOARD_FAB2_LIB.BASEBOARD_FAB2(SCH_1):PAGE95
  Q7E6    3 DRAIN<0> FET_N_DUAL_SMLF-NTJD4001N,FET,A    I69 @BASEBOARD_FAB2_LIB.BASEBOARD_FAB2(SCH_1):PAGE95

H_CPU1_PROCHOT_G_PCH_N @BASEBOARD_FAB2_LIB.BASEBOARD_FAB2(SCH_1):H_CPU1_PROCHOT_G_PCH_N
 R2T69    2      B RES_0402-0.0,5%,1/16W,EMPTY,G2A   I108 @BASEBOARD_FAB2_LIB.BASEBOARD_FAB2(SCH_1):PAGE93
 R7D43    2      B RES_0402-0.0,5%,1/16W,EMPTY,G2A   I110 @BASEBOARD_FAB2_LIB.BASEBOARD_FAB2(SCH_1):PAGE93

H_CPU1_PROCHOT_G_R_N @BASEBOARD_FAB2_LIB.BASEBOARD_FAB2(SCH_1):H_CPU1_PROCHOT_G_R_N
  U2T4    2     B0 GTL2014_SM-IC,D66151-001    I30 @BASEBOARD_FAB2_LIB.BASEBOARD_FAB2(SCH_1):PAGE93
 R2T68    2      B RES_0402-0.0,5%,1/16W,CHIP,G21A   I102 @BASEBOARD_FAB2_LIB.BASEBOARD_FAB2(SCH_1):PAGE93

H_CPU1_THERMTRIP_G_N @BASEBOARD_FAB2_LIB.BASEBOARD_FAB2(SCH_1):H_CPU1_THERMTRIP_G_N
  U2D1 AB15 THERMTRIP_N SKX_EXT_B_BGA1-IC,TBD   I172 @BASEBOARD_FAB2_LIB.BASEBOARD_FAB2(SCH_1):PAGE55
  U3P2    6     B3 GTL2014_SM-IC,D66151-001     I1 @BASEBOARD_FAB2_LIB.BASEBOARD_FAB2(SCH_1):PAGE92
 R3P41    2      B RES_0402-75,1.0%,1/16W,CHIP,G2A     I9 @BASEBOARD_FAB2_LIB.BASEBOARD_FAB2(SCH_1):PAGE92

H_CPU_CATERR_G_N @BASEBOARD_FAB2_LIB.BASEBOARD_FAB2(SCH_1):H_CPU_CATERR_G_N
  U3P2    5     B2 GTL2014_SM-IC,D66151-001     I1 @BASEBOARD_FAB2_LIB.BASEBOARD_FAB2(SCH_1):PAGE92
 R3P59    2      B RES_0402-0.0,5%,1/16W,CHIP,G21A    I97 @BASEBOARD_FAB2_LIB.BASEBOARD_FAB2(SCH_1):PAGE92
 R3P58    2      B RES_0402-0.0,5%,1/16W,CHIP,G21A    I98 @BASEBOARD_FAB2_LIB.BASEBOARD_FAB2(SCH_1):PAGE92

H_CPU_ERR0_GTL_N @BASEBOARD_FAB2_LIB.BASEBOARD_FAB2(SCH_1):H_CPU_ERR0_GTL_N
  U2T4    6     B3 GTL2014_SM-IC,D66151-001    I30 @BASEBOARD_FAB2_LIB.BASEBOARD_FAB2(SCH_1):PAGE93
 R2T16    2      B RES_0402-75,1.0%,1/16W,CHIP,G2A    I67 @BASEBOARD_FAB2_LIB.BASEBOARD_FAB2(SCH_1):PAGE93

H_CPU_ERR0_GTL_R_N @BASEBOARD_FAB2_LIB.BASEBOARD_FAB2(SCH_1):H_CPU_ERR0_GTL_R_N
 R2T20    2      B RES_0402-0.0,5%,1/16W,CHIP,G21A    I16 @BASEBOARD_FAB2_LIB.BASEBOARD_FAB2(SCH_1):PAGE93
 R2T17    2      B RES_0402-0.0,5%,1/16W,CHIP,G21A    I23 @BASEBOARD_FAB2_LIB.BASEBOARD_FAB2(SCH_1):PAGE93
 R2T19    2      B RES_0402-200.0,1%,1/16W,CHIP,GA    I63 @BASEBOARD_FAB2_LIB.BASEBOARD_FAB2(SCH_1):PAGE93
 R2T16    1      A RES_0402-75,1.0%,1/16W,CHIP,G2A    I67 @BASEBOARD_FAB2_LIB.BASEBOARD_FAB2(SCH_1):PAGE93
 R2T57    2      B RES_0402-0.0,5%,1/16W,EMPTY,G2A    I88 @BASEBOARD_FAB2_LIB.BASEBOARD_FAB2(SCH_1):PAGE93

H_CPU_ERR0_PCH_N @BASEBOARD_FAB2_LIB.BASEBOARD_FAB2(SCH_1):H_CPU_ERR0_PCH_N
 R2T57    1      A RES_0402-0.0,5%,1/16W,EMPTY,G2A    I88 @BASEBOARD_FAB2_LIB.BASEBOARD_FAB2(SCH_1):PAGE93
 R2T58    1      A RES_0402-0.0,5%,1/16W,EMPTY,G2A    I94 @BASEBOARD_FAB2_LIB.BASEBOARD_FAB2(SCH_1):PAGE93

H_CPU_ERR1_GTL_N @BASEBOARD_FAB2_LIB.BASEBOARD_FAB2(SCH_1):H_CPU_ERR1_GTL_N
  U2T4    5     B2 GTL2014_SM-IC,D66151-001    I30 @BASEBOARD_FAB2_LIB.BASEBOARD_FAB2(SCH_1):PAGE93
 R2T31    2      B RES_0402-75,1.0%,1/16W,CHIP,G2A    I68 @BASEBOARD_FAB2_LIB.BASEBOARD_FAB2(SCH_1):PAGE93

H_CPU_ERR1_GTL_R_N @BASEBOARD_FAB2_LIB.BASEBOARD_FAB2(SCH_1):H_CPU_ERR1_GTL_R_N
 R2T27    2      B RES_0402-0.0,5%,1/16W,CHIP,G21A    I13 @BASEBOARD_FAB2_LIB.BASEBOARD_FAB2(SCH_1):PAGE93
 R2T32    2      B RES_0402-0.0,5%,1/16W,CHIP,G21A    I15 @BASEBOARD_FAB2_LIB.BASEBOARD_FAB2(SCH_1):PAGE93
 R2T31    1      A RES_0402-75,1.0%,1/16W,CHIP,G2A    I68 @BASEBOARD_FAB2_LIB.BASEBOARD_FAB2(SCH_1):PAGE93
 R2T26    2      B RES_0402-200.0,1%,1/16W,CHIP,GA    I87 @BASEBOARD_FAB2_LIB.BASEBOARD_FAB2(SCH_1):PAGE93
 R2T61    2      B RES_0402-0.0,5%,1/16W,EMPTY,G2A    I89 @BASEBOARD_FAB2_LIB.BASEBOARD_FAB2(SCH_1):PAGE93

H_CPU_ERR1_PCH_N @BASEBOARD_FAB2_LIB.BASEBOARD_FAB2(SCH_1):H_CPU_ERR1_PCH_N
 R2T61    1      A RES_0402-0.0,5%,1/16W,EMPTY,G2A    I89 @BASEBOARD_FAB2_LIB.BASEBOARD_FAB2(SCH_1):PAGE93
 R2T62    1      A RES_0402-0.0,5%,1/16W,EMPTY,G2A    I93 @BASEBOARD_FAB2_LIB.BASEBOARD_FAB2(SCH_1):PAGE93

H_CPU_ERR2_GTL_N @BASEBOARD_FAB2_LIB.BASEBOARD_FAB2(SCH_1):H_CPU_ERR2_GTL_N
  U7D2    5     B2 GTL2014_SM-IC,D66151-001    I32 @BASEBOARD_FAB2_LIB.BASEBOARD_FAB2(SCH_1):PAGE92
 R2T43    2      B RES_0402-75,1.0%,1/16W,CHIP,G2A    I96 @BASEBOARD_FAB2_LIB.BASEBOARD_FAB2(SCH_1):PAGE92

H_CPU_ERR2_G_R_N @BASEBOARD_FAB2_LIB.BASEBOARD_FAB2(SCH_1):H_CPU_ERR2_G_R_N
 R2T44    2      B RES_0402-0.0,5%,1/16W,CHIP,G21A    I92 @BASEBOARD_FAB2_LIB.BASEBOARD_FAB2(SCH_1):PAGE92
 R2T40    2      B RES_0402-0.0,5%,1/16W,CHIP,G21A    I93 @BASEBOARD_FAB2_LIB.BASEBOARD_FAB2(SCH_1):PAGE92
 R2T37    2      B RES_0402-200.0,1%,1/16W,CHIP,GA    I94 @BASEBOARD_FAB2_LIB.BASEBOARD_FAB2(SCH_1):PAGE92
 R2T43    1      A RES_0402-75,1.0%,1/16W,CHIP,G2A    I96 @BASEBOARD_FAB2_LIB.BASEBOARD_FAB2(SCH_1):PAGE92

H_CPU_MSMI_G_N @BASEBOARD_FAB2_LIB.BASEBOARD_FAB2(SCH_1):H_CPU_MSMI_G_N
  U7D2    2     B0 GTL2014_SM-IC,D66151-001    I32 @BASEBOARD_FAB2_LIB.BASEBOARD_FAB2(SCH_1):PAGE92
 R7D28    2      B RES_0402-0.0,5%,1/16W,CHIP,G21A    I67 @BASEBOARD_FAB2_LIB.BASEBOARD_FAB2(SCH_1):PAGE92
 R7D27    2      B RES_0402-0.0,5%,1/16W,CHIP,G21A    I68 @BASEBOARD_FAB2_LIB.BASEBOARD_FAB2(SCH_1):PAGE92

H_PMSYNC_CLK_24M @BASEBOARD_FAB2_LIB.BASEBOARD_FAB2(SCH_1):H_PMSYNC_CLK_24M
 R4P19    2      B RES_0402-49.9,1%,1/16W,CHIP,G2A   I219 @BASEBOARD_FAB2_LIB.BASEBOARD_FAB2(SCH_1):PAGE21
 R7P26    2      B RES_0402-49.9,1%,1/16W,CHIP,G2A   I156 @BASEBOARD_FAB2_LIB.BASEBOARD_FAB2(SCH_1):PAGE55
 R8B20    2      B RES_0402-10.0,1%,1/16W,CHIP,G2A   I110 @BASEBOARD_FAB2_LIB.BASEBOARD_FAB2(SCH_1):PAGE114
 R8B21    1      A RES_0402-49.9,1%,1/16W,EMPTY,GA   I124 @BASEBOARD_FAB2_LIB.BASEBOARD_FAB2(SCH_1):PAGE114

H_PMSYNC_CLK_24M_CPU0 @BASEBOARD_FAB2_LIB.BASEBOARD_FAB2(SCH_1):H_PMSYNC_CLK_24M_CPU0
 R4P19    1      A RES_0402-49.9,1%,1/16W,CHIP,G2A   I219 @BASEBOARD_FAB2_LIB.BASEBOARD_FAB2(SCH_1):PAGE21
  U5D1 AT19 PMSYNC_CLK SKX_EXT_B_BGA1-IC,TBD   I259 @BASEBOARD_FAB2_LIB.BASEBOARD_FAB2(SCH_1):PAGE21

H_PMSYNC_CLK_24M_CPU1 @BASEBOARD_FAB2_LIB.BASEBOARD_FAB2(SCH_1):H_PMSYNC_CLK_24M_CPU1
 R7P26    1      A RES_0402-49.9,1%,1/16W,CHIP,G2A   I156 @BASEBOARD_FAB2_LIB.BASEBOARD_FAB2(SCH_1):PAGE55
  U2D1 AT19 PMSYNC_CLK SKX_EXT_B_BGA1-IC,TBD   I172 @BASEBOARD_FAB2_LIB.BASEBOARD_FAB2(SCH_1):PAGE55

H_PMSYNC_CLK_24M_R @BASEBOARD_FAB2_LIB.BASEBOARD_FAB2(SCH_1):H_PMSYNC_CLK_24M_R
  U7C1 BY51 CLOCKSE_PMSYNCCLK1 LBG_CORE_QAT_EXT_D_BGA1-IC,H91A    I40 @BASEBOARD_FAB2_LIB.BASEBOARD_FAB2(SCH_1):PAGE114
 R8B20    1      A RES_0402-10.0,1%,1/16W,CHIP,G2A   I110 @BASEBOARD_FAB2_LIB.BASEBOARD_FAB2(SCH_1):PAGE114

H_PM_SYNC1_GTL_R @BASEBOARD_FAB2_LIB.BASEBOARD_FAB2(SCH_1):H_PM_SYNC1_GTL_R
  R3N9    1      A RES_0402-10.0,1%,1/16W,CHIP,G2A    I66 @BASEBOARD_FAB2_LIB.BASEBOARD_FAB2(SCH_1):PAGE118
  U7C1  U13 PM_SYNC LBG_CORE_QAT_EXT_D_BGA1-IC,H91A    I73 @BASEBOARD_FAB2_LIB.BASEBOARD_FAB2(SCH_1):PAGE118

H_PM_SYNC_GTL @BASEBOARD_FAB2_LIB.BASEBOARD_FAB2(SCH_1):H_PM_SYNC_GTL
 R4P18    2      B RES_0402-49.9,1%,1/16W,CHIP,G2A   I244 @BASEBOARD_FAB2_LIB.BASEBOARD_FAB2(SCH_1):PAGE21
 R7P25    2      B RES_0402-49.9,1%,1/16W,CHIP,G2A   I170 @BASEBOARD_FAB2_LIB.BASEBOARD_FAB2(SCH_1):PAGE55
  R3N9    2      B RES_0402-10.0,1%,1/16W,CHIP,G2A    I66 @BASEBOARD_FAB2_LIB.BASEBOARD_FAB2(SCH_1):PAGE118
 R3N14    1      A RES_0402-49.9,1%,1/16W,EMPTY,GA    I67 @BASEBOARD_FAB2_LIB.BASEBOARD_FAB2(SCH_1):PAGE118

H_PM_SYNC_GTL_R1 @BASEBOARD_FAB2_LIB.BASEBOARD_FAB2(SCH_1):H_PM_SYNC_GTL_R1
 R4P18    1      A RES_0402-49.9,1%,1/16W,CHIP,G2A   I244 @BASEBOARD_FAB2_LIB.BASEBOARD_FAB2(SCH_1):PAGE21
  U5D1 AR14 PMSYNC SKX_EXT_B_BGA1-IC,TBD   I259 @BASEBOARD_FAB2_LIB.BASEBOARD_FAB2(SCH_1):PAGE21

H_PM_SYNC_GTL_R2 @BASEBOARD_FAB2_LIB.BASEBOARD_FAB2(SCH_1):H_PM_SYNC_GTL_R2
 R7P25    1      A RES_0402-49.9,1%,1/16W,CHIP,G2A   I170 @BASEBOARD_FAB2_LIB.BASEBOARD_FAB2(SCH_1):PAGE55
  U2D1 AR14 PMSYNC SKX_EXT_B_BGA1-IC,TBD   I172 @BASEBOARD_FAB2_LIB.BASEBOARD_FAB2(SCH_1):PAGE55

I2C_BMC_VGA_DDC_SCL @BASEBOARD_FAB2_LIB.BASEBOARD_FAB2(SCH_1):I2C_BMC_VGA_DDC_SCL
 U25W4   R3 GPIOJ6_DDCCLK AST2520A1-GP-GP_ASIC2-GB1-AST2A   I105 @BASEBOARD_FAB2_LIB.BASEBOARD_FAB2(SCH_1):PAGE146
R25W129    2      B RES_0402-4.75K,1%,1/16W,CHIP,GA   I152 @BASEBOARD_FAB2_LIB.BASEBOARD_FAB2(SCH_1):PAGE146
 Q25W4    1 SOURCE<0> FET_N_DUAL_SMLF-2N7002DW,FET,DA    I95 @BASEBOARD_FAB2_LIB.BASEBOARD_FAB2(SCH_1):PAGE255

I2C_BMC_VGA_DDC_SCL_G @BASEBOARD_FAB2_LIB.BASEBOARD_FAB2(SCH_1):I2C_BMC_VGA_DDC_SCL_G
R25W132    2      B RES_0402-4.75K,1%,1/16W,CHIP,GA    I31 @BASEBOARD_FAB2_LIB.BASEBOARD_FAB2(SCH_1):PAGE255
R25W133    1      A RES_0402-33.2,1%,1/16W,CHIP,G2A    I34 @BASEBOARD_FAB2_LIB.BASEBOARD_FAB2(SCH_1):PAGE255
 Q25W4    6 DRAIN<0> FET_N_DUAL_SMLF-2N7002DW,FET,DA    I95 @BASEBOARD_FAB2_LIB.BASEBOARD_FAB2(SCH_1):PAGE255

I2C_BMC_VGA_DDC_SDA @BASEBOARD_FAB2_LIB.BASEBOARD_FAB2(SCH_1):I2C_BMC_VGA_DDC_SDA
 U25W4   T3 GPIOJ7_DDCDAT AST2520A1-GP-GP_ASIC2-GB1-AST2A   I105 @BASEBOARD_FAB2_LIB.BASEBOARD_FAB2(SCH_1):PAGE146
R25W130    2      B RES_0402-4.75K,1%,1/16W,CHIP,GA   I153 @BASEBOARD_FAB2_LIB.BASEBOARD_FAB2(SCH_1):PAGE146
 Q25W4    4 SOURCE<0> FET_N_DUAL_SMLF-2N7002DW,FET,DA    I96 @BASEBOARD_FAB2_LIB.BASEBOARD_FAB2(SCH_1):PAGE255

I2C_BMC_VGA_DDC_SDA_G @BASEBOARD_FAB2_LIB.BASEBOARD_FAB2(SCH_1):I2C_BMC_VGA_DDC_SDA_G
R25W136    1      A RES_0402-33.2,1%,1/16W,CHIP,G2A    I38 @BASEBOARD_FAB2_LIB.BASEBOARD_FAB2(SCH_1):PAGE255
R25W135    2      B RES_0402-4.75K,1%,1/16W,CHIP,GA    I44 @BASEBOARD_FAB2_LIB.BASEBOARD_FAB2(SCH_1):PAGE255
 Q25W4    3 DRAIN<0> FET_N_DUAL_SMLF-2N7002DW,FET,DA    I96 @BASEBOARD_FAB2_LIB.BASEBOARD_FAB2(SCH_1):PAGE255

IRQ_BMC_PCH_NMI_STBY_N @BASEBOARD_FAB2_LIB.BASEBOARD_FAB2(SCH_1):IRQ_BMC_PCH_NMI_STBY_N
  U7C1 BB52 GPP_E6_SATA_DEVSLP2 LBG_CORE_QAT_EXT_D_BGA1-IC,H91A   I147 @BASEBOARD_FAB2_LIB.BASEBOARD_FAB2(SCH_1):PAGE120
 R8E24    1      A RES_0402-33.2,1%,1/16W,CHIP,G2A   I214 @BASEBOARD_FAB2_LIB.BASEBOARD_FAB2(SCH_1):PAGE156
 R8E22    2      B RES_0402-4.75K,1%,1/16W,CHIP,GA   I215 @BASEBOARD_FAB2_LIB.BASEBOARD_FAB2(SCH_1):PAGE156
 U25W4  D19 GPIOE5_NRTS3 AST2520A1-GP-GP_ASIC2-GB1-AST2A   I117 @BASEBOARD_FAB2_LIB.BASEBOARD_FAB2(SCH_1):PAGE145

IRQ_BMC_PCH_NMI_STBY_R_N @BASEBOARD_FAB2_LIB.BASEBOARD_FAB2(SCH_1):IRQ_BMC_PCH_NMI_STBY_R_N
  U7C1 BR42 GPP_D0 LBG_CORE_QAT_EXT_D_BGA1-IC,H91A   I115 @BASEBOARD_FAB2_LIB.BASEBOARD_FAB2(SCH_1):PAGE119
 R8E24    2      B RES_0402-33.2,1%,1/16W,CHIP,G2A   I214 @BASEBOARD_FAB2_LIB.BASEBOARD_FAB2(SCH_1):PAGE156

IRQ_BMC_PCH_SCI_LPC_N @BASEBOARD_FAB2_LIB.BASEBOARD_FAB2(SCH_1):IRQ_BMC_PCH_SCI_LPC_N
  U7C1 BY38 GPP_C14 LBG_CORE_QAT_EXT_D_BGA1-IC,H91A   I115 @BASEBOARD_FAB2_LIB.BASEBOARD_FAB2(SCH_1):PAGE119
  U7C1 BN48 GPP_E10_USB2_OC1_N LBG_CORE_QAT_EXT_D_BGA1-IC,H91A   I147 @BASEBOARD_FAB2_LIB.BASEBOARD_FAB2(SCH_1):PAGE120
  R8C2    2      B RES_0402-4.75K,1%,1/16W,CHIP,GA   I304 @BASEBOARD_FAB2_LIB.BASEBOARD_FAB2(SCH_1):PAGE133
 U25W4 AA21 GPIOZ3_VPOG5_NORA3_SIOSCI# AST2520A1-GP-GP_ASIC2-GB1-AST2A   I104 @BASEBOARD_FAB2_LIB.BASEBOARD_FAB2(SCH_1):PAGE146

IRQ_BMC_PCH_SMI_LPC_N @BASEBOARD_FAB2_LIB.BASEBOARD_FAB2(SCH_1):IRQ_BMC_PCH_SMI_LPC_N
  U7C1 CA34 GPP_C22 LBG_CORE_QAT_EXT_D_BGA1-IC,H91A   I115 @BASEBOARD_FAB2_LIB.BASEBOARD_FAB2(SCH_1):PAGE119
  U7C1 AW54 GPP_E11_USB2_OC2_N LBG_CORE_QAT_EXT_D_BGA1-IC,H91A   I147 @BASEBOARD_FAB2_LIB.BASEBOARD_FAB2(SCH_1):PAGE120
  R8C4    2      B RES_0402-1.00K,1%,1/16W,CHIP,GA   I286 @BASEBOARD_FAB2_LIB.BASEBOARD_FAB2(SCH_1):PAGE133
 U25W4  H21 GPIOB5_LPCPD#_LPCSMI# AST2520A1-GP-GP_ASIC2-GB1-AST2A    I95 @BASEBOARD_FAB2_LIB.BASEBOARD_FAB2(SCH_1):PAGE144

IRQ_BOARD_BMC_ALERT_N @BASEBOARD_FAB2_LIB.BASEBOARD_FAB2(SCH_1):IRQ_BOARD_BMC_ALERT_N
  U7C1 BW24 GPP_I5_DO_RESET_OUT_N LBG_CORE_QAT_EXT_D_BGA1-IC,H91A   I147 @BASEBOARD_FAB2_LIB.BASEBOARD_FAB2(SCH_1):PAGE120
  R2N7    2      B RES_0402-4.75K,1%,1/16W,CHIP,GA   I309 @BASEBOARD_FAB2_LIB.BASEBOARD_FAB2(SCH_1):PAGE133
 U25W4  AA1 GPIOM2_NDSR2_VPIB4 AST2520A1-GP-GP_ASIC2-GB1-AST2A   I117 @BASEBOARD_FAB2_LIB.BASEBOARD_FAB2(SCH_1):PAGE145
  R1C9    1      A RES_0402-0.0,5%,1/16W,EMPTY,G2A     I8 @BASEBOARD_FAB2_LIB.BASEBOARD_FAB2(SCH_1):PAGE182
  J1C1   B5 MNG_TX_DN DM-FCI-CONN76-8R-GP-U-01_CONN-A    I79 @BASEBOARD_FAB2_LIB.BASEBOARD_FAB2(SCH_1):PAGE182

IRQ_CPU0_PROCHOT_G_N @BASEBOARD_FAB2_LIB.BASEBOARD_FAB2(SCH_1):IRQ_CPU0_PROCHOT_G_N
  Q7E5    2 GATE<0> FET_N_DUAL_SMLF-NTJD4001N,FET,A   I111 @BASEBOARD_FAB2_LIB.BASEBOARD_FAB2(SCH_1):PAGE95
  U7E2    4   Y<0> TTL1G08_SOTLF-NC7SZ08,IC,D1032B   I117 @BASEBOARD_FAB2_LIB.BASEBOARD_FAB2(SCH_1):PAGE95

IRQ_CPU0_VRHOT @BASEBOARD_FAB2_LIB.BASEBOARD_FAB2(SCH_1):IRQ_CPU0_VRHOT
  Q7E5    5 GATE<0> FET_N_DUAL_SMLF-NTJD4001N,FET,A    I59 @BASEBOARD_FAB2_LIB.BASEBOARD_FAB2(SCH_1):PAGE95
 R7E10    2      B RES_0402-4.75K,1%,1/16W,CHIP,GA    I62 @BASEBOARD_FAB2_LIB.BASEBOARD_FAB2(SCH_1):PAGE95
  Q7E5    6 DRAIN<0> FET_N_DUAL_SMLF-NTJD4001N,FET,A   I111 @BASEBOARD_FAB2_LIB.BASEBOARD_FAB2(SCH_1):PAGE95

IRQ_CPU1_PROCHOT_G_N @BASEBOARD_FAB2_LIB.BASEBOARD_FAB2(SCH_1):IRQ_CPU1_PROCHOT_G_N
  Q7E6    2 GATE<0> FET_N_DUAL_SMLF-NTJD4001N,FET,A   I112 @BASEBOARD_FAB2_LIB.BASEBOARD_FAB2(SCH_1):PAGE95
  U7E3    4   Y<0> TTL1G08_SOTLF-NC7SZ08,IC,D1032B   I118 @BASEBOARD_FAB2_LIB.BASEBOARD_FAB2(SCH_1):PAGE95

IRQ_CPU1_VRHOT @BASEBOARD_FAB2_LIB.BASEBOARD_FAB2(SCH_1):IRQ_CPU1_VRHOT
  Q7E6    5 GATE<0> FET_N_DUAL_SMLF-NTJD4001N,FET,A    I69 @BASEBOARD_FAB2_LIB.BASEBOARD_FAB2(SCH_1):PAGE95
 R7E11    2      B RES_0402-4.75K,1%,1/16W,CHIP,GA    I72 @BASEBOARD_FAB2_LIB.BASEBOARD_FAB2(SCH_1):PAGE95
  Q7E6    6 DRAIN<0> FET_N_DUAL_SMLF-NTJD4001N,FET,A   I112 @BASEBOARD_FAB2_LIB.BASEBOARD_FAB2(SCH_1):PAGE95

IRQ_DIMM_SAVE_CPU1_R_N @BASEBOARD_FAB2_LIB.BASEBOARD_FAB2(SCH_1):IRQ_DIMM_SAVE_CPU1_R_N
WR8D30    2      B RES_0402-10.0K,1%,1/16W,CHIP,GA    I45 @BASEBOARD_FAB2_LIB.BASEBOARD_FAB2(SCH_1):PAGE89
  Q8W1    5   B<0> NPN_DUAL_SSOPLF-MBT3904,XSTR,CA    I52 @BASEBOARD_FAB2_LIB.BASEBOARD_FAB2(SCH_1):PAGE89

IRQ_DIMM_SAVE_LVT3 @BASEBOARD_FAB2_LIB.BASEBOARD_FAB2(SCH_1):IRQ_DIMM_SAVE_LVT3
 R8D29    2      B RES_0402-4.75K,1%,1/16W,CHIP,GA    I26 @BASEBOARD_FAB2_LIB.BASEBOARD_FAB2(SCH_1):PAGE89
  Q8D1    3   C<0> NPN_DUAL_SSOPLF-MBT3904,XSTR,CA    I35 @BASEBOARD_FAB2_LIB.BASEBOARD_FAB2(SCH_1):PAGE89
  Q8D1    2   B<0> NPN_DUAL_SSOPLF-MBT3904,XSTR,CA    I46 @BASEBOARD_FAB2_LIB.BASEBOARD_FAB2(SCH_1):PAGE89

IRQ_DIMM_SAVE_LVT3_CPU1 @BASEBOARD_FAB2_LIB.BASEBOARD_FAB2(SCH_1):IRQ_DIMM_SAVE_LVT3_CPU1
  R8W9    2      B RES_0402-4.75K,1%,1/16W,CHIP,GA    I49 @BASEBOARD_FAB2_LIB.BASEBOARD_FAB2(SCH_1):PAGE89
  Q8W1    2   B<0> NPN_DUAL_SSOPLF-MBT3904,XSTR,CA    I51 @BASEBOARD_FAB2_LIB.BASEBOARD_FAB2(SCH_1):PAGE89
  Q8W1    3   C<0> NPN_DUAL_SSOPLF-MBT3904,XSTR,CA    I52 @BASEBOARD_FAB2_LIB.BASEBOARD_FAB2(SCH_1):PAGE89

IRQ_DIMM_SAVE_LVT3_N @BASEBOARD_FAB2_LIB.BASEBOARD_FAB2(SCH_1):IRQ_DIMM_SAVE_LVT3_N
 R2P12    1      A RES_0402-0.0,5%,1/16W,EMPTY,G2A    I23 @BASEBOARD_FAB2_LIB.BASEBOARD_FAB2(SCH_1):PAGE89
 R8D31    2      B RES_0402-4.75K,1%,1/16W,CHIP,GA    I27 @BASEBOARD_FAB2_LIB.BASEBOARD_FAB2(SCH_1):PAGE89
 U25W4  D21 GPIOD4_SD2DAT2 AST2520A1-GP-GP_ASIC2-GB1-AST2A   I117 @BASEBOARD_FAB2_LIB.BASEBOARD_FAB2(SCH_1):PAGE145
  Q8D1    6   C<0> NPN_DUAL_SSOPLF-MBT3904,XSTR,CA    I46 @BASEBOARD_FAB2_LIB.BASEBOARD_FAB2(SCH_1):PAGE89
  Q8W1    6   C<0> NPN_DUAL_SSOPLF-MBT3904,XSTR,CA    I51 @BASEBOARD_FAB2_LIB.BASEBOARD_FAB2(SCH_1):PAGE89
 R7W16    2      B RES_0402-0.0,5%,1/16W,CHIP,G21A   I276 @BASEBOARD_FAB2_LIB.BASEBOARD_FAB2(SCH_1):PAGE120

IRQ_DIMM_SAVE_LVT3_R_N @BASEBOARD_FAB2_LIB.BASEBOARD_FAB2(SCH_1):IRQ_DIMM_SAVE_LVT3_R_N
  U7C1 BW20 GPP_I4_DO_RESET_IN_N LBG_CORE_QAT_EXT_D_BGA1-IC,H91A   I147 @BASEBOARD_FAB2_LIB.BASEBOARD_FAB2(SCH_1):PAGE120
 R7W16    1      A RES_0402-0.0,5%,1/16W,CHIP,G21A   I276 @BASEBOARD_FAB2_LIB.BASEBOARD_FAB2(SCH_1):PAGE120

IRQ_DIMM_SAVE_N @BASEBOARD_FAB2_LIB.BASEBOARD_FAB2(SCH_1):IRQ_DIMM_SAVE_N
  R6F4    1      A RES_0402-49.9,1%,1/16W,CHIP,G2A     I3 @BASEBOARD_FAB2_LIB.BASEBOARD_FAB2(SCH_1):PAGE89
  R6F1    1      A RES_0402-49.9,1%,1/16W,CHIP,G2A     I4 @BASEBOARD_FAB2_LIB.BASEBOARD_FAB2(SCH_1):PAGE89
  R6F3    2      B RES_0402-10.0K,1%,1/16W,CHIP,GA     I7 @BASEBOARD_FAB2_LIB.BASEBOARD_FAB2(SCH_1):PAGE89
 R8D30    1      A RES_0402-10.0K,1%,1/16W,CHIP,GA    I34 @BASEBOARD_FAB2_LIB.BASEBOARD_FAB2(SCH_1):PAGE89
  Q1F1    3      C NPN_SM-MMBT3904,IC,C52245-001    I53 @BASEBOARD_FAB2_LIB.BASEBOARD_FAB2(SCH_1):PAGE89

IRQ_DIMM_SAVE_R_N @BASEBOARD_FAB2_LIB.BASEBOARD_FAB2(SCH_1):IRQ_DIMM_SAVE_R_N
 R8D30    2      B RES_0402-10.0K,1%,1/16W,CHIP,GA    I34 @BASEBOARD_FAB2_LIB.BASEBOARD_FAB2(SCH_1):PAGE89
  Q8D1    5   B<0> NPN_DUAL_SSOPLF-MBT3904,XSTR,CA    I35 @BASEBOARD_FAB2_LIB.BASEBOARD_FAB2(SCH_1):PAGE89

IRQ_FORCE_NM_THROTTLE_N @BASEBOARD_FAB2_LIB.BASEBOARD_FAB2(SCH_1):IRQ_FORCE_NM_THROTTLE_N
  U7C1 BY42 GPP_D9_SSATA_DEVSLP3 LBG_CORE_QAT_EXT_D_BGA1-IC,H91A   I115 @BASEBOARD_FAB2_LIB.BASEBOARD_FAB2(SCH_1):PAGE119
  U7C1 BA17 GPP_G20_SSATA_DEVSLP0 LBG_CORE_QAT_EXT_D_BGA1-IC,H91A   I147 @BASEBOARD_FAB2_LIB.BASEBOARD_FAB2(SCH_1):PAGE120
  U8E1    1   A<0> TTL08_QFN15-74LVC08A,IC,D90404B    I10 @BASEBOARD_FAB2_LIB.BASEBOARD_FAB2(SCH_1):PAGE170
  R2P4    2      B RES_0402-33.2,1%,1/16W,CHIP,G2A    I74 @BASEBOARD_FAB2_LIB.BASEBOARD_FAB2(SCH_1):PAGE170
 R2T41    1      A RES_0402-22.1,1.0%,1/16W,CHIP,A   I136 @BASEBOARD_FAB2_LIB.BASEBOARD_FAB2(SCH_1):PAGE145

IRQ_FORCE_NM_THROTTLE_R_N @BASEBOARD_FAB2_LIB.BASEBOARD_FAB2(SCH_1):IRQ_FORCE_NM_THROTTLE_R_N
  R2P3    2      B RES_0402-4.75K,1%,1/16W,CHIP,GA     I2 @BASEBOARD_FAB2_LIB.BASEBOARD_FAB2(SCH_1):PAGE170
  U8D3    4      Y TTL1G07_A_SOP-74LVC1G07,IC,C88B     I4 @BASEBOARD_FAB2_LIB.BASEBOARD_FAB2(SCH_1):PAGE170
  R2P4    1      A RES_0402-33.2,1%,1/16W,CHIP,G2A    I74 @BASEBOARD_FAB2_LIB.BASEBOARD_FAB2(SCH_1):PAGE170

IRQ_HFI0_CPU0_LVT2_N @BASEBOARD_FAB2_LIB.BASEBOARD_FAB2(SCH_1):IRQ_HFI0_CPU0_LVT2_N
  U5D1 BP19 CD_HFI0_INT_N SKX_EXT_B_BGA1-IC,TBD    I61 @BASEBOARD_FAB2_LIB.BASEBOARD_FAB2(SCH_1):PAGE29
  J8B1    8    IO8 SCONN24_H46321001_SM-SCONN,H46A     I1 @BASEBOARD_FAB2_LIB.BASEBOARD_FAB2(SCH_1):PAGE91
 R8B10    2      B RES_0402-4.75K,1%,1/16W,CHIP,GA    I16 @BASEBOARD_FAB2_LIB.BASEBOARD_FAB2(SCH_1):PAGE91

IRQ_HFI1_CPU0_LVT2_N @BASEBOARD_FAB2_LIB.BASEBOARD_FAB2(SCH_1):IRQ_HFI1_CPU0_LVT2_N
  U5D1 BM21 CD_HFI1_INT_N SKX_EXT_B_BGA1-IC,TBD    I61 @BASEBOARD_FAB2_LIB.BASEBOARD_FAB2(SCH_1):PAGE29
  J8B1   16   IO16 SCONN24_H46321001_SM-SCONN,H46A     I1 @BASEBOARD_FAB2_LIB.BASEBOARD_FAB2(SCH_1):PAGE91
 R8B17    2      B RES_0402-4.75K,1%,1/16W,CHIP,GA    I18 @BASEBOARD_FAB2_LIB.BASEBOARD_FAB2(SCH_1):PAGE91

IRQ_HSC_FAULT_N @BASEBOARD_FAB2_LIB.BASEBOARD_FAB2(SCH_1):IRQ_HSC_FAULT_N
  U7C1 BJ44 GPP_D2 LBG_CORE_QAT_EXT_D_BGA1-IC,H91A   I115 @BASEBOARD_FAB2_LIB.BASEBOARD_FAB2(SCH_1):PAGE119
  R2M4    2      B RES_0402-1.00K,1%,1/16W,CHIP,GA   I284 @BASEBOARD_FAB2_LIB.BASEBOARD_FAB2(SCH_1):PAGE133
 R1D30    2      B RES_0402-33.2,1%,1/16W,CHIP,G2A   I110 @BASEBOARD_FAB2_LIB.BASEBOARD_FAB2(SCH_1):PAGE199
 U25W4  N19 GPIOAB0_VPODE_NOROE# AST2520A1-GP-GP_ASIC2-GB1-AST2A   I105 @BASEBOARD_FAB2_LIB.BASEBOARD_FAB2(SCH_1):PAGE146

IRQ_HSC_FAULT_R_N @BASEBOARD_FAB2_LIB.BASEBOARD_FAB2(SCH_1):IRQ_HSC_FAULT_R_N
 EU1D2    6 FAULT_N ADM1278_SM-IC,G99251-001    I10 @BASEBOARD_FAB2_LIB.BASEBOARD_FAB2(SCH_1):PAGE199
 R1D30    1      A RES_0402-33.2,1%,1/16W,CHIP,G2A   I110 @BASEBOARD_FAB2_LIB.BASEBOARD_FAB2(SCH_1):PAGE199

IRQ_LOM_ALERT_N @BASEBOARD_FAB2_LIB.BASEBOARD_FAB2(SCH_1):IRQ_LOM_ALERT_N
  U7C1 BY47 GPP_D11_SSATA_DEVSLP5 LBG_CORE_QAT_EXT_D_BGA1-IC,H91A   I115 @BASEBOARD_FAB2_LIB.BASEBOARD_FAB2(SCH_1):PAGE119
 EU9E1   35 SMB_ALRT_N SPRINGVILLE_SM1-IC,G47144-004    I72 @BASEBOARD_FAB2_LIB.BASEBOARD_FAB2(SCH_1):PAGE139
  R9E7    2      B RES_0402-3.32K,1%,1/16W,CHIP,GA   I193 @BASEBOARD_FAB2_LIB.BASEBOARD_FAB2(SCH_1):PAGE139
 U25W4  N18 GPIOAA6_VPOR8_NORD6_SALT13 AST2520A1-GP-GP_ASIC2-GB1-AST2A   I104 @BASEBOARD_FAB2_LIB.BASEBOARD_FAB2(SCH_1):PAGE146

IRQ_LPC_SERIRQ_N @BASEBOARD_FAB2_LIB.BASEBOARD_FAB2(SCH_1):IRQ_LPC_SERIRQ_N
  U7C1   P2 GPP_A6_SERIRQ_ESPI_CS1_N LBG_CORE_QAT_EXT_D_BGA1-IC,H91A   I115 @BASEBOARD_FAB2_LIB.BASEBOARD_FAB2(SCH_1):PAGE119
  R7D3    2      B RES_0402-4.75K,1%,1/16W,CHIP,GA   I243 @BASEBOARD_FAB2_LIB.BASEBOARD_FAB2(SCH_1):PAGE133
R25W73    1      A RES_0402-33.2,1%,1/16W,CHIP,G2A    I73 @BASEBOARD_FAB2_LIB.BASEBOARD_FAB2(SCH_1):PAGE146

IRQ_LPC_SERIRQ_R @BASEBOARD_FAB2_LIB.BASEBOARD_FAB2(SCH_1):IRQ_LPC_SERIRQ_R
R25W73    2      B RES_0402-33.2,1%,1/16W,CHIP,G2A    I73 @BASEBOARD_FAB2_LIB.BASEBOARD_FAB2(SCH_1):PAGE146
 U25W4  F22 GPIOAC6_ESPIALT#_LSIRQ# AST2520A1-GP-GP_ASIC2-GB1-AST2A   I105 @BASEBOARD_FAB2_LIB.BASEBOARD_FAB2(SCH_1):PAGE146

IRQ_LVC3_WAKE_N @BASEBOARD_FAB2_LIB.BASEBOARD_FAB2(SCH_1):IRQ_LVC3_WAKE_N
 R3N13    2      B RES_0402-4.75K,1%,1/16W,CHIP,GA    I71 @BASEBOARD_FAB2_LIB.BASEBOARD_FAB2(SCH_1):PAGE118
  U7C1   K9 WAKE_N LBG_CORE_QAT_EXT_D_BGA1-IC,H91A    I73 @BASEBOARD_FAB2_LIB.BASEBOARD_FAB2(SCH_1):PAGE118
 R8E17    2      B RES_0402-33.2,1%,1/16W,CHIP,G2A     I2 @BASEBOARD_FAB2_LIB.BASEBOARD_FAB2(SCH_1):PAGE142

IRQ_LVC3_WAKE_R_N @BASEBOARD_FAB2_LIB.BASEBOARD_FAB2(SCH_1):IRQ_LVC3_WAKE_R_N
  U8E4    4      Y TTL1G126_A_SOT-74HC1G126,IC,A7B     I1 @BASEBOARD_FAB2_LIB.BASEBOARD_FAB2(SCH_1):PAGE142
 R8E17    1      A RES_0402-33.2,1%,1/16W,CHIP,G2A     I2 @BASEBOARD_FAB2_LIB.BASEBOARD_FAB2(SCH_1):PAGE142

IRQ_MEZZ_LAN_ALERT_N @BASEBOARD_FAB2_LIB.BASEBOARD_FAB2(SCH_1):IRQ_MEZZ_LAN_ALERT_N
  U7C1 BW45 GPP_D3 LBG_CORE_QAT_EXT_D_BGA1-IC,H91A   I115 @BASEBOARD_FAB2_LIB.BASEBOARD_FAB2(SCH_1):PAGE119
 R8F23    2      B RES_0402-2.21K,1%,1/16W,CHIP,GA   I296 @BASEBOARD_FAB2_LIB.BASEBOARD_FAB2(SCH_1):PAGE157
  J9B3   28   IO28 SCONN120_A28699018_SM-SCONN,A2A   I336 @BASEBOARD_FAB2_LIB.BASEBOARD_FAB2(SCH_1):PAGE186
 U25W4  D15 GPIOG6_SGPS2I0_SALT3 AST2520A1-GP-GP_ASIC2-GB1-AST2A   I117 @BASEBOARD_FAB2_LIB.BASEBOARD_FAB2(SCH_1):PAGE145
 U32W2    7   SCLB TCA9517DGKR-GP_DISCRET-G8-TCA9A   I204 @BASEBOARD_FAB2_LIB.BASEBOARD_FAB2(SCH_1):PAGE185

IRQ_OC_DETECT_N @BASEBOARD_FAB2_LIB.BASEBOARD_FAB2(SCH_1):IRQ_OC_DETECT_N
  U7C1  AG7 GPP_F0_SATAXPCIE3_SATAGP3 LBG_CORE_QAT_EXT_D_BGA1-IC,H91A   I147 @BASEBOARD_FAB2_LIB.BASEBOARD_FAB2(SCH_1):PAGE120
  U1D1    2      A TTL1G126_A_SOT-74HC1G126,IC,A7B   I103 @BASEBOARD_FAB2_LIB.BASEBOARD_FAB2(SCH_1):PAGE200
  U1D2    1   OUTB TPS3700_SM-IC,H69492-001   I170 @BASEBOARD_FAB2_LIB.BASEBOARD_FAB2(SCH_1):PAGE200
 R1D23    2      B RES_0402-10.0K,1%,1/16W,CHIP,GA   I191 @BASEBOARD_FAB2_LIB.BASEBOARD_FAB2(SCH_1):PAGE200
 U25W4   T1 GPIOL1_NDCD1_VPIDE AST2520A1-GP-GP_ASIC2-GB1-AST2A   I117 @BASEBOARD_FAB2_LIB.BASEBOARD_FAB2(SCH_1):PAGE145
 R9P15    2      B RES_0402-0.0,5%,1/16W,CHIP,G21A   I243 @BASEBOARD_FAB2_LIB.BASEBOARD_FAB2(SCH_1):PAGE200

IRQ_OOB_MGMT_RISER_ALERT_N @BASEBOARD_FAB2_LIB.BASEBOARD_FAB2(SCH_1):IRQ_OOB_MGMT_RISER_ALERT_N
  J8G1   16   IO16 SCONN200_H68296001_SM-CONN,H68A   I258 @BASEBOARD_FAB2_LIB.BASEBOARD_FAB2(SCH_1):PAGE108
  U7C1 BV42 GPP_D16_SML0BALERT_IE_N LBG_CORE_QAT_EXT_D_BGA1-IC,H91A   I115 @BASEBOARD_FAB2_LIB.BASEBOARD_FAB2(SCH_1):PAGE119
 R2T29    2      B RES_0402-2.21K,1%,1/16W,CHIP,GA   I298 @BASEBOARD_FAB2_LIB.BASEBOARD_FAB2(SCH_1):PAGE157
 U25W4  D16 GPIOG5_SGPS2LD_SALT2 AST2520A1-GP-GP_ASIC2-GB1-AST2A   I117 @BASEBOARD_FAB2_LIB.BASEBOARD_FAB2(SCH_1):PAGE145

IRQ_PCH_NIC_ALERT_N @BASEBOARD_FAB2_LIB.BASEBOARD_FAB2(SCH_1):IRQ_PCH_NIC_ALERT_N
  U7C1 BG22 GPP_B16 LBG_CORE_QAT_EXT_D_BGA1-IC,H91A   I115 @BASEBOARD_FAB2_LIB.BASEBOARD_FAB2(SCH_1):PAGE119
  U7C1 AR17 GPP_F21_LAN_SMBALRT_N LBG_CORE_QAT_EXT_D_BGA1-IC,H91A   I147 @BASEBOARD_FAB2_LIB.BASEBOARD_FAB2(SCH_1):PAGE120
 R8C25    2      B RES_0402-4.75K,1%,1/16W,CHIP,GA   I333 @BASEBOARD_FAB2_LIB.BASEBOARD_FAB2(SCH_1):PAGE133
 U25W4  E17 GPIOG4_SGPS2CK_SALT1 AST2520A1-GP-GP_ASIC2-GB1-AST2A   I117 @BASEBOARD_FAB2_LIB.BASEBOARD_FAB2(SCH_1):PAGE145

IRQ_PIRQA_SPI_TPM_N @BASEBOARD_FAB2_LIB.BASEBOARD_FAB2(SCH_1):IRQ_PIRQA_SPI_TPM_N
  U7C1  AA2 GPP_A7_PIRQA_N_ESPI_ALERT0_N LBG_CORE_QAT_EXT_D_BGA1-IC,H91A   I115 @BASEBOARD_FAB2_LIB.BASEBOARD_FAB2(SCH_1):PAGE119
  R7D7    2      B RES_0402-1.00K,1%,1/16W,CHIP,GA   I331 @BASEBOARD_FAB2_LIB.BASEBOARD_FAB2(SCH_1):PAGE133
  R8E1    2      B RES_0402-0.0,5%,1/16W,CHIP,G21A    I99 @BASEBOARD_FAB2_LIB.BASEBOARD_FAB2(SCH_1):PAGE184

IRQ_PVCCIN_CPU0_VRHOT_LVC3_N @BASEBOARD_FAB2_LIB.BASEBOARD_FAB2(SCH_1):IRQ_PVCCIN_CPU0_VRHOT_LVC3_N
  U7E2    2   B<0> TTL1G08_SOTLF-NC7SZ08,IC,D1032B   I117 @BASEBOARD_FAB2_LIB.BASEBOARD_FAB2(SCH_1):PAGE95
 R6P45    2      B RES_0402-33.2,1%,1/16W,CHIP,G2A   I128 @BASEBOARD_FAB2_LIB.BASEBOARD_FAB2(SCH_1):PAGE201
 U25W4  B22 GPIOF2_NDSR4_LHAD2 AST2520A1-GP-GP_ASIC2-GB1-AST2A   I117 @BASEBOARD_FAB2_LIB.BASEBOARD_FAB2(SCH_1):PAGE145

IRQ_PVCCIN_CPU0_VRHOT_LVC3_R_N @BASEBOARD_FAB2_LIB.BASEBOARD_FAB2(SCH_1):IRQ_PVCCIN_CPU0_VRHOT_LVC3_R_N
  R4E3    2      B RES_0402-1.00K,1%,1/16W,CHIP,GA   I111 @BASEBOARD_FAB2_LIB.BASEBOARD_FAB2(SCH_1):PAGE201
 R6P45    1      A RES_0402-33.2,1%,1/16W,CHIP,G2A   I128 @BASEBOARD_FAB2_LIB.BASEBOARD_FAB2(SCH_1):PAGE201
 EU4D4   13 VRHOT_N PXE1610B_QFN-IC,H79206-001   I155 @BASEBOARD_FAB2_LIB.BASEBOARD_FAB2(SCH_1):PAGE201

IRQ_PVCCIN_CPU1_VRHOT_LVC3_N @BASEBOARD_FAB2_LIB.BASEBOARD_FAB2(SCH_1):IRQ_PVCCIN_CPU1_VRHOT_LVC3_N
  U7E3    2   B<0> TTL1G08_SOTLF-NC7SZ08,IC,D1032B   I118 @BASEBOARD_FAB2_LIB.BASEBOARD_FAB2(SCH_1):PAGE95
  R9P3    2      B RES_0402-33.2,1%,1/16W,CHIP,G2A   I117 @BASEBOARD_FAB2_LIB.BASEBOARD_FAB2(SCH_1):PAGE206
 U25W4  B21 GPIOF3_NRI4_LHAD3 AST2520A1-GP-GP_ASIC2-GB1-AST2A   I117 @BASEBOARD_FAB2_LIB.BASEBOARD_FAB2(SCH_1):PAGE145

IRQ_PVCCIN_CPU1_VRHOT_LVC3_R_N @BASEBOARD_FAB2_LIB.BASEBOARD_FAB2(SCH_1):IRQ_PVCCIN_CPU1_VRHOT_LVC3_R_N
  R1D6    2      B RES_0402-1.00K,1%,1/16W,CHIP,GA     I6 @BASEBOARD_FAB2_LIB.BASEBOARD_FAB2(SCH_1):PAGE206
  R9P3    1      A RES_0402-33.2,1%,1/16W,CHIP,G2A   I117 @BASEBOARD_FAB2_LIB.BASEBOARD_FAB2(SCH_1):PAGE206
 EU1C2   13 VRHOT_N PXE1610B_QFN-IC,H79206-001   I130 @BASEBOARD_FAB2_LIB.BASEBOARD_FAB2(SCH_1):PAGE206

IRQ_PVCCIO_CPU0_VRHOT_N @BASEBOARD_FAB2_LIB.BASEBOARD_FAB2(SCH_1):IRQ_PVCCIO_CPU0_VRHOT_N
 R3P18    2      B RES_0402-1.00K,1%,1/16W,CHIP,GA    I64 @BASEBOARD_FAB2_LIB.BASEBOARD_FAB2(SCH_1):PAGE211
 EU3P1   11 VRHOT_N PXE1110B_QFN-IC,H89187-001    I93 @BASEBOARD_FAB2_LIB.BASEBOARD_FAB2(SCH_1):PAGE211

IRQ_PVCCIO_CPU1_VRHOT_N @BASEBOARD_FAB2_LIB.BASEBOARD_FAB2(SCH_1):IRQ_PVCCIO_CPU1_VRHOT_N
 R4D49    2      B RES_0402-1.00K,1%,1/16W,CHIP,GA    I63 @BASEBOARD_FAB2_LIB.BASEBOARD_FAB2(SCH_1):PAGE213
 EU4D5   11 VRHOT_N PXE1110B_QFN-IC,H89187-001    I96 @BASEBOARD_FAB2_LIB.BASEBOARD_FAB2(SCH_1):PAGE213

IRQ_PVDDQ_ABC_VRHOT_LVT3_N @BASEBOARD_FAB2_LIB.BASEBOARD_FAB2(SCH_1):IRQ_PVDDQ_ABC_VRHOT_LVT3_N
  Q3U1    2 GATE<0> FET_N_DUAL_SMLF-NTJD4001N,FET,A    I49 @BASEBOARD_FAB2_LIB.BASEBOARD_FAB2(SCH_1):PAGE94
  U7C1  BN7 GPP_B4_CPU_GP3 LBG_CORE_QAT_EXT_D_BGA1-IC,H91A   I115 @BASEBOARD_FAB2_LIB.BASEBOARD_FAB2(SCH_1):PAGE119
 U25W4  J19 GPIOF0_NCTS4_LHAD0 AST2520A1-GP-GP_ASIC2-GB1-AST2A   I117 @BASEBOARD_FAB2_LIB.BASEBOARD_FAB2(SCH_1):PAGE145
 R7F23    2      B RES_0402-33.2,1%,1/16W,CHIP,G2A    I53 @BASEBOARD_FAB2_LIB.BASEBOARD_FAB2(SCH_1):PAGE215

IRQ_PVDDQ_ABC_VRHOT_LVT3_R_N @BASEBOARD_FAB2_LIB.BASEBOARD_FAB2(SCH_1):IRQ_PVDDQ_ABC_VRHOT_LVT3_R_N
 R7F27    2      B RES_0402-1.00K,1%,1/16W,CHIP,GA    I50 @BASEBOARD_FAB2_LIB.BASEBOARD_FAB2(SCH_1):PAGE215
 R7F23    1      A RES_0402-33.2,1%,1/16W,CHIP,G2A    I53 @BASEBOARD_FAB2_LIB.BASEBOARD_FAB2(SCH_1):PAGE215
 EU7G1   11 VRHOT_N PXM1310B_QFN-IC,H89186-001    I69 @BASEBOARD_FAB2_LIB.BASEBOARD_FAB2(SCH_1):PAGE215

IRQ_PVDDQ_DEF_VRHOT_LVT3_N @BASEBOARD_FAB2_LIB.BASEBOARD_FAB2(SCH_1):IRQ_PVDDQ_DEF_VRHOT_LVT3_N
  Q7E1    2 GATE<0> FET_N_DUAL_SMLF-NTJD4001N,FET,A    I60 @BASEBOARD_FAB2_LIB.BASEBOARD_FAB2(SCH_1):PAGE94
  U7C1 BK17 GPP_B5_SRCCLKREQ0_N LBG_CORE_QAT_EXT_D_BGA1-IC,H91A   I115 @BASEBOARD_FAB2_LIB.BASEBOARD_FAB2(SCH_1):PAGE119
  R7B1    2      B RES_0402-33.2,1%,1/16W,CHIP,G2A    I59 @BASEBOARD_FAB2_LIB.BASEBOARD_FAB2(SCH_1):PAGE218
 U25W4 AB21 GPIOZ2_VPOG4_NORA2_SIOPBO# AST2520A1-GP-GP_ASIC2-GB1-AST2A   I104 @BASEBOARD_FAB2_LIB.BASEBOARD_FAB2(SCH_1):PAGE146

IRQ_PVDDQ_DEF_VRHOT_LVT3_R_N @BASEBOARD_FAB2_LIB.BASEBOARD_FAB2(SCH_1):IRQ_PVDDQ_DEF_VRHOT_LVT3_R_N
  R7B1    1      A RES_0402-33.2,1%,1/16W,CHIP,G2A    I59 @BASEBOARD_FAB2_LIB.BASEBOARD_FAB2(SCH_1):PAGE218
  R7B4    2      B RES_0402-1.00K,1%,1/16W,CHIP,GA    I57 @BASEBOARD_FAB2_LIB.BASEBOARD_FAB2(SCH_1):PAGE218
 EU7A5   11 VRHOT_N PXM1310B_QFN-IC,H89186-001    I69 @BASEBOARD_FAB2_LIB.BASEBOARD_FAB2(SCH_1):PAGE218

IRQ_PVDDQ_GHJ_VRHOT_LVT3_N @BASEBOARD_FAB2_LIB.BASEBOARD_FAB2(SCH_1):IRQ_PVDDQ_GHJ_VRHOT_LVT3_N
  Q7E2    2 GATE<0> FET_N_DUAL_SMLF-NTJD4001N,FET,A    I69 @BASEBOARD_FAB2_LIB.BASEBOARD_FAB2(SCH_1):PAGE94
  U7C1 BG18 GPP_B6_SRCCLKREQ1_N LBG_CORE_QAT_EXT_D_BGA1-IC,H91A   I115 @BASEBOARD_FAB2_LIB.BASEBOARD_FAB2(SCH_1):PAGE119
 U25W4  H20 GPIOB7 AST2520A1-GP-GP_ASIC2-GB1-AST2A    I95 @BASEBOARD_FAB2_LIB.BASEBOARD_FAB2(SCH_1):PAGE144
  R1G8    2      B RES_0402-33.2,1%,1/16W,CHIP,G2A    I55 @BASEBOARD_FAB2_LIB.BASEBOARD_FAB2(SCH_1):PAGE223

IRQ_PVDDQ_GHJ_VRHOT_LVT3_R_N @BASEBOARD_FAB2_LIB.BASEBOARD_FAB2(SCH_1):IRQ_PVDDQ_GHJ_VRHOT_LVT3_R_N
 R1G11    2      B RES_0402-1.00K,1%,1/16W,CHIP,GA    I49 @BASEBOARD_FAB2_LIB.BASEBOARD_FAB2(SCH_1):PAGE223
  R1G8    1      A RES_0402-33.2,1%,1/16W,CHIP,G2A    I55 @BASEBOARD_FAB2_LIB.BASEBOARD_FAB2(SCH_1):PAGE223
 EU1G2   11 VRHOT_N PXM1310B_QFN-IC,H89186-001    I69 @BASEBOARD_FAB2_LIB.BASEBOARD_FAB2(SCH_1):PAGE223

IRQ_PVDDQ_KLM_VRHOT_LVT3_N @BASEBOARD_FAB2_LIB.BASEBOARD_FAB2(SCH_1):IRQ_PVDDQ_KLM_VRHOT_LVT3_N
  Q4B1    2 GATE<0> FET_N_DUAL_SMLF-NTJD4001N,FET,A    I84 @BASEBOARD_FAB2_LIB.BASEBOARD_FAB2(SCH_1):PAGE94
  U7C1 BR13 GPP_B7_SRCCLKREQ2_N LBG_CORE_QAT_EXT_D_BGA1-IC,H91A   I115 @BASEBOARD_FAB2_LIB.BASEBOARD_FAB2(SCH_1):PAGE119
 U25W4  A21 GPIOF4_NDTR4_LHCLK AST2520A1-GP-GP_ASIC2-GB1-AST2A   I117 @BASEBOARD_FAB2_LIB.BASEBOARD_FAB2(SCH_1):PAGE145
  R1B4    2      B RES_0402-33.2,1%,1/16W,CHIP,G2A    I54 @BASEBOARD_FAB2_LIB.BASEBOARD_FAB2(SCH_1):PAGE226

IRQ_PVDDQ_KLM_VRHOT_LVT3_R_N @BASEBOARD_FAB2_LIB.BASEBOARD_FAB2(SCH_1):IRQ_PVDDQ_KLM_VRHOT_LVT3_R_N
  R1B1    2      B RES_0402-1.00K,1%,1/16W,CHIP,GA    I49 @BASEBOARD_FAB2_LIB.BASEBOARD_FAB2(SCH_1):PAGE226
  R1B4    1      A RES_0402-33.2,1%,1/16W,CHIP,G2A    I54 @BASEBOARD_FAB2_LIB.BASEBOARD_FAB2(SCH_1):PAGE226
 EU1B1   11 VRHOT_N PXM1310B_QFN-IC,H89186-001    I69 @BASEBOARD_FAB2_LIB.BASEBOARD_FAB2(SCH_1):PAGE226

IRQ_PVNN_PCH_VRHOT_N @BASEBOARD_FAB2_LIB.BASEBOARD_FAB2(SCH_1):IRQ_PVNN_PCH_VRHOT_N
  R8A5    2      B RES_0402-1.00K,1%,1/16W,CHIP,GA   I216 @BASEBOARD_FAB2_LIB.BASEBOARD_FAB2(SCH_1):PAGE235
 EU8A1   11 VRHOT_N PXE1110B_QFN-IC,H89187-001   I229 @BASEBOARD_FAB2_LIB.BASEBOARD_FAB2(SCH_1):PAGE235

IRQ_SML0_ALERT_N @BASEBOARD_FAB2_LIB.BASEBOARD_FAB2(SCH_1):IRQ_SML0_ALERT_N
  U7C1 BW34 GPP_C5_SML0ALERT_IE_N LBG_CORE_QAT_EXT_D_BGA1-IC,H91A   I115 @BASEBOARD_FAB2_LIB.BASEBOARD_FAB2(SCH_1):PAGE119
  Q8E2    3    DRN FET_N_SOT23LF-2N7002,FET,C7925A    I13 @BASEBOARD_FAB2_LIB.BASEBOARD_FAB2(SCH_1):PAGE126
  R8C9    2      B RES_0402-4.75K,1%,1/16W,CHIP,GA    I20 @BASEBOARD_FAB2_LIB.BASEBOARD_FAB2(SCH_1):PAGE126
 U25W4  R18 GPIOS2_VPOB4_SALT5 AST2520A1-GP-GP_ASIC2-GB1-AST2A   I104 @BASEBOARD_FAB2_LIB.BASEBOARD_FAB2(SCH_1):PAGE146

IRQ_SML1_PMBUS_ALERT_BUF_N @BASEBOARD_FAB2_LIB.BASEBOARD_FAB2(SCH_1):IRQ_SML1_PMBUS_ALERT_BUF_N
  U8D3    2      A TTL1G07_A_SOP-74LVC1G07,IC,C88B     I4 @BASEBOARD_FAB2_LIB.BASEBOARD_FAB2(SCH_1):PAGE170
  U8D5    4      Y TTL1G126_A_SOT-74HC1G126,IC,A7B    I38 @BASEBOARD_FAB2_LIB.BASEBOARD_FAB2(SCH_1):PAGE170
 R8D26    2      B RES_0402-4.75K,1%,1/16W,CHIP,GA    I71 @BASEBOARD_FAB2_LIB.BASEBOARD_FAB2(SCH_1):PAGE170

IRQ_SML1_PMBUS_ALERT_N @BASEBOARD_FAB2_LIB.BASEBOARD_FAB2(SCH_1):IRQ_SML1_PMBUS_ALERT_N
  U8D5    2      A TTL1G126_A_SOT-74HC1G126,IC,A7B    I38 @BASEBOARD_FAB2_LIB.BASEBOARD_FAB2(SCH_1):PAGE170
  C8D3    1      A CAP_0402LF-470PF,50V,10%,EMPTYA    I42 @BASEBOARD_FAB2_LIB.BASEBOARD_FAB2(SCH_1):PAGE170
 R1D26    2      B RES_0402-33.2,1%,1/16W,CHIP,G2A   I109 @BASEBOARD_FAB2_LIB.BASEBOARD_FAB2(SCH_1):PAGE199
 U25W4  V21 GPIOAA1_VPOR3_NORD1_SALT8 AST2520A1-GP-GP_ASIC2-GB1-AST2A   I104 @BASEBOARD_FAB2_LIB.BASEBOARD_FAB2(SCH_1):PAGE146
  R2P8    2      B RES_0402-4.75K,1%,1/16W,CHIP,GA    I75 @BASEBOARD_FAB2_LIB.BASEBOARD_FAB2(SCH_1):PAGE170
 R7W18    1      A RES_0402-0.0,5%,1/16W,CHIP,G21A   I277 @BASEBOARD_FAB2_LIB.BASEBOARD_FAB2(SCH_1):PAGE120

IRQ_SML1_PMBUS_ALERT_R1_N @BASEBOARD_FAB2_LIB.BASEBOARD_FAB2(SCH_1):IRQ_SML1_PMBUS_ALERT_R1_N
  U7C1  AP7 GPP_F12_SATA_SDATAOUT1 LBG_CORE_QAT_EXT_D_BGA1-IC,H91A   I147 @BASEBOARD_FAB2_LIB.BASEBOARD_FAB2(SCH_1):PAGE120
 R7W18    2      B RES_0402-0.0,5%,1/16W,CHIP,G21A   I277 @BASEBOARD_FAB2_LIB.BASEBOARD_FAB2(SCH_1):PAGE120

IRQ_SML1_PMBUS_ALERT_R_N @BASEBOARD_FAB2_LIB.BASEBOARD_FAB2(SCH_1):IRQ_SML1_PMBUS_ALERT_R_N
 EU1D2   13 GPO1_ALERT1_N_CONV ADM1278_SM-IC,G99251-001    I10 @BASEBOARD_FAB2_LIB.BASEBOARD_FAB2(SCH_1):PAGE199
 R1D26    1      A RES_0402-33.2,1%,1/16W,CHIP,G2A   I109 @BASEBOARD_FAB2_LIB.BASEBOARD_FAB2(SCH_1):PAGE199
  J1F3    5    IO5 CONN8_H62179001_PIP-CONN,H6217A   I106 @BASEBOARD_FAB2_LIB.BASEBOARD_FAB2(SCH_1):PAGE181
  J1F1   A6 PMBUS_ALERT# DM-FCI-CONN76-8R-GP-U-01_CONN-A   I134 @BASEBOARD_FAB2_LIB.BASEBOARD_FAB2(SCH_1):PAGE181

IRQ_SPI_TPM_N_R @BASEBOARD_FAB2_LIB.BASEBOARD_FAB2(SCH_1):IRQ_SPI_TPM_N_R
  J8E1    9    IO9 SCONN11_H67026001_SM-CONN,H670A    I87 @BASEBOARD_FAB2_LIB.BASEBOARD_FAB2(SCH_1):PAGE184
  R8E1    1      A RES_0402-0.0,5%,1/16W,CHIP,G21A    I99 @BASEBOARD_FAB2_LIB.BASEBOARD_FAB2(SCH_1):PAGE184

IRQ_UV_DETECT_N @BASEBOARD_FAB2_LIB.BASEBOARD_FAB2(SCH_1):IRQ_UV_DETECT_N
  U7C1 AU58 GPP_E12_USB2_OC3_N LBG_CORE_QAT_EXT_D_BGA1-IC,H91A   I147 @BASEBOARD_FAB2_LIB.BASEBOARD_FAB2(SCH_1):PAGE120
  U8E1    4   A<0> TTL08_QFN15-74LVC08A,IC,D90404B    I11 @BASEBOARD_FAB2_LIB.BASEBOARD_FAB2(SCH_1):PAGE170
  Q9P1    3 DRAIN<0> FET_N_DUAL_SMLF-2N7002DW,FET,DA   I199 @BASEBOARD_FAB2_LIB.BASEBOARD_FAB2(SCH_1):PAGE200
  R9P4    2      B RES_0402-2.7K,1%,1/16W,CHIP,G2A   I210 @BASEBOARD_FAB2_LIB.BASEBOARD_FAB2(SCH_1):PAGE200
 CR9P1    1      C DIODE_SMLF-BAT54WS,IC,C73510-0A   I214 @BASEBOARD_FAB2_LIB.BASEBOARD_FAB2(SCH_1):PAGE200
 U25W4   T2 GPIOL0_NCTS1 AST2520A1-GP-GP_ASIC2-GB1-AST2A   I117 @BASEBOARD_FAB2_LIB.BASEBOARD_FAB2(SCH_1):PAGE145

ISENSE_P1V05_PCH_STBY_PH1_IMON @BASEBOARD_FAB2_LIB.BASEBOARD_FAB2(SCH_1):ISENSE_P1V05_PCH_STBY_PH1_IMON
 EU8A1   26 BISEN1 PXE1110B_QFN-IC,H89187-001   I229 @BASEBOARD_FAB2_LIB.BASEBOARD_FAB2(SCH_1):PAGE235
 EU7A2   38   IOUT IR354XX_SM-IR35412,IC,H73684-0A   I117 @BASEBOARD_FAB2_LIB.BASEBOARD_FAB2(SCH_1):PAGE236
  CF24    2      2 SC22P50V2JN-4GP_SMD-BCG-SC22P5A   I240 @BASEBOARD_FAB2_LIB.BASEBOARD_FAB2(SCH_1):PAGE235
  RF24    2      B RES_0402-1.0K,0.1%,1/16W,CHIP,A   I242 @BASEBOARD_FAB2_LIB.BASEBOARD_FAB2(SCH_1):PAGE235

ISENSE_PVCCIN_CPU0_PH1_IMON @BASEBOARD_FAB2_LIB.BASEBOARD_FAB2(SCH_1):ISENSE_PVCCIN_CPU0_PH1_IMON
 EU4D4   24 AISEN1 PXE1610B_QFN-IC,H79206-001   I155 @BASEBOARD_FAB2_LIB.BASEBOARD_FAB2(SCH_1):PAGE201
 EU4E1   38   IOUT IR354XX_SM-IR35411,IC,H73688-0A    I63 @BASEBOARD_FAB2_LIB.BASEBOARD_FAB2(SCH_1):PAGE202
   CF1    2      2 SC22P50V2JN-4GP_SMD-BCG-SC22P5A   I168 @BASEBOARD_FAB2_LIB.BASEBOARD_FAB2(SCH_1):PAGE201
   RF1    2      B RES_0402-1.0K,0.1%,1/16W,CHIP,A   I182 @BASEBOARD_FAB2_LIB.BASEBOARD_FAB2(SCH_1):PAGE201

ISENSE_PVCCIN_CPU0_PH2_IMON @BASEBOARD_FAB2_LIB.BASEBOARD_FAB2(SCH_1):ISENSE_PVCCIN_CPU0_PH2_IMON
 EU4D4   26 AISEN2 PXE1610B_QFN-IC,H79206-001   I155 @BASEBOARD_FAB2_LIB.BASEBOARD_FAB2(SCH_1):PAGE201
 EU4D6   38   IOUT IR354XX_SM-IR35411,IC,H73688-0A    I64 @BASEBOARD_FAB2_LIB.BASEBOARD_FAB2(SCH_1):PAGE202
   CF2    2      2 SC22P50V2JN-4GP_SMD-BCG-SC22P5A   I169 @BASEBOARD_FAB2_LIB.BASEBOARD_FAB2(SCH_1):PAGE201
   RF2    2      B RES_0402-1.0K,0.1%,1/16W,CHIP,A   I183 @BASEBOARD_FAB2_LIB.BASEBOARD_FAB2(SCH_1):PAGE201

ISENSE_PVCCIN_CPU0_PH3_IMON @BASEBOARD_FAB2_LIB.BASEBOARD_FAB2(SCH_1):ISENSE_PVCCIN_CPU0_PH3_IMON
 EU4D4   28 AISEN3 PXE1610B_QFN-IC,H79206-001   I155 @BASEBOARD_FAB2_LIB.BASEBOARD_FAB2(SCH_1):PAGE201
 EU4D3   38   IOUT IR354XX_SM-IR35411,IC,H73688-0A    I70 @BASEBOARD_FAB2_LIB.BASEBOARD_FAB2(SCH_1):PAGE203
   CF3    2      2 SC22P50V2JN-4GP_SMD-BCG-SC22P5A   I170 @BASEBOARD_FAB2_LIB.BASEBOARD_FAB2(SCH_1):PAGE201
   RF3    2      B RES_0402-1.0K,0.1%,1/16W,CHIP,A   I184 @BASEBOARD_FAB2_LIB.BASEBOARD_FAB2(SCH_1):PAGE201

ISENSE_PVCCIN_CPU0_PH4_IMON @BASEBOARD_FAB2_LIB.BASEBOARD_FAB2(SCH_1):ISENSE_PVCCIN_CPU0_PH4_IMON
 EU4D4   30 AISEN4 PXE1610B_QFN-IC,H79206-001   I155 @BASEBOARD_FAB2_LIB.BASEBOARD_FAB2(SCH_1):PAGE201
 EU4D1   38   IOUT IR354XX_SM-IR35411,IC,H73688-0A    I71 @BASEBOARD_FAB2_LIB.BASEBOARD_FAB2(SCH_1):PAGE203
   CF4    2      2 SC22P50V2JN-4GP_SMD-BCG-SC22P5A   I171 @BASEBOARD_FAB2_LIB.BASEBOARD_FAB2(SCH_1):PAGE201
   RF4    2      B RES_0402-1.0K,0.1%,1/16W,CHIP,A   I185 @BASEBOARD_FAB2_LIB.BASEBOARD_FAB2(SCH_1):PAGE201

ISENSE_PVCCIN_CPU0_PH5_IMON @BASEBOARD_FAB2_LIB.BASEBOARD_FAB2(SCH_1):ISENSE_PVCCIN_CPU0_PH5_IMON
 EU4D4   32 AISEN5 PXE1610B_QFN-IC,H79206-001   I155 @BASEBOARD_FAB2_LIB.BASEBOARD_FAB2(SCH_1):PAGE201
 EU4C2   38   IOUT IR354XX_SM-IR35411,IC,H73688-0A    I71 @BASEBOARD_FAB2_LIB.BASEBOARD_FAB2(SCH_1):PAGE204
   CF5    2      2 SC22P50V2JN-4GP_SMD-BCG-SC22P5A   I172 @BASEBOARD_FAB2_LIB.BASEBOARD_FAB2(SCH_1):PAGE201
   RF5    2      B RES_0402-1.0K,0.1%,1/16W,CHIP,A   I186 @BASEBOARD_FAB2_LIB.BASEBOARD_FAB2(SCH_1):PAGE201

ISENSE_PVCCIN_CPU1_PH1_IMON @BASEBOARD_FAB2_LIB.BASEBOARD_FAB2(SCH_1):ISENSE_PVCCIN_CPU1_PH1_IMON
 EU1C2   24 AISEN1 PXE1610B_QFN-IC,H79206-001   I130 @BASEBOARD_FAB2_LIB.BASEBOARD_FAB2(SCH_1):PAGE206
 EU1E2   38   IOUT IR354XX_SM-IR35411,IC,H73688-0A    I20 @BASEBOARD_FAB2_LIB.BASEBOARD_FAB2(SCH_1):PAGE207
   CF7    2      2 SC22P50V2JN-4GP_SMD-BCG-SC22P5A   I137 @BASEBOARD_FAB2_LIB.BASEBOARD_FAB2(SCH_1):PAGE206
   RF7    2      B RES_0402-1.0K,0.1%,1/16W,CHIP,A   I150 @BASEBOARD_FAB2_LIB.BASEBOARD_FAB2(SCH_1):PAGE206

ISENSE_PVCCIN_CPU1_PH2_IMON @BASEBOARD_FAB2_LIB.BASEBOARD_FAB2(SCH_1):ISENSE_PVCCIN_CPU1_PH2_IMON
 EU1C2   26 AISEN2 PXE1610B_QFN-IC,H79206-001   I130 @BASEBOARD_FAB2_LIB.BASEBOARD_FAB2(SCH_1):PAGE206
   CF8    2      2 SC22P50V2JN-4GP_SMD-BCG-SC22P5A   I138 @BASEBOARD_FAB2_LIB.BASEBOARD_FAB2(SCH_1):PAGE206
   RF8    2      B RES_0402-1.0K,0.1%,1/16W,CHIP,A   I151 @BASEBOARD_FAB2_LIB.BASEBOARD_FAB2(SCH_1):PAGE206
 EU1D4   38   IOUT IR354XX_SM-IR35411,IC,H73688-0A   I113 @BASEBOARD_FAB2_LIB.BASEBOARD_FAB2(SCH_1):PAGE207

ISENSE_PVCCIN_CPU1_PH3_IMON @BASEBOARD_FAB2_LIB.BASEBOARD_FAB2(SCH_1):ISENSE_PVCCIN_CPU1_PH3_IMON
 EU1C2   28 AISEN3 PXE1610B_QFN-IC,H79206-001   I130 @BASEBOARD_FAB2_LIB.BASEBOARD_FAB2(SCH_1):PAGE206
 EU1D3   38   IOUT IR354XX_SM-IR35411,IC,H73688-0A    I27 @BASEBOARD_FAB2_LIB.BASEBOARD_FAB2(SCH_1):PAGE208
   CF9    2      2 SC22P50V2JN-4GP_SMD-BCG-SC22P5A   I139 @BASEBOARD_FAB2_LIB.BASEBOARD_FAB2(SCH_1):PAGE206
   RF9    2      B RES_0402-1.0K,0.1%,1/16W,CHIP,A   I152 @BASEBOARD_FAB2_LIB.BASEBOARD_FAB2(SCH_1):PAGE206

ISENSE_PVCCIN_CPU1_PH4_IMON @BASEBOARD_FAB2_LIB.BASEBOARD_FAB2(SCH_1):ISENSE_PVCCIN_CPU1_PH4_IMON
 EU1C2   30 AISEN4 PXE1610B_QFN-IC,H79206-001   I130 @BASEBOARD_FAB2_LIB.BASEBOARD_FAB2(SCH_1):PAGE206
 EU1D1   38   IOUT IR354XX_SM-IR35411,IC,H73688-0A    I71 @BASEBOARD_FAB2_LIB.BASEBOARD_FAB2(SCH_1):PAGE208
  CF10    2      2 SC22P50V2JN-4GP_SMD-BCG-SC22P5A   I140 @BASEBOARD_FAB2_LIB.BASEBOARD_FAB2(SCH_1):PAGE206
  RF10    2      B RES_0402-1.0K,0.1%,1/16W,CHIP,A   I153 @BASEBOARD_FAB2_LIB.BASEBOARD_FAB2(SCH_1):PAGE206

ISENSE_PVCCIN_CPU1_PH5_IMON @BASEBOARD_FAB2_LIB.BASEBOARD_FAB2(SCH_1):ISENSE_PVCCIN_CPU1_PH5_IMON
 EU1C2   32 AISEN5 PXE1610B_QFN-IC,H79206-001   I130 @BASEBOARD_FAB2_LIB.BASEBOARD_FAB2(SCH_1):PAGE206
 EU1C3   38   IOUT IR354XX_SM-IR35411,IC,H73688-0A    I56 @BASEBOARD_FAB2_LIB.BASEBOARD_FAB2(SCH_1):PAGE209
  CF11    2      2 SC22P50V2JN-4GP_SMD-BCG-SC22P5A   I141 @BASEBOARD_FAB2_LIB.BASEBOARD_FAB2(SCH_1):PAGE206
  RF11    2      B RES_0402-1.0K,0.1%,1/16W,CHIP,A   I154 @BASEBOARD_FAB2_LIB.BASEBOARD_FAB2(SCH_1):PAGE206

ISENSE_PVCCIO_CPU0_PH1_IMON @BASEBOARD_FAB2_LIB.BASEBOARD_FAB2(SCH_1):ISENSE_PVCCIO_CPU0_PH1_IMON
 EU3P1   22 AISEN1 PXE1110B_QFN-IC,H89187-001    I93 @BASEBOARD_FAB2_LIB.BASEBOARD_FAB2(SCH_1):PAGE211
 EU7C1   38   IOUT IR354XX_SM-IR35412,IC,H73684-0A   I101 @BASEBOARD_FAB2_LIB.BASEBOARD_FAB2(SCH_1):PAGE212
  CF13    2      2 SC22P50V2JN-4GP_SMD-BCG-SC22P5A    I95 @BASEBOARD_FAB2_LIB.BASEBOARD_FAB2(SCH_1):PAGE211
  RF13    2      B RES_0402-1.0K,0.1%,1/16W,CHIP,A    I96 @BASEBOARD_FAB2_LIB.BASEBOARD_FAB2(SCH_1):PAGE211

ISENSE_PVCCIO_CPU1_PH1_IMON @BASEBOARD_FAB2_LIB.BASEBOARD_FAB2(SCH_1):ISENSE_PVCCIO_CPU1_PH1_IMON
 EU4D5   22 AISEN1 PXE1110B_QFN-IC,H89187-001    I96 @BASEBOARD_FAB2_LIB.BASEBOARD_FAB2(SCH_1):PAGE213
 EU4E2   38   IOUT IR354XX_SM-IR35412,IC,H73684-0A   I126 @BASEBOARD_FAB2_LIB.BASEBOARD_FAB2(SCH_1):PAGE214
  CF14    2      2 SC22P50V2JN-4GP_SMD-BCG-SC22P5A    I98 @BASEBOARD_FAB2_LIB.BASEBOARD_FAB2(SCH_1):PAGE213
  RF14    2      B RES_0402-1.0K,0.1%,1/16W,CHIP,A    I99 @BASEBOARD_FAB2_LIB.BASEBOARD_FAB2(SCH_1):PAGE213

ISENSE_PVDDQ_ABC_PH1_IMON @BASEBOARD_FAB2_LIB.BASEBOARD_FAB2(SCH_1):ISENSE_PVDDQ_ABC_PH1_IMON
 EU7G2   38   IOUT IR354XX_SM-IR35411,IC,H73688-0A   I102 @BASEBOARD_FAB2_LIB.BASEBOARD_FAB2(SCH_1):PAGE216
  RF15    2      B RES_0402-1.0K,0.1%,1/16W,CHIP,A    I15 @BASEBOARD_FAB2_LIB.BASEBOARD_FAB2(SCH_1):PAGE215
  CF15    2      2 SC22P50V2JN-4GP_SMD-BCG-SC22P5A    I16 @BASEBOARD_FAB2_LIB.BASEBOARD_FAB2(SCH_1):PAGE215
 EU7G1   22 AISEN1 PXM1310B_QFN-IC,H89186-001    I69 @BASEBOARD_FAB2_LIB.BASEBOARD_FAB2(SCH_1):PAGE215

ISENSE_PVDDQ_ABC_PH2_IMON @BASEBOARD_FAB2_LIB.BASEBOARD_FAB2(SCH_1):ISENSE_PVDDQ_ABC_PH2_IMON
 EU7G3   38   IOUT IR354XX_SM-IR35411,IC,H73688-0A   I103 @BASEBOARD_FAB2_LIB.BASEBOARD_FAB2(SCH_1):PAGE216
  CF16    2      2 SC22P50V2JN-4GP_SMD-BCG-SC22P5A    I26 @BASEBOARD_FAB2_LIB.BASEBOARD_FAB2(SCH_1):PAGE215
  RF16    2      B RES_0402-1.0K,0.1%,1/16W,CHIP,A    I27 @BASEBOARD_FAB2_LIB.BASEBOARD_FAB2(SCH_1):PAGE215
 EU7G1   24 AISEN2 PXM1310B_QFN-IC,H89186-001    I69 @BASEBOARD_FAB2_LIB.BASEBOARD_FAB2(SCH_1):PAGE215

ISENSE_PVDDQ_DEF_PH1_IMON @BASEBOARD_FAB2_LIB.BASEBOARD_FAB2(SCH_1):ISENSE_PVDDQ_DEF_PH1_IMON
 EU7A1   38   IOUT IR354XX_SM-IR35411,IC,H73688-0A   I106 @BASEBOARD_FAB2_LIB.BASEBOARD_FAB2(SCH_1):PAGE219
  RF17    2      B RES_0402-1.0K,0.1%,1/16W,CHIP,A    I18 @BASEBOARD_FAB2_LIB.BASEBOARD_FAB2(SCH_1):PAGE218
 EU7A5   22 AISEN1 PXM1310B_QFN-IC,H89186-001    I69 @BASEBOARD_FAB2_LIB.BASEBOARD_FAB2(SCH_1):PAGE218
  CF17    2      2 SC22P50V2JN-4GP_SMD-BCG-SC22P5A    I17 @BASEBOARD_FAB2_LIB.BASEBOARD_FAB2(SCH_1):PAGE218

ISENSE_PVDDQ_DEF_PH2_IMON @BASEBOARD_FAB2_LIB.BASEBOARD_FAB2(SCH_1):ISENSE_PVDDQ_DEF_PH2_IMON
 EU7A4   38   IOUT IR354XX_SM-IR35411,IC,H73688-0A   I107 @BASEBOARD_FAB2_LIB.BASEBOARD_FAB2(SCH_1):PAGE219
  RF18    2      B RES_0402-1.0K,0.1%,1/16W,CHIP,A    I19 @BASEBOARD_FAB2_LIB.BASEBOARD_FAB2(SCH_1):PAGE218
  CF18    2      2 SC22P50V2JN-4GP_SMD-BCG-SC22P5A    I20 @BASEBOARD_FAB2_LIB.BASEBOARD_FAB2(SCH_1):PAGE218
 EU7A5   24 AISEN2 PXM1310B_QFN-IC,H89186-001    I69 @BASEBOARD_FAB2_LIB.BASEBOARD_FAB2(SCH_1):PAGE218

ISENSE_PVDDQ_GHJ_PH1_IMON @BASEBOARD_FAB2_LIB.BASEBOARD_FAB2(SCH_1):ISENSE_PVDDQ_GHJ_PH1_IMON
  RF19    2      B RES_0402-1.0K,0.1%,1/16W,CHIP,A    I16 @BASEBOARD_FAB2_LIB.BASEBOARD_FAB2(SCH_1):PAGE223
 EU1G1   38   IOUT IR354XX_SM-IR35411,IC,H73688-0A   I110 @BASEBOARD_FAB2_LIB.BASEBOARD_FAB2(SCH_1):PAGE224
  CF19    2      2 SC22P50V2JN-4GP_SMD-BCG-SC22P5A    I15 @BASEBOARD_FAB2_LIB.BASEBOARD_FAB2(SCH_1):PAGE223
 EU1G2   22 AISEN1 PXM1310B_QFN-IC,H89186-001    I69 @BASEBOARD_FAB2_LIB.BASEBOARD_FAB2(SCH_1):PAGE223

ISENSE_PVDDQ_GHJ_PH2_IMON @BASEBOARD_FAB2_LIB.BASEBOARD_FAB2(SCH_1):ISENSE_PVDDQ_GHJ_PH2_IMON
 EU1F1   38   IOUT IR354XX_SM-IR35411,IC,H73688-0A   I111 @BASEBOARD_FAB2_LIB.BASEBOARD_FAB2(SCH_1):PAGE224
  RF20    2      B RES_0402-1.0K,0.1%,1/16W,CHIP,A    I19 @BASEBOARD_FAB2_LIB.BASEBOARD_FAB2(SCH_1):PAGE223
 EU1G2   24 AISEN2 PXM1310B_QFN-IC,H89186-001    I69 @BASEBOARD_FAB2_LIB.BASEBOARD_FAB2(SCH_1):PAGE223
  CF20    2      2 SC22P50V2JN-4GP_SMD-BCG-SC22P5A    I17 @BASEBOARD_FAB2_LIB.BASEBOARD_FAB2(SCH_1):PAGE223

ISENSE_PVDDQ_KLM_PH1_IMON @BASEBOARD_FAB2_LIB.BASEBOARD_FAB2(SCH_1):ISENSE_PVDDQ_KLM_PH1_IMON
  RF21    2      B RES_0402-1.0K,0.1%,1/16W,CHIP,A    I16 @BASEBOARD_FAB2_LIB.BASEBOARD_FAB2(SCH_1):PAGE226
 EU1A2   38   IOUT IR354XX_SM-IR35411,IC,H73688-0A   I101 @BASEBOARD_FAB2_LIB.BASEBOARD_FAB2(SCH_1):PAGE227
  CF21    2      2 SC22P50V2JN-4GP_SMD-BCG-SC22P5A    I15 @BASEBOARD_FAB2_LIB.BASEBOARD_FAB2(SCH_1):PAGE226
 EU1B1   22 AISEN1 PXM1310B_QFN-IC,H89186-001    I69 @BASEBOARD_FAB2_LIB.BASEBOARD_FAB2(SCH_1):PAGE226

ISENSE_PVDDQ_KLM_PH2_IMON @BASEBOARD_FAB2_LIB.BASEBOARD_FAB2(SCH_1):ISENSE_PVDDQ_KLM_PH2_IMON
 EU1A1   38   IOUT IR354XX_SM-IR35411,IC,H73688-0A   I102 @BASEBOARD_FAB2_LIB.BASEBOARD_FAB2(SCH_1):PAGE227
  RF22    2      B RES_0402-1.0K,0.1%,1/16W,CHIP,A    I18 @BASEBOARD_FAB2_LIB.BASEBOARD_FAB2(SCH_1):PAGE226
 EU1B1   24 AISEN2 PXM1310B_QFN-IC,H89186-001    I69 @BASEBOARD_FAB2_LIB.BASEBOARD_FAB2(SCH_1):PAGE226
  CF22    2      2 SC22P50V2JN-4GP_SMD-BCG-SC22P5A    I17 @BASEBOARD_FAB2_LIB.BASEBOARD_FAB2(SCH_1):PAGE226

ISENSE_PVNN_PCH_PH1_IMON @BASEBOARD_FAB2_LIB.BASEBOARD_FAB2(SCH_1):ISENSE_PVNN_PCH_PH1_IMON
 EU8A1   22 AISEN1 PXE1110B_QFN-IC,H89187-001   I229 @BASEBOARD_FAB2_LIB.BASEBOARD_FAB2(SCH_1):PAGE235
 EU7A3   38   IOUT IR354XX_SM-IR35412,IC,H73684-0A   I116 @BASEBOARD_FAB2_LIB.BASEBOARD_FAB2(SCH_1):PAGE236
  CF23    2      2 SC22P50V2JN-4GP_SMD-BCG-SC22P5A   I239 @BASEBOARD_FAB2_LIB.BASEBOARD_FAB2(SCH_1):PAGE235
  RF23    2      B RES_0402-1.0K,0.1%,1/16W,CHIP,A   I241 @BASEBOARD_FAB2_LIB.BASEBOARD_FAB2(SCH_1):PAGE235

ISENSE_PVSA_CPU0_IMON @BASEBOARD_FAB2_LIB.BASEBOARD_FAB2(SCH_1):ISENSE_PVSA_CPU0_IMON
 EU4D4   38 BISEN1 PXE1610B_QFN-IC,H79206-001   I155 @BASEBOARD_FAB2_LIB.BASEBOARD_FAB2(SCH_1):PAGE201
 EU4C1   38   IOUT IR354XX_SM-IR35412,IC,H73684-0A    I46 @BASEBOARD_FAB2_LIB.BASEBOARD_FAB2(SCH_1):PAGE205
   CF6    2      2 SC22P50V2JN-4GP_SMD-BCG-SC22P5A   I173 @BASEBOARD_FAB2_LIB.BASEBOARD_FAB2(SCH_1):PAGE201
   RF6    2      B RES_0402-1.0K,0.1%,1/16W,CHIP,A   I180 @BASEBOARD_FAB2_LIB.BASEBOARD_FAB2(SCH_1):PAGE201

ISENSE_PVSA_CPU1_IMON @BASEBOARD_FAB2_LIB.BASEBOARD_FAB2(SCH_1):ISENSE_PVSA_CPU1_IMON
 EU1C2   38 BISEN1 PXE1610B_QFN-IC,H79206-001   I130 @BASEBOARD_FAB2_LIB.BASEBOARD_FAB2(SCH_1):PAGE206
 EU1C1   38   IOUT IR354XX_SM-IR35412,IC,H73684-0A    I51 @BASEBOARD_FAB2_LIB.BASEBOARD_FAB2(SCH_1):PAGE210
  CF12    2      2 SC22P50V2JN-4GP_SMD-BCG-SC22P5A   I142 @BASEBOARD_FAB2_LIB.BASEBOARD_FAB2(SCH_1):PAGE206
  RF12    2      B RES_0402-1.0K,0.1%,1/16W,CHIP,A   I149 @BASEBOARD_FAB2_LIB.BASEBOARD_FAB2(SCH_1):PAGE206

ISENSE_TMP421_1_BC @BASEBOARD_FAB2_LIB.BASEBOARD_FAB2(SCH_1):ISENSE_TMP421_1_BC
  R9B5    1      A RES_0402-49.9,1%,1/16W,CHIP,G2A     I5 @BASEBOARD_FAB2_LIB.BASEBOARD_FAB2(SCH_1):PAGE167
  Q9B1    B      B 2SB2907A-B0-00001-GP_DISCRET-GA    I93 @BASEBOARD_FAB2_LIB.BASEBOARD_FAB2(SCH_1):PAGE167
  Q9B1    C      C 2SB2907A-B0-00001-GP_DISCRET-GA    I93 @BASEBOARD_FAB2_LIB.BASEBOARD_FAB2(SCH_1):PAGE167

ISENSE_TMP421_1_DXN @BASEBOARD_FAB2_LIB.BASEBOARD_FAB2(SCH_1):ISENSE_TMP421_1_DXN
  U9B4    2    DXN TMP421_TSSOP-IC,G62962-001     I1 @BASEBOARD_FAB2_LIB.BASEBOARD_FAB2(SCH_1):PAGE167
  R9B5    2      B RES_0402-49.9,1%,1/16W,CHIP,G2A     I5 @BASEBOARD_FAB2_LIB.BASEBOARD_FAB2(SCH_1):PAGE167
  C1M4    2      B CAP_0402LF-47.0PF,50V,5%,EMPTYA     I7 @BASEBOARD_FAB2_LIB.BASEBOARD_FAB2(SCH_1):PAGE167

ISENSE_TMP421_1_DXP @BASEBOARD_FAB2_LIB.BASEBOARD_FAB2(SCH_1):ISENSE_TMP421_1_DXP
  U9B4    1    DXP TMP421_TSSOP-IC,G62962-001     I1 @BASEBOARD_FAB2_LIB.BASEBOARD_FAB2(SCH_1):PAGE167
  R9B4    2      B RES_0402-49.9,1%,1/16W,CHIP,G2A     I6 @BASEBOARD_FAB2_LIB.BASEBOARD_FAB2(SCH_1):PAGE167
  C1M4    1      A CAP_0402LF-47.0PF,50V,5%,EMPTYA     I7 @BASEBOARD_FAB2_LIB.BASEBOARD_FAB2(SCH_1):PAGE167

ISENSE_TMP421_1_E @BASEBOARD_FAB2_LIB.BASEBOARD_FAB2(SCH_1):ISENSE_TMP421_1_E
  R9B4    1      A RES_0402-49.9,1%,1/16W,CHIP,G2A     I6 @BASEBOARD_FAB2_LIB.BASEBOARD_FAB2(SCH_1):PAGE167
  Q9B1    E      E 2SB2907A-B0-00001-GP_DISCRET-GA    I93 @BASEBOARD_FAB2_LIB.BASEBOARD_FAB2(SCH_1):PAGE167

ISENSE_TMP421_2_BC @BASEBOARD_FAB2_LIB.BASEBOARD_FAB2(SCH_1):ISENSE_TMP421_2_BC
  R9R6    1      A RES_0402-49.9,1%,1/16W,CHIP,G2A    I26 @BASEBOARD_FAB2_LIB.BASEBOARD_FAB2(SCH_1):PAGE167
  Q1E1    B      B 2SB2907A-B0-00001-GP_DISCRET-GA    I94 @BASEBOARD_FAB2_LIB.BASEBOARD_FAB2(SCH_1):PAGE167
  Q1E1    C      C 2SB2907A-B0-00001-GP_DISCRET-GA    I94 @BASEBOARD_FAB2_LIB.BASEBOARD_FAB2(SCH_1):PAGE167

ISENSE_TMP421_2_DXN @BASEBOARD_FAB2_LIB.BASEBOARD_FAB2(SCH_1):ISENSE_TMP421_2_DXN
 C1E19    2      B CAP_0402LF-47.0PF,50V,5%,EMPTYA    I24 @BASEBOARD_FAB2_LIB.BASEBOARD_FAB2(SCH_1):PAGE167
  R9R6    2      B RES_0402-49.9,1%,1/16W,CHIP,G2A    I26 @BASEBOARD_FAB2_LIB.BASEBOARD_FAB2(SCH_1):PAGE167
  U1E1    2    DXN TMP421_TSSOP-IC,G62962-001    I30 @BASEBOARD_FAB2_LIB.BASEBOARD_FAB2(SCH_1):PAGE167

ISENSE_TMP421_2_DXP @BASEBOARD_FAB2_LIB.BASEBOARD_FAB2(SCH_1):ISENSE_TMP421_2_DXP
 C1E19    1      A CAP_0402LF-47.0PF,50V,5%,EMPTYA    I24 @BASEBOARD_FAB2_LIB.BASEBOARD_FAB2(SCH_1):PAGE167
  R9R5    2      B RES_0402-49.9,1%,1/16W,CHIP,G2A    I25 @BASEBOARD_FAB2_LIB.BASEBOARD_FAB2(SCH_1):PAGE167
  U1E1    1    DXP TMP421_TSSOP-IC,G62962-001    I30 @BASEBOARD_FAB2_LIB.BASEBOARD_FAB2(SCH_1):PAGE167

ISENSE_TMP421_2_E @BASEBOARD_FAB2_LIB.BASEBOARD_FAB2(SCH_1):ISENSE_TMP421_2_E
  R9R5    1      A RES_0402-49.9,1%,1/16W,CHIP,G2A    I25 @BASEBOARD_FAB2_LIB.BASEBOARD_FAB2(SCH_1):PAGE167
  Q1E1    E      E 2SB2907A-B0-00001-GP_DISCRET-GA    I94 @BASEBOARD_FAB2_LIB.BASEBOARD_FAB2(SCH_1):PAGE167

JTAG_BMC_BUF_TDI @BASEBOARD_FAB2_LIB.BASEBOARD_FAB2(SCH_1):JTAG_BMC_BUF_TDI
R25W160    2      B RES_0402-1.00K,1%,1/16W,CHIP,GA    I20 @BASEBOARD_FAB2_LIB.BASEBOARD_FAB2(SCH_1):PAGE269
U25W10   10     A2 GTL2014_SM-IC,D66151-001    I49 @BASEBOARD_FAB2_LIB.BASEBOARD_FAB2(SCH_1):PAGE269
U25W16    3   B<3> TTL3126_QFNLF-74CBTLV3126,IC,DB    I38 @BASEBOARD_FAB2_LIB.BASEBOARD_FAB2(SCH_1):PAGE268

JTAG_BMC_BUF_TDO @BASEBOARD_FAB2_LIB.BASEBOARD_FAB2(SCH_1):JTAG_BMC_BUF_TDO
U25W16    8   B<1> TTL3126_QFNLF-74CBTLV3126,IC,DB    I38 @BASEBOARD_FAB2_LIB.BASEBOARD_FAB2(SCH_1):PAGE268
R25W187    2      B RES_0402-0.0,5%,1/16W,CHIP,G21A    I66 @BASEBOARD_FAB2_LIB.BASEBOARD_FAB2(SCH_1):PAGE268

JTAG_BMC_BUF_TDO_R @BASEBOARD_FAB2_LIB.BASEBOARD_FAB2(SCH_1):JTAG_BMC_BUF_TDO_R
U25W11    9     A3 GTL2014_SM-IC,D66151-001    I33 @BASEBOARD_FAB2_LIB.BASEBOARD_FAB2(SCH_1):PAGE268
R25W187    1      A RES_0402-0.0,5%,1/16W,CHIP,G21A    I66 @BASEBOARD_FAB2_LIB.BASEBOARD_FAB2(SCH_1):PAGE268

JTAG_BMC_BUF_TMS @BASEBOARD_FAB2_LIB.BASEBOARD_FAB2(SCH_1):JTAG_BMC_BUF_TMS
R25W161    2      B RES_0402-1.00K,1%,1/16W,CHIP,GA    I21 @BASEBOARD_FAB2_LIB.BASEBOARD_FAB2(SCH_1):PAGE269
U25W10    9     A3 GTL2014_SM-IC,D66151-001    I49 @BASEBOARD_FAB2_LIB.BASEBOARD_FAB2(SCH_1):PAGE269
U25W16    6   B<2> TTL3126_QFNLF-74CBTLV3126,IC,DB    I38 @BASEBOARD_FAB2_LIB.BASEBOARD_FAB2(SCH_1):PAGE268

JTAG_BMC_TCK @BASEBOARD_FAB2_LIB.BASEBOARD_FAB2(SCH_1):JTAG_BMC_TCK
 R8G17    1      A RES_0402-0.0,5%,1/16W,CHIP,G21A    I25 @BASEBOARD_FAB2_LIB.BASEBOARD_FAB2(SCH_1):PAGE189
 U25W4  C10    TCK AST2520A1-GP-GP_ASIC2-GB1-AST2A    I95 @BASEBOARD_FAB2_LIB.BASEBOARD_FAB2(SCH_1):PAGE144
U25W19    2      A TTL1G126_A_SOT-74HC1G126,IC,A7B    I76 @BASEBOARD_FAB2_LIB.BASEBOARD_FAB2(SCH_1):PAGE269

JTAG_BMC_TCK0 @BASEBOARD_FAB2_LIB.BASEBOARD_FAB2(SCH_1):JTAG_BMC_TCK0
R25W168    1      A RES_0402-1.00K,1%,1/16W,CHIP,GA    I11 @BASEBOARD_FAB2_LIB.BASEBOARD_FAB2(SCH_1):PAGE269
U25W12    4  OE<2> TTL3126_QFNLF-74CBTLV3126,IC,DB    I33 @BASEBOARD_FAB2_LIB.BASEBOARD_FAB2(SCH_1):PAGE269
U25W13    1     NC MAX4564EKA-GP_SCRET-GC1-MAX456A    I53 @BASEBOARD_FAB2_LIB.BASEBOARD_FAB2(SCH_1):PAGE269

JTAG_BMC_TCK1 @BASEBOARD_FAB2_LIB.BASEBOARD_FAB2(SCH_1):JTAG_BMC_TCK1
R25W169    1      A RES_0402-1.00K,1%,1/16W,CHIP,GA    I12 @BASEBOARD_FAB2_LIB.BASEBOARD_FAB2(SCH_1):PAGE269
U25W12   10  OE<1> TTL3126_QFNLF-74CBTLV3126,IC,DB    I33 @BASEBOARD_FAB2_LIB.BASEBOARD_FAB2(SCH_1):PAGE269
U25W13    4     NO MAX4564EKA-GP_SCRET-GC1-MAX456A    I53 @BASEBOARD_FAB2_LIB.BASEBOARD_FAB2(SCH_1):PAGE269

JTAG_BMC_TCK_BUF @BASEBOARD_FAB2_LIB.BASEBOARD_FAB2(SCH_1):JTAG_BMC_TCK_BUF
U25W13    8    COM MAX4564EKA-GP_SCRET-GC1-MAX456A    I53 @BASEBOARD_FAB2_LIB.BASEBOARD_FAB2(SCH_1):PAGE269
U25W19    4      Y TTL1G126_A_SOT-74HC1G126,IC,A7B    I76 @BASEBOARD_FAB2_LIB.BASEBOARD_FAB2(SCH_1):PAGE269

JTAG_BMC_TDI @BASEBOARD_FAB2_LIB.BASEBOARD_FAB2(SCH_1):JTAG_BMC_TDI
  R8G8    1      A RES_0402-0.0,5%,1/16W,CHIP,G21A    I17 @BASEBOARD_FAB2_LIB.BASEBOARD_FAB2(SCH_1):PAGE189
 U25W4  D12    TDI AST2520A1-GP-GP_ASIC2-GB1-AST2A    I95 @BASEBOARD_FAB2_LIB.BASEBOARD_FAB2(SCH_1):PAGE144
U25W16    2   A<3> TTL3126_QFNLF-74CBTLV3126,IC,DB    I38 @BASEBOARD_FAB2_LIB.BASEBOARD_FAB2(SCH_1):PAGE268

JTAG_BMC_TDO @BASEBOARD_FAB2_LIB.BASEBOARD_FAB2(SCH_1):JTAG_BMC_TDO
 R7G17    1      A RES_0402-0.0,5%,1/16W,CHIP,G21A    I37 @BASEBOARD_FAB2_LIB.BASEBOARD_FAB2(SCH_1):PAGE189
 U25W4  D11    TDO AST2520A1-GP-GP_ASIC2-GB1-AST2A    I95 @BASEBOARD_FAB2_LIB.BASEBOARD_FAB2(SCH_1):PAGE144
U25W16    9   A<1> TTL3126_QFNLF-74CBTLV3126,IC,DB    I38 @BASEBOARD_FAB2_LIB.BASEBOARD_FAB2(SCH_1):PAGE268

JTAG_BMC_TMS @BASEBOARD_FAB2_LIB.BASEBOARD_FAB2(SCH_1):JTAG_BMC_TMS
 R8G14    1      A RES_0402-0.0,5%,1/16W,CHIP,G21A    I20 @BASEBOARD_FAB2_LIB.BASEBOARD_FAB2(SCH_1):PAGE189
 U25W4   C8    TMS AST2520A1-GP-GP_ASIC2-GB1-AST2A    I95 @BASEBOARD_FAB2_LIB.BASEBOARD_FAB2(SCH_1):PAGE144
U25W16    5   A<2> TTL3126_QFNLF-74CBTLV3126,IC,DB    I38 @BASEBOARD_FAB2_LIB.BASEBOARD_FAB2(SCH_1):PAGE268

JTAG_BMC_TRST_BUF_N @BASEBOARD_FAB2_LIB.BASEBOARD_FAB2(SCH_1):JTAG_BMC_TRST_BUF_N
R25W170    1      A RES_0402-1.00K,1%,1/16W,CHIP,GA    I13 @BASEBOARD_FAB2_LIB.BASEBOARD_FAB2(SCH_1):PAGE269
U25W12   13  OE<0> TTL3126_QFNLF-74CBTLV3126,IC,DB    I33 @BASEBOARD_FAB2_LIB.BASEBOARD_FAB2(SCH_1):PAGE269
U25W17    4   Y<0> TTL1G08_SOTLF-NC7SZ08,IC,D1032B    I61 @BASEBOARD_FAB2_LIB.BASEBOARD_FAB2(SCH_1):PAGE269

JTAG_BMC_TRST_N @BASEBOARD_FAB2_LIB.BASEBOARD_FAB2(SCH_1):JTAG_BMC_TRST_N
 R8G10    1      A RES_0402-0.0,5%,1/16W,CHIP,G21A     I7 @BASEBOARD_FAB2_LIB.BASEBOARD_FAB2(SCH_1):PAGE189
 U25W4  E11  NTRST AST2520A1-GP-GP_ASIC2-GB1-AST2A    I95 @BASEBOARD_FAB2_LIB.BASEBOARD_FAB2(SCH_1):PAGE144
U25W17    1   A<0> TTL1G08_SOTLF-NC7SZ08,IC,D1032B    I61 @BASEBOARD_FAB2_LIB.BASEBOARD_FAB2(SCH_1):PAGE269
 R8W12    2      B RES_0402-0.0,5%,1/16W,CHIP,G21A    I58 @BASEBOARD_FAB2_LIB.BASEBOARD_FAB2(SCH_1):PAGE245

JTAG_MCP_CPU0_TDI @BASEBOARD_FAB2_LIB.BASEBOARD_FAB2(SCH_1):JTAG_MCP_CPU0_TDI
  U5D1 BY21 CD_TDI SKX_EXT_B_BGA1-IC,TBD    I61 @BASEBOARD_FAB2_LIB.BASEBOARD_FAB2(SCH_1):PAGE29
  U2M1    1     B1 NC7SB3157_SMLF-IC,C99406-001   I255 @BASEBOARD_FAB2_LIB.BASEBOARD_FAB2(SCH_1):PAGE113
  R4R6    2      B RES_0402-1.00K,1%,1/16W,CHIP,GA   I270 @BASEBOARD_FAB2_LIB.BASEBOARD_FAB2(SCH_1):PAGE113

JTAG_MCP_CPU0_TDI_R @BASEBOARD_FAB2_LIB.BASEBOARD_FAB2(SCH_1):JTAG_MCP_CPU0_TDI_R
  U4R1    4      B 74CBTLV1G125_SMLF-IC,C88177-00A   I206 @BASEBOARD_FAB2_LIB.BASEBOARD_FAB2(SCH_1):PAGE113
  C4R2    1      A CAP_A_0402V-0.1UF,16V,10%,X7R,A   I246 @BASEBOARD_FAB2_LIB.BASEBOARD_FAB2(SCH_1):PAGE113
  R4R6    1      A RES_0402-1.00K,1%,1/16W,CHIP,GA   I270 @BASEBOARD_FAB2_LIB.BASEBOARD_FAB2(SCH_1):PAGE113
  R5W1    2      B RES_0402-0.0,5%,1/16W,CHIP,G21A   I272 @BASEBOARD_FAB2_LIB.BASEBOARD_FAB2(SCH_1):PAGE113

JTAG_MCP_CPU0_TDO @BASEBOARD_FAB2_LIB.BASEBOARD_FAB2(SCH_1):JTAG_MCP_CPU0_TDO
  U5D1 CC22 CD_TDO SKX_EXT_B_BGA1-IC,TBD    I61 @BASEBOARD_FAB2_LIB.BASEBOARD_FAB2(SCH_1):PAGE29
  U1M2    1     B1 NC7SB3157_SMLF-IC,C99406-001   I107 @BASEBOARD_FAB2_LIB.BASEBOARD_FAB2(SCH_1):PAGE113
  U1M6    2      A 74CBTLV1G125_SMLF-IC,C88177-00A   I127 @BASEBOARD_FAB2_LIB.BASEBOARD_FAB2(SCH_1):PAGE113

JTAG_MCP_CPU1_TDI @BASEBOARD_FAB2_LIB.BASEBOARD_FAB2(SCH_1):JTAG_MCP_CPU1_TDI
  U2D1 BY21 CD_TDI SKX_EXT_B_BGA1-IC,TBD    I23 @BASEBOARD_FAB2_LIB.BASEBOARD_FAB2(SCH_1):PAGE63
  U1M6    4      B 74CBTLV1G125_SMLF-IC,C88177-00A   I127 @BASEBOARD_FAB2_LIB.BASEBOARD_FAB2(SCH_1):PAGE113
  U2M1    3     B0 NC7SB3157_SMLF-IC,C99406-001   I255 @BASEBOARD_FAB2_LIB.BASEBOARD_FAB2(SCH_1):PAGE113
  R6M8    2      B RES_0402-1.00K,1%,1/16W,CHIP,GA   I271 @BASEBOARD_FAB2_LIB.BASEBOARD_FAB2(SCH_1):PAGE113

JTAG_MCP_CPU1_TDI_R @BASEBOARD_FAB2_LIB.BASEBOARD_FAB2(SCH_1):JTAG_MCP_CPU1_TDI_R
  U6M1    4      B 74CBTLV1G125_SMLF-IC,C88177-00A   I190 @BASEBOARD_FAB2_LIB.BASEBOARD_FAB2(SCH_1):PAGE113
  C6M6    1      A CAP_A_0402V-0.1UF,16V,10%,X7R,A   I250 @BASEBOARD_FAB2_LIB.BASEBOARD_FAB2(SCH_1):PAGE113
  R6M8    1      A RES_0402-1.00K,1%,1/16W,CHIP,GA   I271 @BASEBOARD_FAB2_LIB.BASEBOARD_FAB2(SCH_1):PAGE113
  R5W2    2      B RES_0402-0.0,5%,1/16W,CHIP,G21A   I273 @BASEBOARD_FAB2_LIB.BASEBOARD_FAB2(SCH_1):PAGE113

JTAG_MCP_CPU1_TDO @BASEBOARD_FAB2_LIB.BASEBOARD_FAB2(SCH_1):JTAG_MCP_CPU1_TDO
  U2D1 CC22 CD_TDO SKX_EXT_B_BGA1-IC,TBD    I23 @BASEBOARD_FAB2_LIB.BASEBOARD_FAB2(SCH_1):PAGE63
  U1M2    3     B0 NC7SB3157_SMLF-IC,C99406-001   I107 @BASEBOARD_FAB2_LIB.BASEBOARD_FAB2(SCH_1):PAGE113

JTAG_MCP_MUX_TDI @BASEBOARD_FAB2_LIB.BASEBOARD_FAB2(SCH_1):JTAG_MCP_MUX_TDI
  J9B4    9    IO9 SCONN10_C12536004_SMLF-CONN,C1A   I175 @BASEBOARD_FAB2_LIB.BASEBOARD_FAB2(SCH_1):PAGE113
 R1M20    2      B RES_0402-1.00K,1%,1/16W,CHIP,GA   I204 @BASEBOARD_FAB2_LIB.BASEBOARD_FAB2(SCH_1):PAGE113
  U2M1    4      A NC7SB3157_SMLF-IC,C99406-001   I255 @BASEBOARD_FAB2_LIB.BASEBOARD_FAB2(SCH_1):PAGE113

JTAG_MCP_MUX_TDO @BASEBOARD_FAB2_LIB.BASEBOARD_FAB2(SCH_1):JTAG_MCP_MUX_TDO
  U1M2    4      A NC7SB3157_SMLF-IC,C99406-001   I107 @BASEBOARD_FAB2_LIB.BASEBOARD_FAB2(SCH_1):PAGE113
  J9B4    3    IO3 SCONN10_C12536004_SMLF-CONN,C1A   I175 @BASEBOARD_FAB2_LIB.BASEBOARD_FAB2(SCH_1):PAGE113
 R9B12    2      B RES_0402-1.00K,1%,1/16W,CHIP,GA   I203 @BASEBOARD_FAB2_LIB.BASEBOARD_FAB2(SCH_1):PAGE113

JTAG_MCP_TCK @BASEBOARD_FAB2_LIB.BASEBOARD_FAB2(SCH_1):JTAG_MCP_TCK
  U5D1 CB23 CD_TCLK SKX_EXT_B_BGA1-IC,TBD    I61 @BASEBOARD_FAB2_LIB.BASEBOARD_FAB2(SCH_1):PAGE29
  U2D1 CB23 CD_TCLK SKX_EXT_B_BGA1-IC,TBD    I23 @BASEBOARD_FAB2_LIB.BASEBOARD_FAB2(SCH_1):PAGE63
  R9B9    1      A RES_0402-1.00K,1%,1/16W,CHIP,GA   I179 @BASEBOARD_FAB2_LIB.BASEBOARD_FAB2(SCH_1):PAGE113
 R9B10    1      A RES_0402-49.9,1%,1/16W,CHIP,G2A   I180 @BASEBOARD_FAB2_LIB.BASEBOARD_FAB2(SCH_1):PAGE113
 R9B11    1      A RES_0402-0.0,5%,1/16W,CHIP,G21A   I239 @BASEBOARD_FAB2_LIB.BASEBOARD_FAB2(SCH_1):PAGE113

JTAG_MCP_TCK_R @BASEBOARD_FAB2_LIB.BASEBOARD_FAB2(SCH_1):JTAG_MCP_TCK_R
  J9B4    1    IO1 SCONN10_C12536004_SMLF-CONN,C1A   I175 @BASEBOARD_FAB2_LIB.BASEBOARD_FAB2(SCH_1):PAGE113
 R9B11    2      B RES_0402-0.0,5%,1/16W,CHIP,G21A   I239 @BASEBOARD_FAB2_LIB.BASEBOARD_FAB2(SCH_1):PAGE113

JTAG_MCP_TCK_R1 @BASEBOARD_FAB2_LIB.BASEBOARD_FAB2(SCH_1):JTAG_MCP_TCK_R1
 R9B10    2      B RES_0402-49.9,1%,1/16W,CHIP,G2A   I180 @BASEBOARD_FAB2_LIB.BASEBOARD_FAB2(SCH_1):PAGE113
  U9A5    2      A 74CBTLV1G125_SMLF-IC,C88177-00A   I185 @BASEBOARD_FAB2_LIB.BASEBOARD_FAB2(SCH_1):PAGE113

JTAG_MCP_TMS @BASEBOARD_FAB2_LIB.BASEBOARD_FAB2(SCH_1):JTAG_MCP_TMS
  U5D1 CE24 CD_TMS SKX_EXT_B_BGA1-IC,TBD    I61 @BASEBOARD_FAB2_LIB.BASEBOARD_FAB2(SCH_1):PAGE29
  U2D1 CE24 CD_TMS SKX_EXT_B_BGA1-IC,TBD    I23 @BASEBOARD_FAB2_LIB.BASEBOARD_FAB2(SCH_1):PAGE63
 R1M22    2      B RES_0402-49.9,1%,1/16W,CHIP,G2A   I195 @BASEBOARD_FAB2_LIB.BASEBOARD_FAB2(SCH_1):PAGE113
 R1M19    2      B RES_0402-1.00K,1%,1/16W,CHIP,GA   I202 @BASEBOARD_FAB2_LIB.BASEBOARD_FAB2(SCH_1):PAGE113
 R9B13    1      A RES_0402-0.0,5%,1/16W,CHIP,G21A   I240 @BASEBOARD_FAB2_LIB.BASEBOARD_FAB2(SCH_1):PAGE113

JTAG_MCP_TMS_R @BASEBOARD_FAB2_LIB.BASEBOARD_FAB2(SCH_1):JTAG_MCP_TMS_R
  J9B4    5    IO5 SCONN10_C12536004_SMLF-CONN,C1A   I175 @BASEBOARD_FAB2_LIB.BASEBOARD_FAB2(SCH_1):PAGE113
 R9B13    2      B RES_0402-0.0,5%,1/16W,CHIP,G21A   I240 @BASEBOARD_FAB2_LIB.BASEBOARD_FAB2(SCH_1):PAGE113

JTAG_MCP_TMS_R1 @BASEBOARD_FAB2_LIB.BASEBOARD_FAB2(SCH_1):JTAG_MCP_TMS_R1
 R1M22    1      A RES_0402-49.9,1%,1/16W,CHIP,G2A   I195 @BASEBOARD_FAB2_LIB.BASEBOARD_FAB2(SCH_1):PAGE113
  U1M5    4      B 74CBTLV1G125_SMLF-IC,C88177-00A   I196 @BASEBOARD_FAB2_LIB.BASEBOARD_FAB2(SCH_1):PAGE113
 C1M33    1      A CAP_A_0402V-0.1UF,16V,10%,X7R,A   I248 @BASEBOARD_FAB2_LIB.BASEBOARD_FAB2(SCH_1):PAGE113

JTAG_MCP_TRST_N @BASEBOARD_FAB2_LIB.BASEBOARD_FAB2(SCH_1):JTAG_MCP_TRST_N
  U5D1 CD23 CD_TRST_N SKX_EXT_B_BGA1-IC,TBD    I61 @BASEBOARD_FAB2_LIB.BASEBOARD_FAB2(SCH_1):PAGE29
  U2D1 CD23 CD_TRST_N SKX_EXT_B_BGA1-IC,TBD    I23 @BASEBOARD_FAB2_LIB.BASEBOARD_FAB2(SCH_1):PAGE63
  J9B4    6    IO6 SCONN10_C12536004_SMLF-CONN,C1A   I175 @BASEBOARD_FAB2_LIB.BASEBOARD_FAB2(SCH_1):PAGE113
 R1M23    1      A RES_0402-1.00K,1%,1/16W,EMPTY,A   I199 @BASEBOARD_FAB2_LIB.BASEBOARD_FAB2(SCH_1):PAGE113
 R1M21    2      B RES_0402-1.00K,1%,1/16W,CHIP,GA   I205 @BASEBOARD_FAB2_LIB.BASEBOARD_FAB2(SCH_1):PAGE113

JTAG_PCH_GBE_CLK @BASEBOARD_FAB2_LIB.BASEBOARD_FAB2(SCH_1):JTAG_PCH_GBE_CLK
  U7C1 BV21 GPP_I1_LAN_TCK LBG_CORE_QAT_EXT_D_BGA1-IC,H91A   I147 @BASEBOARD_FAB2_LIB.BASEBOARD_FAB2(SCH_1):PAGE120
 R8G15    1      A RES_0402-0.0,5%,1/16W,EMPTY,G2A    I24 @BASEBOARD_FAB2_LIB.BASEBOARD_FAB2(SCH_1):PAGE189

JTAG_PCH_GBE_TDI @BASEBOARD_FAB2_LIB.BASEBOARD_FAB2(SCH_1):JTAG_PCH_GBE_TDI
  U7C1 BY23 GPP_I3_LAN_TDI LBG_CORE_QAT_EXT_D_BGA1-IC,H91A   I147 @BASEBOARD_FAB2_LIB.BASEBOARD_FAB2(SCH_1):PAGE120
 R7G19    1      A RES_0402-0.0,5%,1/16W,EMPTY,G2A     I8 @BASEBOARD_FAB2_LIB.BASEBOARD_FAB2(SCH_1):PAGE189

JTAG_PCH_GBE_TDO @BASEBOARD_FAB2_LIB.BASEBOARD_FAB2(SCH_1):JTAG_PCH_GBE_TDO
  U7C1 CA20 GPP_I0_LAN_TDO LBG_CORE_QAT_EXT_D_BGA1-IC,H91A   I147 @BASEBOARD_FAB2_LIB.BASEBOARD_FAB2(SCH_1):PAGE120
 R7G16    1      A RES_0402-0.0,5%,1/16W,EMPTY,G2A    I27 @BASEBOARD_FAB2_LIB.BASEBOARD_FAB2(SCH_1):PAGE189

JTAG_PCH_GBE_TMS @BASEBOARD_FAB2_LIB.BASEBOARD_FAB2(SCH_1):JTAG_PCH_GBE_TMS
  U7C1 CA22 GPP_I2_LAN_TMS LBG_CORE_QAT_EXT_D_BGA1-IC,H91A   I147 @BASEBOARD_FAB2_LIB.BASEBOARD_FAB2(SCH_1):PAGE120
 R8G12    1      A RES_0402-0.0,5%,1/16W,EMPTY,G2A    I21 @BASEBOARD_FAB2_LIB.BASEBOARD_FAB2(SCH_1):PAGE189

JTAG_PCH_GBE_TRST_N @BASEBOARD_FAB2_LIB.BASEBOARD_FAB2(SCH_1):JTAG_PCH_GBE_TRST_N
  U7C1 CA24 GPP_I7_LAN_TRST_N LBG_CORE_QAT_EXT_D_BGA1-IC,H91A   I147 @BASEBOARD_FAB2_LIB.BASEBOARD_FAB2(SCH_1):PAGE120
  R8G9    1      A RES_0402-0.0,5%,1/16W,EMPTY,G2A     I9 @BASEBOARD_FAB2_LIB.BASEBOARD_FAB2(SCH_1):PAGE189

JTAG_PCH_PLD_TCK @BASEBOARD_FAB2_LIB.BASEBOARD_FAB2(SCH_1):JTAG_PCH_PLD_TCK
  U7C1 AL18 GPP_F6_SATA_DEVSLP4 LBG_CORE_QAT_EXT_D_BGA1-IC,H91A   I147 @BASEBOARD_FAB2_LIB.BASEBOARD_FAB2(SCH_1):PAGE120
 R8G16    1      A RES_0402-0.0,5%,1/16W,EMPTY,G2A    I22 @BASEBOARD_FAB2_LIB.BASEBOARD_FAB2(SCH_1):PAGE189

JTAG_PCH_PLD_TDI @BASEBOARD_FAB2_LIB.BASEBOARD_FAB2(SCH_1):JTAG_PCH_PLD_TDI
  U7C1 AK17 GPP_F7_SATA_DEVSLP5 LBG_CORE_QAT_EXT_D_BGA1-IC,H91A   I147 @BASEBOARD_FAB2_LIB.BASEBOARD_FAB2(SCH_1):PAGE120
 R7G18    1      A RES_0402-0.0,5%,1/16W,EMPTY,G2A    I13 @BASEBOARD_FAB2_LIB.BASEBOARD_FAB2(SCH_1):PAGE189

JTAG_PCH_PLD_TDO @BASEBOARD_FAB2_LIB.BASEBOARD_FAB2(SCH_1):JTAG_PCH_PLD_TDO
  U7C1 AR20 GPP_F9_SATA_DEVSLP7 LBG_CORE_QAT_EXT_D_BGA1-IC,H91A   I147 @BASEBOARD_FAB2_LIB.BASEBOARD_FAB2(SCH_1):PAGE120
 R7G15    1      A RES_0402-0.0,5%,1/16W,EMPTY,G2A    I36 @BASEBOARD_FAB2_LIB.BASEBOARD_FAB2(SCH_1):PAGE189

JTAG_PCH_PLD_TMS @BASEBOARD_FAB2_LIB.BASEBOARD_FAB2(SCH_1):JTAG_PCH_PLD_TMS
  U7C1  AH9 GPP_F8_SATA_DEVSLP6 LBG_CORE_QAT_EXT_D_BGA1-IC,H91A   I147 @BASEBOARD_FAB2_LIB.BASEBOARD_FAB2(SCH_1):PAGE120
 R8G11    1      A RES_0402-0.0,5%,1/16W,EMPTY,G2A    I19 @BASEBOARD_FAB2_LIB.BASEBOARD_FAB2(SCH_1):PAGE189

JTAG_PLD_TCK @BASEBOARD_FAB2_LIB.BASEBOARD_FAB2(SCH_1):JTAG_PLD_TCK
 R8G18    1      A RES_0402-0.0,5%,1/16W,CHIP,G21A    I26 @BASEBOARD_FAB2_LIB.BASEBOARD_FAB2(SCH_1):PAGE189
  U8D7   A7 PT16C_TCK LCMXO2_A_256BGA-IC,H63395-001    I59 @BASEBOARD_FAB2_LIB.BASEBOARD_FAB2(SCH_1):PAGE191

JTAG_PLD_TCK_MUX @BASEBOARD_FAB2_LIB.BASEBOARD_FAB2(SCH_1):JTAG_PLD_TCK_MUX
 R8G18    2      B RES_0402-0.0,5%,1/16W,CHIP,G21A    I26 @BASEBOARD_FAB2_LIB.BASEBOARD_FAB2(SCH_1):PAGE189
 U1L10    5   A<2> TTL3126_QFNLF-74CBTLV3126,IC,DB    I67 @BASEBOARD_FAB2_LIB.BASEBOARD_FAB2(SCH_1):PAGE189
 R8W11    2      B RES_0402-0.0,5%,1/16W,CHIP,G21A    I57 @BASEBOARD_FAB2_LIB.BASEBOARD_FAB2(SCH_1):PAGE245

JTAG_PLD_TDI @BASEBOARD_FAB2_LIB.BASEBOARD_FAB2(SCH_1):JTAG_PLD_TDI
  R8G7    1      A RES_0402-0.0,5%,1/16W,CHIP,G21A    I18 @BASEBOARD_FAB2_LIB.BASEBOARD_FAB2(SCH_1):PAGE189
  U8D7   A6 PT12D_TDI LCMXO2_A_256BGA-IC,H63395-001    I59 @BASEBOARD_FAB2_LIB.BASEBOARD_FAB2(SCH_1):PAGE191

JTAG_PLD_TDI_MUX @BASEBOARD_FAB2_LIB.BASEBOARD_FAB2(SCH_1):JTAG_PLD_TDI_MUX
  R8G7    2      B RES_0402-0.0,5%,1/16W,CHIP,G21A    I18 @BASEBOARD_FAB2_LIB.BASEBOARD_FAB2(SCH_1):PAGE189
 U1L10   12   A<0> TTL3126_QFNLF-74CBTLV3126,IC,DB    I67 @BASEBOARD_FAB2_LIB.BASEBOARD_FAB2(SCH_1):PAGE189

JTAG_PLD_TDO @BASEBOARD_FAB2_LIB.BASEBOARD_FAB2(SCH_1):JTAG_PLD_TDO
  U8D7   C6 PT12C_TDO LCMXO2_A_256BGA-IC,H63395-001    I59 @BASEBOARD_FAB2_LIB.BASEBOARD_FAB2(SCH_1):PAGE191
  U8W1    2      A 74CBTLV1G125_SMLF-IC,C88177-00A    I64 @BASEBOARD_FAB2_LIB.BASEBOARD_FAB2(SCH_1):PAGE245
  U8W2    1     B1 NC7SB3157_SMLF-IC,C99406-001    I66 @BASEBOARD_FAB2_LIB.BASEBOARD_FAB2(SCH_1):PAGE245

JTAG_PLD_TDO_MUX @BASEBOARD_FAB2_LIB.BASEBOARD_FAB2(SCH_1):JTAG_PLD_TDO_MUX
 R7G14    2      B RES_0402-0.0,5%,1/16W,CHIP,G21A    I38 @BASEBOARD_FAB2_LIB.BASEBOARD_FAB2(SCH_1):PAGE189
 U1L10    2   A<3> TTL3126_QFNLF-74CBTLV3126,IC,DB    I67 @BASEBOARD_FAB2_LIB.BASEBOARD_FAB2(SCH_1):PAGE189

JTAG_PLD_TDO_MUX_R @BASEBOARD_FAB2_LIB.BASEBOARD_FAB2(SCH_1):JTAG_PLD_TDO_MUX_R
 R7G14    1      A RES_0402-0.0,5%,1/16W,CHIP,G21A    I38 @BASEBOARD_FAB2_LIB.BASEBOARD_FAB2(SCH_1):PAGE189
  U8W2    4      A NC7SB3157_SMLF-IC,C99406-001    I66 @BASEBOARD_FAB2_LIB.BASEBOARD_FAB2(SCH_1):PAGE245

JTAG_PLD_TMS @BASEBOARD_FAB2_LIB.BASEBOARD_FAB2(SCH_1):JTAG_PLD_TMS
 R8G13    1      A RES_0402-0.0,5%,1/16W,CHIP,G21A    I23 @BASEBOARD_FAB2_LIB.BASEBOARD_FAB2(SCH_1):PAGE189
  U8D7   B8 PT16D_TMS LCMXO2_A_256BGA-IC,H63395-001    I59 @BASEBOARD_FAB2_LIB.BASEBOARD_FAB2(SCH_1):PAGE191

JTAG_PLD_TMS_MUX @BASEBOARD_FAB2_LIB.BASEBOARD_FAB2(SCH_1):JTAG_PLD_TMS_MUX
 R8G13    2      B RES_0402-0.0,5%,1/16W,CHIP,G21A    I23 @BASEBOARD_FAB2_LIB.BASEBOARD_FAB2(SCH_1):PAGE189
 U1L10    9   A<1> TTL3126_QFNLF-74CBTLV3126,IC,DB    I67 @BASEBOARD_FAB2_LIB.BASEBOARD_FAB2(SCH_1):PAGE189
 R8W10    2      B RES_0402-0.0,5%,1/16W,CHIP,G21A    I56 @BASEBOARD_FAB2_LIB.BASEBOARD_FAB2(SCH_1):PAGE245

JTAG_RISER_N @BASEBOARD_FAB2_LIB.BASEBOARD_FAB2(SCH_1):JTAG_RISER_N
 U25W4  B14 GPIOA0_MAC1LINK AST2520A1-GP-GP_ASIC2-GB1-AST2A   I117 @BASEBOARD_FAB2_LIB.BASEBOARD_FAB2(SCH_1):PAGE145
  U8W1    1   OE_N 74CBTLV1G125_SMLF-IC,C88177-00A    I64 @BASEBOARD_FAB2_LIB.BASEBOARD_FAB2(SCH_1):PAGE245
  U8W2    6      S NC7SB3157_SMLF-IC,C99406-001    I66 @BASEBOARD_FAB2_LIB.BASEBOARD_FAB2(SCH_1):PAGE245
 R8W15    2      B RES_0402-4.75K,1%,1/16W,CHIP,GA    I78 @BASEBOARD_FAB2_LIB.BASEBOARD_FAB2(SCH_1):PAGE245

JTAG_RISER_TCK @BASEBOARD_FAB2_LIB.BASEBOARD_FAB2(SCH_1):JTAG_RISER_TCK
 CONX8   56     56 SMC-CONN60A-22-GP_CONN-G7-SMC-A    I48 @BASEBOARD_FAB2_LIB.BASEBOARD_FAB2(SCH_1):PAGE245
 R8W11    1      A RES_0402-0.0,5%,1/16W,CHIP,G21A    I57 @BASEBOARD_FAB2_LIB.BASEBOARD_FAB2(SCH_1):PAGE245

JTAG_RISER_TDI @BASEBOARD_FAB2_LIB.BASEBOARD_FAB2(SCH_1):JTAG_RISER_TDI
 CONX8   51     51 SMC-CONN60A-22-GP_CONN-G7-SMC-A    I48 @BASEBOARD_FAB2_LIB.BASEBOARD_FAB2(SCH_1):PAGE245
 R8W13    2      B RES_0402-0.0,5%,1/16W,CHIP,G21A    I59 @BASEBOARD_FAB2_LIB.BASEBOARD_FAB2(SCH_1):PAGE245

JTAG_RISER_TDI_R @BASEBOARD_FAB2_LIB.BASEBOARD_FAB2(SCH_1):JTAG_RISER_TDI_R
 R8W13    1      A RES_0402-0.0,5%,1/16W,CHIP,G21A    I59 @BASEBOARD_FAB2_LIB.BASEBOARD_FAB2(SCH_1):PAGE245
  U8W1    4      B 74CBTLV1G125_SMLF-IC,C88177-00A    I64 @BASEBOARD_FAB2_LIB.BASEBOARD_FAB2(SCH_1):PAGE245

JTAG_RISER_TDO @BASEBOARD_FAB2_LIB.BASEBOARD_FAB2(SCH_1):JTAG_RISER_TDO
 CONX8   53     53 SMC-CONN60A-22-GP_CONN-G7-SMC-A    I48 @BASEBOARD_FAB2_LIB.BASEBOARD_FAB2(SCH_1):PAGE245
 R8W14    2      B RES_0402-0.0,5%,1/16W,CHIP,G21A    I60 @BASEBOARD_FAB2_LIB.BASEBOARD_FAB2(SCH_1):PAGE245

JTAG_RISER_TDO_R @BASEBOARD_FAB2_LIB.BASEBOARD_FAB2(SCH_1):JTAG_RISER_TDO_R
 R8W14    1      A RES_0402-0.0,5%,1/16W,CHIP,G21A    I60 @BASEBOARD_FAB2_LIB.BASEBOARD_FAB2(SCH_1):PAGE245
  U8W2    3     B0 NC7SB3157_SMLF-IC,C99406-001    I66 @BASEBOARD_FAB2_LIB.BASEBOARD_FAB2(SCH_1):PAGE245

JTAG_RISER_TMS @BASEBOARD_FAB2_LIB.BASEBOARD_FAB2(SCH_1):JTAG_RISER_TMS
 CONX8   54     54 SMC-CONN60A-22-GP_CONN-G7-SMC-A    I48 @BASEBOARD_FAB2_LIB.BASEBOARD_FAB2(SCH_1):PAGE245
 R8W10    1      A RES_0402-0.0,5%,1/16W,CHIP,G21A    I56 @BASEBOARD_FAB2_LIB.BASEBOARD_FAB2(SCH_1):PAGE245

JTAG_RISER_TRST @BASEBOARD_FAB2_LIB.BASEBOARD_FAB2(SCH_1):JTAG_RISER_TRST
 CONX8   60     60 SMC-CONN60A-22-GP_CONN-G7-SMC-A    I48 @BASEBOARD_FAB2_LIB.BASEBOARD_FAB2(SCH_1):PAGE245
 R8W12    1      A RES_0402-0.0,5%,1/16W,CHIP,G21A    I58 @BASEBOARD_FAB2_LIB.BASEBOARD_FAB2(SCH_1):PAGE245

JTAG_TCK @BASEBOARD_FAB2_LIB.BASEBOARD_FAB2(SCH_1):JTAG_TCK
 R8G16    2      B RES_0402-0.0,5%,1/16W,EMPTY,G2A    I22 @BASEBOARD_FAB2_LIB.BASEBOARD_FAB2(SCH_1):PAGE189
 R8G15    2      B RES_0402-0.0,5%,1/16W,EMPTY,G2A    I24 @BASEBOARD_FAB2_LIB.BASEBOARD_FAB2(SCH_1):PAGE189
 R8G17    2      B RES_0402-0.0,5%,1/16W,CHIP,G21A    I25 @BASEBOARD_FAB2_LIB.BASEBOARD_FAB2(SCH_1):PAGE189
 R8G22    1      A RES_0402-0.0,5%,1/16W,CHIP,G21A    I66 @BASEBOARD_FAB2_LIB.BASEBOARD_FAB2(SCH_1):PAGE189
 U1L10    6   B<2> TTL3126_QFNLF-74CBTLV3126,IC,DB    I67 @BASEBOARD_FAB2_LIB.BASEBOARD_FAB2(SCH_1):PAGE189

JTAG_TCK_R @BASEBOARD_FAB2_LIB.BASEBOARD_FAB2(SCH_1):JTAG_TCK_R
  J7G2    8    IO8 CONN8_C77962004_PIP-CONN,C7796A    I47 @BASEBOARD_FAB2_LIB.BASEBOARD_FAB2(SCH_1):PAGE189
 R8G23    1      A RES_0402-4.75K,1%,1/16W,CHIP,GA    I56 @BASEBOARD_FAB2_LIB.BASEBOARD_FAB2(SCH_1):PAGE189
 R8G22    2      B RES_0402-0.0,5%,1/16W,CHIP,G21A    I66 @BASEBOARD_FAB2_LIB.BASEBOARD_FAB2(SCH_1):PAGE189

JTAG_TDI @BASEBOARD_FAB2_LIB.BASEBOARD_FAB2(SCH_1):JTAG_TDI
 R7G19    2      B RES_0402-0.0,5%,1/16W,EMPTY,G2A     I8 @BASEBOARD_FAB2_LIB.BASEBOARD_FAB2(SCH_1):PAGE189
 R7G18    2      B RES_0402-0.0,5%,1/16W,EMPTY,G2A    I13 @BASEBOARD_FAB2_LIB.BASEBOARD_FAB2(SCH_1):PAGE189
  R8G8    2      B RES_0402-0.0,5%,1/16W,CHIP,G21A    I17 @BASEBOARD_FAB2_LIB.BASEBOARD_FAB2(SCH_1):PAGE189
 R8G19    1      A RES_0402-0.0,5%,1/16W,CHIP,G21A    I64 @BASEBOARD_FAB2_LIB.BASEBOARD_FAB2(SCH_1):PAGE189
 U1L10   11   B<0> TTL3126_QFNLF-74CBTLV3126,IC,DB    I67 @BASEBOARD_FAB2_LIB.BASEBOARD_FAB2(SCH_1):PAGE189

JTAG_TDI_R @BASEBOARD_FAB2_LIB.BASEBOARD_FAB2(SCH_1):JTAG_TDI_R
  J7G2    3    IO3 CONN8_C77962004_PIP-CONN,C7796A    I47 @BASEBOARD_FAB2_LIB.BASEBOARD_FAB2(SCH_1):PAGE189
 R7G23    2      B RES_0402-10.0K,1%,1/16W,CHIP,GA    I51 @BASEBOARD_FAB2_LIB.BASEBOARD_FAB2(SCH_1):PAGE189
 R8G19    2      B RES_0402-0.0,5%,1/16W,CHIP,G21A    I64 @BASEBOARD_FAB2_LIB.BASEBOARD_FAB2(SCH_1):PAGE189

JTAG_TDO @BASEBOARD_FAB2_LIB.BASEBOARD_FAB2(SCH_1):JTAG_TDO
 R7G16    2      B RES_0402-0.0,5%,1/16W,EMPTY,G2A    I27 @BASEBOARD_FAB2_LIB.BASEBOARD_FAB2(SCH_1):PAGE189
 R7G15    2      B RES_0402-0.0,5%,1/16W,EMPTY,G2A    I36 @BASEBOARD_FAB2_LIB.BASEBOARD_FAB2(SCH_1):PAGE189
 R7G17    2      B RES_0402-0.0,5%,1/16W,CHIP,G21A    I37 @BASEBOARD_FAB2_LIB.BASEBOARD_FAB2(SCH_1):PAGE189
 R7G21    1      A RES_0402-0.0,5%,1/16W,CHIP,G21A    I63 @BASEBOARD_FAB2_LIB.BASEBOARD_FAB2(SCH_1):PAGE189
 U1L10    3   B<3> TTL3126_QFNLF-74CBTLV3126,IC,DB    I67 @BASEBOARD_FAB2_LIB.BASEBOARD_FAB2(SCH_1):PAGE189

JTAG_TDO_R @BASEBOARD_FAB2_LIB.BASEBOARD_FAB2(SCH_1):JTAG_TDO_R
  J7G2    2    IO2 CONN8_C77962004_PIP-CONN,C7796A    I47 @BASEBOARD_FAB2_LIB.BASEBOARD_FAB2(SCH_1):PAGE189
 R7G22    2      B RES_0402-10.0K,1%,1/16W,CHIP,GA    I53 @BASEBOARD_FAB2_LIB.BASEBOARD_FAB2(SCH_1):PAGE189
 R7G21    2      B RES_0402-0.0,5%,1/16W,CHIP,G21A    I63 @BASEBOARD_FAB2_LIB.BASEBOARD_FAB2(SCH_1):PAGE189

JTAG_TMS @BASEBOARD_FAB2_LIB.BASEBOARD_FAB2(SCH_1):JTAG_TMS
 R8G11    2      B RES_0402-0.0,5%,1/16W,EMPTY,G2A    I19 @BASEBOARD_FAB2_LIB.BASEBOARD_FAB2(SCH_1):PAGE189
 R8G14    2      B RES_0402-0.0,5%,1/16W,CHIP,G21A    I20 @BASEBOARD_FAB2_LIB.BASEBOARD_FAB2(SCH_1):PAGE189
 R8G12    2      B RES_0402-0.0,5%,1/16W,EMPTY,G2A    I21 @BASEBOARD_FAB2_LIB.BASEBOARD_FAB2(SCH_1):PAGE189
 R8G21    1      A RES_0402-0.0,5%,1/16W,CHIP,G21A    I65 @BASEBOARD_FAB2_LIB.BASEBOARD_FAB2(SCH_1):PAGE189
 U1L10    8   B<1> TTL3126_QFNLF-74CBTLV3126,IC,DB    I67 @BASEBOARD_FAB2_LIB.BASEBOARD_FAB2(SCH_1):PAGE189

JTAG_TMS_R @BASEBOARD_FAB2_LIB.BASEBOARD_FAB2(SCH_1):JTAG_TMS_R
  J7G2    6    IO6 CONN8_C77962004_PIP-CONN,C7796A    I47 @BASEBOARD_FAB2_LIB.BASEBOARD_FAB2(SCH_1):PAGE189
 R8G20    2      B RES_0402-10.0K,1%,1/16W,CHIP,GA    I50 @BASEBOARD_FAB2_LIB.BASEBOARD_FAB2(SCH_1):PAGE189
 R8G21    2      B RES_0402-0.0,5%,1/16W,CHIP,G21A    I65 @BASEBOARD_FAB2_LIB.BASEBOARD_FAB2(SCH_1):PAGE189

JTAG_TRST_N @BASEBOARD_FAB2_LIB.BASEBOARD_FAB2(SCH_1):JTAG_TRST_N
 R8G10    2      B RES_0402-0.0,5%,1/16W,CHIP,G21A     I7 @BASEBOARD_FAB2_LIB.BASEBOARD_FAB2(SCH_1):PAGE189
  R8G9    2      B RES_0402-0.0,5%,1/16W,EMPTY,G2A     I9 @BASEBOARD_FAB2_LIB.BASEBOARD_FAB2(SCH_1):PAGE189
  J7G2    4    IO4 CONN8_C77962004_PIP-CONN,C7796A    I47 @BASEBOARD_FAB2_LIB.BASEBOARD_FAB2(SCH_1):PAGE189

KR_P0_OCP_RX_C_DN @BASEBOARD_FAB2_LIB.BASEBOARD_FAB2(SCH_1):KR_P0_OCP_RX_C_DN
  U7C1 BH31 LAN_RX_P0N LBG_CORE_QAT_EXT_D_BGA1-IC,H91A    I73 @BASEBOARD_FAB2_LIB.BASEBOARD_FAB2(SCH_1):PAGE118
 C8C14    2      B CAP_A_0402V-0.1UF,16V,10%,X7R,A    I86 @BASEBOARD_FAB2_LIB.BASEBOARD_FAB2(SCH_1):PAGE188

KR_P0_OCP_RX_C_DP @BASEBOARD_FAB2_LIB.BASEBOARD_FAB2(SCH_1):KR_P0_OCP_RX_C_DP
  U7C1 BF31 LAN_RX_P0P LBG_CORE_QAT_EXT_D_BGA1-IC,H91A    I73 @BASEBOARD_FAB2_LIB.BASEBOARD_FAB2(SCH_1):PAGE118
 C8C15    2      B CAP_A_0402V-0.1UF,16V,10%,X7R,A    I82 @BASEBOARD_FAB2_LIB.BASEBOARD_FAB2(SCH_1):PAGE188

KR_P0_OCP_RX_DN @BASEBOARD_FAB2_LIB.BASEBOARD_FAB2(SCH_1):KR_P0_OCP_RX_DN
  J8E4   53   IO53 SCONN64_H87568002_A_SMT-CONN,HA    I27 @BASEBOARD_FAB2_LIB.BASEBOARD_FAB2(SCH_1):PAGE188
 C8C14    1      A CAP_A_0402V-0.1UF,16V,10%,X7R,A    I86 @BASEBOARD_FAB2_LIB.BASEBOARD_FAB2(SCH_1):PAGE188

KR_P0_OCP_RX_DP @BASEBOARD_FAB2_LIB.BASEBOARD_FAB2(SCH_1):KR_P0_OCP_RX_DP
  J8E4   52   IO52 SCONN64_H87568002_A_SMT-CONN,HA    I27 @BASEBOARD_FAB2_LIB.BASEBOARD_FAB2(SCH_1):PAGE188
 C8C15    1      A CAP_A_0402V-0.1UF,16V,10%,X7R,A    I82 @BASEBOARD_FAB2_LIB.BASEBOARD_FAB2(SCH_1):PAGE188

KR_P0_OCP_TX_DN @BASEBOARD_FAB2_LIB.BASEBOARD_FAB2(SCH_1):KR_P0_OCP_TX_DN
  U7C1 BM27 LAN_TX_P0N LBG_CORE_QAT_EXT_D_BGA1-IC,H91A    I73 @BASEBOARD_FAB2_LIB.BASEBOARD_FAB2(SCH_1):PAGE118
  J8E4   41   IO41 SCONN64_H87568002_A_SMT-CONN,HA    I27 @BASEBOARD_FAB2_LIB.BASEBOARD_FAB2(SCH_1):PAGE188

KR_P0_OCP_TX_DP @BASEBOARD_FAB2_LIB.BASEBOARD_FAB2(SCH_1):KR_P0_OCP_TX_DP
  U7C1 BR27 LAN_TX_P0P LBG_CORE_QAT_EXT_D_BGA1-IC,H91A    I73 @BASEBOARD_FAB2_LIB.BASEBOARD_FAB2(SCH_1):PAGE118
  J8E4   40   IO40 SCONN64_H87568002_A_SMT-CONN,HA    I27 @BASEBOARD_FAB2_LIB.BASEBOARD_FAB2(SCH_1):PAGE188

KR_P1_OCP_RX_C_DN @BASEBOARD_FAB2_LIB.BASEBOARD_FAB2(SCH_1):KR_P1_OCP_RX_C_DN
  U7C1 BG29 LAN_RX_P1N LBG_CORE_QAT_EXT_D_BGA1-IC,H91A    I73 @BASEBOARD_FAB2_LIB.BASEBOARD_FAB2(SCH_1):PAGE118
 C8C13    2      B CAP_A_0402V-0.1UF,16V,10%,X7R,A   I120 @BASEBOARD_FAB2_LIB.BASEBOARD_FAB2(SCH_1):PAGE188

KR_P1_OCP_RX_C_DP @BASEBOARD_FAB2_LIB.BASEBOARD_FAB2(SCH_1):KR_P1_OCP_RX_C_DP
  U7C1 BJ29 LAN_RX_P1P LBG_CORE_QAT_EXT_D_BGA1-IC,H91A    I73 @BASEBOARD_FAB2_LIB.BASEBOARD_FAB2(SCH_1):PAGE118
 C8C12    2      B CAP_A_0402V-0.1UF,16V,10%,X7R,A   I121 @BASEBOARD_FAB2_LIB.BASEBOARD_FAB2(SCH_1):PAGE188

KR_P1_OCP_RX_DN @BASEBOARD_FAB2_LIB.BASEBOARD_FAB2(SCH_1):KR_P1_OCP_RX_DN
  J8E4   59   IO59 SCONN64_H87568002_A_SMT-CONN,HA    I27 @BASEBOARD_FAB2_LIB.BASEBOARD_FAB2(SCH_1):PAGE188
 C8C13    1      A CAP_A_0402V-0.1UF,16V,10%,X7R,A   I120 @BASEBOARD_FAB2_LIB.BASEBOARD_FAB2(SCH_1):PAGE188

KR_P1_OCP_RX_DP @BASEBOARD_FAB2_LIB.BASEBOARD_FAB2(SCH_1):KR_P1_OCP_RX_DP
  J8E4   58   IO58 SCONN64_H87568002_A_SMT-CONN,HA    I27 @BASEBOARD_FAB2_LIB.BASEBOARD_FAB2(SCH_1):PAGE188
 C8C12    1      A CAP_A_0402V-0.1UF,16V,10%,X7R,A   I121 @BASEBOARD_FAB2_LIB.BASEBOARD_FAB2(SCH_1):PAGE188

KR_P1_OCP_TX_DN @BASEBOARD_FAB2_LIB.BASEBOARD_FAB2(SCH_1):KR_P1_OCP_TX_DN
  U7C1 BM24 LAN_TX_P1N LBG_CORE_QAT_EXT_D_BGA1-IC,H91A    I73 @BASEBOARD_FAB2_LIB.BASEBOARD_FAB2(SCH_1):PAGE118
  J8E4   47   IO47 SCONN64_H87568002_A_SMT-CONN,HA    I27 @BASEBOARD_FAB2_LIB.BASEBOARD_FAB2(SCH_1):PAGE188

KR_P1_OCP_TX_DP @BASEBOARD_FAB2_LIB.BASEBOARD_FAB2(SCH_1):KR_P1_OCP_TX_DP
  U7C1 BR24 LAN_TX_P1P LBG_CORE_QAT_EXT_D_BGA1-IC,H91A    I73 @BASEBOARD_FAB2_LIB.BASEBOARD_FAB2(SCH_1):PAGE118
  J8E4   46   IO46 SCONN64_H87568002_A_SMT-CONN,HA    I27 @BASEBOARD_FAB2_LIB.BASEBOARD_FAB2(SCH_1):PAGE188

L10_100OHM_6INCH_DN @BASEBOARD_FAB2_LIB.BASEBOARD_FAB2(SCH_1):L10_100OHM_6INCH_DN
 T1P22    2      2 TPAD-DIFF-4P-GP_DISCRET-GB3-TPA    I45 @BASEBOARD_FAB2_LIB.BASEBOARD_FAB2(SCH_1):PAGE271

L10_100OHM_6INCH_DP @BASEBOARD_FAB2_LIB.BASEBOARD_FAB2(SCH_1):L10_100OHM_6INCH_DP
 T1P22    1      1 TPAD-DIFF-4P-GP_DISCRET-GB3-TPA    I45 @BASEBOARD_FAB2_LIB.BASEBOARD_FAB2(SCH_1):PAGE271

L10_40OHM_6INCH @BASEBOARD_FAB2_LIB.BASEBOARD_FAB2(SCH_1):L10_40OHM_6INCH
 T1P28    1      1 TPAD-SE-2P-GP_DISCRET-GA1-TPADA    I60 @BASEBOARD_FAB2_LIB.BASEBOARD_FAB2(SCH_1):PAGE271

L10_50OHM_6INCH @BASEBOARD_FAB2_LIB.BASEBOARD_FAB2(SCH_1):L10_50OHM_6INCH
 T1P34    1      1 TPAD-SE-2P-GP_DISCRET-GA1-TPADA    I62 @BASEBOARD_FAB2_LIB.BASEBOARD_FAB2(SCH_1):PAGE271

L10_73OHM_6INCH_DN @BASEBOARD_FAB2_LIB.BASEBOARD_FAB2(SCH_1):L10_73OHM_6INCH_DN
 T1P10    2      2 TPAD-DIFF-4P-GP_DISCRET-GB3-TPA    I15 @BASEBOARD_FAB2_LIB.BASEBOARD_FAB2(SCH_1):PAGE271

L10_73OHM_6INCH_DP @BASEBOARD_FAB2_LIB.BASEBOARD_FAB2(SCH_1):L10_73OHM_6INCH_DP
 T1P10    1      1 TPAD-DIFF-4P-GP_DISCRET-GB3-TPA    I15 @BASEBOARD_FAB2_LIB.BASEBOARD_FAB2(SCH_1):PAGE271

L10_85OHM_10INCH_DN @BASEBOARD_FAB2_LIB.BASEBOARD_FAB2(SCH_1):L10_85OHM_10INCH_DN
 T1D19    2     DN TEST-PAD-12P-1-GP-U_DISCRET-GBA    I23 @BASEBOARD_FAB2_LIB.BASEBOARD_FAB2(SCH_1):PAGE272
 T1D20    1     DP TEST-PAD-12P-1-GP-U_DISCRET-GBA    I24 @BASEBOARD_FAB2_LIB.BASEBOARD_FAB2(SCH_1):PAGE272

L10_85OHM_10INCH_DP @BASEBOARD_FAB2_LIB.BASEBOARD_FAB2(SCH_1):L10_85OHM_10INCH_DP
 T1D19    1     DP TEST-PAD-12P-1-GP-U_DISCRET-GBA    I23 @BASEBOARD_FAB2_LIB.BASEBOARD_FAB2(SCH_1):PAGE272
 T1D20    2     DN TEST-PAD-12P-1-GP-U_DISCRET-GBA    I24 @BASEBOARD_FAB2_LIB.BASEBOARD_FAB2(SCH_1):PAGE272

L10_85OHM_5INCH_DN @BASEBOARD_FAB2_LIB.BASEBOARD_FAB2(SCH_1):L10_85OHM_5INCH_DN
  T1D8    1     DP TEST-PAD-12P-1-GP-U_DISCRET-GBA    I13 @BASEBOARD_FAB2_LIB.BASEBOARD_FAB2(SCH_1):PAGE270
  T1D7    2     DN TEST-PAD-12P-1-GP-U_DISCRET-GBA    I16 @BASEBOARD_FAB2_LIB.BASEBOARD_FAB2(SCH_1):PAGE270

L10_85OHM_5INCH_DP @BASEBOARD_FAB2_LIB.BASEBOARD_FAB2(SCH_1):L10_85OHM_5INCH_DP
  T1D8    2     DN TEST-PAD-12P-1-GP-U_DISCRET-GBA    I13 @BASEBOARD_FAB2_LIB.BASEBOARD_FAB2(SCH_1):PAGE270
  T1D7    1     DP TEST-PAD-12P-1-GP-U_DISCRET-GBA    I16 @BASEBOARD_FAB2_LIB.BASEBOARD_FAB2(SCH_1):PAGE270

L10_85OHM_6INCH_DN @BASEBOARD_FAB2_LIB.BASEBOARD_FAB2(SCH_1):L10_85OHM_6INCH_DN
  T1P4    2      2 TPAD-DIFF-4P-GP_DISCRET-GB3-TPA     I7 @BASEBOARD_FAB2_LIB.BASEBOARD_FAB2(SCH_1):PAGE271

L10_85OHM_6INCH_DP @BASEBOARD_FAB2_LIB.BASEBOARD_FAB2(SCH_1):L10_85OHM_6INCH_DP
  T1P4    1      1 TPAD-DIFF-4P-GP_DISCRET-GB3-TPA     I7 @BASEBOARD_FAB2_LIB.BASEBOARD_FAB2(SCH_1):PAGE271

L12_100OHM_6INCH_DN @BASEBOARD_FAB2_LIB.BASEBOARD_FAB2(SCH_1):L12_100OHM_6INCH_DN
 T1P23    2      2 TPAD-DIFF-4P-GP_DISCRET-GB3-TPA    I47 @BASEBOARD_FAB2_LIB.BASEBOARD_FAB2(SCH_1):PAGE271

L12_100OHM_6INCH_DP @BASEBOARD_FAB2_LIB.BASEBOARD_FAB2(SCH_1):L12_100OHM_6INCH_DP
 T1P23    1      1 TPAD-DIFF-4P-GP_DISCRET-GB3-TPA    I47 @BASEBOARD_FAB2_LIB.BASEBOARD_FAB2(SCH_1):PAGE271

L12_40OHM_6INCH @BASEBOARD_FAB2_LIB.BASEBOARD_FAB2(SCH_1):L12_40OHM_6INCH
 T1P29    1      1 TPAD-SE-2P-GP_DISCRET-GA1-TPADA    I56 @BASEBOARD_FAB2_LIB.BASEBOARD_FAB2(SCH_1):PAGE271

L12_50OHM_6INCH @BASEBOARD_FAB2_LIB.BASEBOARD_FAB2(SCH_1):L12_50OHM_6INCH
 T1P35    1      1 TPAD-SE-2P-GP_DISCRET-GA1-TPADA    I67 @BASEBOARD_FAB2_LIB.BASEBOARD_FAB2(SCH_1):PAGE271

L12_73OHM_6INCH_DN @BASEBOARD_FAB2_LIB.BASEBOARD_FAB2(SCH_1):L12_73OHM_6INCH_DN
 T1P11    2      2 TPAD-DIFF-4P-GP_DISCRET-GB3-TPA    I23 @BASEBOARD_FAB2_LIB.BASEBOARD_FAB2(SCH_1):PAGE271

L12_73OHM_6INCH_DP @BASEBOARD_FAB2_LIB.BASEBOARD_FAB2(SCH_1):L12_73OHM_6INCH_DP
 T1P11    1      1 TPAD-DIFF-4P-GP_DISCRET-GB3-TPA    I23 @BASEBOARD_FAB2_LIB.BASEBOARD_FAB2(SCH_1):PAGE271

L12_85OHM_10INCH_DN @BASEBOARD_FAB2_LIB.BASEBOARD_FAB2(SCH_1):L12_85OHM_10INCH_DN
 T1D21    2     DN TEST-PAD-12P-1-GP-U_DISCRET-GBA    I16 @BASEBOARD_FAB2_LIB.BASEBOARD_FAB2(SCH_1):PAGE272
 T1D22    1     DP TEST-PAD-12P-1-GP-U_DISCRET-GBA    I21 @BASEBOARD_FAB2_LIB.BASEBOARD_FAB2(SCH_1):PAGE272

L12_85OHM_10INCH_DP @BASEBOARD_FAB2_LIB.BASEBOARD_FAB2(SCH_1):L12_85OHM_10INCH_DP
 T1D21    1     DP TEST-PAD-12P-1-GP-U_DISCRET-GBA    I16 @BASEBOARD_FAB2_LIB.BASEBOARD_FAB2(SCH_1):PAGE272
 T1D22    2     DN TEST-PAD-12P-1-GP-U_DISCRET-GBA    I21 @BASEBOARD_FAB2_LIB.BASEBOARD_FAB2(SCH_1):PAGE272

L12_85OHM_5INCH_DN @BASEBOARD_FAB2_LIB.BASEBOARD_FAB2(SCH_1):L12_85OHM_5INCH_DN
 T1D10    1     DP TEST-PAD-12P-1-GP-U_DISCRET-GBA    I17 @BASEBOARD_FAB2_LIB.BASEBOARD_FAB2(SCH_1):PAGE270
  T1D9    2     DN TEST-PAD-12P-1-GP-U_DISCRET-GBA    I18 @BASEBOARD_FAB2_LIB.BASEBOARD_FAB2(SCH_1):PAGE270

L12_85OHM_5INCH_DP @BASEBOARD_FAB2_LIB.BASEBOARD_FAB2(SCH_1):L12_85OHM_5INCH_DP
 T1D10    2     DN TEST-PAD-12P-1-GP-U_DISCRET-GBA    I17 @BASEBOARD_FAB2_LIB.BASEBOARD_FAB2(SCH_1):PAGE270
  T1D9    1     DP TEST-PAD-12P-1-GP-U_DISCRET-GBA    I18 @BASEBOARD_FAB2_LIB.BASEBOARD_FAB2(SCH_1):PAGE270

L12_85OHM_6INCH_DN @BASEBOARD_FAB2_LIB.BASEBOARD_FAB2(SCH_1):L12_85OHM_6INCH_DN
  T1P5    2      2 TPAD-DIFF-4P-GP_DISCRET-GB3-TPA    I11 @BASEBOARD_FAB2_LIB.BASEBOARD_FAB2(SCH_1):PAGE271

L12_85OHM_6INCH_DP @BASEBOARD_FAB2_LIB.BASEBOARD_FAB2(SCH_1):L12_85OHM_6INCH_DP
  T1P5    1      1 TPAD-DIFF-4P-GP_DISCRET-GB3-TPA    I11 @BASEBOARD_FAB2_LIB.BASEBOARD_FAB2(SCH_1):PAGE271

L12_95OHM_6INCH_DN @BASEBOARD_FAB2_LIB.BASEBOARD_FAB2(SCH_1):L12_95OHM_6INCH_DN
 T1P17    2      2 TPAD-DIFF-4P-GP_DISCRET-GB3-TPA    I36 @BASEBOARD_FAB2_LIB.BASEBOARD_FAB2(SCH_1):PAGE271

L12_95OHM_6INCH_DP @BASEBOARD_FAB2_LIB.BASEBOARD_FAB2(SCH_1):L12_95OHM_6INCH_DP
 T1P17    1      1 TPAD-DIFF-4P-GP_DISCRET-GB3-TPA    I36 @BASEBOARD_FAB2_LIB.BASEBOARD_FAB2(SCH_1):PAGE271

L14_100OHM_6INCH_DN @BASEBOARD_FAB2_LIB.BASEBOARD_FAB2(SCH_1):L14_100OHM_6INCH_DN
 T1P24    2      2 TPAD-DIFF-4P-GP_DISCRET-GB3-TPA    I38 @BASEBOARD_FAB2_LIB.BASEBOARD_FAB2(SCH_1):PAGE271

L14_100OHM_6INCH_DP @BASEBOARD_FAB2_LIB.BASEBOARD_FAB2(SCH_1):L14_100OHM_6INCH_DP
 T1P24    1      1 TPAD-DIFF-4P-GP_DISCRET-GB3-TPA    I38 @BASEBOARD_FAB2_LIB.BASEBOARD_FAB2(SCH_1):PAGE271

L14_40OHM_6INCH @BASEBOARD_FAB2_LIB.BASEBOARD_FAB2(SCH_1):L14_40OHM_6INCH
 T1P30    1      1 TPAD-SE-2P-GP_DISCRET-GA1-TPADA    I61 @BASEBOARD_FAB2_LIB.BASEBOARD_FAB2(SCH_1):PAGE271

L14_50OHM_6INCH @BASEBOARD_FAB2_LIB.BASEBOARD_FAB2(SCH_1):L14_50OHM_6INCH
 T1P36    1      1 TPAD-SE-2P-GP_DISCRET-GA1-TPADA    I63 @BASEBOARD_FAB2_LIB.BASEBOARD_FAB2(SCH_1):PAGE271

L14_73OHM_6INCH_DN @BASEBOARD_FAB2_LIB.BASEBOARD_FAB2(SCH_1):L14_73OHM_6INCH_DN
 T1P12    2      2 TPAD-DIFF-4P-GP_DISCRET-GB3-TPA    I24 @BASEBOARD_FAB2_LIB.BASEBOARD_FAB2(SCH_1):PAGE271

L14_73OHM_6INCH_DP @BASEBOARD_FAB2_LIB.BASEBOARD_FAB2(SCH_1):L14_73OHM_6INCH_DP
 T1P12    1      1 TPAD-DIFF-4P-GP_DISCRET-GB3-TPA    I24 @BASEBOARD_FAB2_LIB.BASEBOARD_FAB2(SCH_1):PAGE271

L14_85OHM_10INCH_DN @BASEBOARD_FAB2_LIB.BASEBOARD_FAB2(SCH_1):L14_85OHM_10INCH_DN
 T1D23    2     DN TEST-PAD-12P-1-GP-U_DISCRET-GBA     I9 @BASEBOARD_FAB2_LIB.BASEBOARD_FAB2(SCH_1):PAGE272
 T1D24    1     DP TEST-PAD-12P-1-GP-U_DISCRET-GBA    I12 @BASEBOARD_FAB2_LIB.BASEBOARD_FAB2(SCH_1):PAGE272

L14_85OHM_10INCH_DP @BASEBOARD_FAB2_LIB.BASEBOARD_FAB2(SCH_1):L14_85OHM_10INCH_DP
 T1D23    1     DP TEST-PAD-12P-1-GP-U_DISCRET-GBA     I9 @BASEBOARD_FAB2_LIB.BASEBOARD_FAB2(SCH_1):PAGE272
 T1D24    2     DN TEST-PAD-12P-1-GP-U_DISCRET-GBA    I12 @BASEBOARD_FAB2_LIB.BASEBOARD_FAB2(SCH_1):PAGE272

L14_85OHM_5INCH_DN @BASEBOARD_FAB2_LIB.BASEBOARD_FAB2(SCH_1):L14_85OHM_5INCH_DN
 T1D12    1     DP TEST-PAD-12P-1-GP-U_DISCRET-GBA    I21 @BASEBOARD_FAB2_LIB.BASEBOARD_FAB2(SCH_1):PAGE270
 T1D11    2     DN TEST-PAD-12P-1-GP-U_DISCRET-GBA    I24 @BASEBOARD_FAB2_LIB.BASEBOARD_FAB2(SCH_1):PAGE270

L14_85OHM_5INCH_DP @BASEBOARD_FAB2_LIB.BASEBOARD_FAB2(SCH_1):L14_85OHM_5INCH_DP
 T1D12    2     DN TEST-PAD-12P-1-GP-U_DISCRET-GBA    I21 @BASEBOARD_FAB2_LIB.BASEBOARD_FAB2(SCH_1):PAGE270
 T1D11    1     DP TEST-PAD-12P-1-GP-U_DISCRET-GBA    I24 @BASEBOARD_FAB2_LIB.BASEBOARD_FAB2(SCH_1):PAGE270

L14_85OHM_6INCH_DN @BASEBOARD_FAB2_LIB.BASEBOARD_FAB2(SCH_1):L14_85OHM_6INCH_DN
  T1P6    2      2 TPAD-DIFF-4P-GP_DISCRET-GB3-TPA    I13 @BASEBOARD_FAB2_LIB.BASEBOARD_FAB2(SCH_1):PAGE271

L14_85OHM_6INCH_DP @BASEBOARD_FAB2_LIB.BASEBOARD_FAB2(SCH_1):L14_85OHM_6INCH_DP
  T1P6    1      1 TPAD-DIFF-4P-GP_DISCRET-GB3-TPA    I13 @BASEBOARD_FAB2_LIB.BASEBOARD_FAB2(SCH_1):PAGE271

L1_100OHM_6INCH_DN @BASEBOARD_FAB2_LIB.BASEBOARD_FAB2(SCH_1):L1_100OHM_6INCH_DN
 T1P19    2      2 TPAD-DIFF-4P-GP_DISCRET-GB3-TPA    I39 @BASEBOARD_FAB2_LIB.BASEBOARD_FAB2(SCH_1):PAGE271

L1_100OHM_6INCH_DP @BASEBOARD_FAB2_LIB.BASEBOARD_FAB2(SCH_1):L1_100OHM_6INCH_DP
 T1P19    1      1 TPAD-DIFF-4P-GP_DISCRET-GB3-TPA    I39 @BASEBOARD_FAB2_LIB.BASEBOARD_FAB2(SCH_1):PAGE271

L1_40OHM_6INCH @BASEBOARD_FAB2_LIB.BASEBOARD_FAB2(SCH_1):L1_40OHM_6INCH
 T1P25    1      1 TPAD-SE-2P-GP_DISCRET-GA1-TPADA    I50 @BASEBOARD_FAB2_LIB.BASEBOARD_FAB2(SCH_1):PAGE271

L1_50OHM_6INCH @BASEBOARD_FAB2_LIB.BASEBOARD_FAB2(SCH_1):L1_50OHM_6INCH
 T1P31    1      1 TPAD-SE-2P-GP_DISCRET-GA1-TPADA    I71 @BASEBOARD_FAB2_LIB.BASEBOARD_FAB2(SCH_1):PAGE271

L1_73OHM_6INCH_DN @BASEBOARD_FAB2_LIB.BASEBOARD_FAB2(SCH_1):L1_73OHM_6INCH_DN
  T1P7    2      2 TPAD-DIFF-4P-GP_DISCRET-GB3-TPA    I17 @BASEBOARD_FAB2_LIB.BASEBOARD_FAB2(SCH_1):PAGE271

L1_73OHM_6INCH_DP @BASEBOARD_FAB2_LIB.BASEBOARD_FAB2(SCH_1):L1_73OHM_6INCH_DP
  T1P7    1      1 TPAD-DIFF-4P-GP_DISCRET-GB3-TPA    I17 @BASEBOARD_FAB2_LIB.BASEBOARD_FAB2(SCH_1):PAGE271

L1_85OHM_10INCH_DN @BASEBOARD_FAB2_LIB.BASEBOARD_FAB2(SCH_1):L1_85OHM_10INCH_DN
 T1D13    2     DN TEST-PAD-12P-1-GP-U_DISCRET-GBA     I5 @BASEBOARD_FAB2_LIB.BASEBOARD_FAB2(SCH_1):PAGE272
 T1D14    1     DP TEST-PAD-12P-1-GP-U_DISCRET-GBA    I22 @BASEBOARD_FAB2_LIB.BASEBOARD_FAB2(SCH_1):PAGE272

L1_85OHM_10INCH_DP @BASEBOARD_FAB2_LIB.BASEBOARD_FAB2(SCH_1):L1_85OHM_10INCH_DP
 T1D13    1     DP TEST-PAD-12P-1-GP-U_DISCRET-GBA     I5 @BASEBOARD_FAB2_LIB.BASEBOARD_FAB2(SCH_1):PAGE272
 T1D14    2     DN TEST-PAD-12P-1-GP-U_DISCRET-GBA    I22 @BASEBOARD_FAB2_LIB.BASEBOARD_FAB2(SCH_1):PAGE272

L1_85OHM_5INCH_DN @BASEBOARD_FAB2_LIB.BASEBOARD_FAB2(SCH_1):L1_85OHM_5INCH_DN
  T1D1    2     DN TEST-PAD-12P-1-GP-U_DISCRET-GBA     I1 @BASEBOARD_FAB2_LIB.BASEBOARD_FAB2(SCH_1):PAGE270
  T1D2    1     DP TEST-PAD-12P-1-GP-U_DISCRET-GBA     I3 @BASEBOARD_FAB2_LIB.BASEBOARD_FAB2(SCH_1):PAGE270

L1_85OHM_5INCH_DP @BASEBOARD_FAB2_LIB.BASEBOARD_FAB2(SCH_1):L1_85OHM_5INCH_DP
  T1D1    1     DP TEST-PAD-12P-1-GP-U_DISCRET-GBA     I1 @BASEBOARD_FAB2_LIB.BASEBOARD_FAB2(SCH_1):PAGE270
  T1D2    2     DN TEST-PAD-12P-1-GP-U_DISCRET-GBA     I3 @BASEBOARD_FAB2_LIB.BASEBOARD_FAB2(SCH_1):PAGE270

L1_85OHM_6INCH_DN @BASEBOARD_FAB2_LIB.BASEBOARD_FAB2(SCH_1):L1_85OHM_6INCH_DN
  T1P1    2      2 TPAD-DIFF-4P-GP_DISCRET-GB3-TPA     I3 @BASEBOARD_FAB2_LIB.BASEBOARD_FAB2(SCH_1):PAGE271

L1_85OHM_6INCH_DP @BASEBOARD_FAB2_LIB.BASEBOARD_FAB2(SCH_1):L1_85OHM_6INCH_DP
  T1P1    1      1 TPAD-DIFF-4P-GP_DISCRET-GB3-TPA     I3 @BASEBOARD_FAB2_LIB.BASEBOARD_FAB2(SCH_1):PAGE271

L1_95OHM_6INCH_DN @BASEBOARD_FAB2_LIB.BASEBOARD_FAB2(SCH_1):L1_95OHM_6INCH_DN
 T1P14    2      2 TPAD-DIFF-4P-GP_DISCRET-GB3-TPA    I30 @BASEBOARD_FAB2_LIB.BASEBOARD_FAB2(SCH_1):PAGE271

L1_95OHM_6INCH_DP @BASEBOARD_FAB2_LIB.BASEBOARD_FAB2(SCH_1):L1_95OHM_6INCH_DP
 T1P14    1      1 TPAD-DIFF-4P-GP_DISCRET-GB3-TPA    I30 @BASEBOARD_FAB2_LIB.BASEBOARD_FAB2(SCH_1):PAGE271

L3_40OHM_6INCH @BASEBOARD_FAB2_LIB.BASEBOARD_FAB2(SCH_1):L3_40OHM_6INCH
 T1P26    1      1 TPAD-SE-2P-GP_DISCRET-GA1-TPADA    I52 @BASEBOARD_FAB2_LIB.BASEBOARD_FAB2(SCH_1):PAGE271

L3_50OHM_6INCH @BASEBOARD_FAB2_LIB.BASEBOARD_FAB2(SCH_1):L3_50OHM_6INCH
 T1P32    1      1 TPAD-SE-2P-GP_DISCRET-GA1-TPADA    I72 @BASEBOARD_FAB2_LIB.BASEBOARD_FAB2(SCH_1):PAGE271

L3_73OHM_6INCH_DN @BASEBOARD_FAB2_LIB.BASEBOARD_FAB2(SCH_1):L3_73OHM_6INCH_DN
  T1P8    2      2 TPAD-DIFF-4P-GP_DISCRET-GB3-TPA    I16 @BASEBOARD_FAB2_LIB.BASEBOARD_FAB2(SCH_1):PAGE271

L3_73OHM_6INCH_DP @BASEBOARD_FAB2_LIB.BASEBOARD_FAB2(SCH_1):L3_73OHM_6INCH_DP
  T1P8    1      1 TPAD-DIFF-4P-GP_DISCRET-GB3-TPA    I16 @BASEBOARD_FAB2_LIB.BASEBOARD_FAB2(SCH_1):PAGE271

L3_85OHM_10INCH_DN @BASEBOARD_FAB2_LIB.BASEBOARD_FAB2(SCH_1):L3_85OHM_10INCH_DN
 T1D15    2     DN TEST-PAD-12P-1-GP-U_DISCRET-GBA     I3 @BASEBOARD_FAB2_LIB.BASEBOARD_FAB2(SCH_1):PAGE272
 T1D16    1     DP TEST-PAD-12P-1-GP-U_DISCRET-GBA    I14 @BASEBOARD_FAB2_LIB.BASEBOARD_FAB2(SCH_1):PAGE272

L3_85OHM_10INCH_DP @BASEBOARD_FAB2_LIB.BASEBOARD_FAB2(SCH_1):L3_85OHM_10INCH_DP
 T1D15    1     DP TEST-PAD-12P-1-GP-U_DISCRET-GBA     I3 @BASEBOARD_FAB2_LIB.BASEBOARD_FAB2(SCH_1):PAGE272
 T1D16    2     DN TEST-PAD-12P-1-GP-U_DISCRET-GBA    I14 @BASEBOARD_FAB2_LIB.BASEBOARD_FAB2(SCH_1):PAGE272

L3_85OHM_5INCH_DN @BASEBOARD_FAB2_LIB.BASEBOARD_FAB2(SCH_1):L3_85OHM_5INCH_DN
  T1D3    2     DN TEST-PAD-12P-1-GP-U_DISCRET-GBA     I5 @BASEBOARD_FAB2_LIB.BASEBOARD_FAB2(SCH_1):PAGE270
  T1D4    1     DP TEST-PAD-12P-1-GP-U_DISCRET-GBA     I6 @BASEBOARD_FAB2_LIB.BASEBOARD_FAB2(SCH_1):PAGE270

L3_85OHM_5INCH_DP @BASEBOARD_FAB2_LIB.BASEBOARD_FAB2(SCH_1):L3_85OHM_5INCH_DP
  T1D3    1     DP TEST-PAD-12P-1-GP-U_DISCRET-GBA     I5 @BASEBOARD_FAB2_LIB.BASEBOARD_FAB2(SCH_1):PAGE270
  T1D4    2     DN TEST-PAD-12P-1-GP-U_DISCRET-GBA     I6 @BASEBOARD_FAB2_LIB.BASEBOARD_FAB2(SCH_1):PAGE270

L3_85OHM_6INCH_DN @BASEBOARD_FAB2_LIB.BASEBOARD_FAB2(SCH_1):L3_85OHM_6INCH_DN
  T1P2    2      2 TPAD-DIFF-4P-GP_DISCRET-GB3-TPA     I5 @BASEBOARD_FAB2_LIB.BASEBOARD_FAB2(SCH_1):PAGE271

L3_85OHM_6INCH_DP @BASEBOARD_FAB2_LIB.BASEBOARD_FAB2(SCH_1):L3_85OHM_6INCH_DP
  T1P2    1      1 TPAD-DIFF-4P-GP_DISCRET-GB3-TPA     I5 @BASEBOARD_FAB2_LIB.BASEBOARD_FAB2(SCH_1):PAGE271

L5_40OHM_6INCH @BASEBOARD_FAB2_LIB.BASEBOARD_FAB2(SCH_1):L5_40OHM_6INCH
 T1P27    1      1 TPAD-SE-2P-GP_DISCRET-GA1-TPADA    I54 @BASEBOARD_FAB2_LIB.BASEBOARD_FAB2(SCH_1):PAGE271

L5_50OHM_6INCH @BASEBOARD_FAB2_LIB.BASEBOARD_FAB2(SCH_1):L5_50OHM_6INCH
 T1P33    1      1 TPAD-SE-2P-GP_DISCRET-GA1-TPADA    I73 @BASEBOARD_FAB2_LIB.BASEBOARD_FAB2(SCH_1):PAGE271

L5_73OHM_6INCH_DN @BASEBOARD_FAB2_LIB.BASEBOARD_FAB2(SCH_1):L5_73OHM_6INCH_DN
  T1P9    2      2 TPAD-DIFF-4P-GP_DISCRET-GB3-TPA    I19 @BASEBOARD_FAB2_LIB.BASEBOARD_FAB2(SCH_1):PAGE271

L5_73OHM_6INCH_DP @BASEBOARD_FAB2_LIB.BASEBOARD_FAB2(SCH_1):L5_73OHM_6INCH_DP
  T1P9    1      1 TPAD-DIFF-4P-GP_DISCRET-GB3-TPA    I19 @BASEBOARD_FAB2_LIB.BASEBOARD_FAB2(SCH_1):PAGE271

L5_85OHM_10INCH_DN @BASEBOARD_FAB2_LIB.BASEBOARD_FAB2(SCH_1):L5_85OHM_10INCH_DN
 T1D17    2     DN TEST-PAD-12P-1-GP-U_DISCRET-GBA     I1 @BASEBOARD_FAB2_LIB.BASEBOARD_FAB2(SCH_1):PAGE272
 T1D18    1     DP TEST-PAD-12P-1-GP-U_DISCRET-GBA     I8 @BASEBOARD_FAB2_LIB.BASEBOARD_FAB2(SCH_1):PAGE272

L5_85OHM_10INCH_DP @BASEBOARD_FAB2_LIB.BASEBOARD_FAB2(SCH_1):L5_85OHM_10INCH_DP
 T1D17    1     DP TEST-PAD-12P-1-GP-U_DISCRET-GBA     I1 @BASEBOARD_FAB2_LIB.BASEBOARD_FAB2(SCH_1):PAGE272
 T1D18    2     DN TEST-PAD-12P-1-GP-U_DISCRET-GBA     I8 @BASEBOARD_FAB2_LIB.BASEBOARD_FAB2(SCH_1):PAGE272

L5_85OHM_5INCH_DN @BASEBOARD_FAB2_LIB.BASEBOARD_FAB2(SCH_1):L5_85OHM_5INCH_DN
  T1D6    1     DP TEST-PAD-12P-1-GP-U_DISCRET-GBA     I9 @BASEBOARD_FAB2_LIB.BASEBOARD_FAB2(SCH_1):PAGE270
  T1D5    2     DN TEST-PAD-12P-1-GP-U_DISCRET-GBA    I12 @BASEBOARD_FAB2_LIB.BASEBOARD_FAB2(SCH_1):PAGE270

L5_85OHM_5INCH_DP @BASEBOARD_FAB2_LIB.BASEBOARD_FAB2(SCH_1):L5_85OHM_5INCH_DP
  T1D6    2     DN TEST-PAD-12P-1-GP-U_DISCRET-GBA     I9 @BASEBOARD_FAB2_LIB.BASEBOARD_FAB2(SCH_1):PAGE270
  T1D5    1     DP TEST-PAD-12P-1-GP-U_DISCRET-GBA    I12 @BASEBOARD_FAB2_LIB.BASEBOARD_FAB2(SCH_1):PAGE270

L5_85OHM_6INCH_DN @BASEBOARD_FAB2_LIB.BASEBOARD_FAB2(SCH_1):L5_85OHM_6INCH_DN
  T1P3    2      2 TPAD-DIFF-4P-GP_DISCRET-GB3-TPA     I8 @BASEBOARD_FAB2_LIB.BASEBOARD_FAB2(SCH_1):PAGE271

L5_85OHM_6INCH_DP @BASEBOARD_FAB2_LIB.BASEBOARD_FAB2(SCH_1):L5_85OHM_6INCH_DP
  T1P3    1      1 TPAD-DIFF-4P-GP_DISCRET-GB3-TPA     I8 @BASEBOARD_FAB2_LIB.BASEBOARD_FAB2(SCH_1):PAGE271

LED_GBE_P0_0 @BASEBOARD_FAB2_LIB.BASEBOARD_FAB2(SCH_1):LED_GBE_P0_0
  U7C1  BL1 GPP_J0_LAN_LED_P0_0 LBG_CORE_QAT_EXT_D_BGA1-IC,H91A   I147 @BASEBOARD_FAB2_LIB.BASEBOARD_FAB2(SCH_1):PAGE120
  J8E4   43   IO43 SCONN64_H87568002_A_SMT-CONN,HA    I27 @BASEBOARD_FAB2_LIB.BASEBOARD_FAB2(SCH_1):PAGE188

LED_GBE_P0_1 @BASEBOARD_FAB2_LIB.BASEBOARD_FAB2(SCH_1):LED_GBE_P0_1
  U7C1  BK4 GPP_J1_LAN_LED_P0_1 LBG_CORE_QAT_EXT_D_BGA1-IC,H91A   I147 @BASEBOARD_FAB2_LIB.BASEBOARD_FAB2(SCH_1):PAGE120
  J8E4   44   IO44 SCONN64_H87568002_A_SMT-CONN,HA    I27 @BASEBOARD_FAB2_LIB.BASEBOARD_FAB2(SCH_1):PAGE188

LED_GBE_P1_0 @BASEBOARD_FAB2_LIB.BASEBOARD_FAB2(SCH_1):LED_GBE_P1_0
  U7C1  BP4 GPP_J2_LAN_LED_P1_0 LBG_CORE_QAT_EXT_D_BGA1-IC,H91A   I147 @BASEBOARD_FAB2_LIB.BASEBOARD_FAB2(SCH_1):PAGE120
  J8E4    8    IO8 SCONN64_H87568002_A_SMT-CONN,HA    I27 @BASEBOARD_FAB2_LIB.BASEBOARD_FAB2(SCH_1):PAGE188

LED_GBE_P1_1 @BASEBOARD_FAB2_LIB.BASEBOARD_FAB2(SCH_1):LED_GBE_P1_1
  U7C1  BK2 GPP_J3_LAN_LED_P1_1 LBG_CORE_QAT_EXT_D_BGA1-IC,H91A   I147 @BASEBOARD_FAB2_LIB.BASEBOARD_FAB2(SCH_1):PAGE120
  J8E4    9    IO9 SCONN64_H87568002_A_SMT-CONN,HA    I27 @BASEBOARD_FAB2_LIB.BASEBOARD_FAB2(SCH_1):PAGE188

LED_GBE_P2_0 @BASEBOARD_FAB2_LIB.BASEBOARD_FAB2(SCH_1):LED_GBE_P2_0
  U7C1  BL3 GPP_J4_LAN_LED_P2_0 LBG_CORE_QAT_EXT_D_BGA1-IC,H91A   I147 @BASEBOARD_FAB2_LIB.BASEBOARD_FAB2(SCH_1):PAGE120
  J8E4   14   IO14 SCONN64_H87568002_A_SMT-CONN,HA    I27 @BASEBOARD_FAB2_LIB.BASEBOARD_FAB2(SCH_1):PAGE188

LED_GBE_P2_1 @BASEBOARD_FAB2_LIB.BASEBOARD_FAB2(SCH_1):LED_GBE_P2_1
  U7C1  BU6 GPP_J5_LAN_LED_P2_1 LBG_CORE_QAT_EXT_D_BGA1-IC,H91A   I147 @BASEBOARD_FAB2_LIB.BASEBOARD_FAB2(SCH_1):PAGE120
  J8E4   15   IO15 SCONN64_H87568002_A_SMT-CONN,HA    I27 @BASEBOARD_FAB2_LIB.BASEBOARD_FAB2(SCH_1):PAGE188

LED_GBE_P3_0 @BASEBOARD_FAB2_LIB.BASEBOARD_FAB2(SCH_1):LED_GBE_P3_0
  U7C1 CA13 GPP_J6_LAN_LED_P3_0 LBG_CORE_QAT_EXT_D_BGA1-IC,H91A   I147 @BASEBOARD_FAB2_LIB.BASEBOARD_FAB2(SCH_1):PAGE120
  J8E4   55   IO55 SCONN64_H87568002_A_SMT-CONN,HA    I27 @BASEBOARD_FAB2_LIB.BASEBOARD_FAB2(SCH_1):PAGE188

LED_GBE_P3_1 @BASEBOARD_FAB2_LIB.BASEBOARD_FAB2(SCH_1):LED_GBE_P3_1
  U7C1  BM2 GPP_J7_LAN_LED_P3_1 LBG_CORE_QAT_EXT_D_BGA1-IC,H91A   I147 @BASEBOARD_FAB2_LIB.BASEBOARD_FAB2(SCH_1):PAGE120
  J8E4   56   IO56 SCONN64_H87568002_A_SMT-CONN,HA    I27 @BASEBOARD_FAB2_LIB.BASEBOARD_FAB2(SCH_1):PAGE188

LED_HFI0_CPU0_N @BASEBOARD_FAB2_LIB.BASEBOARD_FAB2(SCH_1):LED_HFI0_CPU0_N
  U5D1 BK21 CD_HFI0_LED_N SKX_EXT_B_BGA1-IC,TBD    I61 @BASEBOARD_FAB2_LIB.BASEBOARD_FAB2(SCH_1):PAGE29
  J8B1    5    IO5 SCONN24_H46321001_SM-SCONN,H46A     I1 @BASEBOARD_FAB2_LIB.BASEBOARD_FAB2(SCH_1):PAGE91
  R8B5    2      B RES_0402-4.75K,1%,1/16W,CHIP,GA    I22 @BASEBOARD_FAB2_LIB.BASEBOARD_FAB2(SCH_1):PAGE91

LED_HFI1_CPU0_N @BASEBOARD_FAB2_LIB.BASEBOARD_FAB2(SCH_1):LED_HFI1_CPU0_N
  U5D1 BM23 CD_HFI1_LED_N SKX_EXT_B_BGA1-IC,TBD    I61 @BASEBOARD_FAB2_LIB.BASEBOARD_FAB2(SCH_1):PAGE29
  J8B1   13   IO13 SCONN24_H46321001_SM-SCONN,H46A     I1 @BASEBOARD_FAB2_LIB.BASEBOARD_FAB2(SCH_1):PAGE91
 R8B18    2      B RES_0402-4.75K,1%,1/16W,CHIP,GA    I20 @BASEBOARD_FAB2_LIB.BASEBOARD_FAB2(SCH_1):PAGE91

LED_LAN_0_N @BASEBOARD_FAB2_LIB.BASEBOARD_FAB2(SCH_1):LED_LAN_0_N
 EU9E1   31   LED0 SPRINGVILLE_SM1-IC,G47144-004    I72 @BASEBOARD_FAB2_LIB.BASEBOARD_FAB2(SCH_1):PAGE139
  R9G3    2      B RES_0402-75,1.0%,1/16W,CHIP,G2A   I135 @BASEBOARD_FAB2_LIB.BASEBOARD_FAB2(SCH_1):PAGE141
  C9G3    1      A CAP_0402LF-470PF,50V,10%,X7R,AA   I138 @BASEBOARD_FAB2_LIB.BASEBOARD_FAB2(SCH_1):PAGE141

LED_LAN_0_R_N @BASEBOARD_FAB2_LIB.BASEBOARD_FAB2(SCH_1):LED_LAN_0_R_N
 JA9G1   L2     L2 SKT-RJ45-LED-XFOR-1-GP_SOCKET-A   I129 @BASEBOARD_FAB2_LIB.BASEBOARD_FAB2(SCH_1):PAGE141
  R9G3    1      A RES_0402-75,1.0%,1/16W,CHIP,G2A   I135 @BASEBOARD_FAB2_LIB.BASEBOARD_FAB2(SCH_1):PAGE141

LED_LAN_1_N @BASEBOARD_FAB2_LIB.BASEBOARD_FAB2(SCH_1):LED_LAN_1_N
 EU9E1   30   LED1 SPRINGVILLE_SM1-IC,G47144-004    I72 @BASEBOARD_FAB2_LIB.BASEBOARD_FAB2(SCH_1):PAGE139
  R9G1    1      A RES_0402-150.0,1%,1/16W,CHIP,GA   I157 @BASEBOARD_FAB2_LIB.BASEBOARD_FAB2(SCH_1):PAGE141
 C9F22    1      A CAP_0402LF-470PF,50V,10%,X7R,AA   I159 @BASEBOARD_FAB2_LIB.BASEBOARD_FAB2(SCH_1):PAGE141

LED_LAN_1_R_N @BASEBOARD_FAB2_LIB.BASEBOARD_FAB2(SCH_1):LED_LAN_1_R_N
 JA9G1   L3     L3 SKT-RJ45-LED-XFOR-1-GP_SOCKET-A   I129 @BASEBOARD_FAB2_LIB.BASEBOARD_FAB2(SCH_1):PAGE141
  R9G1    2      B RES_0402-150.0,1%,1/16W,CHIP,GA   I157 @BASEBOARD_FAB2_LIB.BASEBOARD_FAB2(SCH_1):PAGE141

LED_LAN_2_N @BASEBOARD_FAB2_LIB.BASEBOARD_FAB2(SCH_1):LED_LAN_2_N
 EU9E1   33   LED2 SPRINGVILLE_SM1-IC,G47144-004    I72 @BASEBOARD_FAB2_LIB.BASEBOARD_FAB2(SCH_1):PAGE139
  R9G2    2      B RES_0402-75,1.0%,1/16W,CHIP,G2A   I134 @BASEBOARD_FAB2_LIB.BASEBOARD_FAB2(SCH_1):PAGE141
  C9G1    1      A CAP_0402LF-470PF,50V,10%,X7R,AA   I140 @BASEBOARD_FAB2_LIB.BASEBOARD_FAB2(SCH_1):PAGE141

LED_LAN_2_R_N @BASEBOARD_FAB2_LIB.BASEBOARD_FAB2(SCH_1):LED_LAN_2_R_N
 JA9G1   L1     L1 SKT-RJ45-LED-XFOR-1-GP_SOCKET-A   I129 @BASEBOARD_FAB2_LIB.BASEBOARD_FAB2(SCH_1):PAGE141
  R9G2    1      A RES_0402-75,1.0%,1/16W,CHIP,G2A   I134 @BASEBOARD_FAB2_LIB.BASEBOARD_FAB2(SCH_1):PAGE141

LED_P5V_STBY @BASEBOARD_FAB2_LIB.BASEBOARD_FAB2(SCH_1):LED_P5V_STBY
 DS9A6    1      A LED_A1LF-GREEN,IC,C97278-010    I31 @BASEBOARD_FAB2_LIB.BASEBOARD_FAB2(SCH_1):PAGE177
 R1L37    2      B RES_0402-301.0,1%,1/16W,CHIP,GA    I33 @BASEBOARD_FAB2_LIB.BASEBOARD_FAB2(SCH_1):PAGE177

LED_PCH_SATA_HDD_N @BASEBOARD_FAB2_LIB.BASEBOARD_FAB2(SCH_1):LED_PCH_SATA_HDD_N
  U7C1 AV56 GPP_E8_SATA_LED_N LBG_CORE_QAT_EXT_D_BGA1-IC,H91A   I147 @BASEBOARD_FAB2_LIB.BASEBOARD_FAB2(SCH_1):PAGE120
 R1M10    1      A RES_0402-0.0,5%,1/16W,CHIP,G21A     I6 @BASEBOARD_FAB2_LIB.BASEBOARD_FAB2(SCH_1):PAGE177

LED_PCH_SSATA_HDD_N @BASEBOARD_FAB2_LIB.BASEBOARD_FAB2(SCH_1):LED_PCH_SSATA_HDD_N
  U7C1 AL11 GPP_F14_SSATA_LED_N LBG_CORE_QAT_EXT_D_BGA1-IC,H91A   I147 @BASEBOARD_FAB2_LIB.BASEBOARD_FAB2(SCH_1):PAGE120
 R1M13    1      A RES_0402-0.0,5%,1/16W,CHIP,G21A     I3 @BASEBOARD_FAB2_LIB.BASEBOARD_FAB2(SCH_1):PAGE177

LED_POSTCODE_0 @BASEBOARD_FAB2_LIB.BASEBOARD_FAB2(SCH_1):LED_POSTCODE_0
 R1L32    1      A RES_0402-10.0,1%,1/16W,CHIP,G2A    I65 @BASEBOARD_FAB2_LIB.BASEBOARD_FAB2(SCH_1):PAGE155
 U25W4  A18 GPIOH0_NCTS6 AST2520A1-GP-GP_ASIC2-GB1-AST2A   I104 @BASEBOARD_FAB2_LIB.BASEBOARD_FAB2(SCH_1):PAGE146

LED_POSTCODE_0_R @BASEBOARD_FAB2_LIB.BASEBOARD_FAB2(SCH_1):LED_POSTCODE_0_R
 R1L32    2      B RES_0402-10.0,1%,1/16W,CHIP,G2A    I65 @BASEBOARD_FAB2_LIB.BASEBOARD_FAB2(SCH_1):PAGE155
  J9A2    1    IO1 CONN14_H54902001_PIP-CONN,H549A   I171 @BASEBOARD_FAB2_LIB.BASEBOARD_FAB2(SCH_1):PAGE155
  U6W1    4    P00 TCA9555PWR-GP_DISCRET-GC1-TCA9A   I120 @BASEBOARD_FAB2_LIB.BASEBOARD_FAB2(SCH_1):PAGE247

LED_POSTCODE_1 @BASEBOARD_FAB2_LIB.BASEBOARD_FAB2(SCH_1):LED_POSTCODE_1
 R1L30    1      A RES_0402-10.0,1%,1/16W,CHIP,G2A    I66 @BASEBOARD_FAB2_LIB.BASEBOARD_FAB2(SCH_1):PAGE155
 U25W4  B18 GPIOH1_NDCD6 AST2520A1-GP-GP_ASIC2-GB1-AST2A   I104 @BASEBOARD_FAB2_LIB.BASEBOARD_FAB2(SCH_1):PAGE146

LED_POSTCODE_1_R @BASEBOARD_FAB2_LIB.BASEBOARD_FAB2(SCH_1):LED_POSTCODE_1_R
 R1L30    2      B RES_0402-10.0,1%,1/16W,CHIP,G2A    I66 @BASEBOARD_FAB2_LIB.BASEBOARD_FAB2(SCH_1):PAGE155
  J9A2    2    IO2 CONN14_H54902001_PIP-CONN,H549A   I171 @BASEBOARD_FAB2_LIB.BASEBOARD_FAB2(SCH_1):PAGE155
  U6W1    5    P01 TCA9555PWR-GP_DISCRET-GC1-TCA9A   I120 @BASEBOARD_FAB2_LIB.BASEBOARD_FAB2(SCH_1):PAGE247

LED_POSTCODE_2 @BASEBOARD_FAB2_LIB.BASEBOARD_FAB2(SCH_1):LED_POSTCODE_2
 R1L25    1      A RES_0402-10.0,1%,1/16W,CHIP,G2A    I67 @BASEBOARD_FAB2_LIB.BASEBOARD_FAB2(SCH_1):PAGE155
 U25W4  D17 GPIOH2_NDSR6 AST2520A1-GP-GP_ASIC2-GB1-AST2A   I104 @BASEBOARD_FAB2_LIB.BASEBOARD_FAB2(SCH_1):PAGE146

LED_POSTCODE_2_R @BASEBOARD_FAB2_LIB.BASEBOARD_FAB2(SCH_1):LED_POSTCODE_2_R
 R1L25    2      B RES_0402-10.0,1%,1/16W,CHIP,G2A    I67 @BASEBOARD_FAB2_LIB.BASEBOARD_FAB2(SCH_1):PAGE155
  J9A2    3    IO3 CONN14_H54902001_PIP-CONN,H549A   I171 @BASEBOARD_FAB2_LIB.BASEBOARD_FAB2(SCH_1):PAGE155
  U6W1    6    P02 TCA9555PWR-GP_DISCRET-GC1-TCA9A   I120 @BASEBOARD_FAB2_LIB.BASEBOARD_FAB2(SCH_1):PAGE247

LED_POSTCODE_3 @BASEBOARD_FAB2_LIB.BASEBOARD_FAB2(SCH_1):LED_POSTCODE_3
 R1L24    1      A RES_0402-10.0,1%,1/16W,CHIP,G2A    I68 @BASEBOARD_FAB2_LIB.BASEBOARD_FAB2(SCH_1):PAGE155
 U25W4  C17 GPIOH3_NRI6 AST2520A1-GP-GP_ASIC2-GB1-AST2A   I104 @BASEBOARD_FAB2_LIB.BASEBOARD_FAB2(SCH_1):PAGE146

LED_POSTCODE_3_R @BASEBOARD_FAB2_LIB.BASEBOARD_FAB2(SCH_1):LED_POSTCODE_3_R
 R1L24    2      B RES_0402-10.0,1%,1/16W,CHIP,G2A    I68 @BASEBOARD_FAB2_LIB.BASEBOARD_FAB2(SCH_1):PAGE155
  J9A2    4    IO4 CONN14_H54902001_PIP-CONN,H549A   I171 @BASEBOARD_FAB2_LIB.BASEBOARD_FAB2(SCH_1):PAGE155
  U6W1    7    P03 TCA9555PWR-GP_DISCRET-GC1-TCA9A   I120 @BASEBOARD_FAB2_LIB.BASEBOARD_FAB2(SCH_1):PAGE247

LED_POSTCODE_4 @BASEBOARD_FAB2_LIB.BASEBOARD_FAB2(SCH_1):LED_POSTCODE_4
 R1L20    1      A RES_0402-10.0,1%,1/16W,CHIP,G2A    I73 @BASEBOARD_FAB2_LIB.BASEBOARD_FAB2(SCH_1):PAGE155
 U25W4  A17 GPIOH4_NDTR6 AST2520A1-GP-GP_ASIC2-GB1-AST2A   I104 @BASEBOARD_FAB2_LIB.BASEBOARD_FAB2(SCH_1):PAGE146

LED_POSTCODE_4_R @BASEBOARD_FAB2_LIB.BASEBOARD_FAB2(SCH_1):LED_POSTCODE_4_R
 R1L20    2      B RES_0402-10.0,1%,1/16W,CHIP,G2A    I73 @BASEBOARD_FAB2_LIB.BASEBOARD_FAB2(SCH_1):PAGE155
  J9A2    5    IO5 CONN14_H54902001_PIP-CONN,H549A   I171 @BASEBOARD_FAB2_LIB.BASEBOARD_FAB2(SCH_1):PAGE155
  U6W1    8    P04 TCA9555PWR-GP_DISCRET-GC1-TCA9A   I120 @BASEBOARD_FAB2_LIB.BASEBOARD_FAB2(SCH_1):PAGE247

LED_POSTCODE_5 @BASEBOARD_FAB2_LIB.BASEBOARD_FAB2(SCH_1):LED_POSTCODE_5
 R1L18    1      A RES_0402-10.0,1%,1/16W,CHIP,G2A    I74 @BASEBOARD_FAB2_LIB.BASEBOARD_FAB2(SCH_1):PAGE155
 U25W4  B17 GPIOH5_NRTS6 AST2520A1-GP-GP_ASIC2-GB1-AST2A   I104 @BASEBOARD_FAB2_LIB.BASEBOARD_FAB2(SCH_1):PAGE146

LED_POSTCODE_5_R @BASEBOARD_FAB2_LIB.BASEBOARD_FAB2(SCH_1):LED_POSTCODE_5_R
 R1L18    2      B RES_0402-10.0,1%,1/16W,CHIP,G2A    I74 @BASEBOARD_FAB2_LIB.BASEBOARD_FAB2(SCH_1):PAGE155
  J9A2    6    IO6 CONN14_H54902001_PIP-CONN,H549A   I171 @BASEBOARD_FAB2_LIB.BASEBOARD_FAB2(SCH_1):PAGE155
  U6W1    9    P05 TCA9555PWR-GP_DISCRET-GC1-TCA9A   I120 @BASEBOARD_FAB2_LIB.BASEBOARD_FAB2(SCH_1):PAGE247

LED_POSTCODE_6 @BASEBOARD_FAB2_LIB.BASEBOARD_FAB2(SCH_1):LED_POSTCODE_6
 R1L14    1      A RES_0402-10.0,1%,1/16W,CHIP,G2A    I75 @BASEBOARD_FAB2_LIB.BASEBOARD_FAB2(SCH_1):PAGE155
 U25W4  A16 GPIOH6_TXD6 AST2520A1-GP-GP_ASIC2-GB1-AST2A   I104 @BASEBOARD_FAB2_LIB.BASEBOARD_FAB2(SCH_1):PAGE146

LED_POSTCODE_6_R @BASEBOARD_FAB2_LIB.BASEBOARD_FAB2(SCH_1):LED_POSTCODE_6_R
 R1L14    2      B RES_0402-10.0,1%,1/16W,CHIP,G2A    I75 @BASEBOARD_FAB2_LIB.BASEBOARD_FAB2(SCH_1):PAGE155
  J9A2    7    IO7 CONN14_H54902001_PIP-CONN,H549A   I171 @BASEBOARD_FAB2_LIB.BASEBOARD_FAB2(SCH_1):PAGE155
  U6W1   10    P06 TCA9555PWR-GP_DISCRET-GC1-TCA9A   I120 @BASEBOARD_FAB2_LIB.BASEBOARD_FAB2(SCH_1):PAGE247

LED_POSTCODE_7 @BASEBOARD_FAB2_LIB.BASEBOARD_FAB2(SCH_1):LED_POSTCODE_7
 R1L11    1      A RES_0402-10.0,1%,1/16W,CHIP,G2A    I76 @BASEBOARD_FAB2_LIB.BASEBOARD_FAB2(SCH_1):PAGE155
 U25W4  D18 GPIOH7_RXD6 AST2520A1-GP-GP_ASIC2-GB1-AST2A   I104 @BASEBOARD_FAB2_LIB.BASEBOARD_FAB2(SCH_1):PAGE146

LED_POSTCODE_7_R @BASEBOARD_FAB2_LIB.BASEBOARD_FAB2(SCH_1):LED_POSTCODE_7_R
 R1L11    2      B RES_0402-10.0,1%,1/16W,CHIP,G2A    I76 @BASEBOARD_FAB2_LIB.BASEBOARD_FAB2(SCH_1):PAGE155
  J9A2    8    IO8 CONN14_H54902001_PIP-CONN,H549A   I171 @BASEBOARD_FAB2_LIB.BASEBOARD_FAB2(SCH_1):PAGE155
  U6W1   11    P07 TCA9555PWR-GP_DISCRET-GC1-TCA9A   I120 @BASEBOARD_FAB2_LIB.BASEBOARD_FAB2(SCH_1):PAGE247

LED_SAS_ACT_R_N @BASEBOARD_FAB2_LIB.BASEBOARD_FAB2(SCH_1):LED_SAS_ACT_R_N
 R1M13    2      B RES_0402-0.0,5%,1/16W,CHIP,G21A     I3 @BASEBOARD_FAB2_LIB.BASEBOARD_FAB2(SCH_1):PAGE177
 R1M12    2      B RES_0402-10.0K,1%,1/16W,CHIP,GA     I8 @BASEBOARD_FAB2_LIB.BASEBOARD_FAB2(SCH_1):PAGE177
  U1M1    2   B<0> TTL1G08_SOTLF-NC7SZ08,IC,D1032C    I70 @BASEBOARD_FAB2_LIB.BASEBOARD_FAB2(SCH_1):PAGE177

LED_SATA_ACT_R_N @BASEBOARD_FAB2_LIB.BASEBOARD_FAB2(SCH_1):LED_SATA_ACT_R_N
 R1M10    2      B RES_0402-0.0,5%,1/16W,CHIP,G21A     I6 @BASEBOARD_FAB2_LIB.BASEBOARD_FAB2(SCH_1):PAGE177
 R1M11    2      B RES_0402-10.0K,1%,1/16W,CHIP,GA     I9 @BASEBOARD_FAB2_LIB.BASEBOARD_FAB2(SCH_1):PAGE177
  U1M1    1   A<0> TTL1G08_SOTLF-NC7SZ08,IC,D1032C    I70 @BASEBOARD_FAB2_LIB.BASEBOARD_FAB2(SCH_1):PAGE177

LPC_LAD0_IO0 @BASEBOARD_FAB2_LIB.BASEBOARD_FAB2(SCH_1):LPC_LAD0_IO0
  U7C1   Y3 GPP_A1_LAD0_ESPI_IO0 LBG_CORE_QAT_EXT_D_BGA1-IC,H91A   I115 @BASEBOARD_FAB2_LIB.BASEBOARD_FAB2(SCH_1):PAGE119
 R3N26    1      A RES_0402-33.2,1%,1/16W,CHIP,G2A    I75 @BASEBOARD_FAB2_LIB.BASEBOARD_FAB2(SCH_1):PAGE146

LPC_LAD0_IO0_R @BASEBOARD_FAB2_LIB.BASEBOARD_FAB2(SCH_1):LPC_LAD0_IO0_R
 R3N26    2      B RES_0402-33.2,1%,1/16W,CHIP,G2A    I75 @BASEBOARD_FAB2_LIB.BASEBOARD_FAB2(SCH_1):PAGE146
 U25W4  G21 GPIOAC0_ESPID0_LAD0 AST2520A1-GP-GP_ASIC2-GB1-AST2A   I105 @BASEBOARD_FAB2_LIB.BASEBOARD_FAB2(SCH_1):PAGE146

LPC_LAD1_IO1 @BASEBOARD_FAB2_LIB.BASEBOARD_FAB2(SCH_1):LPC_LAD1_IO1
  U7C1   N1 GPP_A2_LAD1_ESPI_IO1 LBG_CORE_QAT_EXT_D_BGA1-IC,H91A   I115 @BASEBOARD_FAB2_LIB.BASEBOARD_FAB2(SCH_1):PAGE119
R25W69    1      A RES_0402-33.2,1%,1/16W,CHIP,G2A    I85 @BASEBOARD_FAB2_LIB.BASEBOARD_FAB2(SCH_1):PAGE146

LPC_LAD1_IO1_R @BASEBOARD_FAB2_LIB.BASEBOARD_FAB2(SCH_1):LPC_LAD1_IO1_R
R25W69    2      B RES_0402-33.2,1%,1/16W,CHIP,G2A    I85 @BASEBOARD_FAB2_LIB.BASEBOARD_FAB2(SCH_1):PAGE146
 U25W4  G20 GPIOAC1_ESPID1_LAD1 AST2520A1-GP-GP_ASIC2-GB1-AST2A   I105 @BASEBOARD_FAB2_LIB.BASEBOARD_FAB2(SCH_1):PAGE146

LPC_LAD2_IO2 @BASEBOARD_FAB2_LIB.BASEBOARD_FAB2(SCH_1):LPC_LAD2_IO2
  U7C1   W2 GPP_A3_LAD2_ESPI_IO2 LBG_CORE_QAT_EXT_D_BGA1-IC,H91A   I115 @BASEBOARD_FAB2_LIB.BASEBOARD_FAB2(SCH_1):PAGE119
 R3N24    1      A RES_0402-33.2,1%,1/16W,CHIP,G2A    I74 @BASEBOARD_FAB2_LIB.BASEBOARD_FAB2(SCH_1):PAGE146

LPC_LAD2_IO2_R @BASEBOARD_FAB2_LIB.BASEBOARD_FAB2(SCH_1):LPC_LAD2_IO2_R
 R3N24    2      B RES_0402-33.2,1%,1/16W,CHIP,G2A    I74 @BASEBOARD_FAB2_LIB.BASEBOARD_FAB2(SCH_1):PAGE146
 U25W4  D22 GPIOAC2_ESPID2_LAD2 AST2520A1-GP-GP_ASIC2-GB1-AST2A   I105 @BASEBOARD_FAB2_LIB.BASEBOARD_FAB2(SCH_1):PAGE146

LPC_LAD3_IO3 @BASEBOARD_FAB2_LIB.BASEBOARD_FAB2(SCH_1):LPC_LAD3_IO3
  U7C1   Y1 GPP_A4_LAD3_ESPI_IO3 LBG_CORE_QAT_EXT_D_BGA1-IC,H91A   I115 @BASEBOARD_FAB2_LIB.BASEBOARD_FAB2(SCH_1):PAGE119
R25W68    1      A RES_0402-33.2,1%,1/16W,CHIP,G2A    I84 @BASEBOARD_FAB2_LIB.BASEBOARD_FAB2(SCH_1):PAGE146

LPC_LAD3_IO3_R @BASEBOARD_FAB2_LIB.BASEBOARD_FAB2(SCH_1):LPC_LAD3_IO3_R
R25W68    2      B RES_0402-33.2,1%,1/16W,CHIP,G2A    I84 @BASEBOARD_FAB2_LIB.BASEBOARD_FAB2(SCH_1):PAGE146
 U25W4  E22 GPIOAC3_ESPID3_LAD3 AST2520A1-GP-GP_ASIC2-GB1-AST2A   I105 @BASEBOARD_FAB2_LIB.BASEBOARD_FAB2(SCH_1):PAGE146

LPC_LFRAME_N_CS0_N @BASEBOARD_FAB2_LIB.BASEBOARD_FAB2(SCH_1):LPC_LFRAME_N_CS0_N
  U7C1   P4 GPP_A5_LFRAME_N_ESPI_CS0_N LBG_CORE_QAT_EXT_D_BGA1-IC,H91A   I115 @BASEBOARD_FAB2_LIB.BASEBOARD_FAB2(SCH_1):PAGE119
R25W72    1      A RES_0402-33.2,1%,1/16W,CHIP,G2A    I71 @BASEBOARD_FAB2_LIB.BASEBOARD_FAB2(SCH_1):PAGE146

LPC_LFRAME_N_CS0_R_N @BASEBOARD_FAB2_LIB.BASEBOARD_FAB2(SCH_1):LPC_LFRAME_N_CS0_R_N
R25W72    2      B RES_0402-33.2,1%,1/16W,CHIP,G2A    I71 @BASEBOARD_FAB2_LIB.BASEBOARD_FAB2(SCH_1):PAGE146
 U25W4  F21 GPIOAC5_ESPICS#_LFRAME# AST2520A1-GP-GP_ASIC2-GB1-AST2A   I105 @BASEBOARD_FAB2_LIB.BASEBOARD_FAB2(SCH_1):PAGE146

M_ABC_RST_N @BASEBOARD_FAB2_LIB.BASEBOARD_FAB2(SCH_1):M_ABC_RST_N
  U5D1  U64 DDR012_RESET_N SKX_EXT_B_BGA1-IC,TBD   I259 @BASEBOARD_FAB2_LIB.BASEBOARD_FAB2(SCH_1):PAGE21
  J4G1   58 RESET_N SCONN288_H44441004_PIP-SCONN,HA     I1 @BASEBOARD_FAB2_LIB.BASEBOARD_FAB2(SCH_1):PAGE43
  J6T1   58 RESET_N SCONN288_H44441003_PIP-SCONN,HA    I13 @BASEBOARD_FAB2_LIB.BASEBOARD_FAB2(SCH_1):PAGE44
  J4G2   58 RESET_N SCONN288_H44441004_PIP-SCONN,HA   I111 @BASEBOARD_FAB2_LIB.BASEBOARD_FAB2(SCH_1):PAGE45
  J6U1   58 RESET_N SCONN288_H44441003_PIP-SCONN,HA    I14 @BASEBOARD_FAB2_LIB.BASEBOARD_FAB2(SCH_1):PAGE46
  J4G3   58 RESET_N SCONN288_H44441004_PIP-SCONN,HA   I111 @BASEBOARD_FAB2_LIB.BASEBOARD_FAB2(SCH_1):PAGE47
  J6U2   58 RESET_N SCONN288_H44441003_PIP-SCONN,HA   I111 @BASEBOARD_FAB2_LIB.BASEBOARD_FAB2(SCH_1):PAGE48

M_A_ACT_N @BASEBOARD_FAB2_LIB.BASEBOARD_FAB2(SCH_1):M_A_ACT_N
  U5D1  J60 DDR0_ACT_N SKX_EXT_B_BGA1-IC,TBD   I172 @BASEBOARD_FAB2_LIB.BASEBOARD_FAB2(SCH_1):PAGE23
  J4G1   62  ACT_N SCONN288_H44441004_PIP-SCONN,HA     I1 @BASEBOARD_FAB2_LIB.BASEBOARD_FAB2(SCH_1):PAGE43
  J6T1   62  ACT_N SCONN288_H44441003_PIP-SCONN,HA    I13 @BASEBOARD_FAB2_LIB.BASEBOARD_FAB2(SCH_1):PAGE44

M_A_ALERT_N @BASEBOARD_FAB2_LIB.BASEBOARD_FAB2(SCH_1):M_A_ALERT_N
  U5D1  B61 DDR0_ALERT_N SKX_EXT_B_BGA1-IC,TBD   I172 @BASEBOARD_FAB2_LIB.BASEBOARD_FAB2(SCH_1):PAGE23
  J4G1  208 ALERT_N SCONN288_H44441004_PIP-SCONN,HA     I1 @BASEBOARD_FAB2_LIB.BASEBOARD_FAB2(SCH_1):PAGE43
  J6T1  208 ALERT_N SCONN288_H44441003_PIP-SCONN,HA    I13 @BASEBOARD_FAB2_LIB.BASEBOARD_FAB2(SCH_1):PAGE44

M_A_BA<0> @BASEBOARD_FAB2_LIB.BASEBOARD_FAB2(SCH_1):M_A_BA(0)
  U5D1  C52 DDR0_BA<0> SKX_EXT_B_BGA1-IC,TBD   I172 @BASEBOARD_FAB2_LIB.BASEBOARD_FAB2(SCH_1):PAGE23
  J4G1   81  BA<0> SCONN288_H44441004_PIP-SCONN,HA     I1 @BASEBOARD_FAB2_LIB.BASEBOARD_FAB2(SCH_1):PAGE43
  J6T1   81  BA<0> SCONN288_H44441003_PIP-SCONN,HA    I13 @BASEBOARD_FAB2_LIB.BASEBOARD_FAB2(SCH_1):PAGE44

M_A_BA<1> @BASEBOARD_FAB2_LIB.BASEBOARD_FAB2(SCH_1):M_A_BA(1)
  U5D1  G54 DDR0_BA<1> SKX_EXT_B_BGA1-IC,TBD   I172 @BASEBOARD_FAB2_LIB.BASEBOARD_FAB2(SCH_1):PAGE23
  J4G1  224  BA<1> SCONN288_H44441004_PIP-SCONN,HA     I1 @BASEBOARD_FAB2_LIB.BASEBOARD_FAB2(SCH_1):PAGE43
  J6T1  224  BA<1> SCONN288_H44441003_PIP-SCONN,HA    I13 @BASEBOARD_FAB2_LIB.BASEBOARD_FAB2(SCH_1):PAGE44

M_A_BG<0> @BASEBOARD_FAB2_LIB.BASEBOARD_FAB2(SCH_1):M_A_BG(0)
  U5D1  D61 DDR0_BG<0> SKX_EXT_B_BGA1-IC,TBD   I172 @BASEBOARD_FAB2_LIB.BASEBOARD_FAB2(SCH_1):PAGE23
  J4G1   63  BG<0> SCONN288_H44441004_PIP-SCONN,HA     I1 @BASEBOARD_FAB2_LIB.BASEBOARD_FAB2(SCH_1):PAGE43
  J6T1   63  BG<0> SCONN288_H44441003_PIP-SCONN,HA    I13 @BASEBOARD_FAB2_LIB.BASEBOARD_FAB2(SCH_1):PAGE44

M_A_BG<1> @BASEBOARD_FAB2_LIB.BASEBOARD_FAB2(SCH_1):M_A_BG(1)
  U5D1  F63 DDR0_BG<1> SKX_EXT_B_BGA1-IC,TBD   I172 @BASEBOARD_FAB2_LIB.BASEBOARD_FAB2(SCH_1):PAGE23
  J4G1  207  BG<1> SCONN288_H44441004_PIP-SCONN,HA     I1 @BASEBOARD_FAB2_LIB.BASEBOARD_FAB2(SCH_1):PAGE43
  J6T1  207  BG<1> SCONN288_H44441003_PIP-SCONN,HA    I13 @BASEBOARD_FAB2_LIB.BASEBOARD_FAB2(SCH_1):PAGE44

M_A_C<2> @BASEBOARD_FAB2_LIB.BASEBOARD_FAB2(SCH_1):M_A_C(2)
  U5D1  G46 DDR0_CID<2> SKX_EXT_B_BGA1-IC,TBD   I172 @BASEBOARD_FAB2_LIB.BASEBOARD_FAB2(SCH_1):PAGE23
  J4G1  235   C<2> SCONN288_H44441004_PIP-SCONN,HA     I1 @BASEBOARD_FAB2_LIB.BASEBOARD_FAB2(SCH_1):PAGE43
  J6T1  235   C<2> SCONN288_H44441003_PIP-SCONN,HA    I13 @BASEBOARD_FAB2_LIB.BASEBOARD_FAB2(SCH_1):PAGE44

M_A_CKE<0> @BASEBOARD_FAB2_LIB.BASEBOARD_FAB2(SCH_1):M_A_CKE(0)
  U5D1  C62 DDR0_CKE<0> SKX_EXT_B_BGA1-IC,TBD   I172 @BASEBOARD_FAB2_LIB.BASEBOARD_FAB2(SCH_1):PAGE23
  J4G1   60 CKE<0> SCONN288_H44441004_PIP-SCONN,HA     I1 @BASEBOARD_FAB2_LIB.BASEBOARD_FAB2(SCH_1):PAGE43

M_A_CKE<1> @BASEBOARD_FAB2_LIB.BASEBOARD_FAB2(SCH_1):M_A_CKE(1)
  U5D1  C64 DDR0_CKE<1> SKX_EXT_B_BGA1-IC,TBD   I172 @BASEBOARD_FAB2_LIB.BASEBOARD_FAB2(SCH_1):PAGE23
  J4G1  203 CKE<1> SCONN288_H44441004_PIP-SCONN,HA     I1 @BASEBOARD_FAB2_LIB.BASEBOARD_FAB2(SCH_1):PAGE43

M_A_CKE<2> @BASEBOARD_FAB2_LIB.BASEBOARD_FAB2(SCH_1):M_A_CKE(2)
  U5D1  B63 DDR0_CKE<2> SKX_EXT_B_BGA1-IC,TBD   I172 @BASEBOARD_FAB2_LIB.BASEBOARD_FAB2(SCH_1):PAGE23
  J6T1   60 CKE<0> SCONN288_H44441003_PIP-SCONN,HA    I13 @BASEBOARD_FAB2_LIB.BASEBOARD_FAB2(SCH_1):PAGE44

M_A_CKE<3> @BASEBOARD_FAB2_LIB.BASEBOARD_FAB2(SCH_1):M_A_CKE(3)
  U5D1  D63 DDR0_CKE<3> SKX_EXT_B_BGA1-IC,TBD   I172 @BASEBOARD_FAB2_LIB.BASEBOARD_FAB2(SCH_1):PAGE23
  J6T1  203 CKE<1> SCONN288_H44441003_PIP-SCONN,HA    I13 @BASEBOARD_FAB2_LIB.BASEBOARD_FAB2(SCH_1):PAGE44

M_A_CLK_DN<0> @BASEBOARD_FAB2_LIB.BASEBOARD_FAB2(SCH_1):M_A_CLK_DN(0)
  U5D1  F55 DDR0_CLK_DN<0> SKX_EXT_B_BGA1-IC,TBD   I172 @BASEBOARD_FAB2_LIB.BASEBOARD_FAB2(SCH_1):PAGE23
  J4G1   75   CK0N SCONN288_H44441004_PIP-SCONN,HA     I1 @BASEBOARD_FAB2_LIB.BASEBOARD_FAB2(SCH_1):PAGE43

M_A_CLK_DN<1> @BASEBOARD_FAB2_LIB.BASEBOARD_FAB2(SCH_1):M_A_CLK_DN(1)
  U5D1  C54 DDR0_CLK_DN<1> SKX_EXT_B_BGA1-IC,TBD   I172 @BASEBOARD_FAB2_LIB.BASEBOARD_FAB2(SCH_1):PAGE23
  J4G1  219   CK1N SCONN288_H44441004_PIP-SCONN,HA     I1 @BASEBOARD_FAB2_LIB.BASEBOARD_FAB2(SCH_1):PAGE43

M_A_CLK_DN<2> @BASEBOARD_FAB2_LIB.BASEBOARD_FAB2(SCH_1):M_A_CLK_DN(2)
  U5D1  J56 DDR0_CLK_DN<2> SKX_EXT_B_BGA1-IC,TBD   I172 @BASEBOARD_FAB2_LIB.BASEBOARD_FAB2(SCH_1):PAGE23
  J6T1   75   CK0N SCONN288_H44441003_PIP-SCONN,HA    I13 @BASEBOARD_FAB2_LIB.BASEBOARD_FAB2(SCH_1):PAGE44

M_A_CLK_DN<3> @BASEBOARD_FAB2_LIB.BASEBOARD_FAB2(SCH_1):M_A_CLK_DN(3)
  U5D1  C56 DDR0_CLK_DN<3> SKX_EXT_B_BGA1-IC,TBD   I172 @BASEBOARD_FAB2_LIB.BASEBOARD_FAB2(SCH_1):PAGE23
  J6T1  219   CK1N SCONN288_H44441003_PIP-SCONN,HA    I13 @BASEBOARD_FAB2_LIB.BASEBOARD_FAB2(SCH_1):PAGE44

M_A_CLK_DP<0> @BASEBOARD_FAB2_LIB.BASEBOARD_FAB2(SCH_1):M_A_CLK_DP(0)
  U5D1  D55 DDR0_CLK_DP<0> SKX_EXT_B_BGA1-IC,TBD   I172 @BASEBOARD_FAB2_LIB.BASEBOARD_FAB2(SCH_1):PAGE23
  J4G1   74   CK0P SCONN288_H44441004_PIP-SCONN,HA     I1 @BASEBOARD_FAB2_LIB.BASEBOARD_FAB2(SCH_1):PAGE43

M_A_CLK_DP<1> @BASEBOARD_FAB2_LIB.BASEBOARD_FAB2(SCH_1):M_A_CLK_DP(1)
  U5D1  B55 DDR0_CLK_DP<1> SKX_EXT_B_BGA1-IC,TBD   I172 @BASEBOARD_FAB2_LIB.BASEBOARD_FAB2(SCH_1):PAGE23
  J4G1  218   CK1P SCONN288_H44441004_PIP-SCONN,HA     I1 @BASEBOARD_FAB2_LIB.BASEBOARD_FAB2(SCH_1):PAGE43

M_A_CLK_DP<2> @BASEBOARD_FAB2_LIB.BASEBOARD_FAB2(SCH_1):M_A_CLK_DP(2)
  U5D1  G56 DDR0_CLK_DP<2> SKX_EXT_B_BGA1-IC,TBD   I172 @BASEBOARD_FAB2_LIB.BASEBOARD_FAB2(SCH_1):PAGE23
  J6T1   74   CK0P SCONN288_H44441003_PIP-SCONN,HA    I13 @BASEBOARD_FAB2_LIB.BASEBOARD_FAB2(SCH_1):PAGE44

M_A_CLK_DP<3> @BASEBOARD_FAB2_LIB.BASEBOARD_FAB2(SCH_1):M_A_CLK_DP(3)
  U5D1  B57 DDR0_CLK_DP<3> SKX_EXT_B_BGA1-IC,TBD   I172 @BASEBOARD_FAB2_LIB.BASEBOARD_FAB2(SCH_1):PAGE23
  J6T1  218   CK1P SCONN288_H44441003_PIP-SCONN,HA    I13 @BASEBOARD_FAB2_LIB.BASEBOARD_FAB2(SCH_1):PAGE44

M_A_CPU_VREF @BASEBOARD_FAB2_LIB.BASEBOARD_FAB2(SCH_1):M_A_CPU_VREF
  U5D1 AJ64 DDR0_CAVREF SKX_EXT_B_BGA1-IC,TBD   I259 @BASEBOARD_FAB2_LIB.BASEBOARD_FAB2(SCH_1):PAGE21
  R4F3    1      A RES_0402-2,1.0%,1/16W,CHIP,G21A     I5 @BASEBOARD_FAB2_LIB.BASEBOARD_FAB2(SCH_1):PAGE98
  C4F9    1      A CAP_A_0402V-0.01UF,25V,10%,X7RA     I7 @BASEBOARD_FAB2_LIB.BASEBOARD_FAB2(SCH_1):PAGE98

M_A_CS_N<0> @BASEBOARD_FAB2_LIB.BASEBOARD_FAB2(SCH_1):M_A_CS_N(0)
  U5D1  G52 DDR0_CS_N<0> SKX_EXT_B_BGA1-IC,TBD   I172 @BASEBOARD_FAB2_LIB.BASEBOARD_FAB2(SCH_1):PAGE23
  J4G1   84   S0_N SCONN288_H44441004_PIP-SCONN,HA     I1 @BASEBOARD_FAB2_LIB.BASEBOARD_FAB2(SCH_1):PAGE43

M_A_CS_N<1> @BASEBOARD_FAB2_LIB.BASEBOARD_FAB2(SCH_1):M_A_CS_N(1)
  U5D1  F49 DDR0_CS_N<1> SKX_EXT_B_BGA1-IC,TBD   I172 @BASEBOARD_FAB2_LIB.BASEBOARD_FAB2(SCH_1):PAGE23
  J4G1   89   S1_N SCONN288_H44441004_PIP-SCONN,HA     I1 @BASEBOARD_FAB2_LIB.BASEBOARD_FAB2(SCH_1):PAGE43

M_A_CS_N<2> @BASEBOARD_FAB2_LIB.BASEBOARD_FAB2(SCH_1):M_A_CS_N(2)
  U5D1  D47 DDR0_CS_N<2> SKX_EXT_B_BGA1-IC,TBD   I172 @BASEBOARD_FAB2_LIB.BASEBOARD_FAB2(SCH_1):PAGE23
  J4G1   93 S2_N_C<0> SCONN288_H44441004_PIP-SCONN,HA     I1 @BASEBOARD_FAB2_LIB.BASEBOARD_FAB2(SCH_1):PAGE43

M_A_CS_N<3> @BASEBOARD_FAB2_LIB.BASEBOARD_FAB2(SCH_1):M_A_CS_N(3)
  U5D1  F47 DDR0_CS_N<3> SKX_EXT_B_BGA1-IC,TBD   I172 @BASEBOARD_FAB2_LIB.BASEBOARD_FAB2(SCH_1):PAGE23
  J4G1  237 S3_N_C<1> SCONN288_H44441004_PIP-SCONN,HA     I1 @BASEBOARD_FAB2_LIB.BASEBOARD_FAB2(SCH_1):PAGE43

M_A_CS_N<4> @BASEBOARD_FAB2_LIB.BASEBOARD_FAB2(SCH_1):M_A_CS_N(4)
  U5D1  B51 DDR0_CS_N<4> SKX_EXT_B_BGA1-IC,TBD   I172 @BASEBOARD_FAB2_LIB.BASEBOARD_FAB2(SCH_1):PAGE23
  J6T1   84   S0_N SCONN288_H44441003_PIP-SCONN,HA    I13 @BASEBOARD_FAB2_LIB.BASEBOARD_FAB2(SCH_1):PAGE44

M_A_CS_N<5> @BASEBOARD_FAB2_LIB.BASEBOARD_FAB2(SCH_1):M_A_CS_N(5)
  U5D1  D49 DDR0_CS_N<5> SKX_EXT_B_BGA1-IC,TBD   I172 @BASEBOARD_FAB2_LIB.BASEBOARD_FAB2(SCH_1):PAGE23
  J6T1   89   S1_N SCONN288_H44441003_PIP-SCONN,HA    I13 @BASEBOARD_FAB2_LIB.BASEBOARD_FAB2(SCH_1):PAGE44

M_A_CS_N<6> @BASEBOARD_FAB2_LIB.BASEBOARD_FAB2(SCH_1):M_A_CS_N(6)
  U5D1  F45 DDR0_CS_N<6> SKX_EXT_B_BGA1-IC,TBD   I172 @BASEBOARD_FAB2_LIB.BASEBOARD_FAB2(SCH_1):PAGE23
  J6T1   93 S2_N_C<0> SCONN288_H44441003_PIP-SCONN,HA    I13 @BASEBOARD_FAB2_LIB.BASEBOARD_FAB2(SCH_1):PAGE44

M_A_CS_N<7> @BASEBOARD_FAB2_LIB.BASEBOARD_FAB2(SCH_1):M_A_CS_N(7)
  U5D1  K45 DDR0_CS_N<7> SKX_EXT_B_BGA1-IC,TBD   I172 @BASEBOARD_FAB2_LIB.BASEBOARD_FAB2(SCH_1):PAGE23
  J6T1  237 S3_N_C<1> SCONN288_H44441003_PIP-SCONN,HA    I13 @BASEBOARD_FAB2_LIB.BASEBOARD_FAB2(SCH_1):PAGE44

M_A_DQ<0> @BASEBOARD_FAB2_LIB.BASEBOARD_FAB2(SCH_1):M_A_DQ(0)
  U5D1 AN86 DDR0_DQ<0> SKX_EXT_B_BGA1-IC,TBD   I172 @BASEBOARD_FAB2_LIB.BASEBOARD_FAB2(SCH_1):PAGE23
  J4G1  150  DQ<1> SCONN288_H44441004_PIP-SCONN,HA     I1 @BASEBOARD_FAB2_LIB.BASEBOARD_FAB2(SCH_1):PAGE43
  J6T1    5  DQ<0> SCONN288_H44441003_PIP-SCONN,HA    I13 @BASEBOARD_FAB2_LIB.BASEBOARD_FAB2(SCH_1):PAGE44

M_A_DQ<10> @BASEBOARD_FAB2_LIB.BASEBOARD_FAB2(SCH_1):M_A_DQ(10)
  U5D1  L86 DDR0_DQ<10> SKX_EXT_B_BGA1-IC,TBD   I172 @BASEBOARD_FAB2_LIB.BASEBOARD_FAB2(SCH_1):PAGE23
  J4G1  168 DQ<11> SCONN288_H44441004_PIP-SCONN,HA     I1 @BASEBOARD_FAB2_LIB.BASEBOARD_FAB2(SCH_1):PAGE43
  J6T1   23 DQ<10> SCONN288_H44441003_PIP-SCONN,HA    I13 @BASEBOARD_FAB2_LIB.BASEBOARD_FAB2(SCH_1):PAGE44

M_A_DQ<11> @BASEBOARD_FAB2_LIB.BASEBOARD_FAB2(SCH_1):M_A_DQ(11)
  U5D1  L84 DDR0_DQ<11> SKX_EXT_B_BGA1-IC,TBD   I172 @BASEBOARD_FAB2_LIB.BASEBOARD_FAB2(SCH_1):PAGE23
  J4G1   23 DQ<10> SCONN288_H44441004_PIP-SCONN,HA     I1 @BASEBOARD_FAB2_LIB.BASEBOARD_FAB2(SCH_1):PAGE43
  J6T1  168 DQ<11> SCONN288_H44441003_PIP-SCONN,HA    I13 @BASEBOARD_FAB2_LIB.BASEBOARD_FAB2(SCH_1):PAGE44

M_A_DQ<12> @BASEBOARD_FAB2_LIB.BASEBOARD_FAB2(SCH_1):M_A_DQ(12)
  U5D1 AA86 DDR0_DQ<12> SKX_EXT_B_BGA1-IC,TBD   I172 @BASEBOARD_FAB2_LIB.BASEBOARD_FAB2(SCH_1):PAGE23
  J4G1  159 DQ<13> SCONN288_H44441004_PIP-SCONN,HA     I1 @BASEBOARD_FAB2_LIB.BASEBOARD_FAB2(SCH_1):PAGE43
  J6T1   14 DQ<12> SCONN288_H44441003_PIP-SCONN,HA    I13 @BASEBOARD_FAB2_LIB.BASEBOARD_FAB2(SCH_1):PAGE44

M_A_DQ<13> @BASEBOARD_FAB2_LIB.BASEBOARD_FAB2(SCH_1):M_A_DQ(13)
  U5D1 AA84 DDR0_DQ<13> SKX_EXT_B_BGA1-IC,TBD   I172 @BASEBOARD_FAB2_LIB.BASEBOARD_FAB2(SCH_1):PAGE23
  J4G1   14 DQ<12> SCONN288_H44441004_PIP-SCONN,HA     I1 @BASEBOARD_FAB2_LIB.BASEBOARD_FAB2(SCH_1):PAGE43
  J6T1  159 DQ<13> SCONN288_H44441003_PIP-SCONN,HA    I13 @BASEBOARD_FAB2_LIB.BASEBOARD_FAB2(SCH_1):PAGE44

M_A_DQ<14> @BASEBOARD_FAB2_LIB.BASEBOARD_FAB2(SCH_1):M_A_DQ(14)
  U5D1  N86 DDR0_DQ<14> SKX_EXT_B_BGA1-IC,TBD   I172 @BASEBOARD_FAB2_LIB.BASEBOARD_FAB2(SCH_1):PAGE23
  J4G1  166 DQ<15> SCONN288_H44441004_PIP-SCONN,HA     I1 @BASEBOARD_FAB2_LIB.BASEBOARD_FAB2(SCH_1):PAGE43
  J6T1   21 DQ<14> SCONN288_H44441003_PIP-SCONN,HA    I13 @BASEBOARD_FAB2_LIB.BASEBOARD_FAB2(SCH_1):PAGE44

M_A_DQ<15> @BASEBOARD_FAB2_LIB.BASEBOARD_FAB2(SCH_1):M_A_DQ(15)
  U5D1  N84 DDR0_DQ<15> SKX_EXT_B_BGA1-IC,TBD   I172 @BASEBOARD_FAB2_LIB.BASEBOARD_FAB2(SCH_1):PAGE23
  J4G1   21 DQ<14> SCONN288_H44441004_PIP-SCONN,HA     I1 @BASEBOARD_FAB2_LIB.BASEBOARD_FAB2(SCH_1):PAGE43
  J6T1  166 DQ<15> SCONN288_H44441003_PIP-SCONN,HA    I13 @BASEBOARD_FAB2_LIB.BASEBOARD_FAB2(SCH_1):PAGE44

M_A_DQ<16> @BASEBOARD_FAB2_LIB.BASEBOARD_FAB2(SCH_1):M_A_DQ(16)
  U5D1  V81 DDR0_DQ<16> SKX_EXT_B_BGA1-IC,TBD   I172 @BASEBOARD_FAB2_LIB.BASEBOARD_FAB2(SCH_1):PAGE23
  J4G1  172 DQ<17> SCONN288_H44441004_PIP-SCONN,HA     I1 @BASEBOARD_FAB2_LIB.BASEBOARD_FAB2(SCH_1):PAGE43
  J6T1   27 DQ<16> SCONN288_H44441003_PIP-SCONN,HA    I13 @BASEBOARD_FAB2_LIB.BASEBOARD_FAB2(SCH_1):PAGE44

M_A_DQ<17> @BASEBOARD_FAB2_LIB.BASEBOARD_FAB2(SCH_1):M_A_DQ(17)
  U5D1  T79 DDR0_DQ<17> SKX_EXT_B_BGA1-IC,TBD   I172 @BASEBOARD_FAB2_LIB.BASEBOARD_FAB2(SCH_1):PAGE23
  J4G1   27 DQ<16> SCONN288_H44441004_PIP-SCONN,HA     I1 @BASEBOARD_FAB2_LIB.BASEBOARD_FAB2(SCH_1):PAGE43
  J6T1  172 DQ<17> SCONN288_H44441003_PIP-SCONN,HA    I13 @BASEBOARD_FAB2_LIB.BASEBOARD_FAB2(SCH_1):PAGE44

M_A_DQ<18> @BASEBOARD_FAB2_LIB.BASEBOARD_FAB2(SCH_1):M_A_DQ(18)
  U5D1  N82 DDR0_DQ<18> SKX_EXT_B_BGA1-IC,TBD   I172 @BASEBOARD_FAB2_LIB.BASEBOARD_FAB2(SCH_1):PAGE23
  J4G1  179 DQ<19> SCONN288_H44441004_PIP-SCONN,HA     I1 @BASEBOARD_FAB2_LIB.BASEBOARD_FAB2(SCH_1):PAGE43
  J6T1   34 DQ<18> SCONN288_H44441003_PIP-SCONN,HA    I13 @BASEBOARD_FAB2_LIB.BASEBOARD_FAB2(SCH_1):PAGE44

M_A_DQ<19> @BASEBOARD_FAB2_LIB.BASEBOARD_FAB2(SCH_1):M_A_DQ(19)
  U5D1  M81 DDR0_DQ<19> SKX_EXT_B_BGA1-IC,TBD   I172 @BASEBOARD_FAB2_LIB.BASEBOARD_FAB2(SCH_1):PAGE23
  J4G1   34 DQ<18> SCONN288_H44441004_PIP-SCONN,HA     I1 @BASEBOARD_FAB2_LIB.BASEBOARD_FAB2(SCH_1):PAGE43
  J6T1  179 DQ<19> SCONN288_H44441003_PIP-SCONN,HA    I13 @BASEBOARD_FAB2_LIB.BASEBOARD_FAB2(SCH_1):PAGE44

M_A_DQ<1> @BASEBOARD_FAB2_LIB.BASEBOARD_FAB2(SCH_1):M_A_DQ(1)
  U5D1 AN84 DDR0_DQ<1> SKX_EXT_B_BGA1-IC,TBD   I172 @BASEBOARD_FAB2_LIB.BASEBOARD_FAB2(SCH_1):PAGE23
  J4G1    5  DQ<0> SCONN288_H44441004_PIP-SCONN,HA     I1 @BASEBOARD_FAB2_LIB.BASEBOARD_FAB2(SCH_1):PAGE43
  J6T1  150  DQ<1> SCONN288_H44441003_PIP-SCONN,HA    I13 @BASEBOARD_FAB2_LIB.BASEBOARD_FAB2(SCH_1):PAGE44

M_A_DQ<20> @BASEBOARD_FAB2_LIB.BASEBOARD_FAB2(SCH_1):M_A_DQ(20)
  U5D1  W80 DDR0_DQ<20> SKX_EXT_B_BGA1-IC,TBD   I172 @BASEBOARD_FAB2_LIB.BASEBOARD_FAB2(SCH_1):PAGE23
  J4G1  170 DQ<21> SCONN288_H44441004_PIP-SCONN,HA     I1 @BASEBOARD_FAB2_LIB.BASEBOARD_FAB2(SCH_1):PAGE43
  J6T1   25 DQ<20> SCONN288_H44441003_PIP-SCONN,HA    I13 @BASEBOARD_FAB2_LIB.BASEBOARD_FAB2(SCH_1):PAGE44

M_A_DQ<21> @BASEBOARD_FAB2_LIB.BASEBOARD_FAB2(SCH_1):M_A_DQ(21)
  U5D1  V79 DDR0_DQ<21> SKX_EXT_B_BGA1-IC,TBD   I172 @BASEBOARD_FAB2_LIB.BASEBOARD_FAB2(SCH_1):PAGE23
  J4G1   25 DQ<20> SCONN288_H44441004_PIP-SCONN,HA     I1 @BASEBOARD_FAB2_LIB.BASEBOARD_FAB2(SCH_1):PAGE43
  J6T1  170 DQ<21> SCONN288_H44441003_PIP-SCONN,HA    I13 @BASEBOARD_FAB2_LIB.BASEBOARD_FAB2(SCH_1):PAGE44

M_A_DQ<22> @BASEBOARD_FAB2_LIB.BASEBOARD_FAB2(SCH_1):M_A_DQ(22)
  U5D1  R82 DDR0_DQ<22> SKX_EXT_B_BGA1-IC,TBD   I172 @BASEBOARD_FAB2_LIB.BASEBOARD_FAB2(SCH_1):PAGE23
  J4G1  177 DQ<23> SCONN288_H44441004_PIP-SCONN,HA     I1 @BASEBOARD_FAB2_LIB.BASEBOARD_FAB2(SCH_1):PAGE43
  J6T1   32 DQ<22> SCONN288_H44441003_PIP-SCONN,HA    I13 @BASEBOARD_FAB2_LIB.BASEBOARD_FAB2(SCH_1):PAGE44

M_A_DQ<23> @BASEBOARD_FAB2_LIB.BASEBOARD_FAB2(SCH_1):M_A_DQ(23)
  U5D1  N80 DDR0_DQ<23> SKX_EXT_B_BGA1-IC,TBD   I172 @BASEBOARD_FAB2_LIB.BASEBOARD_FAB2(SCH_1):PAGE23
  J4G1   32 DQ<22> SCONN288_H44441004_PIP-SCONN,HA     I1 @BASEBOARD_FAB2_LIB.BASEBOARD_FAB2(SCH_1):PAGE43
  J6T1  177 DQ<23> SCONN288_H44441003_PIP-SCONN,HA    I13 @BASEBOARD_FAB2_LIB.BASEBOARD_FAB2(SCH_1):PAGE44

M_A_DQ<24> @BASEBOARD_FAB2_LIB.BASEBOARD_FAB2(SCH_1):M_A_DQ(24)
  U5D1  L76 DDR0_DQ<24> SKX_EXT_B_BGA1-IC,TBD   I172 @BASEBOARD_FAB2_LIB.BASEBOARD_FAB2(SCH_1):PAGE23
  J4G1  183 DQ<25> SCONN288_H44441004_PIP-SCONN,HA     I1 @BASEBOARD_FAB2_LIB.BASEBOARD_FAB2(SCH_1):PAGE43
  J6T1   38 DQ<24> SCONN288_H44441003_PIP-SCONN,HA    I13 @BASEBOARD_FAB2_LIB.BASEBOARD_FAB2(SCH_1):PAGE44

M_A_DQ<25> @BASEBOARD_FAB2_LIB.BASEBOARD_FAB2(SCH_1):M_A_DQ(25)
  U5D1  R76 DDR0_DQ<25> SKX_EXT_B_BGA1-IC,TBD   I172 @BASEBOARD_FAB2_LIB.BASEBOARD_FAB2(SCH_1):PAGE23
  J4G1   38 DQ<24> SCONN288_H44441004_PIP-SCONN,HA     I1 @BASEBOARD_FAB2_LIB.BASEBOARD_FAB2(SCH_1):PAGE43
  J6T1  183 DQ<25> SCONN288_H44441003_PIP-SCONN,HA    I13 @BASEBOARD_FAB2_LIB.BASEBOARD_FAB2(SCH_1):PAGE44

M_A_DQ<26> @BASEBOARD_FAB2_LIB.BASEBOARD_FAB2(SCH_1):M_A_DQ(26)
  U5D1  M73 DDR0_DQ<26> SKX_EXT_B_BGA1-IC,TBD   I172 @BASEBOARD_FAB2_LIB.BASEBOARD_FAB2(SCH_1):PAGE23
  J4G1  190 DQ<27> SCONN288_H44441004_PIP-SCONN,HA     I1 @BASEBOARD_FAB2_LIB.BASEBOARD_FAB2(SCH_1):PAGE43
  J6T1   45 DQ<26> SCONN288_H44441003_PIP-SCONN,HA    I13 @BASEBOARD_FAB2_LIB.BASEBOARD_FAB2(SCH_1):PAGE44

M_A_DQ<27> @BASEBOARD_FAB2_LIB.BASEBOARD_FAB2(SCH_1):M_A_DQ(27)
  U5D1  P73 DDR0_DQ<27> SKX_EXT_B_BGA1-IC,TBD   I172 @BASEBOARD_FAB2_LIB.BASEBOARD_FAB2(SCH_1):PAGE23
  J4G1   45 DQ<26> SCONN288_H44441004_PIP-SCONN,HA     I1 @BASEBOARD_FAB2_LIB.BASEBOARD_FAB2(SCH_1):PAGE43
  J6T1  190 DQ<27> SCONN288_H44441003_PIP-SCONN,HA    I13 @BASEBOARD_FAB2_LIB.BASEBOARD_FAB2(SCH_1):PAGE44

M_A_DQ<28> @BASEBOARD_FAB2_LIB.BASEBOARD_FAB2(SCH_1):M_A_DQ(28)
  U5D1  M77 DDR0_DQ<28> SKX_EXT_B_BGA1-IC,TBD   I172 @BASEBOARD_FAB2_LIB.BASEBOARD_FAB2(SCH_1):PAGE23
  J4G1  181 DQ<29> SCONN288_H44441004_PIP-SCONN,HA     I1 @BASEBOARD_FAB2_LIB.BASEBOARD_FAB2(SCH_1):PAGE43
  J6T1   36 DQ<28> SCONN288_H44441003_PIP-SCONN,HA    I13 @BASEBOARD_FAB2_LIB.BASEBOARD_FAB2(SCH_1):PAGE44

M_A_DQ<29> @BASEBOARD_FAB2_LIB.BASEBOARD_FAB2(SCH_1):M_A_DQ(29)
  U5D1  P77 DDR0_DQ<29> SKX_EXT_B_BGA1-IC,TBD   I172 @BASEBOARD_FAB2_LIB.BASEBOARD_FAB2(SCH_1):PAGE23
  J4G1   36 DQ<28> SCONN288_H44441004_PIP-SCONN,HA     I1 @BASEBOARD_FAB2_LIB.BASEBOARD_FAB2(SCH_1):PAGE43
  J6T1  181 DQ<29> SCONN288_H44441003_PIP-SCONN,HA    I13 @BASEBOARD_FAB2_LIB.BASEBOARD_FAB2(SCH_1):PAGE44

M_A_DQ<2> @BASEBOARD_FAB2_LIB.BASEBOARD_FAB2(SCH_1):M_A_DQ(2)
  U5D1 AE86 DDR0_DQ<2> SKX_EXT_B_BGA1-IC,TBD   I172 @BASEBOARD_FAB2_LIB.BASEBOARD_FAB2(SCH_1):PAGE23
  J4G1  157  DQ<3> SCONN288_H44441004_PIP-SCONN,HA     I1 @BASEBOARD_FAB2_LIB.BASEBOARD_FAB2(SCH_1):PAGE43
  J6T1   12  DQ<2> SCONN288_H44441003_PIP-SCONN,HA    I13 @BASEBOARD_FAB2_LIB.BASEBOARD_FAB2(SCH_1):PAGE44

M_A_DQ<30> @BASEBOARD_FAB2_LIB.BASEBOARD_FAB2(SCH_1):M_A_DQ(30)
  U5D1  L74 DDR0_DQ<30> SKX_EXT_B_BGA1-IC,TBD   I172 @BASEBOARD_FAB2_LIB.BASEBOARD_FAB2(SCH_1):PAGE23
  J4G1  188 DQ<31> SCONN288_H44441004_PIP-SCONN,HA     I1 @BASEBOARD_FAB2_LIB.BASEBOARD_FAB2(SCH_1):PAGE43
  J6T1   43 DQ<30> SCONN288_H44441003_PIP-SCONN,HA    I13 @BASEBOARD_FAB2_LIB.BASEBOARD_FAB2(SCH_1):PAGE44

M_A_DQ<31> @BASEBOARD_FAB2_LIB.BASEBOARD_FAB2(SCH_1):M_A_DQ(31)
  U5D1  R74 DDR0_DQ<31> SKX_EXT_B_BGA1-IC,TBD   I172 @BASEBOARD_FAB2_LIB.BASEBOARD_FAB2(SCH_1):PAGE23
  J4G1   43 DQ<30> SCONN288_H44441004_PIP-SCONN,HA     I1 @BASEBOARD_FAB2_LIB.BASEBOARD_FAB2(SCH_1):PAGE43
  J6T1  188 DQ<31> SCONN288_H44441003_PIP-SCONN,HA    I13 @BASEBOARD_FAB2_LIB.BASEBOARD_FAB2(SCH_1):PAGE44

M_A_DQ<32> @BASEBOARD_FAB2_LIB.BASEBOARD_FAB2(SCH_1):M_A_DQ(32)
  U5D1  C42 DDR0_DQ<32> SKX_EXT_B_BGA1-IC,TBD   I172 @BASEBOARD_FAB2_LIB.BASEBOARD_FAB2(SCH_1):PAGE23
  J4G1  242 DQ<33> SCONN288_H44441004_PIP-SCONN,HA     I1 @BASEBOARD_FAB2_LIB.BASEBOARD_FAB2(SCH_1):PAGE43
  J6T1   97 DQ<32> SCONN288_H44441003_PIP-SCONN,HA    I13 @BASEBOARD_FAB2_LIB.BASEBOARD_FAB2(SCH_1):PAGE44

M_A_DQ<33> @BASEBOARD_FAB2_LIB.BASEBOARD_FAB2(SCH_1):M_A_DQ(33)
  U5D1  B41 DDR0_DQ<33> SKX_EXT_B_BGA1-IC,TBD   I172 @BASEBOARD_FAB2_LIB.BASEBOARD_FAB2(SCH_1):PAGE23
  J4G1   97 DQ<32> SCONN288_H44441004_PIP-SCONN,HA     I1 @BASEBOARD_FAB2_LIB.BASEBOARD_FAB2(SCH_1):PAGE43
  J6T1  242 DQ<33> SCONN288_H44441003_PIP-SCONN,HA    I13 @BASEBOARD_FAB2_LIB.BASEBOARD_FAB2(SCH_1):PAGE44

M_A_DQ<34> @BASEBOARD_FAB2_LIB.BASEBOARD_FAB2(SCH_1):M_A_DQ(34)
  U5D1  C38 DDR0_DQ<34> SKX_EXT_B_BGA1-IC,TBD   I172 @BASEBOARD_FAB2_LIB.BASEBOARD_FAB2(SCH_1):PAGE23
  J4G1  249 DQ<35> SCONN288_H44441004_PIP-SCONN,HA     I1 @BASEBOARD_FAB2_LIB.BASEBOARD_FAB2(SCH_1):PAGE43
  J6T1  104 DQ<34> SCONN288_H44441003_PIP-SCONN,HA    I13 @BASEBOARD_FAB2_LIB.BASEBOARD_FAB2(SCH_1):PAGE44

M_A_DQ<35> @BASEBOARD_FAB2_LIB.BASEBOARD_FAB2(SCH_1):M_A_DQ(35)
  U5D1  E38 DDR0_DQ<35> SKX_EXT_B_BGA1-IC,TBD   I172 @BASEBOARD_FAB2_LIB.BASEBOARD_FAB2(SCH_1):PAGE23
  J4G1  104 DQ<34> SCONN288_H44441004_PIP-SCONN,HA     I1 @BASEBOARD_FAB2_LIB.BASEBOARD_FAB2(SCH_1):PAGE43
  J6T1  249 DQ<35> SCONN288_H44441003_PIP-SCONN,HA    I13 @BASEBOARD_FAB2_LIB.BASEBOARD_FAB2(SCH_1):PAGE44

M_A_DQ<36> @BASEBOARD_FAB2_LIB.BASEBOARD_FAB2(SCH_1):M_A_DQ(36)
  U5D1  E42 DDR0_DQ<36> SKX_EXT_B_BGA1-IC,TBD   I172 @BASEBOARD_FAB2_LIB.BASEBOARD_FAB2(SCH_1):PAGE23
  J4G1  240 DQ<37> SCONN288_H44441004_PIP-SCONN,HA     I1 @BASEBOARD_FAB2_LIB.BASEBOARD_FAB2(SCH_1):PAGE43
  J6T1   95 DQ<36> SCONN288_H44441003_PIP-SCONN,HA    I13 @BASEBOARD_FAB2_LIB.BASEBOARD_FAB2(SCH_1):PAGE44

M_A_DQ<37> @BASEBOARD_FAB2_LIB.BASEBOARD_FAB2(SCH_1):M_A_DQ(37)
  U5D1  F41 DDR0_DQ<37> SKX_EXT_B_BGA1-IC,TBD   I172 @BASEBOARD_FAB2_LIB.BASEBOARD_FAB2(SCH_1):PAGE23
  J4G1   95 DQ<36> SCONN288_H44441004_PIP-SCONN,HA     I1 @BASEBOARD_FAB2_LIB.BASEBOARD_FAB2(SCH_1):PAGE43
  J6T1  240 DQ<37> SCONN288_H44441003_PIP-SCONN,HA    I13 @BASEBOARD_FAB2_LIB.BASEBOARD_FAB2(SCH_1):PAGE44

M_A_DQ<38> @BASEBOARD_FAB2_LIB.BASEBOARD_FAB2(SCH_1):M_A_DQ(38)
  U5D1  B39 DDR0_DQ<38> SKX_EXT_B_BGA1-IC,TBD   I172 @BASEBOARD_FAB2_LIB.BASEBOARD_FAB2(SCH_1):PAGE23
  J4G1  247 DQ<39> SCONN288_H44441004_PIP-SCONN,HA     I1 @BASEBOARD_FAB2_LIB.BASEBOARD_FAB2(SCH_1):PAGE43
  J6T1  102 DQ<38> SCONN288_H44441003_PIP-SCONN,HA    I13 @BASEBOARD_FAB2_LIB.BASEBOARD_FAB2(SCH_1):PAGE44

M_A_DQ<39> @BASEBOARD_FAB2_LIB.BASEBOARD_FAB2(SCH_1):M_A_DQ(39)
  U5D1  F39 DDR0_DQ<39> SKX_EXT_B_BGA1-IC,TBD   I172 @BASEBOARD_FAB2_LIB.BASEBOARD_FAB2(SCH_1):PAGE23
  J4G1  102 DQ<38> SCONN288_H44441004_PIP-SCONN,HA     I1 @BASEBOARD_FAB2_LIB.BASEBOARD_FAB2(SCH_1):PAGE43
  J6T1  247 DQ<39> SCONN288_H44441003_PIP-SCONN,HA    I13 @BASEBOARD_FAB2_LIB.BASEBOARD_FAB2(SCH_1):PAGE44

M_A_DQ<3> @BASEBOARD_FAB2_LIB.BASEBOARD_FAB2(SCH_1):M_A_DQ(3)
  U5D1 AE84 DDR0_DQ<3> SKX_EXT_B_BGA1-IC,TBD   I172 @BASEBOARD_FAB2_LIB.BASEBOARD_FAB2(SCH_1):PAGE23
  J4G1   12  DQ<2> SCONN288_H44441004_PIP-SCONN,HA     I1 @BASEBOARD_FAB2_LIB.BASEBOARD_FAB2(SCH_1):PAGE43
  J6T1  157  DQ<3> SCONN288_H44441003_PIP-SCONN,HA    I13 @BASEBOARD_FAB2_LIB.BASEBOARD_FAB2(SCH_1):PAGE44

M_A_DQ<40> @BASEBOARD_FAB2_LIB.BASEBOARD_FAB2(SCH_1):M_A_DQ(40)
  U5D1  K37 DDR0_DQ<40> SKX_EXT_B_BGA1-IC,TBD   I172 @BASEBOARD_FAB2_LIB.BASEBOARD_FAB2(SCH_1):PAGE23
  J4G1  253 DQ<41> SCONN288_H44441004_PIP-SCONN,HA     I1 @BASEBOARD_FAB2_LIB.BASEBOARD_FAB2(SCH_1):PAGE43
  J6T1  108 DQ<40> SCONN288_H44441003_PIP-SCONN,HA    I13 @BASEBOARD_FAB2_LIB.BASEBOARD_FAB2(SCH_1):PAGE44

M_A_DQ<41> @BASEBOARD_FAB2_LIB.BASEBOARD_FAB2(SCH_1):M_A_DQ(41)
  U5D1  P37 DDR0_DQ<41> SKX_EXT_B_BGA1-IC,TBD   I172 @BASEBOARD_FAB2_LIB.BASEBOARD_FAB2(SCH_1):PAGE23
  J4G1  108 DQ<40> SCONN288_H44441004_PIP-SCONN,HA     I1 @BASEBOARD_FAB2_LIB.BASEBOARD_FAB2(SCH_1):PAGE43
  J6T1  253 DQ<41> SCONN288_H44441003_PIP-SCONN,HA    I13 @BASEBOARD_FAB2_LIB.BASEBOARD_FAB2(SCH_1):PAGE44

M_A_DQ<42> @BASEBOARD_FAB2_LIB.BASEBOARD_FAB2(SCH_1):M_A_DQ(42)
  U5D1  L34 DDR0_DQ<42> SKX_EXT_B_BGA1-IC,TBD   I172 @BASEBOARD_FAB2_LIB.BASEBOARD_FAB2(SCH_1):PAGE23
  J4G1  260 DQ<43> SCONN288_H44441004_PIP-SCONN,HA     I1 @BASEBOARD_FAB2_LIB.BASEBOARD_FAB2(SCH_1):PAGE43
  J6T1  115 DQ<42> SCONN288_H44441003_PIP-SCONN,HA    I13 @BASEBOARD_FAB2_LIB.BASEBOARD_FAB2(SCH_1):PAGE44

M_A_DQ<43> @BASEBOARD_FAB2_LIB.BASEBOARD_FAB2(SCH_1):M_A_DQ(43)
  U5D1  N34 DDR0_DQ<43> SKX_EXT_B_BGA1-IC,TBD   I172 @BASEBOARD_FAB2_LIB.BASEBOARD_FAB2(SCH_1):PAGE23
  J4G1  115 DQ<42> SCONN288_H44441004_PIP-SCONN,HA     I1 @BASEBOARD_FAB2_LIB.BASEBOARD_FAB2(SCH_1):PAGE43
  J6T1  260 DQ<43> SCONN288_H44441003_PIP-SCONN,HA    I13 @BASEBOARD_FAB2_LIB.BASEBOARD_FAB2(SCH_1):PAGE44

M_A_DQ<44> @BASEBOARD_FAB2_LIB.BASEBOARD_FAB2(SCH_1):M_A_DQ(44)
  U5D1  L38 DDR0_DQ<44> SKX_EXT_B_BGA1-IC,TBD   I172 @BASEBOARD_FAB2_LIB.BASEBOARD_FAB2(SCH_1):PAGE23
  J4G1  251 DQ<45> SCONN288_H44441004_PIP-SCONN,HA     I1 @BASEBOARD_FAB2_LIB.BASEBOARD_FAB2(SCH_1):PAGE43
  J6T1  106 DQ<44> SCONN288_H44441003_PIP-SCONN,HA    I13 @BASEBOARD_FAB2_LIB.BASEBOARD_FAB2(SCH_1):PAGE44

M_A_DQ<45> @BASEBOARD_FAB2_LIB.BASEBOARD_FAB2(SCH_1):M_A_DQ(45)
  U5D1  N38 DDR0_DQ<45> SKX_EXT_B_BGA1-IC,TBD   I172 @BASEBOARD_FAB2_LIB.BASEBOARD_FAB2(SCH_1):PAGE23
  J4G1  106 DQ<44> SCONN288_H44441004_PIP-SCONN,HA     I1 @BASEBOARD_FAB2_LIB.BASEBOARD_FAB2(SCH_1):PAGE43
  J6T1  251 DQ<45> SCONN288_H44441003_PIP-SCONN,HA    I13 @BASEBOARD_FAB2_LIB.BASEBOARD_FAB2(SCH_1):PAGE44

M_A_DQ<46> @BASEBOARD_FAB2_LIB.BASEBOARD_FAB2(SCH_1):M_A_DQ(46)
  U5D1  K35 DDR0_DQ<46> SKX_EXT_B_BGA1-IC,TBD   I172 @BASEBOARD_FAB2_LIB.BASEBOARD_FAB2(SCH_1):PAGE23
  J4G1  258 DQ<47> SCONN288_H44441004_PIP-SCONN,HA     I1 @BASEBOARD_FAB2_LIB.BASEBOARD_FAB2(SCH_1):PAGE43
  J6T1  113 DQ<46> SCONN288_H44441003_PIP-SCONN,HA    I13 @BASEBOARD_FAB2_LIB.BASEBOARD_FAB2(SCH_1):PAGE44

M_A_DQ<47> @BASEBOARD_FAB2_LIB.BASEBOARD_FAB2(SCH_1):M_A_DQ(47)
  U5D1  P35 DDR0_DQ<47> SKX_EXT_B_BGA1-IC,TBD   I172 @BASEBOARD_FAB2_LIB.BASEBOARD_FAB2(SCH_1):PAGE23
  J4G1  113 DQ<46> SCONN288_H44441004_PIP-SCONN,HA     I1 @BASEBOARD_FAB2_LIB.BASEBOARD_FAB2(SCH_1):PAGE43
  J6T1  258 DQ<47> SCONN288_H44441003_PIP-SCONN,HA    I13 @BASEBOARD_FAB2_LIB.BASEBOARD_FAB2(SCH_1):PAGE44

M_A_DQ<48> @BASEBOARD_FAB2_LIB.BASEBOARD_FAB2(SCH_1):M_A_DQ(48)
  U5D1  K31 DDR0_DQ<48> SKX_EXT_B_BGA1-IC,TBD   I172 @BASEBOARD_FAB2_LIB.BASEBOARD_FAB2(SCH_1):PAGE23
  J4G1  264 DQ<49> SCONN288_H44441004_PIP-SCONN,HA     I1 @BASEBOARD_FAB2_LIB.BASEBOARD_FAB2(SCH_1):PAGE43
  J6T1  119 DQ<48> SCONN288_H44441003_PIP-SCONN,HA    I13 @BASEBOARD_FAB2_LIB.BASEBOARD_FAB2(SCH_1):PAGE44

M_A_DQ<49> @BASEBOARD_FAB2_LIB.BASEBOARD_FAB2(SCH_1):M_A_DQ(49)
  U5D1  P31 DDR0_DQ<49> SKX_EXT_B_BGA1-IC,TBD   I172 @BASEBOARD_FAB2_LIB.BASEBOARD_FAB2(SCH_1):PAGE23
  J4G1  119 DQ<48> SCONN288_H44441004_PIP-SCONN,HA     I1 @BASEBOARD_FAB2_LIB.BASEBOARD_FAB2(SCH_1):PAGE43
  J6T1  264 DQ<49> SCONN288_H44441003_PIP-SCONN,HA    I13 @BASEBOARD_FAB2_LIB.BASEBOARD_FAB2(SCH_1):PAGE44

M_A_DQ<4> @BASEBOARD_FAB2_LIB.BASEBOARD_FAB2(SCH_1):M_A_DQ(4)
  U5D1 AR86 DDR0_DQ<4> SKX_EXT_B_BGA1-IC,TBD   I172 @BASEBOARD_FAB2_LIB.BASEBOARD_FAB2(SCH_1):PAGE23
  J4G1  148  DQ<5> SCONN288_H44441004_PIP-SCONN,HA     I1 @BASEBOARD_FAB2_LIB.BASEBOARD_FAB2(SCH_1):PAGE43
  J6T1    3  DQ<4> SCONN288_H44441003_PIP-SCONN,HA    I13 @BASEBOARD_FAB2_LIB.BASEBOARD_FAB2(SCH_1):PAGE44

M_A_DQ<50> @BASEBOARD_FAB2_LIB.BASEBOARD_FAB2(SCH_1):M_A_DQ(50)
  U5D1  L28 DDR0_DQ<50> SKX_EXT_B_BGA1-IC,TBD   I172 @BASEBOARD_FAB2_LIB.BASEBOARD_FAB2(SCH_1):PAGE23
  J4G1  271 DQ<51> SCONN288_H44441004_PIP-SCONN,HA     I1 @BASEBOARD_FAB2_LIB.BASEBOARD_FAB2(SCH_1):PAGE43
  J6T1  126 DQ<50> SCONN288_H44441003_PIP-SCONN,HA    I13 @BASEBOARD_FAB2_LIB.BASEBOARD_FAB2(SCH_1):PAGE44

M_A_DQ<51> @BASEBOARD_FAB2_LIB.BASEBOARD_FAB2(SCH_1):M_A_DQ(51)
  U5D1  N28 DDR0_DQ<51> SKX_EXT_B_BGA1-IC,TBD   I172 @BASEBOARD_FAB2_LIB.BASEBOARD_FAB2(SCH_1):PAGE23
  J4G1  126 DQ<50> SCONN288_H44441004_PIP-SCONN,HA     I1 @BASEBOARD_FAB2_LIB.BASEBOARD_FAB2(SCH_1):PAGE43
  J6T1  271 DQ<51> SCONN288_H44441003_PIP-SCONN,HA    I13 @BASEBOARD_FAB2_LIB.BASEBOARD_FAB2(SCH_1):PAGE44

M_A_DQ<52> @BASEBOARD_FAB2_LIB.BASEBOARD_FAB2(SCH_1):M_A_DQ(52)
  U5D1  L32 DDR0_DQ<52> SKX_EXT_B_BGA1-IC,TBD   I172 @BASEBOARD_FAB2_LIB.BASEBOARD_FAB2(SCH_1):PAGE23
  J4G1  262 DQ<53> SCONN288_H44441004_PIP-SCONN,HA     I1 @BASEBOARD_FAB2_LIB.BASEBOARD_FAB2(SCH_1):PAGE43
  J6T1  117 DQ<52> SCONN288_H44441003_PIP-SCONN,HA    I13 @BASEBOARD_FAB2_LIB.BASEBOARD_FAB2(SCH_1):PAGE44

M_A_DQ<53> @BASEBOARD_FAB2_LIB.BASEBOARD_FAB2(SCH_1):M_A_DQ(53)
  U5D1  N32 DDR0_DQ<53> SKX_EXT_B_BGA1-IC,TBD   I172 @BASEBOARD_FAB2_LIB.BASEBOARD_FAB2(SCH_1):PAGE23
  J4G1  117 DQ<52> SCONN288_H44441004_PIP-SCONN,HA     I1 @BASEBOARD_FAB2_LIB.BASEBOARD_FAB2(SCH_1):PAGE43
  J6T1  262 DQ<53> SCONN288_H44441003_PIP-SCONN,HA    I13 @BASEBOARD_FAB2_LIB.BASEBOARD_FAB2(SCH_1):PAGE44

M_A_DQ<54> @BASEBOARD_FAB2_LIB.BASEBOARD_FAB2(SCH_1):M_A_DQ(54)
  U5D1  K29 DDR0_DQ<54> SKX_EXT_B_BGA1-IC,TBD   I172 @BASEBOARD_FAB2_LIB.BASEBOARD_FAB2(SCH_1):PAGE23
  J4G1  269 DQ<55> SCONN288_H44441004_PIP-SCONN,HA     I1 @BASEBOARD_FAB2_LIB.BASEBOARD_FAB2(SCH_1):PAGE43
  J6T1  124 DQ<54> SCONN288_H44441003_PIP-SCONN,HA    I13 @BASEBOARD_FAB2_LIB.BASEBOARD_FAB2(SCH_1):PAGE44

M_A_DQ<55> @BASEBOARD_FAB2_LIB.BASEBOARD_FAB2(SCH_1):M_A_DQ(55)
  U5D1  P29 DDR0_DQ<55> SKX_EXT_B_BGA1-IC,TBD   I172 @BASEBOARD_FAB2_LIB.BASEBOARD_FAB2(SCH_1):PAGE23
  J4G1  124 DQ<54> SCONN288_H44441004_PIP-SCONN,HA     I1 @BASEBOARD_FAB2_LIB.BASEBOARD_FAB2(SCH_1):PAGE43
  J6T1  269 DQ<55> SCONN288_H44441003_PIP-SCONN,HA    I13 @BASEBOARD_FAB2_LIB.BASEBOARD_FAB2(SCH_1):PAGE44

M_A_DQ<56> @BASEBOARD_FAB2_LIB.BASEBOARD_FAB2(SCH_1):M_A_DQ(56)
  U5D1  K25 DDR0_DQ<56> SKX_EXT_B_BGA1-IC,TBD   I172 @BASEBOARD_FAB2_LIB.BASEBOARD_FAB2(SCH_1):PAGE23
  J4G1  275 DQ<57> SCONN288_H44441004_PIP-SCONN,HA     I1 @BASEBOARD_FAB2_LIB.BASEBOARD_FAB2(SCH_1):PAGE43
  J6T1  130 DQ<56> SCONN288_H44441003_PIP-SCONN,HA    I13 @BASEBOARD_FAB2_LIB.BASEBOARD_FAB2(SCH_1):PAGE44

M_A_DQ<57> @BASEBOARD_FAB2_LIB.BASEBOARD_FAB2(SCH_1):M_A_DQ(57)
  U5D1  P25 DDR0_DQ<57> SKX_EXT_B_BGA1-IC,TBD   I172 @BASEBOARD_FAB2_LIB.BASEBOARD_FAB2(SCH_1):PAGE23
  J4G1  130 DQ<56> SCONN288_H44441004_PIP-SCONN,HA     I1 @BASEBOARD_FAB2_LIB.BASEBOARD_FAB2(SCH_1):PAGE43
  J6T1  275 DQ<57> SCONN288_H44441003_PIP-SCONN,HA    I13 @BASEBOARD_FAB2_LIB.BASEBOARD_FAB2(SCH_1):PAGE44

M_A_DQ<58> @BASEBOARD_FAB2_LIB.BASEBOARD_FAB2(SCH_1):M_A_DQ(58)
  U5D1  P23 DDR0_DQ<58> SKX_EXT_B_BGA1-IC,TBD   I172 @BASEBOARD_FAB2_LIB.BASEBOARD_FAB2(SCH_1):PAGE23
  J4G1  282 DQ<59> SCONN288_H44441004_PIP-SCONN,HA     I1 @BASEBOARD_FAB2_LIB.BASEBOARD_FAB2(SCH_1):PAGE43
  J6T1  137 DQ<58> SCONN288_H44441003_PIP-SCONN,HA    I13 @BASEBOARD_FAB2_LIB.BASEBOARD_FAB2(SCH_1):PAGE44

M_A_DQ<59> @BASEBOARD_FAB2_LIB.BASEBOARD_FAB2(SCH_1):M_A_DQ(59)
  U5D1  T23 DDR0_DQ<59> SKX_EXT_B_BGA1-IC,TBD   I172 @BASEBOARD_FAB2_LIB.BASEBOARD_FAB2(SCH_1):PAGE23
  J4G1  137 DQ<58> SCONN288_H44441004_PIP-SCONN,HA     I1 @BASEBOARD_FAB2_LIB.BASEBOARD_FAB2(SCH_1):PAGE43
  J6T1  282 DQ<59> SCONN288_H44441003_PIP-SCONN,HA    I13 @BASEBOARD_FAB2_LIB.BASEBOARD_FAB2(SCH_1):PAGE44

M_A_DQ<5> @BASEBOARD_FAB2_LIB.BASEBOARD_FAB2(SCH_1):M_A_DQ(5)
  U5D1 AR84 DDR0_DQ<5> SKX_EXT_B_BGA1-IC,TBD   I172 @BASEBOARD_FAB2_LIB.BASEBOARD_FAB2(SCH_1):PAGE23
  J4G1    3  DQ<4> SCONN288_H44441004_PIP-SCONN,HA     I1 @BASEBOARD_FAB2_LIB.BASEBOARD_FAB2(SCH_1):PAGE43
  J6T1  148  DQ<5> SCONN288_H44441003_PIP-SCONN,HA    I13 @BASEBOARD_FAB2_LIB.BASEBOARD_FAB2(SCH_1):PAGE44

M_A_DQ<60> @BASEBOARD_FAB2_LIB.BASEBOARD_FAB2(SCH_1):M_A_DQ(60)
  U5D1  L26 DDR0_DQ<60> SKX_EXT_B_BGA1-IC,TBD   I172 @BASEBOARD_FAB2_LIB.BASEBOARD_FAB2(SCH_1):PAGE23
  J4G1  273 DQ<61> SCONN288_H44441004_PIP-SCONN,HA     I1 @BASEBOARD_FAB2_LIB.BASEBOARD_FAB2(SCH_1):PAGE43
  J6T1  128 DQ<60> SCONN288_H44441003_PIP-SCONN,HA    I13 @BASEBOARD_FAB2_LIB.BASEBOARD_FAB2(SCH_1):PAGE44

M_A_DQ<61> @BASEBOARD_FAB2_LIB.BASEBOARD_FAB2(SCH_1):M_A_DQ(61)
  U5D1  N26 DDR0_DQ<61> SKX_EXT_B_BGA1-IC,TBD   I172 @BASEBOARD_FAB2_LIB.BASEBOARD_FAB2(SCH_1):PAGE23
  J4G1  128 DQ<60> SCONN288_H44441004_PIP-SCONN,HA     I1 @BASEBOARD_FAB2_LIB.BASEBOARD_FAB2(SCH_1):PAGE43
  J6T1  273 DQ<61> SCONN288_H44441003_PIP-SCONN,HA    I13 @BASEBOARD_FAB2_LIB.BASEBOARD_FAB2(SCH_1):PAGE44

M_A_DQ<62> @BASEBOARD_FAB2_LIB.BASEBOARD_FAB2(SCH_1):M_A_DQ(62)
  U5D1  H23 DDR0_DQ<62> SKX_EXT_B_BGA1-IC,TBD   I172 @BASEBOARD_FAB2_LIB.BASEBOARD_FAB2(SCH_1):PAGE23
  J4G1  280 DQ<63> SCONN288_H44441004_PIP-SCONN,HA     I1 @BASEBOARD_FAB2_LIB.BASEBOARD_FAB2(SCH_1):PAGE43
  J6T1  135 DQ<62> SCONN288_H44441003_PIP-SCONN,HA    I13 @BASEBOARD_FAB2_LIB.BASEBOARD_FAB2(SCH_1):PAGE44

M_A_DQ<63> @BASEBOARD_FAB2_LIB.BASEBOARD_FAB2(SCH_1):M_A_DQ(63)
  U5D1  K23 DDR0_DQ<63> SKX_EXT_B_BGA1-IC,TBD   I172 @BASEBOARD_FAB2_LIB.BASEBOARD_FAB2(SCH_1):PAGE23
  J4G1  135 DQ<62> SCONN288_H44441004_PIP-SCONN,HA     I1 @BASEBOARD_FAB2_LIB.BASEBOARD_FAB2(SCH_1):PAGE43
  J6T1  280 DQ<63> SCONN288_H44441003_PIP-SCONN,HA    I13 @BASEBOARD_FAB2_LIB.BASEBOARD_FAB2(SCH_1):PAGE44

M_A_DQ<6> @BASEBOARD_FAB2_LIB.BASEBOARD_FAB2(SCH_1):M_A_DQ(6)
  U5D1 AG86 DDR0_DQ<6> SKX_EXT_B_BGA1-IC,TBD   I172 @BASEBOARD_FAB2_LIB.BASEBOARD_FAB2(SCH_1):PAGE23
  J4G1  155  DQ<7> SCONN288_H44441004_PIP-SCONN,HA     I1 @BASEBOARD_FAB2_LIB.BASEBOARD_FAB2(SCH_1):PAGE43
  J6T1   10  DQ<6> SCONN288_H44441003_PIP-SCONN,HA    I13 @BASEBOARD_FAB2_LIB.BASEBOARD_FAB2(SCH_1):PAGE44

M_A_DQ<7> @BASEBOARD_FAB2_LIB.BASEBOARD_FAB2(SCH_1):M_A_DQ(7)
  U5D1 AG84 DDR0_DQ<7> SKX_EXT_B_BGA1-IC,TBD   I172 @BASEBOARD_FAB2_LIB.BASEBOARD_FAB2(SCH_1):PAGE23
  J4G1   10  DQ<6> SCONN288_H44441004_PIP-SCONN,HA     I1 @BASEBOARD_FAB2_LIB.BASEBOARD_FAB2(SCH_1):PAGE43
  J6T1  155  DQ<7> SCONN288_H44441003_PIP-SCONN,HA    I13 @BASEBOARD_FAB2_LIB.BASEBOARD_FAB2(SCH_1):PAGE44

M_A_DQ<8> @BASEBOARD_FAB2_LIB.BASEBOARD_FAB2(SCH_1):M_A_DQ(8)
  U5D1  W86 DDR0_DQ<8> SKX_EXT_B_BGA1-IC,TBD   I172 @BASEBOARD_FAB2_LIB.BASEBOARD_FAB2(SCH_1):PAGE23
  J4G1  161  DQ<9> SCONN288_H44441004_PIP-SCONN,HA     I1 @BASEBOARD_FAB2_LIB.BASEBOARD_FAB2(SCH_1):PAGE43
  J6T1   16  DQ<8> SCONN288_H44441003_PIP-SCONN,HA    I13 @BASEBOARD_FAB2_LIB.BASEBOARD_FAB2(SCH_1):PAGE44

M_A_DQ<9> @BASEBOARD_FAB2_LIB.BASEBOARD_FAB2(SCH_1):M_A_DQ(9)
  U5D1  W84 DDR0_DQ<9> SKX_EXT_B_BGA1-IC,TBD   I172 @BASEBOARD_FAB2_LIB.BASEBOARD_FAB2(SCH_1):PAGE23
  J4G1   16  DQ<8> SCONN288_H44441004_PIP-SCONN,HA     I1 @BASEBOARD_FAB2_LIB.BASEBOARD_FAB2(SCH_1):PAGE43
  J6T1  161  DQ<9> SCONN288_H44441003_PIP-SCONN,HA    I13 @BASEBOARD_FAB2_LIB.BASEBOARD_FAB2(SCH_1):PAGE44

M_A_DQS_DN<0> @BASEBOARD_FAB2_LIB.BASEBOARD_FAB2(SCH_1):M_A_DQS_DN(0)
  U5D1 AJ84 DDR0_DQS_DN<0> SKX_EXT_B_BGA1-IC,TBD   I172 @BASEBOARD_FAB2_LIB.BASEBOARD_FAB2(SCH_1):PAGE23
  J4G1  152  DQS0N SCONN288_H44441004_PIP-SCONN,HA     I2 @BASEBOARD_FAB2_LIB.BASEBOARD_FAB2(SCH_1):PAGE43
  J6T1  152  DQS0N SCONN288_H44441003_PIP-SCONN,HA   I120 @BASEBOARD_FAB2_LIB.BASEBOARD_FAB2(SCH_1):PAGE44

M_A_DQS_DN<10> @BASEBOARD_FAB2_LIB.BASEBOARD_FAB2(SCH_1):M_A_DQS_DN(10)
  U5D1  U84 DDR0_DQS_DN<10> SKX_EXT_B_BGA1-IC,TBD   I172 @BASEBOARD_FAB2_LIB.BASEBOARD_FAB2(SCH_1):PAGE23
  J4G1   19 DQS10N SCONN288_H44441004_PIP-SCONN,HA     I2 @BASEBOARD_FAB2_LIB.BASEBOARD_FAB2(SCH_1):PAGE43
  J6T1   19 DQS10N SCONN288_H44441003_PIP-SCONN,HA   I120 @BASEBOARD_FAB2_LIB.BASEBOARD_FAB2(SCH_1):PAGE44

M_A_DQS_DN<11> @BASEBOARD_FAB2_LIB.BASEBOARD_FAB2(SCH_1):M_A_DQS_DN(11)
  U5D1  U82 DDR0_DQS_DN<11> SKX_EXT_B_BGA1-IC,TBD   I172 @BASEBOARD_FAB2_LIB.BASEBOARD_FAB2(SCH_1):PAGE23
  J4G1   30 DQS11N SCONN288_H44441004_PIP-SCONN,HA     I2 @BASEBOARD_FAB2_LIB.BASEBOARD_FAB2(SCH_1):PAGE43
  J6T1   30 DQS11N SCONN288_H44441003_PIP-SCONN,HA   I120 @BASEBOARD_FAB2_LIB.BASEBOARD_FAB2(SCH_1):PAGE44

M_A_DQS_DN<12> @BASEBOARD_FAB2_LIB.BASEBOARD_FAB2(SCH_1):M_A_DQS_DN(12)
  U5D1  K75 DDR0_DQS_DN<12> SKX_EXT_B_BGA1-IC,TBD   I172 @BASEBOARD_FAB2_LIB.BASEBOARD_FAB2(SCH_1):PAGE23
  J4G1   41 DQS12N SCONN288_H44441004_PIP-SCONN,HA     I2 @BASEBOARD_FAB2_LIB.BASEBOARD_FAB2(SCH_1):PAGE43
  J6T1   41 DQS12N SCONN288_H44441003_PIP-SCONN,HA   I120 @BASEBOARD_FAB2_LIB.BASEBOARD_FAB2(SCH_1):PAGE44

M_A_DQS_DN<13> @BASEBOARD_FAB2_LIB.BASEBOARD_FAB2(SCH_1):M_A_DQS_DN(13)
  U5D1  A40 DDR0_DQS_DN<13> SKX_EXT_B_BGA1-IC,TBD   I172 @BASEBOARD_FAB2_LIB.BASEBOARD_FAB2(SCH_1):PAGE23
  J4G1  100 DQS13N SCONN288_H44441004_PIP-SCONN,HA     I2 @BASEBOARD_FAB2_LIB.BASEBOARD_FAB2(SCH_1):PAGE43
  J6T1  100 DQS13N SCONN288_H44441003_PIP-SCONN,HA   I120 @BASEBOARD_FAB2_LIB.BASEBOARD_FAB2(SCH_1):PAGE44

M_A_DQS_DN<14> @BASEBOARD_FAB2_LIB.BASEBOARD_FAB2(SCH_1):M_A_DQS_DN(14)
  U5D1  J36 DDR0_DQS_DN<14> SKX_EXT_B_BGA1-IC,TBD   I172 @BASEBOARD_FAB2_LIB.BASEBOARD_FAB2(SCH_1):PAGE23
  J4G1  111 DQS14N SCONN288_H44441004_PIP-SCONN,HA     I2 @BASEBOARD_FAB2_LIB.BASEBOARD_FAB2(SCH_1):PAGE43
  J6T1  111 DQS14N SCONN288_H44441003_PIP-SCONN,HA   I120 @BASEBOARD_FAB2_LIB.BASEBOARD_FAB2(SCH_1):PAGE44

M_A_DQS_DN<15> @BASEBOARD_FAB2_LIB.BASEBOARD_FAB2(SCH_1):M_A_DQS_DN(15)
  U5D1  J30 DDR0_DQS_DN<15> SKX_EXT_B_BGA1-IC,TBD   I172 @BASEBOARD_FAB2_LIB.BASEBOARD_FAB2(SCH_1):PAGE23
  J4G1  122 DQS15N SCONN288_H44441004_PIP-SCONN,HA     I2 @BASEBOARD_FAB2_LIB.BASEBOARD_FAB2(SCH_1):PAGE43
  J6T1  122 DQS15N SCONN288_H44441003_PIP-SCONN,HA   I120 @BASEBOARD_FAB2_LIB.BASEBOARD_FAB2(SCH_1):PAGE44

M_A_DQS_DN<16> @BASEBOARD_FAB2_LIB.BASEBOARD_FAB2(SCH_1):M_A_DQS_DN(16)
  U5D1  J24 DDR0_DQS_DN<16> SKX_EXT_B_BGA1-IC,TBD   I172 @BASEBOARD_FAB2_LIB.BASEBOARD_FAB2(SCH_1):PAGE23
  J4G1  133 DQS16N SCONN288_H44441004_PIP-SCONN,HA     I2 @BASEBOARD_FAB2_LIB.BASEBOARD_FAB2(SCH_1):PAGE43
  J6T1  133 DQS16N SCONN288_H44441003_PIP-SCONN,HA   I120 @BASEBOARD_FAB2_LIB.BASEBOARD_FAB2(SCH_1):PAGE44

M_A_DQS_DN<17> @BASEBOARD_FAB2_LIB.BASEBOARD_FAB2(SCH_1):M_A_DQS_DN(17)
  U5D1 AB67 DDR0_DQS_DN<17> SKX_EXT_B_BGA1-IC,TBD   I172 @BASEBOARD_FAB2_LIB.BASEBOARD_FAB2(SCH_1):PAGE23
  J4G1   52 DQS17N SCONN288_H44441004_PIP-SCONN,HA     I2 @BASEBOARD_FAB2_LIB.BASEBOARD_FAB2(SCH_1):PAGE43
  J6T1   52 DQS17N SCONN288_H44441003_PIP-SCONN,HA   I120 @BASEBOARD_FAB2_LIB.BASEBOARD_FAB2(SCH_1):PAGE44

M_A_DQS_DN<1> @BASEBOARD_FAB2_LIB.BASEBOARD_FAB2(SCH_1):M_A_DQS_DN(1)
  U5D1  R84 DDR0_DQS_DN<1> SKX_EXT_B_BGA1-IC,TBD   I172 @BASEBOARD_FAB2_LIB.BASEBOARD_FAB2(SCH_1):PAGE23
  J4G1  163  DQS1N SCONN288_H44441004_PIP-SCONN,HA     I2 @BASEBOARD_FAB2_LIB.BASEBOARD_FAB2(SCH_1):PAGE43
  J6T1  163  DQS1N SCONN288_H44441003_PIP-SCONN,HA   I120 @BASEBOARD_FAB2_LIB.BASEBOARD_FAB2(SCH_1):PAGE44

M_A_DQS_DN<2> @BASEBOARD_FAB2_LIB.BASEBOARD_FAB2(SCH_1):M_A_DQS_DN(2)
  U5D1  P79 DDR0_DQS_DN<2> SKX_EXT_B_BGA1-IC,TBD   I172 @BASEBOARD_FAB2_LIB.BASEBOARD_FAB2(SCH_1):PAGE23
  J4G1  174  DQS2N SCONN288_H44441004_PIP-SCONN,HA     I2 @BASEBOARD_FAB2_LIB.BASEBOARD_FAB2(SCH_1):PAGE43
  J6T1  174  DQS2N SCONN288_H44441003_PIP-SCONN,HA   I120 @BASEBOARD_FAB2_LIB.BASEBOARD_FAB2(SCH_1):PAGE44

M_A_DQS_DN<3> @BASEBOARD_FAB2_LIB.BASEBOARD_FAB2(SCH_1):M_A_DQS_DN(3)
  U5D1  T75 DDR0_DQS_DN<3> SKX_EXT_B_BGA1-IC,TBD   I172 @BASEBOARD_FAB2_LIB.BASEBOARD_FAB2(SCH_1):PAGE23
  J4G1  185  DQS3N SCONN288_H44441004_PIP-SCONN,HA     I2 @BASEBOARD_FAB2_LIB.BASEBOARD_FAB2(SCH_1):PAGE43
  J6T1  185  DQS3N SCONN288_H44441003_PIP-SCONN,HA   I120 @BASEBOARD_FAB2_LIB.BASEBOARD_FAB2(SCH_1):PAGE44

M_A_DQS_DN<4> @BASEBOARD_FAB2_LIB.BASEBOARD_FAB2(SCH_1):M_A_DQS_DN(4)
  U5D1  G40 DDR0_DQS_DN<4> SKX_EXT_B_BGA1-IC,TBD   I172 @BASEBOARD_FAB2_LIB.BASEBOARD_FAB2(SCH_1):PAGE23
  J4G1  244  DQS4N SCONN288_H44441004_PIP-SCONN,HA     I2 @BASEBOARD_FAB2_LIB.BASEBOARD_FAB2(SCH_1):PAGE43
  J6T1  244  DQS4N SCONN288_H44441003_PIP-SCONN,HA   I120 @BASEBOARD_FAB2_LIB.BASEBOARD_FAB2(SCH_1):PAGE44

M_A_DQS_DN<5> @BASEBOARD_FAB2_LIB.BASEBOARD_FAB2(SCH_1):M_A_DQS_DN(5)
  U5D1  R36 DDR0_DQS_DN<5> SKX_EXT_B_BGA1-IC,TBD   I172 @BASEBOARD_FAB2_LIB.BASEBOARD_FAB2(SCH_1):PAGE23
  J4G1  255  DQS5N SCONN288_H44441004_PIP-SCONN,HA     I2 @BASEBOARD_FAB2_LIB.BASEBOARD_FAB2(SCH_1):PAGE43
  J6T1  255  DQS5N SCONN288_H44441003_PIP-SCONN,HA   I120 @BASEBOARD_FAB2_LIB.BASEBOARD_FAB2(SCH_1):PAGE44

M_A_DQS_DN<6> @BASEBOARD_FAB2_LIB.BASEBOARD_FAB2(SCH_1):M_A_DQS_DN(6)
  U5D1  R30 DDR0_DQS_DN<6> SKX_EXT_B_BGA1-IC,TBD   I172 @BASEBOARD_FAB2_LIB.BASEBOARD_FAB2(SCH_1):PAGE23
  J4G1  266  DQS6N SCONN288_H44441004_PIP-SCONN,HA     I2 @BASEBOARD_FAB2_LIB.BASEBOARD_FAB2(SCH_1):PAGE43
  J6T1  266  DQS6N SCONN288_H44441003_PIP-SCONN,HA   I120 @BASEBOARD_FAB2_LIB.BASEBOARD_FAB2(SCH_1):PAGE44

M_A_DQS_DN<7> @BASEBOARD_FAB2_LIB.BASEBOARD_FAB2(SCH_1):M_A_DQS_DN(7)
  U5D1  N24 DDR0_DQS_DN<7> SKX_EXT_B_BGA1-IC,TBD   I172 @BASEBOARD_FAB2_LIB.BASEBOARD_FAB2(SCH_1):PAGE23
  J4G1  277  DQS7N SCONN288_H44441004_PIP-SCONN,HA     I2 @BASEBOARD_FAB2_LIB.BASEBOARD_FAB2(SCH_1):PAGE43
  J6T1  277  DQS7N SCONN288_H44441003_PIP-SCONN,HA   I120 @BASEBOARD_FAB2_LIB.BASEBOARD_FAB2(SCH_1):PAGE44

M_A_DQS_DN<8> @BASEBOARD_FAB2_LIB.BASEBOARD_FAB2(SCH_1):M_A_DQS_DN(8)
  U5D1 AH67 DDR0_DQS_DN<8> SKX_EXT_B_BGA1-IC,TBD   I172 @BASEBOARD_FAB2_LIB.BASEBOARD_FAB2(SCH_1):PAGE23
  J4G1  196  DQS8N SCONN288_H44441004_PIP-SCONN,HA     I2 @BASEBOARD_FAB2_LIB.BASEBOARD_FAB2(SCH_1):PAGE43
  J6T1  196  DQS8N SCONN288_H44441003_PIP-SCONN,HA   I120 @BASEBOARD_FAB2_LIB.BASEBOARD_FAB2(SCH_1):PAGE44

M_A_DQS_DN<9> @BASEBOARD_FAB2_LIB.BASEBOARD_FAB2(SCH_1):M_A_DQS_DN(9)
  U5D1 AL84 DDR0_DQS_DN<9> SKX_EXT_B_BGA1-IC,TBD   I172 @BASEBOARD_FAB2_LIB.BASEBOARD_FAB2(SCH_1):PAGE23
  J4G1    8  DQS9N SCONN288_H44441004_PIP-SCONN,HA     I2 @BASEBOARD_FAB2_LIB.BASEBOARD_FAB2(SCH_1):PAGE43
  J6T1    8  DQS9N SCONN288_H44441003_PIP-SCONN,HA   I120 @BASEBOARD_FAB2_LIB.BASEBOARD_FAB2(SCH_1):PAGE44

M_A_DQS_DP<0> @BASEBOARD_FAB2_LIB.BASEBOARD_FAB2(SCH_1):M_A_DQS_DP(0)
  U5D1 AH85 DDR0_DQS_DP<0> SKX_EXT_B_BGA1-IC,TBD   I172 @BASEBOARD_FAB2_LIB.BASEBOARD_FAB2(SCH_1):PAGE23
  J4G1  153  DQS0P SCONN288_H44441004_PIP-SCONN,HA     I2 @BASEBOARD_FAB2_LIB.BASEBOARD_FAB2(SCH_1):PAGE43
  J6T1  153  DQS0P SCONN288_H44441003_PIP-SCONN,HA   I120 @BASEBOARD_FAB2_LIB.BASEBOARD_FAB2(SCH_1):PAGE44

M_A_DQS_DP<10> @BASEBOARD_FAB2_LIB.BASEBOARD_FAB2(SCH_1):M_A_DQS_DP(10)
  U5D1  V85 DDR0_DQS_DP<10> SKX_EXT_B_BGA1-IC,TBD   I172 @BASEBOARD_FAB2_LIB.BASEBOARD_FAB2(SCH_1):PAGE23
  J4G1   18 DQS10P SCONN288_H44441004_PIP-SCONN,HA     I2 @BASEBOARD_FAB2_LIB.BASEBOARD_FAB2(SCH_1):PAGE43
  J6T1   18 DQS10P SCONN288_H44441003_PIP-SCONN,HA   I120 @BASEBOARD_FAB2_LIB.BASEBOARD_FAB2(SCH_1):PAGE44

M_A_DQS_DP<11> @BASEBOARD_FAB2_LIB.BASEBOARD_FAB2(SCH_1):M_A_DQS_DP(11)
  U5D1  T81 DDR0_DQS_DP<11> SKX_EXT_B_BGA1-IC,TBD   I172 @BASEBOARD_FAB2_LIB.BASEBOARD_FAB2(SCH_1):PAGE23
  J4G1   29 DQS11P SCONN288_H44441004_PIP-SCONN,HA     I2 @BASEBOARD_FAB2_LIB.BASEBOARD_FAB2(SCH_1):PAGE43
  J6T1   29 DQS11P SCONN288_H44441003_PIP-SCONN,HA   I120 @BASEBOARD_FAB2_LIB.BASEBOARD_FAB2(SCH_1):PAGE44

M_A_DQS_DP<12> @BASEBOARD_FAB2_LIB.BASEBOARD_FAB2(SCH_1):M_A_DQS_DP(12)
  U5D1  M75 DDR0_DQS_DP<12> SKX_EXT_B_BGA1-IC,TBD   I172 @BASEBOARD_FAB2_LIB.BASEBOARD_FAB2(SCH_1):PAGE23
  J4G1   40 DQS12P SCONN288_H44441004_PIP-SCONN,HA     I2 @BASEBOARD_FAB2_LIB.BASEBOARD_FAB2(SCH_1):PAGE43
  J6T1   40 DQS12P SCONN288_H44441003_PIP-SCONN,HA   I120 @BASEBOARD_FAB2_LIB.BASEBOARD_FAB2(SCH_1):PAGE44

M_A_DQS_DP<13> @BASEBOARD_FAB2_LIB.BASEBOARD_FAB2(SCH_1):M_A_DQS_DP(13)
  U5D1  C40 DDR0_DQS_DP<13> SKX_EXT_B_BGA1-IC,TBD   I172 @BASEBOARD_FAB2_LIB.BASEBOARD_FAB2(SCH_1):PAGE23
  J4G1   99 DQS13P SCONN288_H44441004_PIP-SCONN,HA     I2 @BASEBOARD_FAB2_LIB.BASEBOARD_FAB2(SCH_1):PAGE43
  J6T1   99 DQS13P SCONN288_H44441003_PIP-SCONN,HA   I120 @BASEBOARD_FAB2_LIB.BASEBOARD_FAB2(SCH_1):PAGE44

M_A_DQS_DP<14> @BASEBOARD_FAB2_LIB.BASEBOARD_FAB2(SCH_1):M_A_DQS_DP(14)
  U5D1  L36 DDR0_DQS_DP<14> SKX_EXT_B_BGA1-IC,TBD   I172 @BASEBOARD_FAB2_LIB.BASEBOARD_FAB2(SCH_1):PAGE23
  J4G1  110 DQS14P SCONN288_H44441004_PIP-SCONN,HA     I2 @BASEBOARD_FAB2_LIB.BASEBOARD_FAB2(SCH_1):PAGE43
  J6T1  110 DQS14P SCONN288_H44441003_PIP-SCONN,HA   I120 @BASEBOARD_FAB2_LIB.BASEBOARD_FAB2(SCH_1):PAGE44

M_A_DQS_DP<15> @BASEBOARD_FAB2_LIB.BASEBOARD_FAB2(SCH_1):M_A_DQS_DP(15)
  U5D1  L30 DDR0_DQS_DP<15> SKX_EXT_B_BGA1-IC,TBD   I172 @BASEBOARD_FAB2_LIB.BASEBOARD_FAB2(SCH_1):PAGE23
  J4G1  121 DQS15P SCONN288_H44441004_PIP-SCONN,HA     I2 @BASEBOARD_FAB2_LIB.BASEBOARD_FAB2(SCH_1):PAGE43
  J6T1  121 DQS15P SCONN288_H44441003_PIP-SCONN,HA   I120 @BASEBOARD_FAB2_LIB.BASEBOARD_FAB2(SCH_1):PAGE44

M_A_DQS_DP<16> @BASEBOARD_FAB2_LIB.BASEBOARD_FAB2(SCH_1):M_A_DQS_DP(16)
  U5D1  L24 DDR0_DQS_DP<16> SKX_EXT_B_BGA1-IC,TBD   I172 @BASEBOARD_FAB2_LIB.BASEBOARD_FAB2(SCH_1):PAGE23
  J4G1  132 DQS16P SCONN288_H44441004_PIP-SCONN,HA     I2 @BASEBOARD_FAB2_LIB.BASEBOARD_FAB2(SCH_1):PAGE43
  J6T1  132 DQS16P SCONN288_H44441003_PIP-SCONN,HA   I120 @BASEBOARD_FAB2_LIB.BASEBOARD_FAB2(SCH_1):PAGE44

M_A_DQS_DP<17> @BASEBOARD_FAB2_LIB.BASEBOARD_FAB2(SCH_1):M_A_DQS_DP(17)
  U5D1 AD67 DDR0_DQS_DP<17> SKX_EXT_B_BGA1-IC,TBD   I172 @BASEBOARD_FAB2_LIB.BASEBOARD_FAB2(SCH_1):PAGE23
  J4G1   51 DQS17P SCONN288_H44441004_PIP-SCONN,HA     I2 @BASEBOARD_FAB2_LIB.BASEBOARD_FAB2(SCH_1):PAGE43
  J6T1   51 DQS17P SCONN288_H44441003_PIP-SCONN,HA   I120 @BASEBOARD_FAB2_LIB.BASEBOARD_FAB2(SCH_1):PAGE44

M_A_DQS_DP<1> @BASEBOARD_FAB2_LIB.BASEBOARD_FAB2(SCH_1):M_A_DQS_DP(1)
  U5D1  P85 DDR0_DQS_DP<1> SKX_EXT_B_BGA1-IC,TBD   I172 @BASEBOARD_FAB2_LIB.BASEBOARD_FAB2(SCH_1):PAGE23
  J4G1  164  DQS1P SCONN288_H44441004_PIP-SCONN,HA     I2 @BASEBOARD_FAB2_LIB.BASEBOARD_FAB2(SCH_1):PAGE43
  J6T1  164  DQS1P SCONN288_H44441003_PIP-SCONN,HA   I120 @BASEBOARD_FAB2_LIB.BASEBOARD_FAB2(SCH_1):PAGE44

M_A_DQS_DP<2> @BASEBOARD_FAB2_LIB.BASEBOARD_FAB2(SCH_1):M_A_DQS_DP(2)
  U5D1  R80 DDR0_DQS_DP<2> SKX_EXT_B_BGA1-IC,TBD   I172 @BASEBOARD_FAB2_LIB.BASEBOARD_FAB2(SCH_1):PAGE23
  J4G1  175  DQS2P SCONN288_H44441004_PIP-SCONN,HA     I2 @BASEBOARD_FAB2_LIB.BASEBOARD_FAB2(SCH_1):PAGE43
  J6T1  175  DQS2P SCONN288_H44441003_PIP-SCONN,HA   I120 @BASEBOARD_FAB2_LIB.BASEBOARD_FAB2(SCH_1):PAGE44

M_A_DQS_DP<3> @BASEBOARD_FAB2_LIB.BASEBOARD_FAB2(SCH_1):M_A_DQS_DP(3)
  U5D1  P75 DDR0_DQS_DP<3> SKX_EXT_B_BGA1-IC,TBD   I172 @BASEBOARD_FAB2_LIB.BASEBOARD_FAB2(SCH_1):PAGE23
  J4G1  186  DQS3P SCONN288_H44441004_PIP-SCONN,HA     I2 @BASEBOARD_FAB2_LIB.BASEBOARD_FAB2(SCH_1):PAGE43
  J6T1  186  DQS3P SCONN288_H44441003_PIP-SCONN,HA   I120 @BASEBOARD_FAB2_LIB.BASEBOARD_FAB2(SCH_1):PAGE44

M_A_DQS_DP<4> @BASEBOARD_FAB2_LIB.BASEBOARD_FAB2(SCH_1):M_A_DQS_DP(4)
  U5D1  E40 DDR0_DQS_DP<4> SKX_EXT_B_BGA1-IC,TBD   I172 @BASEBOARD_FAB2_LIB.BASEBOARD_FAB2(SCH_1):PAGE23
  J4G1  245  DQS4P SCONN288_H44441004_PIP-SCONN,HA     I2 @BASEBOARD_FAB2_LIB.BASEBOARD_FAB2(SCH_1):PAGE43
  J6T1  245  DQS4P SCONN288_H44441003_PIP-SCONN,HA   I120 @BASEBOARD_FAB2_LIB.BASEBOARD_FAB2(SCH_1):PAGE44

M_A_DQS_DP<5> @BASEBOARD_FAB2_LIB.BASEBOARD_FAB2(SCH_1):M_A_DQS_DP(5)
  U5D1  N36 DDR0_DQS_DP<5> SKX_EXT_B_BGA1-IC,TBD   I172 @BASEBOARD_FAB2_LIB.BASEBOARD_FAB2(SCH_1):PAGE23
  J4G1  256  DQS5P SCONN288_H44441004_PIP-SCONN,HA     I2 @BASEBOARD_FAB2_LIB.BASEBOARD_FAB2(SCH_1):PAGE43
  J6T1  256  DQS5P SCONN288_H44441003_PIP-SCONN,HA   I120 @BASEBOARD_FAB2_LIB.BASEBOARD_FAB2(SCH_1):PAGE44

M_A_DQS_DP<6> @BASEBOARD_FAB2_LIB.BASEBOARD_FAB2(SCH_1):M_A_DQS_DP(6)
  U5D1  N30 DDR0_DQS_DP<6> SKX_EXT_B_BGA1-IC,TBD   I172 @BASEBOARD_FAB2_LIB.BASEBOARD_FAB2(SCH_1):PAGE23
  J4G1  267  DQS6P SCONN288_H44441004_PIP-SCONN,HA     I2 @BASEBOARD_FAB2_LIB.BASEBOARD_FAB2(SCH_1):PAGE43
  J6T1  267  DQS6P SCONN288_H44441003_PIP-SCONN,HA   I120 @BASEBOARD_FAB2_LIB.BASEBOARD_FAB2(SCH_1):PAGE44

M_A_DQS_DP<7> @BASEBOARD_FAB2_LIB.BASEBOARD_FAB2(SCH_1):M_A_DQS_DP(7)
  U5D1  R24 DDR0_DQS_DP<7> SKX_EXT_B_BGA1-IC,TBD   I172 @BASEBOARD_FAB2_LIB.BASEBOARD_FAB2(SCH_1):PAGE23
  J4G1  278  DQS7P SCONN288_H44441004_PIP-SCONN,HA     I2 @BASEBOARD_FAB2_LIB.BASEBOARD_FAB2(SCH_1):PAGE43
  J6T1  278  DQS7P SCONN288_H44441003_PIP-SCONN,HA   I120 @BASEBOARD_FAB2_LIB.BASEBOARD_FAB2(SCH_1):PAGE44

M_A_DQS_DP<8> @BASEBOARD_FAB2_LIB.BASEBOARD_FAB2(SCH_1):M_A_DQS_DP(8)
  U5D1 AF67 DDR0_DQS_DP<8> SKX_EXT_B_BGA1-IC,TBD   I172 @BASEBOARD_FAB2_LIB.BASEBOARD_FAB2(SCH_1):PAGE23
  J4G1  197  DQS8P SCONN288_H44441004_PIP-SCONN,HA     I2 @BASEBOARD_FAB2_LIB.BASEBOARD_FAB2(SCH_1):PAGE43
  J6T1  197  DQS8P SCONN288_H44441003_PIP-SCONN,HA   I120 @BASEBOARD_FAB2_LIB.BASEBOARD_FAB2(SCH_1):PAGE44

M_A_DQS_DP<9> @BASEBOARD_FAB2_LIB.BASEBOARD_FAB2(SCH_1):M_A_DQS_DP(9)
  U5D1 AM85 DDR0_DQS_DP<9> SKX_EXT_B_BGA1-IC,TBD   I172 @BASEBOARD_FAB2_LIB.BASEBOARD_FAB2(SCH_1):PAGE23
  J4G1    7  DQS9P SCONN288_H44441004_PIP-SCONN,HA     I2 @BASEBOARD_FAB2_LIB.BASEBOARD_FAB2(SCH_1):PAGE43
  J6T1    7  DQS9P SCONN288_H44441003_PIP-SCONN,HA   I120 @BASEBOARD_FAB2_LIB.BASEBOARD_FAB2(SCH_1):PAGE44

M_A_ECC<0> @BASEBOARD_FAB2_LIB.BASEBOARD_FAB2(SCH_1):M_A_ECC(0)
  U5D1 AC68 DDR0_ECC<0> SKX_EXT_B_BGA1-IC,TBD   I172 @BASEBOARD_FAB2_LIB.BASEBOARD_FAB2(SCH_1):PAGE23
  J4G1  194  CB<1> SCONN288_H44441004_PIP-SCONN,HA     I1 @BASEBOARD_FAB2_LIB.BASEBOARD_FAB2(SCH_1):PAGE43
  J6T1   49  CB<0> SCONN288_H44441003_PIP-SCONN,HA    I13 @BASEBOARD_FAB2_LIB.BASEBOARD_FAB2(SCH_1):PAGE44

M_A_ECC<1> @BASEBOARD_FAB2_LIB.BASEBOARD_FAB2(SCH_1):M_A_ECC(1)
  U5D1 AG68 DDR0_ECC<1> SKX_EXT_B_BGA1-IC,TBD   I172 @BASEBOARD_FAB2_LIB.BASEBOARD_FAB2(SCH_1):PAGE23
  J4G1   49  CB<0> SCONN288_H44441004_PIP-SCONN,HA     I1 @BASEBOARD_FAB2_LIB.BASEBOARD_FAB2(SCH_1):PAGE43
  J6T1  194  CB<1> SCONN288_H44441003_PIP-SCONN,HA    I13 @BASEBOARD_FAB2_LIB.BASEBOARD_FAB2(SCH_1):PAGE44

M_A_ECC<2> @BASEBOARD_FAB2_LIB.BASEBOARD_FAB2(SCH_1):M_A_ECC(2)
  U5D1 AD65 DDR0_ECC<2> SKX_EXT_B_BGA1-IC,TBD   I172 @BASEBOARD_FAB2_LIB.BASEBOARD_FAB2(SCH_1):PAGE23
  J4G1  201  CB<3> SCONN288_H44441004_PIP-SCONN,HA     I1 @BASEBOARD_FAB2_LIB.BASEBOARD_FAB2(SCH_1):PAGE43
  J6T1   56  CB<2> SCONN288_H44441003_PIP-SCONN,HA    I13 @BASEBOARD_FAB2_LIB.BASEBOARD_FAB2(SCH_1):PAGE44

M_A_ECC<3> @BASEBOARD_FAB2_LIB.BASEBOARD_FAB2(SCH_1):M_A_ECC(3)
  U5D1 AF65 DDR0_ECC<3> SKX_EXT_B_BGA1-IC,TBD   I172 @BASEBOARD_FAB2_LIB.BASEBOARD_FAB2(SCH_1):PAGE23
  J4G1   56  CB<2> SCONN288_H44441004_PIP-SCONN,HA     I1 @BASEBOARD_FAB2_LIB.BASEBOARD_FAB2(SCH_1):PAGE43
  J6T1  201  CB<3> SCONN288_H44441003_PIP-SCONN,HA    I13 @BASEBOARD_FAB2_LIB.BASEBOARD_FAB2(SCH_1):PAGE44

M_A_ECC<4> @BASEBOARD_FAB2_LIB.BASEBOARD_FAB2(SCH_1):M_A_ECC(4)
  U5D1 AD69 DDR0_ECC<4> SKX_EXT_B_BGA1-IC,TBD   I172 @BASEBOARD_FAB2_LIB.BASEBOARD_FAB2(SCH_1):PAGE23
  J4G1  192  CB<5> SCONN288_H44441004_PIP-SCONN,HA     I1 @BASEBOARD_FAB2_LIB.BASEBOARD_FAB2(SCH_1):PAGE43
  J6T1   47  CB<4> SCONN288_H44441003_PIP-SCONN,HA    I13 @BASEBOARD_FAB2_LIB.BASEBOARD_FAB2(SCH_1):PAGE44

M_A_ECC<5> @BASEBOARD_FAB2_LIB.BASEBOARD_FAB2(SCH_1):M_A_ECC(5)
  U5D1 AF69 DDR0_ECC<5> SKX_EXT_B_BGA1-IC,TBD   I172 @BASEBOARD_FAB2_LIB.BASEBOARD_FAB2(SCH_1):PAGE23
  J4G1   47  CB<4> SCONN288_H44441004_PIP-SCONN,HA     I1 @BASEBOARD_FAB2_LIB.BASEBOARD_FAB2(SCH_1):PAGE43
  J6T1  192  CB<5> SCONN288_H44441003_PIP-SCONN,HA    I13 @BASEBOARD_FAB2_LIB.BASEBOARD_FAB2(SCH_1):PAGE44

M_A_ECC<6> @BASEBOARD_FAB2_LIB.BASEBOARD_FAB2(SCH_1):M_A_ECC(6)
  U5D1 AC66 DDR0_ECC<6> SKX_EXT_B_BGA1-IC,TBD   I172 @BASEBOARD_FAB2_LIB.BASEBOARD_FAB2(SCH_1):PAGE23
  J4G1  199  CB<7> SCONN288_H44441004_PIP-SCONN,HA     I1 @BASEBOARD_FAB2_LIB.BASEBOARD_FAB2(SCH_1):PAGE43
  J6T1   54  CB<6> SCONN288_H44441003_PIP-SCONN,HA    I13 @BASEBOARD_FAB2_LIB.BASEBOARD_FAB2(SCH_1):PAGE44

M_A_ECC<7> @BASEBOARD_FAB2_LIB.BASEBOARD_FAB2(SCH_1):M_A_ECC(7)
  U5D1 AG66 DDR0_ECC<7> SKX_EXT_B_BGA1-IC,TBD   I172 @BASEBOARD_FAB2_LIB.BASEBOARD_FAB2(SCH_1):PAGE23
  J4G1   54  CB<6> SCONN288_H44441004_PIP-SCONN,HA     I1 @BASEBOARD_FAB2_LIB.BASEBOARD_FAB2(SCH_1):PAGE43
  J6T1  199  CB<7> SCONN288_H44441003_PIP-SCONN,HA    I13 @BASEBOARD_FAB2_LIB.BASEBOARD_FAB2(SCH_1):PAGE44

M_A_MA<0> @BASEBOARD_FAB2_LIB.BASEBOARD_FAB2(SCH_1):M_A_MA(0)
  U5D1  F53 DDR0_MA<0> SKX_EXT_B_BGA1-IC,TBD   I172 @BASEBOARD_FAB2_LIB.BASEBOARD_FAB2(SCH_1):PAGE23
  J4G1   79     A0 SCONN288_H44441004_PIP-SCONN,HA     I1 @BASEBOARD_FAB2_LIB.BASEBOARD_FAB2(SCH_1):PAGE43
  J6T1   79     A0 SCONN288_H44441003_PIP-SCONN,HA    I13 @BASEBOARD_FAB2_LIB.BASEBOARD_FAB2(SCH_1):PAGE44

M_A_MA<10> @BASEBOARD_FAB2_LIB.BASEBOARD_FAB2(SCH_1):M_A_MA(10)
  U5D1  J54 DDR0_MA<10> SKX_EXT_B_BGA1-IC,TBD   I172 @BASEBOARD_FAB2_LIB.BASEBOARD_FAB2(SCH_1):PAGE23
  J4G1  225    A10 SCONN288_H44441004_PIP-SCONN,HA     I1 @BASEBOARD_FAB2_LIB.BASEBOARD_FAB2(SCH_1):PAGE43
  J6T1  225    A10 SCONN288_H44441003_PIP-SCONN,HA    I13 @BASEBOARD_FAB2_LIB.BASEBOARD_FAB2(SCH_1):PAGE44

M_A_MA<11> @BASEBOARD_FAB2_LIB.BASEBOARD_FAB2(SCH_1):M_A_MA(11)
  U5D1  G62 DDR0_MA<11> SKX_EXT_B_BGA1-IC,TBD   I172 @BASEBOARD_FAB2_LIB.BASEBOARD_FAB2(SCH_1):PAGE23
  J4G1  210    A11 SCONN288_H44441004_PIP-SCONN,HA     I1 @BASEBOARD_FAB2_LIB.BASEBOARD_FAB2(SCH_1):PAGE43
  J6T1  210    A11 SCONN288_H44441003_PIP-SCONN,HA    I13 @BASEBOARD_FAB2_LIB.BASEBOARD_FAB2(SCH_1):PAGE44

M_A_MA<12> @BASEBOARD_FAB2_LIB.BASEBOARD_FAB2(SCH_1):M_A_MA(12)
  U5D1  J64 DDR0_MA<12> SKX_EXT_B_BGA1-IC,TBD   I172 @BASEBOARD_FAB2_LIB.BASEBOARD_FAB2(SCH_1):PAGE23
  J4G1   65    A12 SCONN288_H44441004_PIP-SCONN,HA     I1 @BASEBOARD_FAB2_LIB.BASEBOARD_FAB2(SCH_1):PAGE43
  J6T1   65    A12 SCONN288_H44441003_PIP-SCONN,HA    I13 @BASEBOARD_FAB2_LIB.BASEBOARD_FAB2(SCH_1):PAGE44

M_A_MA<13> @BASEBOARD_FAB2_LIB.BASEBOARD_FAB2(SCH_1):M_A_MA(13)
  U5D1  J48 DDR0_MA<13> SKX_EXT_B_BGA1-IC,TBD   I172 @BASEBOARD_FAB2_LIB.BASEBOARD_FAB2(SCH_1):PAGE23
  J4G1  232    A13 SCONN288_H44441004_PIP-SCONN,HA     I1 @BASEBOARD_FAB2_LIB.BASEBOARD_FAB2(SCH_1):PAGE43
  J6T1  232    A13 SCONN288_H44441003_PIP-SCONN,HA    I13 @BASEBOARD_FAB2_LIB.BASEBOARD_FAB2(SCH_1):PAGE44

M_A_MA<14> @BASEBOARD_FAB2_LIB.BASEBOARD_FAB2(SCH_1):M_A_MA(14)
  U5D1  F51 DDR0_MA<14> SKX_EXT_B_BGA1-IC,TBD   I172 @BASEBOARD_FAB2_LIB.BASEBOARD_FAB2(SCH_1):PAGE23
  J4G1  228 A14_WE_N SCONN288_H44441004_PIP-SCONN,HA     I1 @BASEBOARD_FAB2_LIB.BASEBOARD_FAB2(SCH_1):PAGE43
  J6T1  228 A14_WE_N SCONN288_H44441003_PIP-SCONN,HA    I13 @BASEBOARD_FAB2_LIB.BASEBOARD_FAB2(SCH_1):PAGE44

M_A_MA<15> @BASEBOARD_FAB2_LIB.BASEBOARD_FAB2(SCH_1):M_A_MA(15)
  U5D1  K49 DDR0_MA<15> SKX_EXT_B_BGA1-IC,TBD   I172 @BASEBOARD_FAB2_LIB.BASEBOARD_FAB2(SCH_1):PAGE23
  J4G1   86 A15_CAS_N SCONN288_H44441004_PIP-SCONN,HA     I1 @BASEBOARD_FAB2_LIB.BASEBOARD_FAB2(SCH_1):PAGE43
  J6T1   86 A15_CAS_N SCONN288_H44441003_PIP-SCONN,HA    I13 @BASEBOARD_FAB2_LIB.BASEBOARD_FAB2(SCH_1):PAGE44

M_A_MA<16> @BASEBOARD_FAB2_LIB.BASEBOARD_FAB2(SCH_1):M_A_MA(16)
  U5D1  D51 DDR0_MA<16> SKX_EXT_B_BGA1-IC,TBD   I172 @BASEBOARD_FAB2_LIB.BASEBOARD_FAB2(SCH_1):PAGE23
  J4G1   82 A16_RAS_N SCONN288_H44441004_PIP-SCONN,HA     I1 @BASEBOARD_FAB2_LIB.BASEBOARD_FAB2(SCH_1):PAGE43
  J6T1   82 A16_RAS_N SCONN288_H44441003_PIP-SCONN,HA    I13 @BASEBOARD_FAB2_LIB.BASEBOARD_FAB2(SCH_1):PAGE44

M_A_MA<17> @BASEBOARD_FAB2_LIB.BASEBOARD_FAB2(SCH_1):M_A_MA(17)
  U5D1  K47 DDR0_MA<17> SKX_EXT_B_BGA1-IC,TBD   I172 @BASEBOARD_FAB2_LIB.BASEBOARD_FAB2(SCH_1):PAGE23
  J4G1  234    A17 SCONN288_H44441004_PIP-SCONN,HA     I1 @BASEBOARD_FAB2_LIB.BASEBOARD_FAB2(SCH_1):PAGE43
  J6T1  234    A17 SCONN288_H44441003_PIP-SCONN,HA    I13 @BASEBOARD_FAB2_LIB.BASEBOARD_FAB2(SCH_1):PAGE44

M_A_MA<1> @BASEBOARD_FAB2_LIB.BASEBOARD_FAB2(SCH_1):M_A_MA(1)
  U5D1  F57 DDR0_MA<1> SKX_EXT_B_BGA1-IC,TBD   I172 @BASEBOARD_FAB2_LIB.BASEBOARD_FAB2(SCH_1):PAGE23
  J4G1   72     A1 SCONN288_H44441004_PIP-SCONN,HA     I1 @BASEBOARD_FAB2_LIB.BASEBOARD_FAB2(SCH_1):PAGE43
  J6T1   72     A1 SCONN288_H44441003_PIP-SCONN,HA    I13 @BASEBOARD_FAB2_LIB.BASEBOARD_FAB2(SCH_1):PAGE44

M_A_MA<2> @BASEBOARD_FAB2_LIB.BASEBOARD_FAB2(SCH_1):M_A_MA(2)
  U5D1  D57 DDR0_MA<2> SKX_EXT_B_BGA1-IC,TBD   I172 @BASEBOARD_FAB2_LIB.BASEBOARD_FAB2(SCH_1):PAGE23
  J4G1  216     A2 SCONN288_H44441004_PIP-SCONN,HA     I1 @BASEBOARD_FAB2_LIB.BASEBOARD_FAB2(SCH_1):PAGE43
  J6T1  216     A2 SCONN288_H44441003_PIP-SCONN,HA    I13 @BASEBOARD_FAB2_LIB.BASEBOARD_FAB2(SCH_1):PAGE44

M_A_MA<3> @BASEBOARD_FAB2_LIB.BASEBOARD_FAB2(SCH_1):M_A_MA(3)
  U5D1  C58 DDR0_MA<3> SKX_EXT_B_BGA1-IC,TBD   I172 @BASEBOARD_FAB2_LIB.BASEBOARD_FAB2(SCH_1):PAGE23
  J4G1   71     A3 SCONN288_H44441004_PIP-SCONN,HA     I1 @BASEBOARD_FAB2_LIB.BASEBOARD_FAB2(SCH_1):PAGE43
  J6T1   71     A3 SCONN288_H44441003_PIP-SCONN,HA    I13 @BASEBOARD_FAB2_LIB.BASEBOARD_FAB2(SCH_1):PAGE44

M_A_MA<4> @BASEBOARD_FAB2_LIB.BASEBOARD_FAB2(SCH_1):M_A_MA(4)
  U5D1  G58 DDR0_MA<4> SKX_EXT_B_BGA1-IC,TBD   I172 @BASEBOARD_FAB2_LIB.BASEBOARD_FAB2(SCH_1):PAGE23
  J4G1  214     A4 SCONN288_H44441004_PIP-SCONN,HA     I1 @BASEBOARD_FAB2_LIB.BASEBOARD_FAB2(SCH_1):PAGE43
  J6T1  214     A4 SCONN288_H44441003_PIP-SCONN,HA    I13 @BASEBOARD_FAB2_LIB.BASEBOARD_FAB2(SCH_1):PAGE44

M_A_MA<5> @BASEBOARD_FAB2_LIB.BASEBOARD_FAB2(SCH_1):M_A_MA(5)
  U5D1  F59 DDR0_MA<5> SKX_EXT_B_BGA1-IC,TBD   I172 @BASEBOARD_FAB2_LIB.BASEBOARD_FAB2(SCH_1):PAGE23
  J4G1  213     A5 SCONN288_H44441004_PIP-SCONN,HA     I1 @BASEBOARD_FAB2_LIB.BASEBOARD_FAB2(SCH_1):PAGE43
  J6T1  213     A5 SCONN288_H44441003_PIP-SCONN,HA    I13 @BASEBOARD_FAB2_LIB.BASEBOARD_FAB2(SCH_1):PAGE44

M_A_MA<6> @BASEBOARD_FAB2_LIB.BASEBOARD_FAB2(SCH_1):M_A_MA(6)
  U5D1  D59 DDR0_MA<6> SKX_EXT_B_BGA1-IC,TBD   I172 @BASEBOARD_FAB2_LIB.BASEBOARD_FAB2(SCH_1):PAGE23
  J4G1   69     A6 SCONN288_H44441004_PIP-SCONN,HA     I1 @BASEBOARD_FAB2_LIB.BASEBOARD_FAB2(SCH_1):PAGE43
  J6T1   69     A6 SCONN288_H44441003_PIP-SCONN,HA    I13 @BASEBOARD_FAB2_LIB.BASEBOARD_FAB2(SCH_1):PAGE44

M_A_MA<7> @BASEBOARD_FAB2_LIB.BASEBOARD_FAB2(SCH_1):M_A_MA(7)
  U5D1  G60 DDR0_MA<7> SKX_EXT_B_BGA1-IC,TBD   I172 @BASEBOARD_FAB2_LIB.BASEBOARD_FAB2(SCH_1):PAGE23
  J4G1  211     A7 SCONN288_H44441004_PIP-SCONN,HA     I1 @BASEBOARD_FAB2_LIB.BASEBOARD_FAB2(SCH_1):PAGE43
  J6T1  211     A7 SCONN288_H44441003_PIP-SCONN,HA    I13 @BASEBOARD_FAB2_LIB.BASEBOARD_FAB2(SCH_1):PAGE44

M_A_MA<8> @BASEBOARD_FAB2_LIB.BASEBOARD_FAB2(SCH_1):M_A_MA(8)
  U5D1  C60 DDR0_MA<8> SKX_EXT_B_BGA1-IC,TBD   I172 @BASEBOARD_FAB2_LIB.BASEBOARD_FAB2(SCH_1):PAGE23
  J4G1   68     A8 SCONN288_H44441004_PIP-SCONN,HA     I1 @BASEBOARD_FAB2_LIB.BASEBOARD_FAB2(SCH_1):PAGE43
  J6T1   68     A8 SCONN288_H44441003_PIP-SCONN,HA    I13 @BASEBOARD_FAB2_LIB.BASEBOARD_FAB2(SCH_1):PAGE44

M_A_MA<9> @BASEBOARD_FAB2_LIB.BASEBOARD_FAB2(SCH_1):M_A_MA(9)
  U5D1  F61 DDR0_MA<9> SKX_EXT_B_BGA1-IC,TBD   I172 @BASEBOARD_FAB2_LIB.BASEBOARD_FAB2(SCH_1):PAGE23
  J4G1   66     A9 SCONN288_H44441004_PIP-SCONN,HA     I1 @BASEBOARD_FAB2_LIB.BASEBOARD_FAB2(SCH_1):PAGE43
  J6T1   66     A9 SCONN288_H44441003_PIP-SCONN,HA    I13 @BASEBOARD_FAB2_LIB.BASEBOARD_FAB2(SCH_1):PAGE44

M_A_ODT<0> @BASEBOARD_FAB2_LIB.BASEBOARD_FAB2(SCH_1):M_A_ODT(0)
  U5D1  C50 DDR0_ODT<0> SKX_EXT_B_BGA1-IC,TBD   I172 @BASEBOARD_FAB2_LIB.BASEBOARD_FAB2(SCH_1):PAGE23
  J4G1   87 ODT<0> SCONN288_H44441004_PIP-SCONN,HA     I1 @BASEBOARD_FAB2_LIB.BASEBOARD_FAB2(SCH_1):PAGE43

M_A_ODT<1> @BASEBOARD_FAB2_LIB.BASEBOARD_FAB2(SCH_1):M_A_ODT(1)
  U5D1  C48 DDR0_ODT<1> SKX_EXT_B_BGA1-IC,TBD   I172 @BASEBOARD_FAB2_LIB.BASEBOARD_FAB2(SCH_1):PAGE23
  J4G1   91 ODT<1> SCONN288_H44441004_PIP-SCONN,HA     I1 @BASEBOARD_FAB2_LIB.BASEBOARD_FAB2(SCH_1):PAGE43

M_A_ODT<2> @BASEBOARD_FAB2_LIB.BASEBOARD_FAB2(SCH_1):M_A_ODT(2)
  U5D1  G50 DDR0_ODT<2> SKX_EXT_B_BGA1-IC,TBD   I172 @BASEBOARD_FAB2_LIB.BASEBOARD_FAB2(SCH_1):PAGE23
  J6T1   87 ODT<0> SCONN288_H44441003_PIP-SCONN,HA    I13 @BASEBOARD_FAB2_LIB.BASEBOARD_FAB2(SCH_1):PAGE44

M_A_ODT<3> @BASEBOARD_FAB2_LIB.BASEBOARD_FAB2(SCH_1):M_A_ODT(3)
  U5D1  G48 DDR0_ODT<3> SKX_EXT_B_BGA1-IC,TBD   I172 @BASEBOARD_FAB2_LIB.BASEBOARD_FAB2(SCH_1):PAGE23
  J6T1   91 ODT<1> SCONN288_H44441003_PIP-SCONN,HA    I13 @BASEBOARD_FAB2_LIB.BASEBOARD_FAB2(SCH_1):PAGE44

M_A_PAR @BASEBOARD_FAB2_LIB.BASEBOARD_FAB2(SCH_1):M_A_PAR
  U5D1  D53 DDR0_PAR SKX_EXT_B_BGA1-IC,TBD   I172 @BASEBOARD_FAB2_LIB.BASEBOARD_FAB2(SCH_1):PAGE23
  J4G1  222    PAR SCONN288_H44441004_PIP-SCONN,HA     I1 @BASEBOARD_FAB2_LIB.BASEBOARD_FAB2(SCH_1):PAGE43
  J6T1  222    PAR SCONN288_H44441003_PIP-SCONN,HA    I13 @BASEBOARD_FAB2_LIB.BASEBOARD_FAB2(SCH_1):PAGE44

M_A_VREF @BASEBOARD_FAB2_LIB.BASEBOARD_FAB2(SCH_1):M_A_VREF
  J4G1  146 VREFCA SCONN288_H44441004_PIP-SCONN,HA     I1 @BASEBOARD_FAB2_LIB.BASEBOARD_FAB2(SCH_1):PAGE43
 C4F10    1      A CAP_A_0402V-0.01UF,25V,10%,X7RA   I272 @BASEBOARD_FAB2_LIB.BASEBOARD_FAB2(SCH_1):PAGE43
  C6T1    1      A CAP_A_0402V-0.01UF,25V,10%,X7RA     I2 @BASEBOARD_FAB2_LIB.BASEBOARD_FAB2(SCH_1):PAGE44
  J6T1  146 VREFCA SCONN288_H44441003_PIP-SCONN,HA    I13 @BASEBOARD_FAB2_LIB.BASEBOARD_FAB2(SCH_1):PAGE44
  R4F5    1      A RES_0402-1.00K,1%,1/16W,CHIP,GA     I4 @BASEBOARD_FAB2_LIB.BASEBOARD_FAB2(SCH_1):PAGE98
  R4F3    2      B RES_0402-2,1.0%,1/16W,CHIP,G21A     I5 @BASEBOARD_FAB2_LIB.BASEBOARD_FAB2(SCH_1):PAGE98
  R4F4    2      B RES_0402-1.00K,1%,1/16W,CHIP,GA    I36 @BASEBOARD_FAB2_LIB.BASEBOARD_FAB2(SCH_1):PAGE98

M_B_ACT_N @BASEBOARD_FAB2_LIB.BASEBOARD_FAB2(SCH_1):M_B_ACT_N
  U5D1  T63 DDR1_ACT_N SKX_EXT_B_BGA1-IC,TBD   I172 @BASEBOARD_FAB2_LIB.BASEBOARD_FAB2(SCH_1):PAGE24
  J4G2   62  ACT_N SCONN288_H44441004_PIP-SCONN,HA   I111 @BASEBOARD_FAB2_LIB.BASEBOARD_FAB2(SCH_1):PAGE45
  J6U1   62  ACT_N SCONN288_H44441003_PIP-SCONN,HA    I14 @BASEBOARD_FAB2_LIB.BASEBOARD_FAB2(SCH_1):PAGE46

M_B_ALERT_N @BASEBOARD_FAB2_LIB.BASEBOARD_FAB2(SCH_1):M_B_ALERT_N
  U5D1  W62 DDR1_ALERT_N SKX_EXT_B_BGA1-IC,TBD   I172 @BASEBOARD_FAB2_LIB.BASEBOARD_FAB2(SCH_1):PAGE24
  J4G2  208 ALERT_N SCONN288_H44441004_PIP-SCONN,HA   I111 @BASEBOARD_FAB2_LIB.BASEBOARD_FAB2(SCH_1):PAGE45
  J6U1  208 ALERT_N SCONN288_H44441003_PIP-SCONN,HA    I14 @BASEBOARD_FAB2_LIB.BASEBOARD_FAB2(SCH_1):PAGE46

M_B_BA<0> @BASEBOARD_FAB2_LIB.BASEBOARD_FAB2(SCH_1):M_B_BA(0)
  U5D1  T53 DDR1_BA<0> SKX_EXT_B_BGA1-IC,TBD   I172 @BASEBOARD_FAB2_LIB.BASEBOARD_FAB2(SCH_1):PAGE24
  J4G2   81  BA<0> SCONN288_H44441004_PIP-SCONN,HA   I111 @BASEBOARD_FAB2_LIB.BASEBOARD_FAB2(SCH_1):PAGE45
  J6U1   81  BA<0> SCONN288_H44441003_PIP-SCONN,HA    I14 @BASEBOARD_FAB2_LIB.BASEBOARD_FAB2(SCH_1):PAGE46

M_B_BA<1> @BASEBOARD_FAB2_LIB.BASEBOARD_FAB2(SCH_1):M_B_BA(1)
  U5D1  K55 DDR1_BA<1> SKX_EXT_B_BGA1-IC,TBD   I172 @BASEBOARD_FAB2_LIB.BASEBOARD_FAB2(SCH_1):PAGE24
  J4G2  224  BA<1> SCONN288_H44441004_PIP-SCONN,HA   I111 @BASEBOARD_FAB2_LIB.BASEBOARD_FAB2(SCH_1):PAGE45
  J6U1  224  BA<1> SCONN288_H44441003_PIP-SCONN,HA    I14 @BASEBOARD_FAB2_LIB.BASEBOARD_FAB2(SCH_1):PAGE46

M_B_BG<0> @BASEBOARD_FAB2_LIB.BASEBOARD_FAB2(SCH_1):M_B_BG(0)
  U5D1  M61 DDR1_BG<0> SKX_EXT_B_BGA1-IC,TBD   I172 @BASEBOARD_FAB2_LIB.BASEBOARD_FAB2(SCH_1):PAGE24
  J4G2   63  BG<0> SCONN288_H44441004_PIP-SCONN,HA   I111 @BASEBOARD_FAB2_LIB.BASEBOARD_FAB2(SCH_1):PAGE45
  J6U1   63  BG<0> SCONN288_H44441003_PIP-SCONN,HA    I14 @BASEBOARD_FAB2_LIB.BASEBOARD_FAB2(SCH_1):PAGE46

M_B_BG<1> @BASEBOARD_FAB2_LIB.BASEBOARD_FAB2(SCH_1):M_B_BG(1)
  U5D1  N60 DDR1_BG<1> SKX_EXT_B_BGA1-IC,TBD   I172 @BASEBOARD_FAB2_LIB.BASEBOARD_FAB2(SCH_1):PAGE24
  J4G2  207  BG<1> SCONN288_H44441004_PIP-SCONN,HA   I111 @BASEBOARD_FAB2_LIB.BASEBOARD_FAB2(SCH_1):PAGE45
  J6U1  207  BG<1> SCONN288_H44441003_PIP-SCONN,HA    I14 @BASEBOARD_FAB2_LIB.BASEBOARD_FAB2(SCH_1):PAGE46

M_B_C<2> @BASEBOARD_FAB2_LIB.BASEBOARD_FAB2(SCH_1):M_B_C(2)
  U5D1  M47 DDR1_CID<2> SKX_EXT_B_BGA1-IC,TBD   I172 @BASEBOARD_FAB2_LIB.BASEBOARD_FAB2(SCH_1):PAGE24
  J4G2  235   C<2> SCONN288_H44441004_PIP-SCONN,HA   I111 @BASEBOARD_FAB2_LIB.BASEBOARD_FAB2(SCH_1):PAGE45
  J6U1  235   C<2> SCONN288_H44441003_PIP-SCONN,HA    I14 @BASEBOARD_FAB2_LIB.BASEBOARD_FAB2(SCH_1):PAGE46

M_B_CKE<0> @BASEBOARD_FAB2_LIB.BASEBOARD_FAB2(SCH_1):M_B_CKE(0)
  U5D1  N62 DDR1_CKE<0> SKX_EXT_B_BGA1-IC,TBD   I172 @BASEBOARD_FAB2_LIB.BASEBOARD_FAB2(SCH_1):PAGE24
  J4G2   60 CKE<0> SCONN288_H44441004_PIP-SCONN,HA   I111 @BASEBOARD_FAB2_LIB.BASEBOARD_FAB2(SCH_1):PAGE45

M_B_CKE<1> @BASEBOARD_FAB2_LIB.BASEBOARD_FAB2(SCH_1):M_B_CKE(1)
  U5D1  R64 DDR1_CKE<1> SKX_EXT_B_BGA1-IC,TBD   I172 @BASEBOARD_FAB2_LIB.BASEBOARD_FAB2(SCH_1):PAGE24
  J4G2  203 CKE<1> SCONN288_H44441004_PIP-SCONN,HA   I111 @BASEBOARD_FAB2_LIB.BASEBOARD_FAB2(SCH_1):PAGE45

M_B_CKE<2> @BASEBOARD_FAB2_LIB.BASEBOARD_FAB2(SCH_1):M_B_CKE(2)
  U5D1  K63 DDR1_CKE<2> SKX_EXT_B_BGA1-IC,TBD   I172 @BASEBOARD_FAB2_LIB.BASEBOARD_FAB2(SCH_1):PAGE24
  J6U1   60 CKE<0> SCONN288_H44441003_PIP-SCONN,HA    I14 @BASEBOARD_FAB2_LIB.BASEBOARD_FAB2(SCH_1):PAGE46

M_B_CKE<3> @BASEBOARD_FAB2_LIB.BASEBOARD_FAB2(SCH_1):M_B_CKE(3)
  U5D1  L64 DDR1_CKE<3> SKX_EXT_B_BGA1-IC,TBD   I172 @BASEBOARD_FAB2_LIB.BASEBOARD_FAB2(SCH_1):PAGE24
  J6U1  203 CKE<1> SCONN288_H44441003_PIP-SCONN,HA    I14 @BASEBOARD_FAB2_LIB.BASEBOARD_FAB2(SCH_1):PAGE46

M_B_CLK_DN<0> @BASEBOARD_FAB2_LIB.BASEBOARD_FAB2(SCH_1):M_B_CLK_DN(0)
  U5D1  M53 DDR1_CLK_DN<0> SKX_EXT_B_BGA1-IC,TBD   I172 @BASEBOARD_FAB2_LIB.BASEBOARD_FAB2(SCH_1):PAGE24
  J4G2   75   CK0N SCONN288_H44441004_PIP-SCONN,HA   I111 @BASEBOARD_FAB2_LIB.BASEBOARD_FAB2(SCH_1):PAGE45

M_B_CLK_DN<1> @BASEBOARD_FAB2_LIB.BASEBOARD_FAB2(SCH_1):M_B_CLK_DN(1)
  U5D1  R54 DDR1_CLK_DN<1> SKX_EXT_B_BGA1-IC,TBD   I172 @BASEBOARD_FAB2_LIB.BASEBOARD_FAB2(SCH_1):PAGE24
  J4G2  219   CK1N SCONN288_H44441004_PIP-SCONN,HA   I111 @BASEBOARD_FAB2_LIB.BASEBOARD_FAB2(SCH_1):PAGE45

M_B_CLK_DN<2> @BASEBOARD_FAB2_LIB.BASEBOARD_FAB2(SCH_1):M_B_CLK_DN(2)
  U5D1  N56 DDR1_CLK_DN<2> SKX_EXT_B_BGA1-IC,TBD   I172 @BASEBOARD_FAB2_LIB.BASEBOARD_FAB2(SCH_1):PAGE24
  J6U1   75   CK0N SCONN288_H44441003_PIP-SCONN,HA    I14 @BASEBOARD_FAB2_LIB.BASEBOARD_FAB2(SCH_1):PAGE46

M_B_CLK_DN<3> @BASEBOARD_FAB2_LIB.BASEBOARD_FAB2(SCH_1):M_B_CLK_DN(3)
  U5D1  R56 DDR1_CLK_DN<3> SKX_EXT_B_BGA1-IC,TBD   I172 @BASEBOARD_FAB2_LIB.BASEBOARD_FAB2(SCH_1):PAGE24
  J6U1  219   CK1N SCONN288_H44441003_PIP-SCONN,HA    I14 @BASEBOARD_FAB2_LIB.BASEBOARD_FAB2(SCH_1):PAGE46

M_B_CLK_DP<0> @BASEBOARD_FAB2_LIB.BASEBOARD_FAB2(SCH_1):M_B_CLK_DP(0)
  U5D1  N54 DDR1_CLK_DP<0> SKX_EXT_B_BGA1-IC,TBD   I172 @BASEBOARD_FAB2_LIB.BASEBOARD_FAB2(SCH_1):PAGE24
  J4G2   74   CK0P SCONN288_H44441004_PIP-SCONN,HA   I111 @BASEBOARD_FAB2_LIB.BASEBOARD_FAB2(SCH_1):PAGE45

M_B_CLK_DP<1> @BASEBOARD_FAB2_LIB.BASEBOARD_FAB2(SCH_1):M_B_CLK_DP(1)
  U5D1  T55 DDR1_CLK_DP<1> SKX_EXT_B_BGA1-IC,TBD   I172 @BASEBOARD_FAB2_LIB.BASEBOARD_FAB2(SCH_1):PAGE24
  J4G2  218   CK1P SCONN288_H44441004_PIP-SCONN,HA   I111 @BASEBOARD_FAB2_LIB.BASEBOARD_FAB2(SCH_1):PAGE45

M_B_CLK_DP<2> @BASEBOARD_FAB2_LIB.BASEBOARD_FAB2(SCH_1):M_B_CLK_DP(2)
  U5D1  M57 DDR1_CLK_DP<2> SKX_EXT_B_BGA1-IC,TBD   I172 @BASEBOARD_FAB2_LIB.BASEBOARD_FAB2(SCH_1):PAGE24
  J6U1   74   CK0P SCONN288_H44441003_PIP-SCONN,HA    I14 @BASEBOARD_FAB2_LIB.BASEBOARD_FAB2(SCH_1):PAGE46

M_B_CLK_DP<3> @BASEBOARD_FAB2_LIB.BASEBOARD_FAB2(SCH_1):M_B_CLK_DP(3)
  U5D1  T57 DDR1_CLK_DP<3> SKX_EXT_B_BGA1-IC,TBD   I172 @BASEBOARD_FAB2_LIB.BASEBOARD_FAB2(SCH_1):PAGE24
  J6U1  218   CK1P SCONN288_H44441003_PIP-SCONN,HA    I14 @BASEBOARD_FAB2_LIB.BASEBOARD_FAB2(SCH_1):PAGE46

M_B_CPU_VREF @BASEBOARD_FAB2_LIB.BASEBOARD_FAB2(SCH_1):M_B_CPU_VREF
  U5D1 AK63 DDR1_CAVREF SKX_EXT_B_BGA1-IC,TBD   I259 @BASEBOARD_FAB2_LIB.BASEBOARD_FAB2(SCH_1):PAGE21
  R4G1    1      A RES_0402-2,1.0%,1/16W,CHIP,G21A    I42 @BASEBOARD_FAB2_LIB.BASEBOARD_FAB2(SCH_1):PAGE98
  C4G1    1      A CAP_A_0402V-0.01UF,25V,10%,X7RA    I43 @BASEBOARD_FAB2_LIB.BASEBOARD_FAB2(SCH_1):PAGE98

M_B_CS_N<0> @BASEBOARD_FAB2_LIB.BASEBOARD_FAB2(SCH_1):M_B_CS_N(0)
  U5D1  K51 DDR1_CS_N<0> SKX_EXT_B_BGA1-IC,TBD   I172 @BASEBOARD_FAB2_LIB.BASEBOARD_FAB2(SCH_1):PAGE24
  J4G2   84   S0_N SCONN288_H44441004_PIP-SCONN,HA   I111 @BASEBOARD_FAB2_LIB.BASEBOARD_FAB2(SCH_1):PAGE45

M_B_CS_N<1> @BASEBOARD_FAB2_LIB.BASEBOARD_FAB2(SCH_1):M_B_CS_N(1)
  U5D1  R50 DDR1_CS_N<1> SKX_EXT_B_BGA1-IC,TBD   I172 @BASEBOARD_FAB2_LIB.BASEBOARD_FAB2(SCH_1):PAGE24
  J4G2   89   S1_N SCONN288_H44441004_PIP-SCONN,HA   I111 @BASEBOARD_FAB2_LIB.BASEBOARD_FAB2(SCH_1):PAGE45

M_B_CS_N<2> @BASEBOARD_FAB2_LIB.BASEBOARD_FAB2(SCH_1):M_B_CS_N(2)
  U5D1  N46 DDR1_CS_N<2> SKX_EXT_B_BGA1-IC,TBD   I172 @BASEBOARD_FAB2_LIB.BASEBOARD_FAB2(SCH_1):PAGE24
  J4G2   93 S2_N_C<0> SCONN288_H44441004_PIP-SCONN,HA   I111 @BASEBOARD_FAB2_LIB.BASEBOARD_FAB2(SCH_1):PAGE45

M_B_CS_N<3> @BASEBOARD_FAB2_LIB.BASEBOARD_FAB2(SCH_1):M_B_CS_N(3)
  U5D1  V47 DDR1_CS_N<3> SKX_EXT_B_BGA1-IC,TBD   I172 @BASEBOARD_FAB2_LIB.BASEBOARD_FAB2(SCH_1):PAGE24
  J4G2  237 S3_N_C<1> SCONN288_H44441004_PIP-SCONN,HA   I111 @BASEBOARD_FAB2_LIB.BASEBOARD_FAB2(SCH_1):PAGE45

M_B_CS_N<4> @BASEBOARD_FAB2_LIB.BASEBOARD_FAB2(SCH_1):M_B_CS_N(4)
  U5D1  J50 DDR1_CS_N<4> SKX_EXT_B_BGA1-IC,TBD   I172 @BASEBOARD_FAB2_LIB.BASEBOARD_FAB2(SCH_1):PAGE24
  J6U1   84   S0_N SCONN288_H44441003_PIP-SCONN,HA    I14 @BASEBOARD_FAB2_LIB.BASEBOARD_FAB2(SCH_1):PAGE46

M_B_CS_N<5> @BASEBOARD_FAB2_LIB.BASEBOARD_FAB2(SCH_1):M_B_CS_N(5)
  U5D1  T49 DDR1_CS_N<5> SKX_EXT_B_BGA1-IC,TBD   I172 @BASEBOARD_FAB2_LIB.BASEBOARD_FAB2(SCH_1):PAGE24
  J6U1   89   S1_N SCONN288_H44441003_PIP-SCONN,HA    I14 @BASEBOARD_FAB2_LIB.BASEBOARD_FAB2(SCH_1):PAGE46

M_B_CS_N<6> @BASEBOARD_FAB2_LIB.BASEBOARD_FAB2(SCH_1):M_B_CS_N(6)
  U5D1  M45 DDR1_CS_N<6> SKX_EXT_B_BGA1-IC,TBD   I172 @BASEBOARD_FAB2_LIB.BASEBOARD_FAB2(SCH_1):PAGE24
  J6U1   93 S2_N_C<0> SCONN288_H44441003_PIP-SCONN,HA    I14 @BASEBOARD_FAB2_LIB.BASEBOARD_FAB2(SCH_1):PAGE46

M_B_CS_N<7> @BASEBOARD_FAB2_LIB.BASEBOARD_FAB2(SCH_1):M_B_CS_N(7)
  U5D1  R46 DDR1_CS_N<7> SKX_EXT_B_BGA1-IC,TBD   I172 @BASEBOARD_FAB2_LIB.BASEBOARD_FAB2(SCH_1):PAGE24
  J6U1  237 S3_N_C<1> SCONN288_H44441003_PIP-SCONN,HA    I14 @BASEBOARD_FAB2_LIB.BASEBOARD_FAB2(SCH_1):PAGE46

M_B_DQ<0> @BASEBOARD_FAB2_LIB.BASEBOARD_FAB2(SCH_1):M_B_DQ(0)
  U5D1 AV81 DDR1_DQ<0> SKX_EXT_B_BGA1-IC,TBD   I172 @BASEBOARD_FAB2_LIB.BASEBOARD_FAB2(SCH_1):PAGE24
  J4G2  150  DQ<1> SCONN288_H44441004_PIP-SCONN,HA   I111 @BASEBOARD_FAB2_LIB.BASEBOARD_FAB2(SCH_1):PAGE45
  J6U1    5  DQ<0> SCONN288_H44441003_PIP-SCONN,HA    I14 @BASEBOARD_FAB2_LIB.BASEBOARD_FAB2(SCH_1):PAGE46

M_B_DQ<10> @BASEBOARD_FAB2_LIB.BASEBOARD_FAB2(SCH_1):M_B_DQ(10)
  U5D1 AC82 DDR1_DQ<10> SKX_EXT_B_BGA1-IC,TBD   I172 @BASEBOARD_FAB2_LIB.BASEBOARD_FAB2(SCH_1):PAGE24
  J4G2  168 DQ<11> SCONN288_H44441004_PIP-SCONN,HA   I111 @BASEBOARD_FAB2_LIB.BASEBOARD_FAB2(SCH_1):PAGE45
  J6U1   23 DQ<10> SCONN288_H44441003_PIP-SCONN,HA    I14 @BASEBOARD_FAB2_LIB.BASEBOARD_FAB2(SCH_1):PAGE46

M_B_DQ<11> @BASEBOARD_FAB2_LIB.BASEBOARD_FAB2(SCH_1):M_B_DQ(11)
  U5D1 AB81 DDR1_DQ<11> SKX_EXT_B_BGA1-IC,TBD   I172 @BASEBOARD_FAB2_LIB.BASEBOARD_FAB2(SCH_1):PAGE24
  J4G2   23 DQ<10> SCONN288_H44441004_PIP-SCONN,HA   I111 @BASEBOARD_FAB2_LIB.BASEBOARD_FAB2(SCH_1):PAGE45
  J6U1  168 DQ<11> SCONN288_H44441003_PIP-SCONN,HA    I14 @BASEBOARD_FAB2_LIB.BASEBOARD_FAB2(SCH_1):PAGE46

M_B_DQ<12> @BASEBOARD_FAB2_LIB.BASEBOARD_FAB2(SCH_1):M_B_DQ(12)
  U5D1 AJ80 DDR1_DQ<12> SKX_EXT_B_BGA1-IC,TBD   I172 @BASEBOARD_FAB2_LIB.BASEBOARD_FAB2(SCH_1):PAGE24
  J4G2  159 DQ<13> SCONN288_H44441004_PIP-SCONN,HA   I111 @BASEBOARD_FAB2_LIB.BASEBOARD_FAB2(SCH_1):PAGE45
  J6U1   14 DQ<12> SCONN288_H44441003_PIP-SCONN,HA    I14 @BASEBOARD_FAB2_LIB.BASEBOARD_FAB2(SCH_1):PAGE46

M_B_DQ<13> @BASEBOARD_FAB2_LIB.BASEBOARD_FAB2(SCH_1):M_B_DQ(13)
  U5D1 AH79 DDR1_DQ<13> SKX_EXT_B_BGA1-IC,TBD   I172 @BASEBOARD_FAB2_LIB.BASEBOARD_FAB2(SCH_1):PAGE24
  J4G2   14 DQ<12> SCONN288_H44441004_PIP-SCONN,HA   I111 @BASEBOARD_FAB2_LIB.BASEBOARD_FAB2(SCH_1):PAGE45
  J6U1  159 DQ<13> SCONN288_H44441003_PIP-SCONN,HA    I14 @BASEBOARD_FAB2_LIB.BASEBOARD_FAB2(SCH_1):PAGE46

M_B_DQ<14> @BASEBOARD_FAB2_LIB.BASEBOARD_FAB2(SCH_1):M_B_DQ(14)
  U5D1 AE82 DDR1_DQ<14> SKX_EXT_B_BGA1-IC,TBD   I172 @BASEBOARD_FAB2_LIB.BASEBOARD_FAB2(SCH_1):PAGE24
  J4G2  166 DQ<15> SCONN288_H44441004_PIP-SCONN,HA   I111 @BASEBOARD_FAB2_LIB.BASEBOARD_FAB2(SCH_1):PAGE45
  J6U1   21 DQ<14> SCONN288_H44441003_PIP-SCONN,HA    I14 @BASEBOARD_FAB2_LIB.BASEBOARD_FAB2(SCH_1):PAGE46

M_B_DQ<15> @BASEBOARD_FAB2_LIB.BASEBOARD_FAB2(SCH_1):M_B_DQ(15)
  U5D1 AC80 DDR1_DQ<15> SKX_EXT_B_BGA1-IC,TBD   I172 @BASEBOARD_FAB2_LIB.BASEBOARD_FAB2(SCH_1):PAGE24
  J4G2   21 DQ<14> SCONN288_H44441004_PIP-SCONN,HA   I111 @BASEBOARD_FAB2_LIB.BASEBOARD_FAB2(SCH_1):PAGE45
  J6U1  166 DQ<15> SCONN288_H44441003_PIP-SCONN,HA    I14 @BASEBOARD_FAB2_LIB.BASEBOARD_FAB2(SCH_1):PAGE46

M_B_DQ<16> @BASEBOARD_FAB2_LIB.BASEBOARD_FAB2(SCH_1):M_B_DQ(16)
  U5D1  E80 DDR1_DQ<16> SKX_EXT_B_BGA1-IC,TBD   I172 @BASEBOARD_FAB2_LIB.BASEBOARD_FAB2(SCH_1):PAGE24
  J4G2  172 DQ<17> SCONN288_H44441004_PIP-SCONN,HA   I111 @BASEBOARD_FAB2_LIB.BASEBOARD_FAB2(SCH_1):PAGE45
  J6U1   27 DQ<16> SCONN288_H44441003_PIP-SCONN,HA    I14 @BASEBOARD_FAB2_LIB.BASEBOARD_FAB2(SCH_1):PAGE46

M_B_DQ<17> @BASEBOARD_FAB2_LIB.BASEBOARD_FAB2(SCH_1):M_B_DQ(17)
  U5D1  J80 DDR1_DQ<17> SKX_EXT_B_BGA1-IC,TBD   I172 @BASEBOARD_FAB2_LIB.BASEBOARD_FAB2(SCH_1):PAGE24
  J4G2   27 DQ<16> SCONN288_H44441004_PIP-SCONN,HA   I111 @BASEBOARD_FAB2_LIB.BASEBOARD_FAB2(SCH_1):PAGE45
  J6U1  172 DQ<17> SCONN288_H44441003_PIP-SCONN,HA    I14 @BASEBOARD_FAB2_LIB.BASEBOARD_FAB2(SCH_1):PAGE46

M_B_DQ<18> @BASEBOARD_FAB2_LIB.BASEBOARD_FAB2(SCH_1):M_B_DQ(18)
  U5D1  F77 DDR1_DQ<18> SKX_EXT_B_BGA1-IC,TBD   I172 @BASEBOARD_FAB2_LIB.BASEBOARD_FAB2(SCH_1):PAGE24
  J4G2  179 DQ<19> SCONN288_H44441004_PIP-SCONN,HA   I111 @BASEBOARD_FAB2_LIB.BASEBOARD_FAB2(SCH_1):PAGE45
  J6U1   34 DQ<18> SCONN288_H44441003_PIP-SCONN,HA    I14 @BASEBOARD_FAB2_LIB.BASEBOARD_FAB2(SCH_1):PAGE46

M_B_DQ<19> @BASEBOARD_FAB2_LIB.BASEBOARD_FAB2(SCH_1):M_B_DQ(19)
  U5D1  H77 DDR1_DQ<19> SKX_EXT_B_BGA1-IC,TBD   I172 @BASEBOARD_FAB2_LIB.BASEBOARD_FAB2(SCH_1):PAGE24
  J4G2   34 DQ<18> SCONN288_H44441004_PIP-SCONN,HA   I111 @BASEBOARD_FAB2_LIB.BASEBOARD_FAB2(SCH_1):PAGE45
  J6U1  179 DQ<19> SCONN288_H44441003_PIP-SCONN,HA    I14 @BASEBOARD_FAB2_LIB.BASEBOARD_FAB2(SCH_1):PAGE46

M_B_DQ<1> @BASEBOARD_FAB2_LIB.BASEBOARD_FAB2(SCH_1):M_B_DQ(1)
  U5D1 AT79 DDR1_DQ<1> SKX_EXT_B_BGA1-IC,TBD   I172 @BASEBOARD_FAB2_LIB.BASEBOARD_FAB2(SCH_1):PAGE24
  J4G2    5  DQ<0> SCONN288_H44441004_PIP-SCONN,HA   I111 @BASEBOARD_FAB2_LIB.BASEBOARD_FAB2(SCH_1):PAGE45
  J6U1  150  DQ<1> SCONN288_H44441003_PIP-SCONN,HA    I14 @BASEBOARD_FAB2_LIB.BASEBOARD_FAB2(SCH_1):PAGE46

M_B_DQ<20> @BASEBOARD_FAB2_LIB.BASEBOARD_FAB2(SCH_1):M_B_DQ(20)
  U5D1  F81 DDR1_DQ<20> SKX_EXT_B_BGA1-IC,TBD   I172 @BASEBOARD_FAB2_LIB.BASEBOARD_FAB2(SCH_1):PAGE24
  J4G2  170 DQ<21> SCONN288_H44441004_PIP-SCONN,HA   I111 @BASEBOARD_FAB2_LIB.BASEBOARD_FAB2(SCH_1):PAGE45
  J6U1   25 DQ<20> SCONN288_H44441003_PIP-SCONN,HA    I14 @BASEBOARD_FAB2_LIB.BASEBOARD_FAB2(SCH_1):PAGE46

M_B_DQ<21> @BASEBOARD_FAB2_LIB.BASEBOARD_FAB2(SCH_1):M_B_DQ(21)
  U5D1  H81 DDR1_DQ<21> SKX_EXT_B_BGA1-IC,TBD   I172 @BASEBOARD_FAB2_LIB.BASEBOARD_FAB2(SCH_1):PAGE24
  J4G2   25 DQ<20> SCONN288_H44441004_PIP-SCONN,HA   I111 @BASEBOARD_FAB2_LIB.BASEBOARD_FAB2(SCH_1):PAGE45
  J6U1  170 DQ<21> SCONN288_H44441003_PIP-SCONN,HA    I14 @BASEBOARD_FAB2_LIB.BASEBOARD_FAB2(SCH_1):PAGE46

M_B_DQ<22> @BASEBOARD_FAB2_LIB.BASEBOARD_FAB2(SCH_1):M_B_DQ(22)
  U5D1  E78 DDR1_DQ<22> SKX_EXT_B_BGA1-IC,TBD   I172 @BASEBOARD_FAB2_LIB.BASEBOARD_FAB2(SCH_1):PAGE24
  J4G2  177 DQ<23> SCONN288_H44441004_PIP-SCONN,HA   I111 @BASEBOARD_FAB2_LIB.BASEBOARD_FAB2(SCH_1):PAGE45
  J6U1   32 DQ<22> SCONN288_H44441003_PIP-SCONN,HA    I14 @BASEBOARD_FAB2_LIB.BASEBOARD_FAB2(SCH_1):PAGE46

M_B_DQ<23> @BASEBOARD_FAB2_LIB.BASEBOARD_FAB2(SCH_1):M_B_DQ(23)
  U5D1  J78 DDR1_DQ<23> SKX_EXT_B_BGA1-IC,TBD   I172 @BASEBOARD_FAB2_LIB.BASEBOARD_FAB2(SCH_1):PAGE24
  J4G2   32 DQ<22> SCONN288_H44441004_PIP-SCONN,HA   I111 @BASEBOARD_FAB2_LIB.BASEBOARD_FAB2(SCH_1):PAGE45
  J6U1  177 DQ<23> SCONN288_H44441003_PIP-SCONN,HA    I14 @BASEBOARD_FAB2_LIB.BASEBOARD_FAB2(SCH_1):PAGE46

M_B_DQ<24> @BASEBOARD_FAB2_LIB.BASEBOARD_FAB2(SCH_1):M_B_DQ(24)
  U5D1  D75 DDR1_DQ<24> SKX_EXT_B_BGA1-IC,TBD   I172 @BASEBOARD_FAB2_LIB.BASEBOARD_FAB2(SCH_1):PAGE24
  J4G2  183 DQ<25> SCONN288_H44441004_PIP-SCONN,HA   I111 @BASEBOARD_FAB2_LIB.BASEBOARD_FAB2(SCH_1):PAGE45
  J6U1   38 DQ<24> SCONN288_H44441003_PIP-SCONN,HA    I14 @BASEBOARD_FAB2_LIB.BASEBOARD_FAB2(SCH_1):PAGE46

M_B_DQ<25> @BASEBOARD_FAB2_LIB.BASEBOARD_FAB2(SCH_1):M_B_DQ(25)
  U5D1  C74 DDR1_DQ<25> SKX_EXT_B_BGA1-IC,TBD   I172 @BASEBOARD_FAB2_LIB.BASEBOARD_FAB2(SCH_1):PAGE24
  J4G2   38 DQ<24> SCONN288_H44441004_PIP-SCONN,HA   I111 @BASEBOARD_FAB2_LIB.BASEBOARD_FAB2(SCH_1):PAGE45
  J6U1  183 DQ<25> SCONN288_H44441003_PIP-SCONN,HA    I14 @BASEBOARD_FAB2_LIB.BASEBOARD_FAB2(SCH_1):PAGE46

M_B_DQ<26> @BASEBOARD_FAB2_LIB.BASEBOARD_FAB2(SCH_1):M_B_DQ(26)
  U5D1  D71 DDR1_DQ<26> SKX_EXT_B_BGA1-IC,TBD   I172 @BASEBOARD_FAB2_LIB.BASEBOARD_FAB2(SCH_1):PAGE24
  J4G2  190 DQ<27> SCONN288_H44441004_PIP-SCONN,HA   I111 @BASEBOARD_FAB2_LIB.BASEBOARD_FAB2(SCH_1):PAGE45
  J6U1   45 DQ<26> SCONN288_H44441003_PIP-SCONN,HA    I14 @BASEBOARD_FAB2_LIB.BASEBOARD_FAB2(SCH_1):PAGE46

M_B_DQ<27> @BASEBOARD_FAB2_LIB.BASEBOARD_FAB2(SCH_1):M_B_DQ(27)
  U5D1  F71 DDR1_DQ<27> SKX_EXT_B_BGA1-IC,TBD   I172 @BASEBOARD_FAB2_LIB.BASEBOARD_FAB2(SCH_1):PAGE24
  J4G2   45 DQ<26> SCONN288_H44441004_PIP-SCONN,HA   I111 @BASEBOARD_FAB2_LIB.BASEBOARD_FAB2(SCH_1):PAGE45
  J6U1  190 DQ<27> SCONN288_H44441003_PIP-SCONN,HA    I14 @BASEBOARD_FAB2_LIB.BASEBOARD_FAB2(SCH_1):PAGE46

M_B_DQ<28> @BASEBOARD_FAB2_LIB.BASEBOARD_FAB2(SCH_1):M_B_DQ(28)
  U5D1  F75 DDR1_DQ<28> SKX_EXT_B_BGA1-IC,TBD   I172 @BASEBOARD_FAB2_LIB.BASEBOARD_FAB2(SCH_1):PAGE24
  J4G2  181 DQ<29> SCONN288_H44441004_PIP-SCONN,HA   I111 @BASEBOARD_FAB2_LIB.BASEBOARD_FAB2(SCH_1):PAGE45
  J6U1   36 DQ<28> SCONN288_H44441003_PIP-SCONN,HA    I14 @BASEBOARD_FAB2_LIB.BASEBOARD_FAB2(SCH_1):PAGE46

M_B_DQ<29> @BASEBOARD_FAB2_LIB.BASEBOARD_FAB2(SCH_1):M_B_DQ(29)
  U5D1  G74 DDR1_DQ<29> SKX_EXT_B_BGA1-IC,TBD   I172 @BASEBOARD_FAB2_LIB.BASEBOARD_FAB2(SCH_1):PAGE24
  J4G2   36 DQ<28> SCONN288_H44441004_PIP-SCONN,HA   I111 @BASEBOARD_FAB2_LIB.BASEBOARD_FAB2(SCH_1):PAGE45
  J6U1  181 DQ<29> SCONN288_H44441003_PIP-SCONN,HA    I14 @BASEBOARD_FAB2_LIB.BASEBOARD_FAB2(SCH_1):PAGE46

M_B_DQ<2> @BASEBOARD_FAB2_LIB.BASEBOARD_FAB2(SCH_1):M_B_DQ(2)
  U5D1 AN82 DDR1_DQ<2> SKX_EXT_B_BGA1-IC,TBD   I172 @BASEBOARD_FAB2_LIB.BASEBOARD_FAB2(SCH_1):PAGE24
  J4G2  157  DQ<3> SCONN288_H44441004_PIP-SCONN,HA   I111 @BASEBOARD_FAB2_LIB.BASEBOARD_FAB2(SCH_1):PAGE45
  J6U1   12  DQ<2> SCONN288_H44441003_PIP-SCONN,HA    I14 @BASEBOARD_FAB2_LIB.BASEBOARD_FAB2(SCH_1):PAGE46

M_B_DQ<30> @BASEBOARD_FAB2_LIB.BASEBOARD_FAB2(SCH_1):M_B_DQ(30)
  U5D1  C72 DDR1_DQ<30> SKX_EXT_B_BGA1-IC,TBD   I172 @BASEBOARD_FAB2_LIB.BASEBOARD_FAB2(SCH_1):PAGE24
  J4G2  188 DQ<31> SCONN288_H44441004_PIP-SCONN,HA   I111 @BASEBOARD_FAB2_LIB.BASEBOARD_FAB2(SCH_1):PAGE45
  J6U1   43 DQ<30> SCONN288_H44441003_PIP-SCONN,HA    I14 @BASEBOARD_FAB2_LIB.BASEBOARD_FAB2(SCH_1):PAGE46

M_B_DQ<31> @BASEBOARD_FAB2_LIB.BASEBOARD_FAB2(SCH_1):M_B_DQ(31)
  U5D1  G72 DDR1_DQ<31> SKX_EXT_B_BGA1-IC,TBD   I172 @BASEBOARD_FAB2_LIB.BASEBOARD_FAB2(SCH_1):PAGE24
  J4G2   43 DQ<30> SCONN288_H44441004_PIP-SCONN,HA   I111 @BASEBOARD_FAB2_LIB.BASEBOARD_FAB2(SCH_1):PAGE45
  J6U1  188 DQ<31> SCONN288_H44441003_PIP-SCONN,HA    I14 @BASEBOARD_FAB2_LIB.BASEBOARD_FAB2(SCH_1):PAGE46

M_B_DQ<32> @BASEBOARD_FAB2_LIB.BASEBOARD_FAB2(SCH_1):M_B_DQ(32)
  U5D1  K43 DDR1_DQ<32> SKX_EXT_B_BGA1-IC,TBD   I172 @BASEBOARD_FAB2_LIB.BASEBOARD_FAB2(SCH_1):PAGE24
  J4G2  242 DQ<33> SCONN288_H44441004_PIP-SCONN,HA   I111 @BASEBOARD_FAB2_LIB.BASEBOARD_FAB2(SCH_1):PAGE45
  J6U1   97 DQ<32> SCONN288_H44441003_PIP-SCONN,HA    I14 @BASEBOARD_FAB2_LIB.BASEBOARD_FAB2(SCH_1):PAGE46

M_B_DQ<33> @BASEBOARD_FAB2_LIB.BASEBOARD_FAB2(SCH_1):M_B_DQ(33)
  U5D1  H43 DDR1_DQ<33> SKX_EXT_B_BGA1-IC,TBD   I172 @BASEBOARD_FAB2_LIB.BASEBOARD_FAB2(SCH_1):PAGE24
  J4G2   97 DQ<32> SCONN288_H44441004_PIP-SCONN,HA   I111 @BASEBOARD_FAB2_LIB.BASEBOARD_FAB2(SCH_1):PAGE45
  J6U1  242 DQ<33> SCONN288_H44441003_PIP-SCONN,HA    I14 @BASEBOARD_FAB2_LIB.BASEBOARD_FAB2(SCH_1):PAGE46

M_B_DQ<34> @BASEBOARD_FAB2_LIB.BASEBOARD_FAB2(SCH_1):M_B_DQ(34)
  U5D1  L40 DDR1_DQ<34> SKX_EXT_B_BGA1-IC,TBD   I172 @BASEBOARD_FAB2_LIB.BASEBOARD_FAB2(SCH_1):PAGE24
  J4G2  249 DQ<35> SCONN288_H44441004_PIP-SCONN,HA   I111 @BASEBOARD_FAB2_LIB.BASEBOARD_FAB2(SCH_1):PAGE45
  J6U1  104 DQ<34> SCONN288_H44441003_PIP-SCONN,HA    I14 @BASEBOARD_FAB2_LIB.BASEBOARD_FAB2(SCH_1):PAGE46

M_B_DQ<35> @BASEBOARD_FAB2_LIB.BASEBOARD_FAB2(SCH_1):M_B_DQ(35)
  U5D1  N40 DDR1_DQ<35> SKX_EXT_B_BGA1-IC,TBD   I172 @BASEBOARD_FAB2_LIB.BASEBOARD_FAB2(SCH_1):PAGE24
  J4G2  104 DQ<34> SCONN288_H44441004_PIP-SCONN,HA   I111 @BASEBOARD_FAB2_LIB.BASEBOARD_FAB2(SCH_1):PAGE45
  J6U1  249 DQ<35> SCONN288_H44441003_PIP-SCONN,HA    I14 @BASEBOARD_FAB2_LIB.BASEBOARD_FAB2(SCH_1):PAGE46

M_B_DQ<36> @BASEBOARD_FAB2_LIB.BASEBOARD_FAB2(SCH_1):M_B_DQ(36)
  U5D1  P43 DDR1_DQ<36> SKX_EXT_B_BGA1-IC,TBD   I172 @BASEBOARD_FAB2_LIB.BASEBOARD_FAB2(SCH_1):PAGE24
  J4G2  240 DQ<37> SCONN288_H44441004_PIP-SCONN,HA   I111 @BASEBOARD_FAB2_LIB.BASEBOARD_FAB2(SCH_1):PAGE45
  J6U1   95 DQ<36> SCONN288_H44441003_PIP-SCONN,HA    I14 @BASEBOARD_FAB2_LIB.BASEBOARD_FAB2(SCH_1):PAGE46

M_B_DQ<37> @BASEBOARD_FAB2_LIB.BASEBOARD_FAB2(SCH_1):M_B_DQ(37)
  U5D1  T43 DDR1_DQ<37> SKX_EXT_B_BGA1-IC,TBD   I172 @BASEBOARD_FAB2_LIB.BASEBOARD_FAB2(SCH_1):PAGE24
  J4G2   95 DQ<36> SCONN288_H44441004_PIP-SCONN,HA   I111 @BASEBOARD_FAB2_LIB.BASEBOARD_FAB2(SCH_1):PAGE45
  J6U1  240 DQ<37> SCONN288_H44441003_PIP-SCONN,HA    I14 @BASEBOARD_FAB2_LIB.BASEBOARD_FAB2(SCH_1):PAGE46

M_B_DQ<38> @BASEBOARD_FAB2_LIB.BASEBOARD_FAB2(SCH_1):M_B_DQ(38)
  U5D1  K41 DDR1_DQ<38> SKX_EXT_B_BGA1-IC,TBD   I172 @BASEBOARD_FAB2_LIB.BASEBOARD_FAB2(SCH_1):PAGE24
  J4G2  247 DQ<39> SCONN288_H44441004_PIP-SCONN,HA   I111 @BASEBOARD_FAB2_LIB.BASEBOARD_FAB2(SCH_1):PAGE45
  J6U1  102 DQ<38> SCONN288_H44441003_PIP-SCONN,HA    I14 @BASEBOARD_FAB2_LIB.BASEBOARD_FAB2(SCH_1):PAGE46

M_B_DQ<39> @BASEBOARD_FAB2_LIB.BASEBOARD_FAB2(SCH_1):M_B_DQ(39)
  U5D1  P41 DDR1_DQ<39> SKX_EXT_B_BGA1-IC,TBD   I172 @BASEBOARD_FAB2_LIB.BASEBOARD_FAB2(SCH_1):PAGE24
  J4G2  102 DQ<38> SCONN288_H44441004_PIP-SCONN,HA   I111 @BASEBOARD_FAB2_LIB.BASEBOARD_FAB2(SCH_1):PAGE45
  J6U1  247 DQ<39> SCONN288_H44441003_PIP-SCONN,HA    I14 @BASEBOARD_FAB2_LIB.BASEBOARD_FAB2(SCH_1):PAGE46

M_B_DQ<3> @BASEBOARD_FAB2_LIB.BASEBOARD_FAB2(SCH_1):M_B_DQ(3)
  U5D1 AM81 DDR1_DQ<3> SKX_EXT_B_BGA1-IC,TBD   I172 @BASEBOARD_FAB2_LIB.BASEBOARD_FAB2(SCH_1):PAGE24
  J4G2   12  DQ<2> SCONN288_H44441004_PIP-SCONN,HA   I111 @BASEBOARD_FAB2_LIB.BASEBOARD_FAB2(SCH_1):PAGE45
  J6U1  157  DQ<3> SCONN288_H44441003_PIP-SCONN,HA    I14 @BASEBOARD_FAB2_LIB.BASEBOARD_FAB2(SCH_1):PAGE46

M_B_DQ<40> @BASEBOARD_FAB2_LIB.BASEBOARD_FAB2(SCH_1):M_B_DQ(40)
  U5D1  C36 DDR1_DQ<40> SKX_EXT_B_BGA1-IC,TBD   I172 @BASEBOARD_FAB2_LIB.BASEBOARD_FAB2(SCH_1):PAGE24
  J4G2  253 DQ<41> SCONN288_H44441004_PIP-SCONN,HA   I111 @BASEBOARD_FAB2_LIB.BASEBOARD_FAB2(SCH_1):PAGE45
  J6U1  108 DQ<40> SCONN288_H44441003_PIP-SCONN,HA    I14 @BASEBOARD_FAB2_LIB.BASEBOARD_FAB2(SCH_1):PAGE46

M_B_DQ<41> @BASEBOARD_FAB2_LIB.BASEBOARD_FAB2(SCH_1):M_B_DQ(41)
  U5D1  B35 DDR1_DQ<41> SKX_EXT_B_BGA1-IC,TBD   I172 @BASEBOARD_FAB2_LIB.BASEBOARD_FAB2(SCH_1):PAGE24
  J4G2  108 DQ<40> SCONN288_H44441004_PIP-SCONN,HA   I111 @BASEBOARD_FAB2_LIB.BASEBOARD_FAB2(SCH_1):PAGE45
  J6U1  253 DQ<41> SCONN288_H44441003_PIP-SCONN,HA    I14 @BASEBOARD_FAB2_LIB.BASEBOARD_FAB2(SCH_1):PAGE46

M_B_DQ<42> @BASEBOARD_FAB2_LIB.BASEBOARD_FAB2(SCH_1):M_B_DQ(42)
  U5D1  C32 DDR1_DQ<42> SKX_EXT_B_BGA1-IC,TBD   I172 @BASEBOARD_FAB2_LIB.BASEBOARD_FAB2(SCH_1):PAGE24
  J4G2  260 DQ<43> SCONN288_H44441004_PIP-SCONN,HA   I111 @BASEBOARD_FAB2_LIB.BASEBOARD_FAB2(SCH_1):PAGE45
  J6U1  115 DQ<42> SCONN288_H44441003_PIP-SCONN,HA    I14 @BASEBOARD_FAB2_LIB.BASEBOARD_FAB2(SCH_1):PAGE46

M_B_DQ<43> @BASEBOARD_FAB2_LIB.BASEBOARD_FAB2(SCH_1):M_B_DQ(43)
  U5D1  E32 DDR1_DQ<43> SKX_EXT_B_BGA1-IC,TBD   I172 @BASEBOARD_FAB2_LIB.BASEBOARD_FAB2(SCH_1):PAGE24
  J4G2  115 DQ<42> SCONN288_H44441004_PIP-SCONN,HA   I111 @BASEBOARD_FAB2_LIB.BASEBOARD_FAB2(SCH_1):PAGE45
  J6U1  260 DQ<43> SCONN288_H44441003_PIP-SCONN,HA    I14 @BASEBOARD_FAB2_LIB.BASEBOARD_FAB2(SCH_1):PAGE46

M_B_DQ<44> @BASEBOARD_FAB2_LIB.BASEBOARD_FAB2(SCH_1):M_B_DQ(44)
  U5D1  E36 DDR1_DQ<44> SKX_EXT_B_BGA1-IC,TBD   I172 @BASEBOARD_FAB2_LIB.BASEBOARD_FAB2(SCH_1):PAGE24
  J4G2  251 DQ<45> SCONN288_H44441004_PIP-SCONN,HA   I111 @BASEBOARD_FAB2_LIB.BASEBOARD_FAB2(SCH_1):PAGE45
  J6U1  106 DQ<44> SCONN288_H44441003_PIP-SCONN,HA    I14 @BASEBOARD_FAB2_LIB.BASEBOARD_FAB2(SCH_1):PAGE46

M_B_DQ<45> @BASEBOARD_FAB2_LIB.BASEBOARD_FAB2(SCH_1):M_B_DQ(45)
  U5D1  F35 DDR1_DQ<45> SKX_EXT_B_BGA1-IC,TBD   I172 @BASEBOARD_FAB2_LIB.BASEBOARD_FAB2(SCH_1):PAGE24
  J4G2  106 DQ<44> SCONN288_H44441004_PIP-SCONN,HA   I111 @BASEBOARD_FAB2_LIB.BASEBOARD_FAB2(SCH_1):PAGE45
  J6U1  251 DQ<45> SCONN288_H44441003_PIP-SCONN,HA    I14 @BASEBOARD_FAB2_LIB.BASEBOARD_FAB2(SCH_1):PAGE46

M_B_DQ<46> @BASEBOARD_FAB2_LIB.BASEBOARD_FAB2(SCH_1):M_B_DQ(46)
  U5D1  B33 DDR1_DQ<46> SKX_EXT_B_BGA1-IC,TBD   I172 @BASEBOARD_FAB2_LIB.BASEBOARD_FAB2(SCH_1):PAGE24
  J4G2  258 DQ<47> SCONN288_H44441004_PIP-SCONN,HA   I111 @BASEBOARD_FAB2_LIB.BASEBOARD_FAB2(SCH_1):PAGE45
  J6U1  113 DQ<46> SCONN288_H44441003_PIP-SCONN,HA    I14 @BASEBOARD_FAB2_LIB.BASEBOARD_FAB2(SCH_1):PAGE46

M_B_DQ<47> @BASEBOARD_FAB2_LIB.BASEBOARD_FAB2(SCH_1):M_B_DQ(47)
  U5D1  F33 DDR1_DQ<47> SKX_EXT_B_BGA1-IC,TBD   I172 @BASEBOARD_FAB2_LIB.BASEBOARD_FAB2(SCH_1):PAGE24
  J4G2  113 DQ<46> SCONN288_H44441004_PIP-SCONN,HA   I111 @BASEBOARD_FAB2_LIB.BASEBOARD_FAB2(SCH_1):PAGE45
  J6U1  258 DQ<47> SCONN288_H44441003_PIP-SCONN,HA    I14 @BASEBOARD_FAB2_LIB.BASEBOARD_FAB2(SCH_1):PAGE46

M_B_DQ<48> @BASEBOARD_FAB2_LIB.BASEBOARD_FAB2(SCH_1):M_B_DQ(48)
  U5D1  C30 DDR1_DQ<48> SKX_EXT_B_BGA1-IC,TBD   I172 @BASEBOARD_FAB2_LIB.BASEBOARD_FAB2(SCH_1):PAGE24
  J4G2  264 DQ<49> SCONN288_H44441004_PIP-SCONN,HA   I111 @BASEBOARD_FAB2_LIB.BASEBOARD_FAB2(SCH_1):PAGE45
  J6U1  119 DQ<48> SCONN288_H44441003_PIP-SCONN,HA    I14 @BASEBOARD_FAB2_LIB.BASEBOARD_FAB2(SCH_1):PAGE46

M_B_DQ<49> @BASEBOARD_FAB2_LIB.BASEBOARD_FAB2(SCH_1):M_B_DQ(49)
  U5D1  B29 DDR1_DQ<49> SKX_EXT_B_BGA1-IC,TBD   I172 @BASEBOARD_FAB2_LIB.BASEBOARD_FAB2(SCH_1):PAGE24
  J4G2  119 DQ<48> SCONN288_H44441004_PIP-SCONN,HA   I111 @BASEBOARD_FAB2_LIB.BASEBOARD_FAB2(SCH_1):PAGE45
  J6U1  264 DQ<49> SCONN288_H44441003_PIP-SCONN,HA    I14 @BASEBOARD_FAB2_LIB.BASEBOARD_FAB2(SCH_1):PAGE46

M_B_DQ<4> @BASEBOARD_FAB2_LIB.BASEBOARD_FAB2(SCH_1):M_B_DQ(4)
  U5D1 AW80 DDR1_DQ<4> SKX_EXT_B_BGA1-IC,TBD   I172 @BASEBOARD_FAB2_LIB.BASEBOARD_FAB2(SCH_1):PAGE24
  J4G2  148  DQ<5> SCONN288_H44441004_PIP-SCONN,HA   I111 @BASEBOARD_FAB2_LIB.BASEBOARD_FAB2(SCH_1):PAGE45
  J6U1    3  DQ<4> SCONN288_H44441003_PIP-SCONN,HA    I14 @BASEBOARD_FAB2_LIB.BASEBOARD_FAB2(SCH_1):PAGE46

M_B_DQ<50> @BASEBOARD_FAB2_LIB.BASEBOARD_FAB2(SCH_1):M_B_DQ(50)
  U5D1  C26 DDR1_DQ<50> SKX_EXT_B_BGA1-IC,TBD   I172 @BASEBOARD_FAB2_LIB.BASEBOARD_FAB2(SCH_1):PAGE24
  J4G2  271 DQ<51> SCONN288_H44441004_PIP-SCONN,HA   I111 @BASEBOARD_FAB2_LIB.BASEBOARD_FAB2(SCH_1):PAGE45
  J6U1  126 DQ<50> SCONN288_H44441003_PIP-SCONN,HA    I14 @BASEBOARD_FAB2_LIB.BASEBOARD_FAB2(SCH_1):PAGE46

M_B_DQ<51> @BASEBOARD_FAB2_LIB.BASEBOARD_FAB2(SCH_1):M_B_DQ(51)
  U5D1  E26 DDR1_DQ<51> SKX_EXT_B_BGA1-IC,TBD   I172 @BASEBOARD_FAB2_LIB.BASEBOARD_FAB2(SCH_1):PAGE24
  J4G2  126 DQ<50> SCONN288_H44441004_PIP-SCONN,HA   I111 @BASEBOARD_FAB2_LIB.BASEBOARD_FAB2(SCH_1):PAGE45
  J6U1  271 DQ<51> SCONN288_H44441003_PIP-SCONN,HA    I14 @BASEBOARD_FAB2_LIB.BASEBOARD_FAB2(SCH_1):PAGE46

M_B_DQ<52> @BASEBOARD_FAB2_LIB.BASEBOARD_FAB2(SCH_1):M_B_DQ(52)
  U5D1  E30 DDR1_DQ<52> SKX_EXT_B_BGA1-IC,TBD   I172 @BASEBOARD_FAB2_LIB.BASEBOARD_FAB2(SCH_1):PAGE24
  J4G2  262 DQ<53> SCONN288_H44441004_PIP-SCONN,HA   I111 @BASEBOARD_FAB2_LIB.BASEBOARD_FAB2(SCH_1):PAGE45
  J6U1  117 DQ<52> SCONN288_H44441003_PIP-SCONN,HA    I14 @BASEBOARD_FAB2_LIB.BASEBOARD_FAB2(SCH_1):PAGE46

M_B_DQ<53> @BASEBOARD_FAB2_LIB.BASEBOARD_FAB2(SCH_1):M_B_DQ(53)
  U5D1  F29 DDR1_DQ<53> SKX_EXT_B_BGA1-IC,TBD   I172 @BASEBOARD_FAB2_LIB.BASEBOARD_FAB2(SCH_1):PAGE24
  J4G2  117 DQ<52> SCONN288_H44441004_PIP-SCONN,HA   I111 @BASEBOARD_FAB2_LIB.BASEBOARD_FAB2(SCH_1):PAGE45
  J6U1  262 DQ<53> SCONN288_H44441003_PIP-SCONN,HA    I14 @BASEBOARD_FAB2_LIB.BASEBOARD_FAB2(SCH_1):PAGE46

M_B_DQ<54> @BASEBOARD_FAB2_LIB.BASEBOARD_FAB2(SCH_1):M_B_DQ(54)
  U5D1  B27 DDR1_DQ<54> SKX_EXT_B_BGA1-IC,TBD   I172 @BASEBOARD_FAB2_LIB.BASEBOARD_FAB2(SCH_1):PAGE24
  J4G2  269 DQ<55> SCONN288_H44441004_PIP-SCONN,HA   I111 @BASEBOARD_FAB2_LIB.BASEBOARD_FAB2(SCH_1):PAGE45
  J6U1  124 DQ<54> SCONN288_H44441003_PIP-SCONN,HA    I14 @BASEBOARD_FAB2_LIB.BASEBOARD_FAB2(SCH_1):PAGE46

M_B_DQ<55> @BASEBOARD_FAB2_LIB.BASEBOARD_FAB2(SCH_1):M_B_DQ(55)
  U5D1  F27 DDR1_DQ<55> SKX_EXT_B_BGA1-IC,TBD   I172 @BASEBOARD_FAB2_LIB.BASEBOARD_FAB2(SCH_1):PAGE24
  J4G2  124 DQ<54> SCONN288_H44441004_PIP-SCONN,HA   I111 @BASEBOARD_FAB2_LIB.BASEBOARD_FAB2(SCH_1):PAGE45
  J6U1  269 DQ<55> SCONN288_H44441003_PIP-SCONN,HA    I14 @BASEBOARD_FAB2_LIB.BASEBOARD_FAB2(SCH_1):PAGE46

M_B_DQ<56> @BASEBOARD_FAB2_LIB.BASEBOARD_FAB2(SCH_1):M_B_DQ(56)
  U5D1  U28 DDR1_DQ<56> SKX_EXT_B_BGA1-IC,TBD   I172 @BASEBOARD_FAB2_LIB.BASEBOARD_FAB2(SCH_1):PAGE24
  J4G2  275 DQ<57> SCONN288_H44441004_PIP-SCONN,HA   I111 @BASEBOARD_FAB2_LIB.BASEBOARD_FAB2(SCH_1):PAGE45
  J6U1  130 DQ<56> SCONN288_H44441003_PIP-SCONN,HA    I14 @BASEBOARD_FAB2_LIB.BASEBOARD_FAB2(SCH_1):PAGE46

M_B_DQ<57> @BASEBOARD_FAB2_LIB.BASEBOARD_FAB2(SCH_1):M_B_DQ(57)
  U5D1 AA28 DDR1_DQ<57> SKX_EXT_B_BGA1-IC,TBD   I172 @BASEBOARD_FAB2_LIB.BASEBOARD_FAB2(SCH_1):PAGE24
  J4G2  130 DQ<56> SCONN288_H44441004_PIP-SCONN,HA   I111 @BASEBOARD_FAB2_LIB.BASEBOARD_FAB2(SCH_1):PAGE45
  J6U1  275 DQ<57> SCONN288_H44441003_PIP-SCONN,HA    I14 @BASEBOARD_FAB2_LIB.BASEBOARD_FAB2(SCH_1):PAGE46

M_B_DQ<58> @BASEBOARD_FAB2_LIB.BASEBOARD_FAB2(SCH_1):M_B_DQ(58)
  U5D1  V25 DDR1_DQ<58> SKX_EXT_B_BGA1-IC,TBD   I172 @BASEBOARD_FAB2_LIB.BASEBOARD_FAB2(SCH_1):PAGE24
  J4G2  282 DQ<59> SCONN288_H44441004_PIP-SCONN,HA   I111 @BASEBOARD_FAB2_LIB.BASEBOARD_FAB2(SCH_1):PAGE45
  J6U1  137 DQ<58> SCONN288_H44441003_PIP-SCONN,HA    I14 @BASEBOARD_FAB2_LIB.BASEBOARD_FAB2(SCH_1):PAGE46

M_B_DQ<59> @BASEBOARD_FAB2_LIB.BASEBOARD_FAB2(SCH_1):M_B_DQ(59)
  U5D1  Y25 DDR1_DQ<59> SKX_EXT_B_BGA1-IC,TBD   I172 @BASEBOARD_FAB2_LIB.BASEBOARD_FAB2(SCH_1):PAGE24
  J4G2  137 DQ<58> SCONN288_H44441004_PIP-SCONN,HA   I111 @BASEBOARD_FAB2_LIB.BASEBOARD_FAB2(SCH_1):PAGE45
  J6U1  282 DQ<59> SCONN288_H44441003_PIP-SCONN,HA    I14 @BASEBOARD_FAB2_LIB.BASEBOARD_FAB2(SCH_1):PAGE46

M_B_DQ<5> @BASEBOARD_FAB2_LIB.BASEBOARD_FAB2(SCH_1):M_B_DQ(5)
  U5D1 AV79 DDR1_DQ<5> SKX_EXT_B_BGA1-IC,TBD   I172 @BASEBOARD_FAB2_LIB.BASEBOARD_FAB2(SCH_1):PAGE24
  J4G2    3  DQ<4> SCONN288_H44441004_PIP-SCONN,HA   I111 @BASEBOARD_FAB2_LIB.BASEBOARD_FAB2(SCH_1):PAGE45
  J6U1  148  DQ<5> SCONN288_H44441003_PIP-SCONN,HA    I14 @BASEBOARD_FAB2_LIB.BASEBOARD_FAB2(SCH_1):PAGE46

M_B_DQ<60> @BASEBOARD_FAB2_LIB.BASEBOARD_FAB2(SCH_1):M_B_DQ(60)
  U5D1  V29 DDR1_DQ<60> SKX_EXT_B_BGA1-IC,TBD   I172 @BASEBOARD_FAB2_LIB.BASEBOARD_FAB2(SCH_1):PAGE24
  J4G2  273 DQ<61> SCONN288_H44441004_PIP-SCONN,HA   I111 @BASEBOARD_FAB2_LIB.BASEBOARD_FAB2(SCH_1):PAGE45
  J6U1  128 DQ<60> SCONN288_H44441003_PIP-SCONN,HA    I14 @BASEBOARD_FAB2_LIB.BASEBOARD_FAB2(SCH_1):PAGE46

M_B_DQ<61> @BASEBOARD_FAB2_LIB.BASEBOARD_FAB2(SCH_1):M_B_DQ(61)
  U5D1  Y29 DDR1_DQ<61> SKX_EXT_B_BGA1-IC,TBD   I172 @BASEBOARD_FAB2_LIB.BASEBOARD_FAB2(SCH_1):PAGE24
  J4G2  128 DQ<60> SCONN288_H44441004_PIP-SCONN,HA   I111 @BASEBOARD_FAB2_LIB.BASEBOARD_FAB2(SCH_1):PAGE45
  J6U1  273 DQ<61> SCONN288_H44441003_PIP-SCONN,HA    I14 @BASEBOARD_FAB2_LIB.BASEBOARD_FAB2(SCH_1):PAGE46

M_B_DQ<62> @BASEBOARD_FAB2_LIB.BASEBOARD_FAB2(SCH_1):M_B_DQ(62)
  U5D1  U26 DDR1_DQ<62> SKX_EXT_B_BGA1-IC,TBD   I172 @BASEBOARD_FAB2_LIB.BASEBOARD_FAB2(SCH_1):PAGE24
  J4G2  280 DQ<63> SCONN288_H44441004_PIP-SCONN,HA   I111 @BASEBOARD_FAB2_LIB.BASEBOARD_FAB2(SCH_1):PAGE45
  J6U1  135 DQ<62> SCONN288_H44441003_PIP-SCONN,HA    I14 @BASEBOARD_FAB2_LIB.BASEBOARD_FAB2(SCH_1):PAGE46

M_B_DQ<63> @BASEBOARD_FAB2_LIB.BASEBOARD_FAB2(SCH_1):M_B_DQ(63)
  U5D1 AA26 DDR1_DQ<63> SKX_EXT_B_BGA1-IC,TBD   I172 @BASEBOARD_FAB2_LIB.BASEBOARD_FAB2(SCH_1):PAGE24
  J4G2  135 DQ<62> SCONN288_H44441004_PIP-SCONN,HA   I111 @BASEBOARD_FAB2_LIB.BASEBOARD_FAB2(SCH_1):PAGE45
  J6U1  280 DQ<63> SCONN288_H44441003_PIP-SCONN,HA    I14 @BASEBOARD_FAB2_LIB.BASEBOARD_FAB2(SCH_1):PAGE46

M_B_DQ<6> @BASEBOARD_FAB2_LIB.BASEBOARD_FAB2(SCH_1):M_B_DQ(6)
  U5D1 AR82 DDR1_DQ<6> SKX_EXT_B_BGA1-IC,TBD   I172 @BASEBOARD_FAB2_LIB.BASEBOARD_FAB2(SCH_1):PAGE24
  J4G2  155  DQ<7> SCONN288_H44441004_PIP-SCONN,HA   I111 @BASEBOARD_FAB2_LIB.BASEBOARD_FAB2(SCH_1):PAGE45
  J6U1   10  DQ<6> SCONN288_H44441003_PIP-SCONN,HA    I14 @BASEBOARD_FAB2_LIB.BASEBOARD_FAB2(SCH_1):PAGE46

M_B_DQ<7> @BASEBOARD_FAB2_LIB.BASEBOARD_FAB2(SCH_1):M_B_DQ(7)
  U5D1 AN80 DDR1_DQ<7> SKX_EXT_B_BGA1-IC,TBD   I172 @BASEBOARD_FAB2_LIB.BASEBOARD_FAB2(SCH_1):PAGE24
  J4G2   10  DQ<6> SCONN288_H44441004_PIP-SCONN,HA   I111 @BASEBOARD_FAB2_LIB.BASEBOARD_FAB2(SCH_1):PAGE45
  J6U1  155  DQ<7> SCONN288_H44441003_PIP-SCONN,HA    I14 @BASEBOARD_FAB2_LIB.BASEBOARD_FAB2(SCH_1):PAGE46

M_B_DQ<8> @BASEBOARD_FAB2_LIB.BASEBOARD_FAB2(SCH_1):M_B_DQ(8)
  U5D1 AH81 DDR1_DQ<8> SKX_EXT_B_BGA1-IC,TBD   I172 @BASEBOARD_FAB2_LIB.BASEBOARD_FAB2(SCH_1):PAGE24
  J4G2  161  DQ<9> SCONN288_H44441004_PIP-SCONN,HA   I111 @BASEBOARD_FAB2_LIB.BASEBOARD_FAB2(SCH_1):PAGE45
  J6U1   16  DQ<8> SCONN288_H44441003_PIP-SCONN,HA    I14 @BASEBOARD_FAB2_LIB.BASEBOARD_FAB2(SCH_1):PAGE46

M_B_DQ<9> @BASEBOARD_FAB2_LIB.BASEBOARD_FAB2(SCH_1):M_B_DQ(9)
  U5D1 AF79 DDR1_DQ<9> SKX_EXT_B_BGA1-IC,TBD   I172 @BASEBOARD_FAB2_LIB.BASEBOARD_FAB2(SCH_1):PAGE24
  J4G2   16  DQ<8> SCONN288_H44441004_PIP-SCONN,HA   I111 @BASEBOARD_FAB2_LIB.BASEBOARD_FAB2(SCH_1):PAGE45
  J6U1  161  DQ<9> SCONN288_H44441003_PIP-SCONN,HA    I14 @BASEBOARD_FAB2_LIB.BASEBOARD_FAB2(SCH_1):PAGE46

M_B_DQS_DN<0> @BASEBOARD_FAB2_LIB.BASEBOARD_FAB2(SCH_1):M_B_DQS_DN(0)
  U5D1 AP79 DDR1_DQS_DN<0> SKX_EXT_B_BGA1-IC,TBD   I172 @BASEBOARD_FAB2_LIB.BASEBOARD_FAB2(SCH_1):PAGE24
  J4G2  152  DQS0N SCONN288_H44441004_PIP-SCONN,HA    I61 @BASEBOARD_FAB2_LIB.BASEBOARD_FAB2(SCH_1):PAGE45
  J6U1  152  DQS0N SCONN288_H44441003_PIP-SCONN,HA   I112 @BASEBOARD_FAB2_LIB.BASEBOARD_FAB2(SCH_1):PAGE46

M_B_DQS_DN<10> @BASEBOARD_FAB2_LIB.BASEBOARD_FAB2(SCH_1):M_B_DQS_DN(10)
  U5D1 AG82 DDR1_DQS_DN<10> SKX_EXT_B_BGA1-IC,TBD   I172 @BASEBOARD_FAB2_LIB.BASEBOARD_FAB2(SCH_1):PAGE24
  J4G2   19 DQS10N SCONN288_H44441004_PIP-SCONN,HA    I61 @BASEBOARD_FAB2_LIB.BASEBOARD_FAB2(SCH_1):PAGE45
  J6U1   19 DQS10N SCONN288_H44441003_PIP-SCONN,HA   I112 @BASEBOARD_FAB2_LIB.BASEBOARD_FAB2(SCH_1):PAGE46

M_B_DQS_DN<11> @BASEBOARD_FAB2_LIB.BASEBOARD_FAB2(SCH_1):M_B_DQS_DN(11)
  U5D1  D79 DDR1_DQS_DN<11> SKX_EXT_B_BGA1-IC,TBD   I172 @BASEBOARD_FAB2_LIB.BASEBOARD_FAB2(SCH_1):PAGE24
  J4G2   30 DQS11N SCONN288_H44441004_PIP-SCONN,HA    I61 @BASEBOARD_FAB2_LIB.BASEBOARD_FAB2(SCH_1):PAGE45
  J6U1   30 DQS11N SCONN288_H44441003_PIP-SCONN,HA   I112 @BASEBOARD_FAB2_LIB.BASEBOARD_FAB2(SCH_1):PAGE46

M_B_DQS_DN<12> @BASEBOARD_FAB2_LIB.BASEBOARD_FAB2(SCH_1):M_B_DQS_DN(12)
  U5D1  B73 DDR1_DQS_DN<12> SKX_EXT_B_BGA1-IC,TBD   I172 @BASEBOARD_FAB2_LIB.BASEBOARD_FAB2(SCH_1):PAGE24
  J4G2   41 DQS12N SCONN288_H44441004_PIP-SCONN,HA    I61 @BASEBOARD_FAB2_LIB.BASEBOARD_FAB2(SCH_1):PAGE45
  J6U1   41 DQS12N SCONN288_H44441003_PIP-SCONN,HA   I112 @BASEBOARD_FAB2_LIB.BASEBOARD_FAB2(SCH_1):PAGE46

M_B_DQS_DN<13> @BASEBOARD_FAB2_LIB.BASEBOARD_FAB2(SCH_1):M_B_DQS_DN(13)
  U5D1  J42 DDR1_DQS_DN<13> SKX_EXT_B_BGA1-IC,TBD   I172 @BASEBOARD_FAB2_LIB.BASEBOARD_FAB2(SCH_1):PAGE24
  J4G2  100 DQS13N SCONN288_H44441004_PIP-SCONN,HA    I61 @BASEBOARD_FAB2_LIB.BASEBOARD_FAB2(SCH_1):PAGE45
  J6U1  100 DQS13N SCONN288_H44441003_PIP-SCONN,HA   I112 @BASEBOARD_FAB2_LIB.BASEBOARD_FAB2(SCH_1):PAGE46

M_B_DQS_DN<14> @BASEBOARD_FAB2_LIB.BASEBOARD_FAB2(SCH_1):M_B_DQS_DN(14)
  U5D1  A34 DDR1_DQS_DN<14> SKX_EXT_B_BGA1-IC,TBD   I172 @BASEBOARD_FAB2_LIB.BASEBOARD_FAB2(SCH_1):PAGE24
  J4G2  111 DQS14N SCONN288_H44441004_PIP-SCONN,HA    I61 @BASEBOARD_FAB2_LIB.BASEBOARD_FAB2(SCH_1):PAGE45
  J6U1  111 DQS14N SCONN288_H44441003_PIP-SCONN,HA   I112 @BASEBOARD_FAB2_LIB.BASEBOARD_FAB2(SCH_1):PAGE46

M_B_DQS_DN<15> @BASEBOARD_FAB2_LIB.BASEBOARD_FAB2(SCH_1):M_B_DQS_DN(15)
  U5D1  A28 DDR1_DQS_DN<15> SKX_EXT_B_BGA1-IC,TBD   I172 @BASEBOARD_FAB2_LIB.BASEBOARD_FAB2(SCH_1):PAGE24
  J4G2  122 DQS15N SCONN288_H44441004_PIP-SCONN,HA    I61 @BASEBOARD_FAB2_LIB.BASEBOARD_FAB2(SCH_1):PAGE45
  J6U1  122 DQS15N SCONN288_H44441003_PIP-SCONN,HA   I112 @BASEBOARD_FAB2_LIB.BASEBOARD_FAB2(SCH_1):PAGE46

M_B_DQS_DN<16> @BASEBOARD_FAB2_LIB.BASEBOARD_FAB2(SCH_1):M_B_DQS_DN(16)
  U5D1  T27 DDR1_DQS_DN<16> SKX_EXT_B_BGA1-IC,TBD   I172 @BASEBOARD_FAB2_LIB.BASEBOARD_FAB2(SCH_1):PAGE24
  J4G2  133 DQS16N SCONN288_H44441004_PIP-SCONN,HA    I61 @BASEBOARD_FAB2_LIB.BASEBOARD_FAB2(SCH_1):PAGE45
  J6U1  133 DQS16N SCONN288_H44441003_PIP-SCONN,HA   I112 @BASEBOARD_FAB2_LIB.BASEBOARD_FAB2(SCH_1):PAGE46

M_B_DQS_DN<17> @BASEBOARD_FAB2_LIB.BASEBOARD_FAB2(SCH_1):M_B_DQS_DN(17)
  U5D1  G68 DDR1_DQS_DN<17> SKX_EXT_B_BGA1-IC,TBD   I172 @BASEBOARD_FAB2_LIB.BASEBOARD_FAB2(SCH_1):PAGE24
  J4G2   52 DQS17N SCONN288_H44441004_PIP-SCONN,HA    I61 @BASEBOARD_FAB2_LIB.BASEBOARD_FAB2(SCH_1):PAGE45
  J6U1   52 DQS17N SCONN288_H44441003_PIP-SCONN,HA   I112 @BASEBOARD_FAB2_LIB.BASEBOARD_FAB2(SCH_1):PAGE46

M_B_DQS_DN<1> @BASEBOARD_FAB2_LIB.BASEBOARD_FAB2(SCH_1):M_B_DQS_DN(1)
  U5D1 AD79 DDR1_DQS_DN<1> SKX_EXT_B_BGA1-IC,TBD   I172 @BASEBOARD_FAB2_LIB.BASEBOARD_FAB2(SCH_1):PAGE24
  J4G2  163  DQS1N SCONN288_H44441004_PIP-SCONN,HA    I61 @BASEBOARD_FAB2_LIB.BASEBOARD_FAB2(SCH_1):PAGE45
  J6U1  163  DQS1N SCONN288_H44441003_PIP-SCONN,HA   I112 @BASEBOARD_FAB2_LIB.BASEBOARD_FAB2(SCH_1):PAGE46

M_B_DQS_DN<2> @BASEBOARD_FAB2_LIB.BASEBOARD_FAB2(SCH_1):M_B_DQS_DN(2)
  U5D1  K79 DDR1_DQS_DN<2> SKX_EXT_B_BGA1-IC,TBD   I172 @BASEBOARD_FAB2_LIB.BASEBOARD_FAB2(SCH_1):PAGE24
  J4G2  174  DQS2N SCONN288_H44441004_PIP-SCONN,HA    I61 @BASEBOARD_FAB2_LIB.BASEBOARD_FAB2(SCH_1):PAGE45
  J6U1  174  DQS2N SCONN288_H44441003_PIP-SCONN,HA   I112 @BASEBOARD_FAB2_LIB.BASEBOARD_FAB2(SCH_1):PAGE46

M_B_DQS_DN<3> @BASEBOARD_FAB2_LIB.BASEBOARD_FAB2(SCH_1):M_B_DQS_DN(3)
  U5D1  H73 DDR1_DQS_DN<3> SKX_EXT_B_BGA1-IC,TBD   I172 @BASEBOARD_FAB2_LIB.BASEBOARD_FAB2(SCH_1):PAGE24
  J4G2  185  DQS3N SCONN288_H44441004_PIP-SCONN,HA    I61 @BASEBOARD_FAB2_LIB.BASEBOARD_FAB2(SCH_1):PAGE45
  J6U1  185  DQS3N SCONN288_H44441003_PIP-SCONN,HA   I112 @BASEBOARD_FAB2_LIB.BASEBOARD_FAB2(SCH_1):PAGE46

M_B_DQS_DN<4> @BASEBOARD_FAB2_LIB.BASEBOARD_FAB2(SCH_1):M_B_DQS_DN(4)
  U5D1  N42 DDR1_DQS_DN<4> SKX_EXT_B_BGA1-IC,TBD   I172 @BASEBOARD_FAB2_LIB.BASEBOARD_FAB2(SCH_1):PAGE24
  J4G2  244  DQS4N SCONN288_H44441004_PIP-SCONN,HA    I61 @BASEBOARD_FAB2_LIB.BASEBOARD_FAB2(SCH_1):PAGE45
  J6U1  244  DQS4N SCONN288_H44441003_PIP-SCONN,HA   I112 @BASEBOARD_FAB2_LIB.BASEBOARD_FAB2(SCH_1):PAGE46

M_B_DQS_DN<5> @BASEBOARD_FAB2_LIB.BASEBOARD_FAB2(SCH_1):M_B_DQS_DN(5)
  U5D1  G34 DDR1_DQS_DN<5> SKX_EXT_B_BGA1-IC,TBD   I172 @BASEBOARD_FAB2_LIB.BASEBOARD_FAB2(SCH_1):PAGE24
  J4G2  255  DQS5N SCONN288_H44441004_PIP-SCONN,HA    I61 @BASEBOARD_FAB2_LIB.BASEBOARD_FAB2(SCH_1):PAGE45
  J6U1  255  DQS5N SCONN288_H44441003_PIP-SCONN,HA   I112 @BASEBOARD_FAB2_LIB.BASEBOARD_FAB2(SCH_1):PAGE46

M_B_DQS_DN<6> @BASEBOARD_FAB2_LIB.BASEBOARD_FAB2(SCH_1):M_B_DQS_DN(6)
  U5D1  G28 DDR1_DQS_DN<6> SKX_EXT_B_BGA1-IC,TBD   I172 @BASEBOARD_FAB2_LIB.BASEBOARD_FAB2(SCH_1):PAGE24
  J4G2  266  DQS6N SCONN288_H44441004_PIP-SCONN,HA    I61 @BASEBOARD_FAB2_LIB.BASEBOARD_FAB2(SCH_1):PAGE45
  J6U1  266  DQS6N SCONN288_H44441003_PIP-SCONN,HA   I112 @BASEBOARD_FAB2_LIB.BASEBOARD_FAB2(SCH_1):PAGE46

M_B_DQS_DN<7> @BASEBOARD_FAB2_LIB.BASEBOARD_FAB2(SCH_1):M_B_DQS_DN(7)
  U5D1 AB27 DDR1_DQS_DN<7> SKX_EXT_B_BGA1-IC,TBD   I172 @BASEBOARD_FAB2_LIB.BASEBOARD_FAB2(SCH_1):PAGE24
  J4G2  277  DQS7N SCONN288_H44441004_PIP-SCONN,HA    I61 @BASEBOARD_FAB2_LIB.BASEBOARD_FAB2(SCH_1):PAGE45
  J6U1  277  DQS7N SCONN288_H44441003_PIP-SCONN,HA   I112 @BASEBOARD_FAB2_LIB.BASEBOARD_FAB2(SCH_1):PAGE46

M_B_DQS_DN<8> @BASEBOARD_FAB2_LIB.BASEBOARD_FAB2(SCH_1):M_B_DQS_DN(8)
  U5D1  N68 DDR1_DQS_DN<8> SKX_EXT_B_BGA1-IC,TBD   I172 @BASEBOARD_FAB2_LIB.BASEBOARD_FAB2(SCH_1):PAGE24
  J4G2  196  DQS8N SCONN288_H44441004_PIP-SCONN,HA    I61 @BASEBOARD_FAB2_LIB.BASEBOARD_FAB2(SCH_1):PAGE45
  J6U1  196  DQS8N SCONN288_H44441003_PIP-SCONN,HA   I112 @BASEBOARD_FAB2_LIB.BASEBOARD_FAB2(SCH_1):PAGE46

M_B_DQS_DN<9> @BASEBOARD_FAB2_LIB.BASEBOARD_FAB2(SCH_1):M_B_DQS_DN(9)
  U5D1 AU82 DDR1_DQS_DN<9> SKX_EXT_B_BGA1-IC,TBD   I172 @BASEBOARD_FAB2_LIB.BASEBOARD_FAB2(SCH_1):PAGE24
  J4G2    8  DQS9N SCONN288_H44441004_PIP-SCONN,HA    I61 @BASEBOARD_FAB2_LIB.BASEBOARD_FAB2(SCH_1):PAGE45
  J6U1    8  DQS9N SCONN288_H44441003_PIP-SCONN,HA   I112 @BASEBOARD_FAB2_LIB.BASEBOARD_FAB2(SCH_1):PAGE46

M_B_DQS_DP<0> @BASEBOARD_FAB2_LIB.BASEBOARD_FAB2(SCH_1):M_B_DQS_DP(0)
  U5D1 AR80 DDR1_DQS_DP<0> SKX_EXT_B_BGA1-IC,TBD   I172 @BASEBOARD_FAB2_LIB.BASEBOARD_FAB2(SCH_1):PAGE24
  J4G2  153  DQS0P SCONN288_H44441004_PIP-SCONN,HA    I61 @BASEBOARD_FAB2_LIB.BASEBOARD_FAB2(SCH_1):PAGE45
  J6U1  153  DQS0P SCONN288_H44441003_PIP-SCONN,HA   I112 @BASEBOARD_FAB2_LIB.BASEBOARD_FAB2(SCH_1):PAGE46

M_B_DQS_DP<10> @BASEBOARD_FAB2_LIB.BASEBOARD_FAB2(SCH_1):M_B_DQS_DP(10)
  U5D1 AF81 DDR1_DQS_DP<10> SKX_EXT_B_BGA1-IC,TBD   I172 @BASEBOARD_FAB2_LIB.BASEBOARD_FAB2(SCH_1):PAGE24
  J4G2   18 DQS10P SCONN288_H44441004_PIP-SCONN,HA    I61 @BASEBOARD_FAB2_LIB.BASEBOARD_FAB2(SCH_1):PAGE45
  J6U1   18 DQS10P SCONN288_H44441003_PIP-SCONN,HA   I112 @BASEBOARD_FAB2_LIB.BASEBOARD_FAB2(SCH_1):PAGE46

M_B_DQS_DP<11> @BASEBOARD_FAB2_LIB.BASEBOARD_FAB2(SCH_1):M_B_DQS_DP(11)
  U5D1  F79 DDR1_DQS_DP<11> SKX_EXT_B_BGA1-IC,TBD   I172 @BASEBOARD_FAB2_LIB.BASEBOARD_FAB2(SCH_1):PAGE24
  J4G2   29 DQS11P SCONN288_H44441004_PIP-SCONN,HA    I61 @BASEBOARD_FAB2_LIB.BASEBOARD_FAB2(SCH_1):PAGE45
  J6U1   29 DQS11P SCONN288_H44441003_PIP-SCONN,HA   I112 @BASEBOARD_FAB2_LIB.BASEBOARD_FAB2(SCH_1):PAGE46

M_B_DQS_DP<12> @BASEBOARD_FAB2_LIB.BASEBOARD_FAB2(SCH_1):M_B_DQS_DP(12)
  U5D1  D73 DDR1_DQS_DP<12> SKX_EXT_B_BGA1-IC,TBD   I172 @BASEBOARD_FAB2_LIB.BASEBOARD_FAB2(SCH_1):PAGE24
  J4G2   40 DQS12P SCONN288_H44441004_PIP-SCONN,HA    I61 @BASEBOARD_FAB2_LIB.BASEBOARD_FAB2(SCH_1):PAGE45
  J6U1   40 DQS12P SCONN288_H44441003_PIP-SCONN,HA   I112 @BASEBOARD_FAB2_LIB.BASEBOARD_FAB2(SCH_1):PAGE46

M_B_DQS_DP<13> @BASEBOARD_FAB2_LIB.BASEBOARD_FAB2(SCH_1):M_B_DQS_DP(13)
  U5D1  L42 DDR1_DQS_DP<13> SKX_EXT_B_BGA1-IC,TBD   I172 @BASEBOARD_FAB2_LIB.BASEBOARD_FAB2(SCH_1):PAGE24
  J4G2   99 DQS13P SCONN288_H44441004_PIP-SCONN,HA    I61 @BASEBOARD_FAB2_LIB.BASEBOARD_FAB2(SCH_1):PAGE45
  J6U1   99 DQS13P SCONN288_H44441003_PIP-SCONN,HA   I112 @BASEBOARD_FAB2_LIB.BASEBOARD_FAB2(SCH_1):PAGE46

M_B_DQS_DP<14> @BASEBOARD_FAB2_LIB.BASEBOARD_FAB2(SCH_1):M_B_DQS_DP(14)
  U5D1  C34 DDR1_DQS_DP<14> SKX_EXT_B_BGA1-IC,TBD   I172 @BASEBOARD_FAB2_LIB.BASEBOARD_FAB2(SCH_1):PAGE24
  J4G2  110 DQS14P SCONN288_H44441004_PIP-SCONN,HA    I61 @BASEBOARD_FAB2_LIB.BASEBOARD_FAB2(SCH_1):PAGE45
  J6U1  110 DQS14P SCONN288_H44441003_PIP-SCONN,HA   I112 @BASEBOARD_FAB2_LIB.BASEBOARD_FAB2(SCH_1):PAGE46

M_B_DQS_DP<15> @BASEBOARD_FAB2_LIB.BASEBOARD_FAB2(SCH_1):M_B_DQS_DP(15)
  U5D1  C28 DDR1_DQS_DP<15> SKX_EXT_B_BGA1-IC,TBD   I172 @BASEBOARD_FAB2_LIB.BASEBOARD_FAB2(SCH_1):PAGE24
  J4G2  121 DQS15P SCONN288_H44441004_PIP-SCONN,HA    I61 @BASEBOARD_FAB2_LIB.BASEBOARD_FAB2(SCH_1):PAGE45
  J6U1  121 DQS15P SCONN288_H44441003_PIP-SCONN,HA   I112 @BASEBOARD_FAB2_LIB.BASEBOARD_FAB2(SCH_1):PAGE46

M_B_DQS_DP<16> @BASEBOARD_FAB2_LIB.BASEBOARD_FAB2(SCH_1):M_B_DQS_DP(16)
  U5D1  V27 DDR1_DQS_DP<16> SKX_EXT_B_BGA1-IC,TBD   I172 @BASEBOARD_FAB2_LIB.BASEBOARD_FAB2(SCH_1):PAGE24
  J4G2  132 DQS16P SCONN288_H44441004_PIP-SCONN,HA    I61 @BASEBOARD_FAB2_LIB.BASEBOARD_FAB2(SCH_1):PAGE45
  J6U1  132 DQS16P SCONN288_H44441003_PIP-SCONN,HA   I112 @BASEBOARD_FAB2_LIB.BASEBOARD_FAB2(SCH_1):PAGE46

M_B_DQS_DP<17> @BASEBOARD_FAB2_LIB.BASEBOARD_FAB2(SCH_1):M_B_DQS_DP(17)
  U5D1  J68 DDR1_DQS_DP<17> SKX_EXT_B_BGA1-IC,TBD   I172 @BASEBOARD_FAB2_LIB.BASEBOARD_FAB2(SCH_1):PAGE24
  J4G2   51 DQS17P SCONN288_H44441004_PIP-SCONN,HA    I61 @BASEBOARD_FAB2_LIB.BASEBOARD_FAB2(SCH_1):PAGE45
  J6U1   51 DQS17P SCONN288_H44441003_PIP-SCONN,HA   I112 @BASEBOARD_FAB2_LIB.BASEBOARD_FAB2(SCH_1):PAGE46

M_B_DQS_DP<1> @BASEBOARD_FAB2_LIB.BASEBOARD_FAB2(SCH_1):M_B_DQS_DP(1)
  U5D1 AE80 DDR1_DQS_DP<1> SKX_EXT_B_BGA1-IC,TBD   I172 @BASEBOARD_FAB2_LIB.BASEBOARD_FAB2(SCH_1):PAGE24
  J4G2  164  DQS1P SCONN288_H44441004_PIP-SCONN,HA    I61 @BASEBOARD_FAB2_LIB.BASEBOARD_FAB2(SCH_1):PAGE45
  J6U1  164  DQS1P SCONN288_H44441003_PIP-SCONN,HA   I112 @BASEBOARD_FAB2_LIB.BASEBOARD_FAB2(SCH_1):PAGE46

M_B_DQS_DP<2> @BASEBOARD_FAB2_LIB.BASEBOARD_FAB2(SCH_1):M_B_DQS_DP(2)
  U5D1  H79 DDR1_DQS_DP<2> SKX_EXT_B_BGA1-IC,TBD   I172 @BASEBOARD_FAB2_LIB.BASEBOARD_FAB2(SCH_1):PAGE24
  J4G2  175  DQS2P SCONN288_H44441004_PIP-SCONN,HA    I61 @BASEBOARD_FAB2_LIB.BASEBOARD_FAB2(SCH_1):PAGE45
  J6U1  175  DQS2P SCONN288_H44441003_PIP-SCONN,HA   I112 @BASEBOARD_FAB2_LIB.BASEBOARD_FAB2(SCH_1):PAGE46

M_B_DQS_DP<3> @BASEBOARD_FAB2_LIB.BASEBOARD_FAB2(SCH_1):M_B_DQS_DP(3)
  U5D1  F73 DDR1_DQS_DP<3> SKX_EXT_B_BGA1-IC,TBD   I172 @BASEBOARD_FAB2_LIB.BASEBOARD_FAB2(SCH_1):PAGE24
  J4G2  186  DQS3P SCONN288_H44441004_PIP-SCONN,HA    I61 @BASEBOARD_FAB2_LIB.BASEBOARD_FAB2(SCH_1):PAGE45
  J6U1  186  DQS3P SCONN288_H44441003_PIP-SCONN,HA   I112 @BASEBOARD_FAB2_LIB.BASEBOARD_FAB2(SCH_1):PAGE46

M_B_DQS_DP<4> @BASEBOARD_FAB2_LIB.BASEBOARD_FAB2(SCH_1):M_B_DQS_DP(4)
  U5D1  R42 DDR1_DQS_DP<4> SKX_EXT_B_BGA1-IC,TBD   I172 @BASEBOARD_FAB2_LIB.BASEBOARD_FAB2(SCH_1):PAGE24
  J4G2  245  DQS4P SCONN288_H44441004_PIP-SCONN,HA    I61 @BASEBOARD_FAB2_LIB.BASEBOARD_FAB2(SCH_1):PAGE45
  J6U1  245  DQS4P SCONN288_H44441003_PIP-SCONN,HA   I112 @BASEBOARD_FAB2_LIB.BASEBOARD_FAB2(SCH_1):PAGE46

M_B_DQS_DP<5> @BASEBOARD_FAB2_LIB.BASEBOARD_FAB2(SCH_1):M_B_DQS_DP(5)
  U5D1  E34 DDR1_DQS_DP<5> SKX_EXT_B_BGA1-IC,TBD   I172 @BASEBOARD_FAB2_LIB.BASEBOARD_FAB2(SCH_1):PAGE24
  J4G2  256  DQS5P SCONN288_H44441004_PIP-SCONN,HA    I61 @BASEBOARD_FAB2_LIB.BASEBOARD_FAB2(SCH_1):PAGE45
  J6U1  256  DQS5P SCONN288_H44441003_PIP-SCONN,HA   I112 @BASEBOARD_FAB2_LIB.BASEBOARD_FAB2(SCH_1):PAGE46

M_B_DQS_DP<6> @BASEBOARD_FAB2_LIB.BASEBOARD_FAB2(SCH_1):M_B_DQS_DP(6)
  U5D1  E28 DDR1_DQS_DP<6> SKX_EXT_B_BGA1-IC,TBD   I172 @BASEBOARD_FAB2_LIB.BASEBOARD_FAB2(SCH_1):PAGE24
  J4G2  267  DQS6P SCONN288_H44441004_PIP-SCONN,HA    I61 @BASEBOARD_FAB2_LIB.BASEBOARD_FAB2(SCH_1):PAGE45
  J6U1  267  DQS6P SCONN288_H44441003_PIP-SCONN,HA   I112 @BASEBOARD_FAB2_LIB.BASEBOARD_FAB2(SCH_1):PAGE46

M_B_DQS_DP<7> @BASEBOARD_FAB2_LIB.BASEBOARD_FAB2(SCH_1):M_B_DQS_DP(7)
  U5D1  Y27 DDR1_DQS_DP<7> SKX_EXT_B_BGA1-IC,TBD   I172 @BASEBOARD_FAB2_LIB.BASEBOARD_FAB2(SCH_1):PAGE24
  J4G2  278  DQS7P SCONN288_H44441004_PIP-SCONN,HA    I61 @BASEBOARD_FAB2_LIB.BASEBOARD_FAB2(SCH_1):PAGE45
  J6U1  278  DQS7P SCONN288_H44441003_PIP-SCONN,HA   I112 @BASEBOARD_FAB2_LIB.BASEBOARD_FAB2(SCH_1):PAGE46

M_B_DQS_DP<8> @BASEBOARD_FAB2_LIB.BASEBOARD_FAB2(SCH_1):M_B_DQS_DP(8)
  U5D1  L68 DDR1_DQS_DP<8> SKX_EXT_B_BGA1-IC,TBD   I172 @BASEBOARD_FAB2_LIB.BASEBOARD_FAB2(SCH_1):PAGE24
  J4G2  197  DQS8P SCONN288_H44441004_PIP-SCONN,HA    I61 @BASEBOARD_FAB2_LIB.BASEBOARD_FAB2(SCH_1):PAGE45
  J6U1  197  DQS8P SCONN288_H44441003_PIP-SCONN,HA   I112 @BASEBOARD_FAB2_LIB.BASEBOARD_FAB2(SCH_1):PAGE46

M_B_DQS_DP<9> @BASEBOARD_FAB2_LIB.BASEBOARD_FAB2(SCH_1):M_B_DQS_DP(9)
  U5D1 AT81 DDR1_DQS_DP<9> SKX_EXT_B_BGA1-IC,TBD   I172 @BASEBOARD_FAB2_LIB.BASEBOARD_FAB2(SCH_1):PAGE24
  J4G2    7  DQS9P SCONN288_H44441004_PIP-SCONN,HA    I61 @BASEBOARD_FAB2_LIB.BASEBOARD_FAB2(SCH_1):PAGE45
  J6U1    7  DQS9P SCONN288_H44441003_PIP-SCONN,HA   I112 @BASEBOARD_FAB2_LIB.BASEBOARD_FAB2(SCH_1):PAGE46

M_B_ECC<0> @BASEBOARD_FAB2_LIB.BASEBOARD_FAB2(SCH_1):M_B_ECC(0)
  U5D1  J70 DDR1_ECC<0> SKX_EXT_B_BGA1-IC,TBD   I172 @BASEBOARD_FAB2_LIB.BASEBOARD_FAB2(SCH_1):PAGE24
  J4G2  194  CB<1> SCONN288_H44441004_PIP-SCONN,HA   I111 @BASEBOARD_FAB2_LIB.BASEBOARD_FAB2(SCH_1):PAGE45
  J6U1   49  CB<0> SCONN288_H44441003_PIP-SCONN,HA    I14 @BASEBOARD_FAB2_LIB.BASEBOARD_FAB2(SCH_1):PAGE46

M_B_ECC<1> @BASEBOARD_FAB2_LIB.BASEBOARD_FAB2(SCH_1):M_B_ECC(1)
  U5D1  H69 DDR1_ECC<1> SKX_EXT_B_BGA1-IC,TBD   I172 @BASEBOARD_FAB2_LIB.BASEBOARD_FAB2(SCH_1):PAGE24
  J4G2   49  CB<0> SCONN288_H44441004_PIP-SCONN,HA   I111 @BASEBOARD_FAB2_LIB.BASEBOARD_FAB2(SCH_1):PAGE45
  J6U1  194  CB<1> SCONN288_H44441003_PIP-SCONN,HA    I14 @BASEBOARD_FAB2_LIB.BASEBOARD_FAB2(SCH_1):PAGE46

M_B_ECC<2> @BASEBOARD_FAB2_LIB.BASEBOARD_FAB2(SCH_1):M_B_ECC(2)
  U5D1  J66 DDR1_ECC<2> SKX_EXT_B_BGA1-IC,TBD   I172 @BASEBOARD_FAB2_LIB.BASEBOARD_FAB2(SCH_1):PAGE24
  J4G2  201  CB<3> SCONN288_H44441004_PIP-SCONN,HA   I111 @BASEBOARD_FAB2_LIB.BASEBOARD_FAB2(SCH_1):PAGE45
  J6U1   56  CB<2> SCONN288_H44441003_PIP-SCONN,HA    I14 @BASEBOARD_FAB2_LIB.BASEBOARD_FAB2(SCH_1):PAGE46

M_B_ECC<3> @BASEBOARD_FAB2_LIB.BASEBOARD_FAB2(SCH_1):M_B_ECC(3)
  U5D1  L66 DDR1_ECC<3> SKX_EXT_B_BGA1-IC,TBD   I172 @BASEBOARD_FAB2_LIB.BASEBOARD_FAB2(SCH_1):PAGE24
  J4G2   56  CB<2> SCONN288_H44441004_PIP-SCONN,HA   I111 @BASEBOARD_FAB2_LIB.BASEBOARD_FAB2(SCH_1):PAGE45
  J6U1  201  CB<3> SCONN288_H44441003_PIP-SCONN,HA    I14 @BASEBOARD_FAB2_LIB.BASEBOARD_FAB2(SCH_1):PAGE46

M_B_ECC<4> @BASEBOARD_FAB2_LIB.BASEBOARD_FAB2(SCH_1):M_B_ECC(4)
  U5D1  L70 DDR1_ECC<4> SKX_EXT_B_BGA1-IC,TBD   I172 @BASEBOARD_FAB2_LIB.BASEBOARD_FAB2(SCH_1):PAGE24
  J4G2  192  CB<5> SCONN288_H44441004_PIP-SCONN,HA   I111 @BASEBOARD_FAB2_LIB.BASEBOARD_FAB2(SCH_1):PAGE45
  J6U1   47  CB<4> SCONN288_H44441003_PIP-SCONN,HA    I14 @BASEBOARD_FAB2_LIB.BASEBOARD_FAB2(SCH_1):PAGE46

M_B_ECC<5> @BASEBOARD_FAB2_LIB.BASEBOARD_FAB2(SCH_1):M_B_ECC(5)
  U5D1  M69 DDR1_ECC<5> SKX_EXT_B_BGA1-IC,TBD   I172 @BASEBOARD_FAB2_LIB.BASEBOARD_FAB2(SCH_1):PAGE24
  J4G2   47  CB<4> SCONN288_H44441004_PIP-SCONN,HA   I111 @BASEBOARD_FAB2_LIB.BASEBOARD_FAB2(SCH_1):PAGE45
  J6U1  192  CB<5> SCONN288_H44441003_PIP-SCONN,HA    I14 @BASEBOARD_FAB2_LIB.BASEBOARD_FAB2(SCH_1):PAGE46

M_B_ECC<6> @BASEBOARD_FAB2_LIB.BASEBOARD_FAB2(SCH_1):M_B_ECC(6)
  U5D1  H67 DDR1_ECC<6> SKX_EXT_B_BGA1-IC,TBD   I172 @BASEBOARD_FAB2_LIB.BASEBOARD_FAB2(SCH_1):PAGE24
  J4G2  199  CB<7> SCONN288_H44441004_PIP-SCONN,HA   I111 @BASEBOARD_FAB2_LIB.BASEBOARD_FAB2(SCH_1):PAGE45
  J6U1   54  CB<6> SCONN288_H44441003_PIP-SCONN,HA    I14 @BASEBOARD_FAB2_LIB.BASEBOARD_FAB2(SCH_1):PAGE46

M_B_ECC<7> @BASEBOARD_FAB2_LIB.BASEBOARD_FAB2(SCH_1):M_B_ECC(7)
  U5D1  M67 DDR1_ECC<7> SKX_EXT_B_BGA1-IC,TBD   I172 @BASEBOARD_FAB2_LIB.BASEBOARD_FAB2(SCH_1):PAGE24
  J4G2   54  CB<6> SCONN288_H44441004_PIP-SCONN,HA   I111 @BASEBOARD_FAB2_LIB.BASEBOARD_FAB2(SCH_1):PAGE45
  J6U1  199  CB<7> SCONN288_H44441003_PIP-SCONN,HA    I14 @BASEBOARD_FAB2_LIB.BASEBOARD_FAB2(SCH_1):PAGE46

M_B_MA<0> @BASEBOARD_FAB2_LIB.BASEBOARD_FAB2(SCH_1):M_B_MA(0)
  U5D1  J52 DDR1_MA<0> SKX_EXT_B_BGA1-IC,TBD   I172 @BASEBOARD_FAB2_LIB.BASEBOARD_FAB2(SCH_1):PAGE24
  J4G2   79     A0 SCONN288_H44441004_PIP-SCONN,HA   I111 @BASEBOARD_FAB2_LIB.BASEBOARD_FAB2(SCH_1):PAGE45
  J6U1   79     A0 SCONN288_H44441003_PIP-SCONN,HA    I14 @BASEBOARD_FAB2_LIB.BASEBOARD_FAB2(SCH_1):PAGE46

M_B_MA<10> @BASEBOARD_FAB2_LIB.BASEBOARD_FAB2(SCH_1):M_B_MA(10)
  U5D1  M55 DDR1_MA<10> SKX_EXT_B_BGA1-IC,TBD   I172 @BASEBOARD_FAB2_LIB.BASEBOARD_FAB2(SCH_1):PAGE24
  J4G2  225    A10 SCONN288_H44441004_PIP-SCONN,HA   I111 @BASEBOARD_FAB2_LIB.BASEBOARD_FAB2(SCH_1):PAGE45
  J6U1  225    A10 SCONN288_H44441003_PIP-SCONN,HA    I14 @BASEBOARD_FAB2_LIB.BASEBOARD_FAB2(SCH_1):PAGE46

M_B_MA<11> @BASEBOARD_FAB2_LIB.BASEBOARD_FAB2(SCH_1):M_B_MA(11)
  U5D1  R60 DDR1_MA<11> SKX_EXT_B_BGA1-IC,TBD   I172 @BASEBOARD_FAB2_LIB.BASEBOARD_FAB2(SCH_1):PAGE24
  J4G2  210    A11 SCONN288_H44441004_PIP-SCONN,HA   I111 @BASEBOARD_FAB2_LIB.BASEBOARD_FAB2(SCH_1):PAGE45
  J6U1  210    A11 SCONN288_H44441003_PIP-SCONN,HA    I14 @BASEBOARD_FAB2_LIB.BASEBOARD_FAB2(SCH_1):PAGE46

M_B_MA<12> @BASEBOARD_FAB2_LIB.BASEBOARD_FAB2(SCH_1):M_B_MA(12)
  U5D1  T61 DDR1_MA<12> SKX_EXT_B_BGA1-IC,TBD   I172 @BASEBOARD_FAB2_LIB.BASEBOARD_FAB2(SCH_1):PAGE24
  J4G2   65    A12 SCONN288_H44441004_PIP-SCONN,HA   I111 @BASEBOARD_FAB2_LIB.BASEBOARD_FAB2(SCH_1):PAGE45
  J6U1   65    A12 SCONN288_H44441003_PIP-SCONN,HA    I14 @BASEBOARD_FAB2_LIB.BASEBOARD_FAB2(SCH_1):PAGE46

M_B_MA<13> @BASEBOARD_FAB2_LIB.BASEBOARD_FAB2(SCH_1):M_B_MA(13)
  U5D1  M51 DDR1_MA<13> SKX_EXT_B_BGA1-IC,TBD   I172 @BASEBOARD_FAB2_LIB.BASEBOARD_FAB2(SCH_1):PAGE24
  J4G2  232    A13 SCONN288_H44441004_PIP-SCONN,HA   I111 @BASEBOARD_FAB2_LIB.BASEBOARD_FAB2(SCH_1):PAGE45
  J6U1  232    A13 SCONN288_H44441003_PIP-SCONN,HA    I14 @BASEBOARD_FAB2_LIB.BASEBOARD_FAB2(SCH_1):PAGE46

M_B_MA<14> @BASEBOARD_FAB2_LIB.BASEBOARD_FAB2(SCH_1):M_B_MA(14)
  U5D1  T51 DDR1_MA<14> SKX_EXT_B_BGA1-IC,TBD   I172 @BASEBOARD_FAB2_LIB.BASEBOARD_FAB2(SCH_1):PAGE24
  J4G2  228 A14_WE_N SCONN288_H44441004_PIP-SCONN,HA   I111 @BASEBOARD_FAB2_LIB.BASEBOARD_FAB2(SCH_1):PAGE45
  J6U1  228 A14_WE_N SCONN288_H44441003_PIP-SCONN,HA    I14 @BASEBOARD_FAB2_LIB.BASEBOARD_FAB2(SCH_1):PAGE46

M_B_MA<15> @BASEBOARD_FAB2_LIB.BASEBOARD_FAB2(SCH_1):M_B_MA(15)
  U5D1  N52 DDR1_MA<15> SKX_EXT_B_BGA1-IC,TBD   I172 @BASEBOARD_FAB2_LIB.BASEBOARD_FAB2(SCH_1):PAGE24
  J4G2   86 A15_CAS_N SCONN288_H44441004_PIP-SCONN,HA   I111 @BASEBOARD_FAB2_LIB.BASEBOARD_FAB2(SCH_1):PAGE45
  J6U1   86 A15_CAS_N SCONN288_H44441003_PIP-SCONN,HA    I14 @BASEBOARD_FAB2_LIB.BASEBOARD_FAB2(SCH_1):PAGE46

M_B_MA<16> @BASEBOARD_FAB2_LIB.BASEBOARD_FAB2(SCH_1):M_B_MA(16)
  U5D1  R52 DDR1_MA<16> SKX_EXT_B_BGA1-IC,TBD   I172 @BASEBOARD_FAB2_LIB.BASEBOARD_FAB2(SCH_1):PAGE24
  J4G2   82 A16_RAS_N SCONN288_H44441004_PIP-SCONN,HA   I111 @BASEBOARD_FAB2_LIB.BASEBOARD_FAB2(SCH_1):PAGE45
  J6U1   82 A16_RAS_N SCONN288_H44441003_PIP-SCONN,HA    I14 @BASEBOARD_FAB2_LIB.BASEBOARD_FAB2(SCH_1):PAGE46

M_B_MA<17> @BASEBOARD_FAB2_LIB.BASEBOARD_FAB2(SCH_1):M_B_MA(17)
  U5D1  N48 DDR1_MA<17> SKX_EXT_B_BGA1-IC,TBD   I172 @BASEBOARD_FAB2_LIB.BASEBOARD_FAB2(SCH_1):PAGE24
  J4G2  234    A17 SCONN288_H44441004_PIP-SCONN,HA   I111 @BASEBOARD_FAB2_LIB.BASEBOARD_FAB2(SCH_1):PAGE45
  J6U1  234    A17 SCONN288_H44441003_PIP-SCONN,HA    I14 @BASEBOARD_FAB2_LIB.BASEBOARD_FAB2(SCH_1):PAGE46

M_B_MA<1> @BASEBOARD_FAB2_LIB.BASEBOARD_FAB2(SCH_1):M_B_MA(1)
  U5D1  J58 DDR1_MA<1> SKX_EXT_B_BGA1-IC,TBD   I172 @BASEBOARD_FAB2_LIB.BASEBOARD_FAB2(SCH_1):PAGE24
  J4G2   72     A1 SCONN288_H44441004_PIP-SCONN,HA   I111 @BASEBOARD_FAB2_LIB.BASEBOARD_FAB2(SCH_1):PAGE45
  J6U1   72     A1 SCONN288_H44441003_PIP-SCONN,HA    I14 @BASEBOARD_FAB2_LIB.BASEBOARD_FAB2(SCH_1):PAGE46

M_B_MA<2> @BASEBOARD_FAB2_LIB.BASEBOARD_FAB2(SCH_1):M_B_MA(2)
  U5D1  K57 DDR1_MA<2> SKX_EXT_B_BGA1-IC,TBD   I172 @BASEBOARD_FAB2_LIB.BASEBOARD_FAB2(SCH_1):PAGE24
  J4G2  216     A2 SCONN288_H44441004_PIP-SCONN,HA   I111 @BASEBOARD_FAB2_LIB.BASEBOARD_FAB2(SCH_1):PAGE45
  J6U1  216     A2 SCONN288_H44441003_PIP-SCONN,HA    I14 @BASEBOARD_FAB2_LIB.BASEBOARD_FAB2(SCH_1):PAGE46

M_B_MA<3> @BASEBOARD_FAB2_LIB.BASEBOARD_FAB2(SCH_1):M_B_MA(3)
  U5D1  N58 DDR1_MA<3> SKX_EXT_B_BGA1-IC,TBD   I172 @BASEBOARD_FAB2_LIB.BASEBOARD_FAB2(SCH_1):PAGE24
  J4G2   71     A3 SCONN288_H44441004_PIP-SCONN,HA   I111 @BASEBOARD_FAB2_LIB.BASEBOARD_FAB2(SCH_1):PAGE45
  J6U1   71     A3 SCONN288_H44441003_PIP-SCONN,HA    I14 @BASEBOARD_FAB2_LIB.BASEBOARD_FAB2(SCH_1):PAGE46

M_B_MA<4> @BASEBOARD_FAB2_LIB.BASEBOARD_FAB2(SCH_1):M_B_MA(4)
  U5D1  M59 DDR1_MA<4> SKX_EXT_B_BGA1-IC,TBD   I172 @BASEBOARD_FAB2_LIB.BASEBOARD_FAB2(SCH_1):PAGE24
  J4G2  214     A4 SCONN288_H44441004_PIP-SCONN,HA   I111 @BASEBOARD_FAB2_LIB.BASEBOARD_FAB2(SCH_1):PAGE45
  J6U1  214     A4 SCONN288_H44441003_PIP-SCONN,HA    I14 @BASEBOARD_FAB2_LIB.BASEBOARD_FAB2(SCH_1):PAGE46

M_B_MA<5> @BASEBOARD_FAB2_LIB.BASEBOARD_FAB2(SCH_1):M_B_MA(5)
  U5D1  R58 DDR1_MA<5> SKX_EXT_B_BGA1-IC,TBD   I172 @BASEBOARD_FAB2_LIB.BASEBOARD_FAB2(SCH_1):PAGE24
  J4G2  213     A5 SCONN288_H44441004_PIP-SCONN,HA   I111 @BASEBOARD_FAB2_LIB.BASEBOARD_FAB2(SCH_1):PAGE45
  J6U1  213     A5 SCONN288_H44441003_PIP-SCONN,HA    I14 @BASEBOARD_FAB2_LIB.BASEBOARD_FAB2(SCH_1):PAGE46

M_B_MA<6> @BASEBOARD_FAB2_LIB.BASEBOARD_FAB2(SCH_1):M_B_MA(6)
  U5D1  T59 DDR1_MA<6> SKX_EXT_B_BGA1-IC,TBD   I172 @BASEBOARD_FAB2_LIB.BASEBOARD_FAB2(SCH_1):PAGE24
  J4G2   69     A6 SCONN288_H44441004_PIP-SCONN,HA   I111 @BASEBOARD_FAB2_LIB.BASEBOARD_FAB2(SCH_1):PAGE45
  J6U1   69     A6 SCONN288_H44441003_PIP-SCONN,HA    I14 @BASEBOARD_FAB2_LIB.BASEBOARD_FAB2(SCH_1):PAGE46

M_B_MA<7> @BASEBOARD_FAB2_LIB.BASEBOARD_FAB2(SCH_1):M_B_MA(7)
  U5D1  V61 DDR1_MA<7> SKX_EXT_B_BGA1-IC,TBD   I172 @BASEBOARD_FAB2_LIB.BASEBOARD_FAB2(SCH_1):PAGE24
  J4G2  211     A7 SCONN288_H44441004_PIP-SCONN,HA   I111 @BASEBOARD_FAB2_LIB.BASEBOARD_FAB2(SCH_1):PAGE45
  J6U1  211     A7 SCONN288_H44441003_PIP-SCONN,HA    I14 @BASEBOARD_FAB2_LIB.BASEBOARD_FAB2(SCH_1):PAGE46

M_B_MA<8> @BASEBOARD_FAB2_LIB.BASEBOARD_FAB2(SCH_1):M_B_MA(8)
  U5D1  W60 DDR1_MA<8> SKX_EXT_B_BGA1-IC,TBD   I172 @BASEBOARD_FAB2_LIB.BASEBOARD_FAB2(SCH_1):PAGE24
  J4G2   68     A8 SCONN288_H44441004_PIP-SCONN,HA   I111 @BASEBOARD_FAB2_LIB.BASEBOARD_FAB2(SCH_1):PAGE45
  J6U1   68     A8 SCONN288_H44441003_PIP-SCONN,HA    I14 @BASEBOARD_FAB2_LIB.BASEBOARD_FAB2(SCH_1):PAGE46

M_B_MA<9> @BASEBOARD_FAB2_LIB.BASEBOARD_FAB2(SCH_1):M_B_MA(9)
  U5D1  K59 DDR1_MA<9> SKX_EXT_B_BGA1-IC,TBD   I172 @BASEBOARD_FAB2_LIB.BASEBOARD_FAB2(SCH_1):PAGE24
  J4G2   66     A9 SCONN288_H44441004_PIP-SCONN,HA   I111 @BASEBOARD_FAB2_LIB.BASEBOARD_FAB2(SCH_1):PAGE45
  J6U1   66     A9 SCONN288_H44441003_PIP-SCONN,HA    I14 @BASEBOARD_FAB2_LIB.BASEBOARD_FAB2(SCH_1):PAGE46

M_B_ODT<0> @BASEBOARD_FAB2_LIB.BASEBOARD_FAB2(SCH_1):M_B_ODT(0)
  U5D1  N50 DDR1_ODT<0> SKX_EXT_B_BGA1-IC,TBD   I172 @BASEBOARD_FAB2_LIB.BASEBOARD_FAB2(SCH_1):PAGE24
  J4G2   87 ODT<0> SCONN288_H44441004_PIP-SCONN,HA   I111 @BASEBOARD_FAB2_LIB.BASEBOARD_FAB2(SCH_1):PAGE45

M_B_ODT<1> @BASEBOARD_FAB2_LIB.BASEBOARD_FAB2(SCH_1):M_B_ODT(1)
  U5D1  R48 DDR1_ODT<1> SKX_EXT_B_BGA1-IC,TBD   I172 @BASEBOARD_FAB2_LIB.BASEBOARD_FAB2(SCH_1):PAGE24
  J4G2   91 ODT<1> SCONN288_H44441004_PIP-SCONN,HA   I111 @BASEBOARD_FAB2_LIB.BASEBOARD_FAB2(SCH_1):PAGE45

M_B_ODT<2> @BASEBOARD_FAB2_LIB.BASEBOARD_FAB2(SCH_1):M_B_ODT(2)
  U5D1  M49 DDR1_ODT<2> SKX_EXT_B_BGA1-IC,TBD   I172 @BASEBOARD_FAB2_LIB.BASEBOARD_FAB2(SCH_1):PAGE24
  J6U1   87 ODT<0> SCONN288_H44441003_PIP-SCONN,HA    I14 @BASEBOARD_FAB2_LIB.BASEBOARD_FAB2(SCH_1):PAGE46

M_B_ODT<3> @BASEBOARD_FAB2_LIB.BASEBOARD_FAB2(SCH_1):M_B_ODT(3)
  U5D1  T47 DDR1_ODT<3> SKX_EXT_B_BGA1-IC,TBD   I172 @BASEBOARD_FAB2_LIB.BASEBOARD_FAB2(SCH_1):PAGE24
  J6U1   91 ODT<1> SCONN288_H44441003_PIP-SCONN,HA    I14 @BASEBOARD_FAB2_LIB.BASEBOARD_FAB2(SCH_1):PAGE46

M_B_PAR @BASEBOARD_FAB2_LIB.BASEBOARD_FAB2(SCH_1):M_B_PAR
  U5D1  K53 DDR1_PAR SKX_EXT_B_BGA1-IC,TBD   I172 @BASEBOARD_FAB2_LIB.BASEBOARD_FAB2(SCH_1):PAGE24
  J4G2  222    PAR SCONN288_H44441004_PIP-SCONN,HA   I111 @BASEBOARD_FAB2_LIB.BASEBOARD_FAB2(SCH_1):PAGE45
  J6U1  222    PAR SCONN288_H44441003_PIP-SCONN,HA    I14 @BASEBOARD_FAB2_LIB.BASEBOARD_FAB2(SCH_1):PAGE46

M_B_VREF @BASEBOARD_FAB2_LIB.BASEBOARD_FAB2(SCH_1):M_B_VREF
  J4G2  146 VREFCA SCONN288_H44441004_PIP-SCONN,HA   I111 @BASEBOARD_FAB2_LIB.BASEBOARD_FAB2(SCH_1):PAGE45
  C4G3    1      A CAP_A_0402V-0.01UF,25V,10%,X7RA   I179 @BASEBOARD_FAB2_LIB.BASEBOARD_FAB2(SCH_1):PAGE45
  C6U9    1      A CAP_A_0402V-0.01UF,25V,10%,X7RA     I5 @BASEBOARD_FAB2_LIB.BASEBOARD_FAB2(SCH_1):PAGE46
  J6U1  146 VREFCA SCONN288_H44441003_PIP-SCONN,HA    I14 @BASEBOARD_FAB2_LIB.BASEBOARD_FAB2(SCH_1):PAGE46
  R4G2    2      B RES_0402-1.00K,1%,1/16W,CHIP,GA    I38 @BASEBOARD_FAB2_LIB.BASEBOARD_FAB2(SCH_1):PAGE98
  R4G3    1      A RES_0402-1.00K,1%,1/16W,CHIP,GA    I40 @BASEBOARD_FAB2_LIB.BASEBOARD_FAB2(SCH_1):PAGE98
  R4G1    2      B RES_0402-2,1.0%,1/16W,CHIP,G21A    I42 @BASEBOARD_FAB2_LIB.BASEBOARD_FAB2(SCH_1):PAGE98

M_C_ACT_N @BASEBOARD_FAB2_LIB.BASEBOARD_FAB2(SCH_1):M_C_ACT_N
  U5D1 AB61 DDR2_ACT_N SKX_EXT_B_BGA1-IC,TBD   I172 @BASEBOARD_FAB2_LIB.BASEBOARD_FAB2(SCH_1):PAGE25
  J4G3   62  ACT_N SCONN288_H44441004_PIP-SCONN,HA   I111 @BASEBOARD_FAB2_LIB.BASEBOARD_FAB2(SCH_1):PAGE47
  J6U2   62  ACT_N SCONN288_H44441003_PIP-SCONN,HA   I111 @BASEBOARD_FAB2_LIB.BASEBOARD_FAB2(SCH_1):PAGE48

M_C_ALERT_N @BASEBOARD_FAB2_LIB.BASEBOARD_FAB2(SCH_1):M_C_ALERT_N
  U5D1 AD61 DDR2_ALERT_N SKX_EXT_B_BGA1-IC,TBD   I172 @BASEBOARD_FAB2_LIB.BASEBOARD_FAB2(SCH_1):PAGE25
  J4G3  208 ALERT_N SCONN288_H44441004_PIP-SCONN,HA   I111 @BASEBOARD_FAB2_LIB.BASEBOARD_FAB2(SCH_1):PAGE47
  J6U2  208 ALERT_N SCONN288_H44441003_PIP-SCONN,HA   I111 @BASEBOARD_FAB2_LIB.BASEBOARD_FAB2(SCH_1):PAGE48

M_C_BA<0> @BASEBOARD_FAB2_LIB.BASEBOARD_FAB2(SCH_1):M_C_BA(0)
  U5D1  W52 DDR2_BA<0> SKX_EXT_B_BGA1-IC,TBD   I172 @BASEBOARD_FAB2_LIB.BASEBOARD_FAB2(SCH_1):PAGE25
  J4G3   81  BA<0> SCONN288_H44441004_PIP-SCONN,HA   I111 @BASEBOARD_FAB2_LIB.BASEBOARD_FAB2(SCH_1):PAGE47
  J6U2   81  BA<0> SCONN288_H44441003_PIP-SCONN,HA   I111 @BASEBOARD_FAB2_LIB.BASEBOARD_FAB2(SCH_1):PAGE48

M_C_BA<1> @BASEBOARD_FAB2_LIB.BASEBOARD_FAB2(SCH_1):M_C_BA(1)
  U5D1 AE56 DDR2_BA<1> SKX_EXT_B_BGA1-IC,TBD   I172 @BASEBOARD_FAB2_LIB.BASEBOARD_FAB2(SCH_1):PAGE25
  J4G3  224  BA<1> SCONN288_H44441004_PIP-SCONN,HA   I111 @BASEBOARD_FAB2_LIB.BASEBOARD_FAB2(SCH_1):PAGE47
  J6U2  224  BA<1> SCONN288_H44441003_PIP-SCONN,HA   I111 @BASEBOARD_FAB2_LIB.BASEBOARD_FAB2(SCH_1):PAGE48

M_C_BG<0> @BASEBOARD_FAB2_LIB.BASEBOARD_FAB2(SCH_1):M_C_BG(0)
  U5D1 AA60 DDR2_BG<0> SKX_EXT_B_BGA1-IC,TBD   I172 @BASEBOARD_FAB2_LIB.BASEBOARD_FAB2(SCH_1):PAGE25
  J4G3   63  BG<0> SCONN288_H44441004_PIP-SCONN,HA   I111 @BASEBOARD_FAB2_LIB.BASEBOARD_FAB2(SCH_1):PAGE47
  J6U2   63  BG<0> SCONN288_H44441003_PIP-SCONN,HA   I111 @BASEBOARD_FAB2_LIB.BASEBOARD_FAB2(SCH_1):PAGE48

M_C_BG<1> @BASEBOARD_FAB2_LIB.BASEBOARD_FAB2(SCH_1):M_C_BG(1)
  U5D1 AE62 DDR2_BG<1> SKX_EXT_B_BGA1-IC,TBD   I172 @BASEBOARD_FAB2_LIB.BASEBOARD_FAB2(SCH_1):PAGE25
  J4G3  207  BG<1> SCONN288_H44441004_PIP-SCONN,HA   I111 @BASEBOARD_FAB2_LIB.BASEBOARD_FAB2(SCH_1):PAGE47
  J6U2  207  BG<1> SCONN288_H44441003_PIP-SCONN,HA   I111 @BASEBOARD_FAB2_LIB.BASEBOARD_FAB2(SCH_1):PAGE48

M_C_C<2> @BASEBOARD_FAB2_LIB.BASEBOARD_FAB2(SCH_1):M_C_C(2)
  U5D1 AB45 DDR2_CID<2> SKX_EXT_B_BGA1-IC,TBD   I172 @BASEBOARD_FAB2_LIB.BASEBOARD_FAB2(SCH_1):PAGE25
  J4G3  235   C<2> SCONN288_H44441004_PIP-SCONN,HA   I111 @BASEBOARD_FAB2_LIB.BASEBOARD_FAB2(SCH_1):PAGE47
  J6U2  235   C<2> SCONN288_H44441003_PIP-SCONN,HA   I111 @BASEBOARD_FAB2_LIB.BASEBOARD_FAB2(SCH_1):PAGE48

M_C_CKE<0> @BASEBOARD_FAB2_LIB.BASEBOARD_FAB2(SCH_1):M_C_CKE(0)
  U5D1 AA62 DDR2_CKE<0> SKX_EXT_B_BGA1-IC,TBD   I172 @BASEBOARD_FAB2_LIB.BASEBOARD_FAB2(SCH_1):PAGE25
  J4G3   60 CKE<0> SCONN288_H44441004_PIP-SCONN,HA   I111 @BASEBOARD_FAB2_LIB.BASEBOARD_FAB2(SCH_1):PAGE47

M_C_CKE<1> @BASEBOARD_FAB2_LIB.BASEBOARD_FAB2(SCH_1):M_C_CKE(1)
  U5D1 AD63 DDR2_CKE<1> SKX_EXT_B_BGA1-IC,TBD   I172 @BASEBOARD_FAB2_LIB.BASEBOARD_FAB2(SCH_1):PAGE25
  J4G3  203 CKE<1> SCONN288_H44441004_PIP-SCONN,HA   I111 @BASEBOARD_FAB2_LIB.BASEBOARD_FAB2(SCH_1):PAGE47

M_C_CKE<2> @BASEBOARD_FAB2_LIB.BASEBOARD_FAB2(SCH_1):M_C_CKE(2)
  U5D1  V63 DDR2_CKE<2> SKX_EXT_B_BGA1-IC,TBD   I172 @BASEBOARD_FAB2_LIB.BASEBOARD_FAB2(SCH_1):PAGE25
  J6U2   60 CKE<0> SCONN288_H44441003_PIP-SCONN,HA   I111 @BASEBOARD_FAB2_LIB.BASEBOARD_FAB2(SCH_1):PAGE48

M_C_CKE<3> @BASEBOARD_FAB2_LIB.BASEBOARD_FAB2(SCH_1):M_C_CKE(3)
  U5D1 AB63 DDR2_CKE<3> SKX_EXT_B_BGA1-IC,TBD   I172 @BASEBOARD_FAB2_LIB.BASEBOARD_FAB2(SCH_1):PAGE25
  J6U2  203 CKE<1> SCONN288_H44441003_PIP-SCONN,HA   I111 @BASEBOARD_FAB2_LIB.BASEBOARD_FAB2(SCH_1):PAGE48

M_C_CLK_DN<0> @BASEBOARD_FAB2_LIB.BASEBOARD_FAB2(SCH_1):M_C_CLK_DN(0)
  U5D1 AA54 DDR2_CLK_DN<0> SKX_EXT_B_BGA1-IC,TBD   I172 @BASEBOARD_FAB2_LIB.BASEBOARD_FAB2(SCH_1):PAGE25
  J4G3   75   CK0N SCONN288_H44441004_PIP-SCONN,HA   I111 @BASEBOARD_FAB2_LIB.BASEBOARD_FAB2(SCH_1):PAGE47

M_C_CLK_DN<1> @BASEBOARD_FAB2_LIB.BASEBOARD_FAB2(SCH_1):M_C_CLK_DN(1)
  U5D1  W54 DDR2_CLK_DN<1> SKX_EXT_B_BGA1-IC,TBD   I172 @BASEBOARD_FAB2_LIB.BASEBOARD_FAB2(SCH_1):PAGE25
  J4G3  219   CK1N SCONN288_H44441004_PIP-SCONN,HA   I111 @BASEBOARD_FAB2_LIB.BASEBOARD_FAB2(SCH_1):PAGE47

M_C_CLK_DN<2> @BASEBOARD_FAB2_LIB.BASEBOARD_FAB2(SCH_1):M_C_CLK_DN(2)
  U5D1 AA56 DDR2_CLK_DN<2> SKX_EXT_B_BGA1-IC,TBD   I172 @BASEBOARD_FAB2_LIB.BASEBOARD_FAB2(SCH_1):PAGE25
  J6U2   75   CK0N SCONN288_H44441003_PIP-SCONN,HA   I111 @BASEBOARD_FAB2_LIB.BASEBOARD_FAB2(SCH_1):PAGE48

M_C_CLK_DN<3> @BASEBOARD_FAB2_LIB.BASEBOARD_FAB2(SCH_1):M_C_CLK_DN(3)
  U5D1  W56 DDR2_CLK_DN<3> SKX_EXT_B_BGA1-IC,TBD   I172 @BASEBOARD_FAB2_LIB.BASEBOARD_FAB2(SCH_1):PAGE25
  J6U2  219   CK1N SCONN288_H44441003_PIP-SCONN,HA   I111 @BASEBOARD_FAB2_LIB.BASEBOARD_FAB2(SCH_1):PAGE48

M_C_CLK_DP<0> @BASEBOARD_FAB2_LIB.BASEBOARD_FAB2(SCH_1):M_C_CLK_DP(0)
  U5D1 AB55 DDR2_CLK_DP<0> SKX_EXT_B_BGA1-IC,TBD   I172 @BASEBOARD_FAB2_LIB.BASEBOARD_FAB2(SCH_1):PAGE25
  J4G3   74   CK0P SCONN288_H44441004_PIP-SCONN,HA   I111 @BASEBOARD_FAB2_LIB.BASEBOARD_FAB2(SCH_1):PAGE47

M_C_CLK_DP<1> @BASEBOARD_FAB2_LIB.BASEBOARD_FAB2(SCH_1):M_C_CLK_DP(1)
  U5D1  V55 DDR2_CLK_DP<1> SKX_EXT_B_BGA1-IC,TBD   I172 @BASEBOARD_FAB2_LIB.BASEBOARD_FAB2(SCH_1):PAGE25
  J4G3  218   CK1P SCONN288_H44441004_PIP-SCONN,HA   I111 @BASEBOARD_FAB2_LIB.BASEBOARD_FAB2(SCH_1):PAGE47

M_C_CLK_DP<2> @BASEBOARD_FAB2_LIB.BASEBOARD_FAB2(SCH_1):M_C_CLK_DP(2)
  U5D1 AB57 DDR2_CLK_DP<2> SKX_EXT_B_BGA1-IC,TBD   I172 @BASEBOARD_FAB2_LIB.BASEBOARD_FAB2(SCH_1):PAGE25
  J6U2   74   CK0P SCONN288_H44441003_PIP-SCONN,HA   I111 @BASEBOARD_FAB2_LIB.BASEBOARD_FAB2(SCH_1):PAGE48

M_C_CLK_DP<3> @BASEBOARD_FAB2_LIB.BASEBOARD_FAB2(SCH_1):M_C_CLK_DP(3)
  U5D1  V57 DDR2_CLK_DP<3> SKX_EXT_B_BGA1-IC,TBD   I172 @BASEBOARD_FAB2_LIB.BASEBOARD_FAB2(SCH_1):PAGE25
  J6U2  218   CK1P SCONN288_H44441003_PIP-SCONN,HA   I111 @BASEBOARD_FAB2_LIB.BASEBOARD_FAB2(SCH_1):PAGE48

M_C_CPU_VREF @BASEBOARD_FAB2_LIB.BASEBOARD_FAB2(SCH_1):M_C_CPU_VREF
  U5D1 AH63 DDR2_CAVREF SKX_EXT_B_BGA1-IC,TBD   I259 @BASEBOARD_FAB2_LIB.BASEBOARD_FAB2(SCH_1):PAGE21
 R4G20    1      A RES_0402-2,1.0%,1/16W,CHIP,G21A    I50 @BASEBOARD_FAB2_LIB.BASEBOARD_FAB2(SCH_1):PAGE98
 C4G17    1      A CAP_A_0402V-0.01UF,25V,10%,X7RA    I51 @BASEBOARD_FAB2_LIB.BASEBOARD_FAB2(SCH_1):PAGE98

M_C_CS_N<0> @BASEBOARD_FAB2_LIB.BASEBOARD_FAB2(SCH_1):M_C_CS_N(0)
  U5D1  V51 DDR2_CS_N<0> SKX_EXT_B_BGA1-IC,TBD   I172 @BASEBOARD_FAB2_LIB.BASEBOARD_FAB2(SCH_1):PAGE25
  J4G3   84   S0_N SCONN288_H44441004_PIP-SCONN,HA   I111 @BASEBOARD_FAB2_LIB.BASEBOARD_FAB2(SCH_1):PAGE47

M_C_CS_N<1> @BASEBOARD_FAB2_LIB.BASEBOARD_FAB2(SCH_1):M_C_CS_N(1)
  U5D1 AB49 DDR2_CS_N<1> SKX_EXT_B_BGA1-IC,TBD   I172 @BASEBOARD_FAB2_LIB.BASEBOARD_FAB2(SCH_1):PAGE25
  J4G3   89   S1_N SCONN288_H44441004_PIP-SCONN,HA   I111 @BASEBOARD_FAB2_LIB.BASEBOARD_FAB2(SCH_1):PAGE47

M_C_CS_N<2> @BASEBOARD_FAB2_LIB.BASEBOARD_FAB2(SCH_1):M_C_CS_N(2)
  U5D1  W46 DDR2_CS_N<2> SKX_EXT_B_BGA1-IC,TBD   I172 @BASEBOARD_FAB2_LIB.BASEBOARD_FAB2(SCH_1):PAGE25
  J4G3   93 S2_N_C<0> SCONN288_H44441004_PIP-SCONN,HA   I111 @BASEBOARD_FAB2_LIB.BASEBOARD_FAB2(SCH_1):PAGE47

M_C_CS_N<3> @BASEBOARD_FAB2_LIB.BASEBOARD_FAB2(SCH_1):M_C_CS_N(3)
  U5D1 AA46 DDR2_CS_N<3> SKX_EXT_B_BGA1-IC,TBD   I172 @BASEBOARD_FAB2_LIB.BASEBOARD_FAB2(SCH_1):PAGE25
  J4G3  237 S3_N_C<1> SCONN288_H44441004_PIP-SCONN,HA   I111 @BASEBOARD_FAB2_LIB.BASEBOARD_FAB2(SCH_1):PAGE47

M_C_CS_N<4> @BASEBOARD_FAB2_LIB.BASEBOARD_FAB2(SCH_1):M_C_CS_N(4)
  U5D1 AB51 DDR2_CS_N<4> SKX_EXT_B_BGA1-IC,TBD   I172 @BASEBOARD_FAB2_LIB.BASEBOARD_FAB2(SCH_1):PAGE25
  J6U2   84   S0_N SCONN288_H44441003_PIP-SCONN,HA   I111 @BASEBOARD_FAB2_LIB.BASEBOARD_FAB2(SCH_1):PAGE48

M_C_CS_N<5> @BASEBOARD_FAB2_LIB.BASEBOARD_FAB2(SCH_1):M_C_CS_N(5)
  U5D1  W48 DDR2_CS_N<5> SKX_EXT_B_BGA1-IC,TBD   I172 @BASEBOARD_FAB2_LIB.BASEBOARD_FAB2(SCH_1):PAGE25
  J6U2   89   S1_N SCONN288_H44441003_PIP-SCONN,HA   I111 @BASEBOARD_FAB2_LIB.BASEBOARD_FAB2(SCH_1):PAGE48

M_C_CS_N<6> @BASEBOARD_FAB2_LIB.BASEBOARD_FAB2(SCH_1):M_C_CS_N(6)
  U5D1  T45 DDR2_CS_N<6> SKX_EXT_B_BGA1-IC,TBD   I172 @BASEBOARD_FAB2_LIB.BASEBOARD_FAB2(SCH_1):PAGE25
  J6U2   93 S2_N_C<0> SCONN288_H44441003_PIP-SCONN,HA   I111 @BASEBOARD_FAB2_LIB.BASEBOARD_FAB2(SCH_1):PAGE48

M_C_CS_N<7> @BASEBOARD_FAB2_LIB.BASEBOARD_FAB2(SCH_1):M_C_CS_N(7)
  U5D1  V45 DDR2_CS_N<7> SKX_EXT_B_BGA1-IC,TBD   I172 @BASEBOARD_FAB2_LIB.BASEBOARD_FAB2(SCH_1):PAGE25
  J6U2  237 S3_N_C<1> SCONN288_H44441003_PIP-SCONN,HA   I111 @BASEBOARD_FAB2_LIB.BASEBOARD_FAB2(SCH_1):PAGE48

M_C_DQ<0> @BASEBOARD_FAB2_LIB.BASEBOARD_FAB2(SCH_1):M_C_DQ(0)
  U5D1 AR76 DDR2_DQ<0> SKX_EXT_B_BGA1-IC,TBD   I172 @BASEBOARD_FAB2_LIB.BASEBOARD_FAB2(SCH_1):PAGE25
  J4G3  150  DQ<1> SCONN288_H44441004_PIP-SCONN,HA   I111 @BASEBOARD_FAB2_LIB.BASEBOARD_FAB2(SCH_1):PAGE47
  J6U2    5  DQ<0> SCONN288_H44441003_PIP-SCONN,HA   I111 @BASEBOARD_FAB2_LIB.BASEBOARD_FAB2(SCH_1):PAGE48

M_C_DQ<10> @BASEBOARD_FAB2_LIB.BASEBOARD_FAB2(SCH_1):M_C_DQ(10)
  U5D1  Y77 DDR2_DQ<10> SKX_EXT_B_BGA1-IC,TBD   I172 @BASEBOARD_FAB2_LIB.BASEBOARD_FAB2(SCH_1):PAGE25
  J4G3  168 DQ<11> SCONN288_H44441004_PIP-SCONN,HA   I111 @BASEBOARD_FAB2_LIB.BASEBOARD_FAB2(SCH_1):PAGE47
  J6U2   23 DQ<10> SCONN288_H44441003_PIP-SCONN,HA   I111 @BASEBOARD_FAB2_LIB.BASEBOARD_FAB2(SCH_1):PAGE48

M_C_DQ<11> @BASEBOARD_FAB2_LIB.BASEBOARD_FAB2(SCH_1):M_C_DQ(11)
  U5D1  W76 DDR2_DQ<11> SKX_EXT_B_BGA1-IC,TBD   I172 @BASEBOARD_FAB2_LIB.BASEBOARD_FAB2(SCH_1):PAGE25
  J4G3   23 DQ<10> SCONN288_H44441004_PIP-SCONN,HA   I111 @BASEBOARD_FAB2_LIB.BASEBOARD_FAB2(SCH_1):PAGE47
  J6U2  168 DQ<11> SCONN288_H44441003_PIP-SCONN,HA   I111 @BASEBOARD_FAB2_LIB.BASEBOARD_FAB2(SCH_1):PAGE48

M_C_DQ<12> @BASEBOARD_FAB2_LIB.BASEBOARD_FAB2(SCH_1):M_C_DQ(12)
  U5D1 AF75 DDR2_DQ<12> SKX_EXT_B_BGA1-IC,TBD   I172 @BASEBOARD_FAB2_LIB.BASEBOARD_FAB2(SCH_1):PAGE25
  J4G3  159 DQ<13> SCONN288_H44441004_PIP-SCONN,HA   I111 @BASEBOARD_FAB2_LIB.BASEBOARD_FAB2(SCH_1):PAGE47
  J6U2   14 DQ<12> SCONN288_H44441003_PIP-SCONN,HA   I111 @BASEBOARD_FAB2_LIB.BASEBOARD_FAB2(SCH_1):PAGE48

M_C_DQ<13> @BASEBOARD_FAB2_LIB.BASEBOARD_FAB2(SCH_1):M_C_DQ(13)
  U5D1 AE74 DDR2_DQ<13> SKX_EXT_B_BGA1-IC,TBD   I172 @BASEBOARD_FAB2_LIB.BASEBOARD_FAB2(SCH_1):PAGE25
  J4G3   14 DQ<12> SCONN288_H44441004_PIP-SCONN,HA   I111 @BASEBOARD_FAB2_LIB.BASEBOARD_FAB2(SCH_1):PAGE47
  J6U2  159 DQ<13> SCONN288_H44441003_PIP-SCONN,HA   I111 @BASEBOARD_FAB2_LIB.BASEBOARD_FAB2(SCH_1):PAGE48

M_C_DQ<14> @BASEBOARD_FAB2_LIB.BASEBOARD_FAB2(SCH_1):M_C_DQ(14)
  U5D1 AB77 DDR2_DQ<14> SKX_EXT_B_BGA1-IC,TBD   I172 @BASEBOARD_FAB2_LIB.BASEBOARD_FAB2(SCH_1):PAGE25
  J4G3  166 DQ<15> SCONN288_H44441004_PIP-SCONN,HA   I111 @BASEBOARD_FAB2_LIB.BASEBOARD_FAB2(SCH_1):PAGE47
  J6U2   21 DQ<14> SCONN288_H44441003_PIP-SCONN,HA   I111 @BASEBOARD_FAB2_LIB.BASEBOARD_FAB2(SCH_1):PAGE48

M_C_DQ<15> @BASEBOARD_FAB2_LIB.BASEBOARD_FAB2(SCH_1):M_C_DQ(15)
  U5D1  Y75 DDR2_DQ<15> SKX_EXT_B_BGA1-IC,TBD   I172 @BASEBOARD_FAB2_LIB.BASEBOARD_FAB2(SCH_1):PAGE25
  J4G3   21 DQ<14> SCONN288_H44441004_PIP-SCONN,HA   I111 @BASEBOARD_FAB2_LIB.BASEBOARD_FAB2(SCH_1):PAGE47
  J6U2  166 DQ<15> SCONN288_H44441003_PIP-SCONN,HA   I111 @BASEBOARD_FAB2_LIB.BASEBOARD_FAB2(SCH_1):PAGE48

M_C_DQ<16> @BASEBOARD_FAB2_LIB.BASEBOARD_FAB2(SCH_1):M_C_DQ(16)
  U5D1  W72 DDR2_DQ<16> SKX_EXT_B_BGA1-IC,TBD   I172 @BASEBOARD_FAB2_LIB.BASEBOARD_FAB2(SCH_1):PAGE25
  J4G3  172 DQ<17> SCONN288_H44441004_PIP-SCONN,HA   I111 @BASEBOARD_FAB2_LIB.BASEBOARD_FAB2(SCH_1):PAGE47
  J6U2   27 DQ<16> SCONN288_H44441003_PIP-SCONN,HA   I111 @BASEBOARD_FAB2_LIB.BASEBOARD_FAB2(SCH_1):PAGE48

M_C_DQ<17> @BASEBOARD_FAB2_LIB.BASEBOARD_FAB2(SCH_1):M_C_DQ(17)
  U5D1 AA70 DDR2_DQ<17> SKX_EXT_B_BGA1-IC,TBD   I172 @BASEBOARD_FAB2_LIB.BASEBOARD_FAB2(SCH_1):PAGE25
  J4G3   27 DQ<16> SCONN288_H44441004_PIP-SCONN,HA   I111 @BASEBOARD_FAB2_LIB.BASEBOARD_FAB2(SCH_1):PAGE47
  J6U2  172 DQ<17> SCONN288_H44441003_PIP-SCONN,HA   I111 @BASEBOARD_FAB2_LIB.BASEBOARD_FAB2(SCH_1):PAGE48

M_C_DQ<18> @BASEBOARD_FAB2_LIB.BASEBOARD_FAB2(SCH_1):M_C_DQ(18)
  U5D1  R70 DDR2_DQ<18> SKX_EXT_B_BGA1-IC,TBD   I172 @BASEBOARD_FAB2_LIB.BASEBOARD_FAB2(SCH_1):PAGE25
  J4G3  179 DQ<19> SCONN288_H44441004_PIP-SCONN,HA   I111 @BASEBOARD_FAB2_LIB.BASEBOARD_FAB2(SCH_1):PAGE47
  J6U2   34 DQ<18> SCONN288_H44441003_PIP-SCONN,HA   I111 @BASEBOARD_FAB2_LIB.BASEBOARD_FAB2(SCH_1):PAGE48

M_C_DQ<19> @BASEBOARD_FAB2_LIB.BASEBOARD_FAB2(SCH_1):M_C_DQ(19)
  U5D1  T69 DDR2_DQ<19> SKX_EXT_B_BGA1-IC,TBD   I172 @BASEBOARD_FAB2_LIB.BASEBOARD_FAB2(SCH_1):PAGE25
  J4G3   34 DQ<18> SCONN288_H44441004_PIP-SCONN,HA   I111 @BASEBOARD_FAB2_LIB.BASEBOARD_FAB2(SCH_1):PAGE47
  J6U2  179 DQ<19> SCONN288_H44441003_PIP-SCONN,HA   I111 @BASEBOARD_FAB2_LIB.BASEBOARD_FAB2(SCH_1):PAGE48

M_C_DQ<1> @BASEBOARD_FAB2_LIB.BASEBOARD_FAB2(SCH_1):M_C_DQ(1)
  U5D1 AN74 DDR2_DQ<1> SKX_EXT_B_BGA1-IC,TBD   I172 @BASEBOARD_FAB2_LIB.BASEBOARD_FAB2(SCH_1):PAGE25
  J4G3    5  DQ<0> SCONN288_H44441004_PIP-SCONN,HA   I111 @BASEBOARD_FAB2_LIB.BASEBOARD_FAB2(SCH_1):PAGE47
  J6U2  150  DQ<1> SCONN288_H44441003_PIP-SCONN,HA   I111 @BASEBOARD_FAB2_LIB.BASEBOARD_FAB2(SCH_1):PAGE48

M_C_DQ<20> @BASEBOARD_FAB2_LIB.BASEBOARD_FAB2(SCH_1):M_C_DQ(20)
  U5D1 AA72 DDR2_DQ<20> SKX_EXT_B_BGA1-IC,TBD   I172 @BASEBOARD_FAB2_LIB.BASEBOARD_FAB2(SCH_1):PAGE25
  J4G3  170 DQ<21> SCONN288_H44441004_PIP-SCONN,HA   I111 @BASEBOARD_FAB2_LIB.BASEBOARD_FAB2(SCH_1):PAGE47
  J6U2   25 DQ<20> SCONN288_H44441003_PIP-SCONN,HA   I111 @BASEBOARD_FAB2_LIB.BASEBOARD_FAB2(SCH_1):PAGE48

M_C_DQ<21> @BASEBOARD_FAB2_LIB.BASEBOARD_FAB2(SCH_1):M_C_DQ(21)
  U5D1 AB71 DDR2_DQ<21> SKX_EXT_B_BGA1-IC,TBD   I172 @BASEBOARD_FAB2_LIB.BASEBOARD_FAB2(SCH_1):PAGE25
  J4G3   25 DQ<20> SCONN288_H44441004_PIP-SCONN,HA   I111 @BASEBOARD_FAB2_LIB.BASEBOARD_FAB2(SCH_1):PAGE47
  J6U2  170 DQ<21> SCONN288_H44441003_PIP-SCONN,HA   I111 @BASEBOARD_FAB2_LIB.BASEBOARD_FAB2(SCH_1):PAGE48

M_C_DQ<22> @BASEBOARD_FAB2_LIB.BASEBOARD_FAB2(SCH_1):M_C_DQ(22)
  U5D1  T71 DDR2_DQ<22> SKX_EXT_B_BGA1-IC,TBD   I172 @BASEBOARD_FAB2_LIB.BASEBOARD_FAB2(SCH_1):PAGE25
  J4G3  177 DQ<23> SCONN288_H44441004_PIP-SCONN,HA   I111 @BASEBOARD_FAB2_LIB.BASEBOARD_FAB2(SCH_1):PAGE47
  J6U2   32 DQ<22> SCONN288_H44441003_PIP-SCONN,HA   I111 @BASEBOARD_FAB2_LIB.BASEBOARD_FAB2(SCH_1):PAGE48

M_C_DQ<23> @BASEBOARD_FAB2_LIB.BASEBOARD_FAB2(SCH_1):M_C_DQ(23)
  U5D1  V69 DDR2_DQ<23> SKX_EXT_B_BGA1-IC,TBD   I172 @BASEBOARD_FAB2_LIB.BASEBOARD_FAB2(SCH_1):PAGE25
  J4G3   32 DQ<22> SCONN288_H44441004_PIP-SCONN,HA   I111 @BASEBOARD_FAB2_LIB.BASEBOARD_FAB2(SCH_1):PAGE47
  J6U2  177 DQ<23> SCONN288_H44441003_PIP-SCONN,HA   I111 @BASEBOARD_FAB2_LIB.BASEBOARD_FAB2(SCH_1):PAGE48

M_C_DQ<24> @BASEBOARD_FAB2_LIB.BASEBOARD_FAB2(SCH_1):M_C_DQ(24)
  U5D1 AM67 DDR2_DQ<24> SKX_EXT_B_BGA1-IC,TBD   I172 @BASEBOARD_FAB2_LIB.BASEBOARD_FAB2(SCH_1):PAGE25
  J4G3  183 DQ<25> SCONN288_H44441004_PIP-SCONN,HA   I111 @BASEBOARD_FAB2_LIB.BASEBOARD_FAB2(SCH_1):PAGE47
  J6U2   38 DQ<24> SCONN288_H44441003_PIP-SCONN,HA   I111 @BASEBOARD_FAB2_LIB.BASEBOARD_FAB2(SCH_1):PAGE48

M_C_DQ<25> @BASEBOARD_FAB2_LIB.BASEBOARD_FAB2(SCH_1):M_C_DQ(25)
  U5D1 AT67 DDR2_DQ<25> SKX_EXT_B_BGA1-IC,TBD   I172 @BASEBOARD_FAB2_LIB.BASEBOARD_FAB2(SCH_1):PAGE25
  J4G3   38 DQ<24> SCONN288_H44441004_PIP-SCONN,HA   I111 @BASEBOARD_FAB2_LIB.BASEBOARD_FAB2(SCH_1):PAGE47
  J6U2  183 DQ<25> SCONN288_H44441003_PIP-SCONN,HA   I111 @BASEBOARD_FAB2_LIB.BASEBOARD_FAB2(SCH_1):PAGE48

M_C_DQ<26> @BASEBOARD_FAB2_LIB.BASEBOARD_FAB2(SCH_1):M_C_DQ(26)
  U5D1 AN64 DDR2_DQ<26> SKX_EXT_B_BGA1-IC,TBD   I172 @BASEBOARD_FAB2_LIB.BASEBOARD_FAB2(SCH_1):PAGE25
  J4G3  190 DQ<27> SCONN288_H44441004_PIP-SCONN,HA   I111 @BASEBOARD_FAB2_LIB.BASEBOARD_FAB2(SCH_1):PAGE47
  J6U2   45 DQ<26> SCONN288_H44441003_PIP-SCONN,HA   I111 @BASEBOARD_FAB2_LIB.BASEBOARD_FAB2(SCH_1):PAGE48

M_C_DQ<27> @BASEBOARD_FAB2_LIB.BASEBOARD_FAB2(SCH_1):M_C_DQ(27)
  U5D1 AR64 DDR2_DQ<27> SKX_EXT_B_BGA1-IC,TBD   I172 @BASEBOARD_FAB2_LIB.BASEBOARD_FAB2(SCH_1):PAGE25
  J4G3   45 DQ<26> SCONN288_H44441004_PIP-SCONN,HA   I111 @BASEBOARD_FAB2_LIB.BASEBOARD_FAB2(SCH_1):PAGE47
  J6U2  190 DQ<27> SCONN288_H44441003_PIP-SCONN,HA   I111 @BASEBOARD_FAB2_LIB.BASEBOARD_FAB2(SCH_1):PAGE48

M_C_DQ<28> @BASEBOARD_FAB2_LIB.BASEBOARD_FAB2(SCH_1):M_C_DQ(28)
  U5D1 AN68 DDR2_DQ<28> SKX_EXT_B_BGA1-IC,TBD   I172 @BASEBOARD_FAB2_LIB.BASEBOARD_FAB2(SCH_1):PAGE25
  J4G3  181 DQ<29> SCONN288_H44441004_PIP-SCONN,HA   I111 @BASEBOARD_FAB2_LIB.BASEBOARD_FAB2(SCH_1):PAGE47
  J6U2   36 DQ<28> SCONN288_H44441003_PIP-SCONN,HA   I111 @BASEBOARD_FAB2_LIB.BASEBOARD_FAB2(SCH_1):PAGE48

M_C_DQ<29> @BASEBOARD_FAB2_LIB.BASEBOARD_FAB2(SCH_1):M_C_DQ(29)
  U5D1 AR68 DDR2_DQ<29> SKX_EXT_B_BGA1-IC,TBD   I172 @BASEBOARD_FAB2_LIB.BASEBOARD_FAB2(SCH_1):PAGE25
  J4G3   36 DQ<28> SCONN288_H44441004_PIP-SCONN,HA   I111 @BASEBOARD_FAB2_LIB.BASEBOARD_FAB2(SCH_1):PAGE47
  J6U2  181 DQ<29> SCONN288_H44441003_PIP-SCONN,HA   I111 @BASEBOARD_FAB2_LIB.BASEBOARD_FAB2(SCH_1):PAGE48

M_C_DQ<2> @BASEBOARD_FAB2_LIB.BASEBOARD_FAB2(SCH_1):M_C_DQ(2)
  U5D1 AK77 DDR2_DQ<2> SKX_EXT_B_BGA1-IC,TBD   I172 @BASEBOARD_FAB2_LIB.BASEBOARD_FAB2(SCH_1):PAGE25
  J4G3  157  DQ<3> SCONN288_H44441004_PIP-SCONN,HA   I111 @BASEBOARD_FAB2_LIB.BASEBOARD_FAB2(SCH_1):PAGE47
  J6U2   12  DQ<2> SCONN288_H44441003_PIP-SCONN,HA   I111 @BASEBOARD_FAB2_LIB.BASEBOARD_FAB2(SCH_1):PAGE48

M_C_DQ<30> @BASEBOARD_FAB2_LIB.BASEBOARD_FAB2(SCH_1):M_C_DQ(30)
  U5D1 AM65 DDR2_DQ<30> SKX_EXT_B_BGA1-IC,TBD   I172 @BASEBOARD_FAB2_LIB.BASEBOARD_FAB2(SCH_1):PAGE25
  J4G3  188 DQ<31> SCONN288_H44441004_PIP-SCONN,HA   I111 @BASEBOARD_FAB2_LIB.BASEBOARD_FAB2(SCH_1):PAGE47
  J6U2   43 DQ<30> SCONN288_H44441003_PIP-SCONN,HA   I111 @BASEBOARD_FAB2_LIB.BASEBOARD_FAB2(SCH_1):PAGE48

M_C_DQ<31> @BASEBOARD_FAB2_LIB.BASEBOARD_FAB2(SCH_1):M_C_DQ(31)
  U5D1 AT65 DDR2_DQ<31> SKX_EXT_B_BGA1-IC,TBD   I172 @BASEBOARD_FAB2_LIB.BASEBOARD_FAB2(SCH_1):PAGE25
  J4G3   43 DQ<30> SCONN288_H44441004_PIP-SCONN,HA   I111 @BASEBOARD_FAB2_LIB.BASEBOARD_FAB2(SCH_1):PAGE47
  J6U2  188 DQ<31> SCONN288_H44441003_PIP-SCONN,HA   I111 @BASEBOARD_FAB2_LIB.BASEBOARD_FAB2(SCH_1):PAGE48

M_C_DQ<32> @BASEBOARD_FAB2_LIB.BASEBOARD_FAB2(SCH_1):M_C_DQ(32)
  U5D1  U40 DDR2_DQ<32> SKX_EXT_B_BGA1-IC,TBD   I172 @BASEBOARD_FAB2_LIB.BASEBOARD_FAB2(SCH_1):PAGE25
  J4G3  242 DQ<33> SCONN288_H44441004_PIP-SCONN,HA   I111 @BASEBOARD_FAB2_LIB.BASEBOARD_FAB2(SCH_1):PAGE47
  J6U2   97 DQ<32> SCONN288_H44441003_PIP-SCONN,HA   I111 @BASEBOARD_FAB2_LIB.BASEBOARD_FAB2(SCH_1):PAGE48

M_C_DQ<33> @BASEBOARD_FAB2_LIB.BASEBOARD_FAB2(SCH_1):M_C_DQ(33)
  U5D1 AA40 DDR2_DQ<33> SKX_EXT_B_BGA1-IC,TBD   I172 @BASEBOARD_FAB2_LIB.BASEBOARD_FAB2(SCH_1):PAGE25
  J4G3   97 DQ<32> SCONN288_H44441004_PIP-SCONN,HA   I111 @BASEBOARD_FAB2_LIB.BASEBOARD_FAB2(SCH_1):PAGE47
  J6U2  242 DQ<33> SCONN288_H44441003_PIP-SCONN,HA   I111 @BASEBOARD_FAB2_LIB.BASEBOARD_FAB2(SCH_1):PAGE48

M_C_DQ<34> @BASEBOARD_FAB2_LIB.BASEBOARD_FAB2(SCH_1):M_C_DQ(34)
  U5D1  V37 DDR2_DQ<34> SKX_EXT_B_BGA1-IC,TBD   I172 @BASEBOARD_FAB2_LIB.BASEBOARD_FAB2(SCH_1):PAGE25
  J4G3  249 DQ<35> SCONN288_H44441004_PIP-SCONN,HA   I111 @BASEBOARD_FAB2_LIB.BASEBOARD_FAB2(SCH_1):PAGE47
  J6U2  104 DQ<34> SCONN288_H44441003_PIP-SCONN,HA   I111 @BASEBOARD_FAB2_LIB.BASEBOARD_FAB2(SCH_1):PAGE48

M_C_DQ<35> @BASEBOARD_FAB2_LIB.BASEBOARD_FAB2(SCH_1):M_C_DQ(35)
  U5D1  Y37 DDR2_DQ<35> SKX_EXT_B_BGA1-IC,TBD   I172 @BASEBOARD_FAB2_LIB.BASEBOARD_FAB2(SCH_1):PAGE25
  J4G3  104 DQ<34> SCONN288_H44441004_PIP-SCONN,HA   I111 @BASEBOARD_FAB2_LIB.BASEBOARD_FAB2(SCH_1):PAGE47
  J6U2  249 DQ<35> SCONN288_H44441003_PIP-SCONN,HA   I111 @BASEBOARD_FAB2_LIB.BASEBOARD_FAB2(SCH_1):PAGE48

M_C_DQ<36> @BASEBOARD_FAB2_LIB.BASEBOARD_FAB2(SCH_1):M_C_DQ(36)
  U5D1  V41 DDR2_DQ<36> SKX_EXT_B_BGA1-IC,TBD   I172 @BASEBOARD_FAB2_LIB.BASEBOARD_FAB2(SCH_1):PAGE25
  J4G3  240 DQ<37> SCONN288_H44441004_PIP-SCONN,HA   I111 @BASEBOARD_FAB2_LIB.BASEBOARD_FAB2(SCH_1):PAGE47
  J6U2   95 DQ<36> SCONN288_H44441003_PIP-SCONN,HA   I111 @BASEBOARD_FAB2_LIB.BASEBOARD_FAB2(SCH_1):PAGE48

M_C_DQ<37> @BASEBOARD_FAB2_LIB.BASEBOARD_FAB2(SCH_1):M_C_DQ(37)
  U5D1  Y41 DDR2_DQ<37> SKX_EXT_B_BGA1-IC,TBD   I172 @BASEBOARD_FAB2_LIB.BASEBOARD_FAB2(SCH_1):PAGE25
  J4G3   95 DQ<36> SCONN288_H44441004_PIP-SCONN,HA   I111 @BASEBOARD_FAB2_LIB.BASEBOARD_FAB2(SCH_1):PAGE47
  J6U2  240 DQ<37> SCONN288_H44441003_PIP-SCONN,HA   I111 @BASEBOARD_FAB2_LIB.BASEBOARD_FAB2(SCH_1):PAGE48

M_C_DQ<38> @BASEBOARD_FAB2_LIB.BASEBOARD_FAB2(SCH_1):M_C_DQ(38)
  U5D1  U38 DDR2_DQ<38> SKX_EXT_B_BGA1-IC,TBD   I172 @BASEBOARD_FAB2_LIB.BASEBOARD_FAB2(SCH_1):PAGE25
  J4G3  247 DQ<39> SCONN288_H44441004_PIP-SCONN,HA   I111 @BASEBOARD_FAB2_LIB.BASEBOARD_FAB2(SCH_1):PAGE47
  J6U2  102 DQ<38> SCONN288_H44441003_PIP-SCONN,HA   I111 @BASEBOARD_FAB2_LIB.BASEBOARD_FAB2(SCH_1):PAGE48

M_C_DQ<39> @BASEBOARD_FAB2_LIB.BASEBOARD_FAB2(SCH_1):M_C_DQ(39)
  U5D1 AA38 DDR2_DQ<39> SKX_EXT_B_BGA1-IC,TBD   I172 @BASEBOARD_FAB2_LIB.BASEBOARD_FAB2(SCH_1):PAGE25
  J4G3  102 DQ<38> SCONN288_H44441004_PIP-SCONN,HA   I111 @BASEBOARD_FAB2_LIB.BASEBOARD_FAB2(SCH_1):PAGE47
  J6U2  247 DQ<39> SCONN288_H44441003_PIP-SCONN,HA   I111 @BASEBOARD_FAB2_LIB.BASEBOARD_FAB2(SCH_1):PAGE48

M_C_DQ<3> @BASEBOARD_FAB2_LIB.BASEBOARD_FAB2(SCH_1):M_C_DQ(3)
  U5D1 AJ76 DDR2_DQ<3> SKX_EXT_B_BGA1-IC,TBD   I172 @BASEBOARD_FAB2_LIB.BASEBOARD_FAB2(SCH_1):PAGE25
  J4G3   12  DQ<2> SCONN288_H44441004_PIP-SCONN,HA   I111 @BASEBOARD_FAB2_LIB.BASEBOARD_FAB2(SCH_1):PAGE47
  J6U2  157  DQ<3> SCONN288_H44441003_PIP-SCONN,HA   I111 @BASEBOARD_FAB2_LIB.BASEBOARD_FAB2(SCH_1):PAGE48

M_C_DQ<40> @BASEBOARD_FAB2_LIB.BASEBOARD_FAB2(SCH_1):M_C_DQ(40)
  U5D1  U34 DDR2_DQ<40> SKX_EXT_B_BGA1-IC,TBD   I172 @BASEBOARD_FAB2_LIB.BASEBOARD_FAB2(SCH_1):PAGE25
  J4G3  253 DQ<41> SCONN288_H44441004_PIP-SCONN,HA   I111 @BASEBOARD_FAB2_LIB.BASEBOARD_FAB2(SCH_1):PAGE47
  J6U2  108 DQ<40> SCONN288_H44441003_PIP-SCONN,HA   I111 @BASEBOARD_FAB2_LIB.BASEBOARD_FAB2(SCH_1):PAGE48

M_C_DQ<41> @BASEBOARD_FAB2_LIB.BASEBOARD_FAB2(SCH_1):M_C_DQ(41)
  U5D1 AA34 DDR2_DQ<41> SKX_EXT_B_BGA1-IC,TBD   I172 @BASEBOARD_FAB2_LIB.BASEBOARD_FAB2(SCH_1):PAGE25
  J4G3  108 DQ<40> SCONN288_H44441004_PIP-SCONN,HA   I111 @BASEBOARD_FAB2_LIB.BASEBOARD_FAB2(SCH_1):PAGE47
  J6U2  253 DQ<41> SCONN288_H44441003_PIP-SCONN,HA   I111 @BASEBOARD_FAB2_LIB.BASEBOARD_FAB2(SCH_1):PAGE48

M_C_DQ<42> @BASEBOARD_FAB2_LIB.BASEBOARD_FAB2(SCH_1):M_C_DQ(42)
  U5D1  V31 DDR2_DQ<42> SKX_EXT_B_BGA1-IC,TBD   I172 @BASEBOARD_FAB2_LIB.BASEBOARD_FAB2(SCH_1):PAGE25
  J4G3  260 DQ<43> SCONN288_H44441004_PIP-SCONN,HA   I111 @BASEBOARD_FAB2_LIB.BASEBOARD_FAB2(SCH_1):PAGE47
  J6U2  115 DQ<42> SCONN288_H44441003_PIP-SCONN,HA   I111 @BASEBOARD_FAB2_LIB.BASEBOARD_FAB2(SCH_1):PAGE48

M_C_DQ<43> @BASEBOARD_FAB2_LIB.BASEBOARD_FAB2(SCH_1):M_C_DQ(43)
  U5D1  Y31 DDR2_DQ<43> SKX_EXT_B_BGA1-IC,TBD   I172 @BASEBOARD_FAB2_LIB.BASEBOARD_FAB2(SCH_1):PAGE25
  J4G3  115 DQ<42> SCONN288_H44441004_PIP-SCONN,HA   I111 @BASEBOARD_FAB2_LIB.BASEBOARD_FAB2(SCH_1):PAGE47
  J6U2  260 DQ<43> SCONN288_H44441003_PIP-SCONN,HA   I111 @BASEBOARD_FAB2_LIB.BASEBOARD_FAB2(SCH_1):PAGE48

M_C_DQ<44> @BASEBOARD_FAB2_LIB.BASEBOARD_FAB2(SCH_1):M_C_DQ(44)
  U5D1  V35 DDR2_DQ<44> SKX_EXT_B_BGA1-IC,TBD   I172 @BASEBOARD_FAB2_LIB.BASEBOARD_FAB2(SCH_1):PAGE25
  J4G3  251 DQ<45> SCONN288_H44441004_PIP-SCONN,HA   I111 @BASEBOARD_FAB2_LIB.BASEBOARD_FAB2(SCH_1):PAGE47
  J6U2  106 DQ<44> SCONN288_H44441003_PIP-SCONN,HA   I111 @BASEBOARD_FAB2_LIB.BASEBOARD_FAB2(SCH_1):PAGE48

M_C_DQ<45> @BASEBOARD_FAB2_LIB.BASEBOARD_FAB2(SCH_1):M_C_DQ(45)
  U5D1  Y35 DDR2_DQ<45> SKX_EXT_B_BGA1-IC,TBD   I172 @BASEBOARD_FAB2_LIB.BASEBOARD_FAB2(SCH_1):PAGE25
  J4G3  106 DQ<44> SCONN288_H44441004_PIP-SCONN,HA   I111 @BASEBOARD_FAB2_LIB.BASEBOARD_FAB2(SCH_1):PAGE47
  J6U2  251 DQ<45> SCONN288_H44441003_PIP-SCONN,HA   I111 @BASEBOARD_FAB2_LIB.BASEBOARD_FAB2(SCH_1):PAGE48

M_C_DQ<46> @BASEBOARD_FAB2_LIB.BASEBOARD_FAB2(SCH_1):M_C_DQ(46)
  U5D1  U32 DDR2_DQ<46> SKX_EXT_B_BGA1-IC,TBD   I172 @BASEBOARD_FAB2_LIB.BASEBOARD_FAB2(SCH_1):PAGE25
  J4G3  258 DQ<47> SCONN288_H44441004_PIP-SCONN,HA   I111 @BASEBOARD_FAB2_LIB.BASEBOARD_FAB2(SCH_1):PAGE47
  J6U2  113 DQ<46> SCONN288_H44441003_PIP-SCONN,HA   I111 @BASEBOARD_FAB2_LIB.BASEBOARD_FAB2(SCH_1):PAGE48

M_C_DQ<47> @BASEBOARD_FAB2_LIB.BASEBOARD_FAB2(SCH_1):M_C_DQ(47)
  U5D1 AA32 DDR2_DQ<47> SKX_EXT_B_BGA1-IC,TBD   I172 @BASEBOARD_FAB2_LIB.BASEBOARD_FAB2(SCH_1):PAGE25
  J4G3  113 DQ<46> SCONN288_H44441004_PIP-SCONN,HA   I111 @BASEBOARD_FAB2_LIB.BASEBOARD_FAB2(SCH_1):PAGE47
  J6U2  258 DQ<47> SCONN288_H44441003_PIP-SCONN,HA   I111 @BASEBOARD_FAB2_LIB.BASEBOARD_FAB2(SCH_1):PAGE48

M_C_DQ<48> @BASEBOARD_FAB2_LIB.BASEBOARD_FAB2(SCH_1):M_C_DQ(48)
  U5D1 AD31 DDR2_DQ<48> SKX_EXT_B_BGA1-IC,TBD   I172 @BASEBOARD_FAB2_LIB.BASEBOARD_FAB2(SCH_1):PAGE25
  J4G3  264 DQ<49> SCONN288_H44441004_PIP-SCONN,HA   I111 @BASEBOARD_FAB2_LIB.BASEBOARD_FAB2(SCH_1):PAGE47
  J6U2  119 DQ<48> SCONN288_H44441003_PIP-SCONN,HA   I111 @BASEBOARD_FAB2_LIB.BASEBOARD_FAB2(SCH_1):PAGE48

M_C_DQ<49> @BASEBOARD_FAB2_LIB.BASEBOARD_FAB2(SCH_1):M_C_DQ(49)
  U5D1 AH31 DDR2_DQ<49> SKX_EXT_B_BGA1-IC,TBD   I172 @BASEBOARD_FAB2_LIB.BASEBOARD_FAB2(SCH_1):PAGE25
  J4G3  119 DQ<48> SCONN288_H44441004_PIP-SCONN,HA   I111 @BASEBOARD_FAB2_LIB.BASEBOARD_FAB2(SCH_1):PAGE47
  J6U2  264 DQ<49> SCONN288_H44441003_PIP-SCONN,HA   I111 @BASEBOARD_FAB2_LIB.BASEBOARD_FAB2(SCH_1):PAGE48

M_C_DQ<4> @BASEBOARD_FAB2_LIB.BASEBOARD_FAB2(SCH_1):M_C_DQ(4)
  U5D1 AT75 DDR2_DQ<4> SKX_EXT_B_BGA1-IC,TBD   I172 @BASEBOARD_FAB2_LIB.BASEBOARD_FAB2(SCH_1):PAGE25
  J4G3  148  DQ<5> SCONN288_H44441004_PIP-SCONN,HA   I111 @BASEBOARD_FAB2_LIB.BASEBOARD_FAB2(SCH_1):PAGE47
  J6U2    3  DQ<4> SCONN288_H44441003_PIP-SCONN,HA   I111 @BASEBOARD_FAB2_LIB.BASEBOARD_FAB2(SCH_1):PAGE48

M_C_DQ<50> @BASEBOARD_FAB2_LIB.BASEBOARD_FAB2(SCH_1):M_C_DQ(50)
  U5D1 AE28 DDR2_DQ<50> SKX_EXT_B_BGA1-IC,TBD   I172 @BASEBOARD_FAB2_LIB.BASEBOARD_FAB2(SCH_1):PAGE25
  J4G3  271 DQ<51> SCONN288_H44441004_PIP-SCONN,HA   I111 @BASEBOARD_FAB2_LIB.BASEBOARD_FAB2(SCH_1):PAGE47
  J6U2  126 DQ<50> SCONN288_H44441003_PIP-SCONN,HA   I111 @BASEBOARD_FAB2_LIB.BASEBOARD_FAB2(SCH_1):PAGE48

M_C_DQ<51> @BASEBOARD_FAB2_LIB.BASEBOARD_FAB2(SCH_1):M_C_DQ(51)
  U5D1 AG28 DDR2_DQ<51> SKX_EXT_B_BGA1-IC,TBD   I172 @BASEBOARD_FAB2_LIB.BASEBOARD_FAB2(SCH_1):PAGE25
  J4G3  126 DQ<50> SCONN288_H44441004_PIP-SCONN,HA   I111 @BASEBOARD_FAB2_LIB.BASEBOARD_FAB2(SCH_1):PAGE47
  J6U2  271 DQ<51> SCONN288_H44441003_PIP-SCONN,HA   I111 @BASEBOARD_FAB2_LIB.BASEBOARD_FAB2(SCH_1):PAGE48

M_C_DQ<52> @BASEBOARD_FAB2_LIB.BASEBOARD_FAB2(SCH_1):M_C_DQ(52)
  U5D1 AE32 DDR2_DQ<52> SKX_EXT_B_BGA1-IC,TBD   I172 @BASEBOARD_FAB2_LIB.BASEBOARD_FAB2(SCH_1):PAGE25
  J4G3  262 DQ<53> SCONN288_H44441004_PIP-SCONN,HA   I111 @BASEBOARD_FAB2_LIB.BASEBOARD_FAB2(SCH_1):PAGE47
  J6U2  117 DQ<52> SCONN288_H44441003_PIP-SCONN,HA   I111 @BASEBOARD_FAB2_LIB.BASEBOARD_FAB2(SCH_1):PAGE48

M_C_DQ<53> @BASEBOARD_FAB2_LIB.BASEBOARD_FAB2(SCH_1):M_C_DQ(53)
  U5D1 AG32 DDR2_DQ<53> SKX_EXT_B_BGA1-IC,TBD   I172 @BASEBOARD_FAB2_LIB.BASEBOARD_FAB2(SCH_1):PAGE25
  J4G3  117 DQ<52> SCONN288_H44441004_PIP-SCONN,HA   I111 @BASEBOARD_FAB2_LIB.BASEBOARD_FAB2(SCH_1):PAGE47
  J6U2  262 DQ<53> SCONN288_H44441003_PIP-SCONN,HA   I111 @BASEBOARD_FAB2_LIB.BASEBOARD_FAB2(SCH_1):PAGE48

M_C_DQ<54> @BASEBOARD_FAB2_LIB.BASEBOARD_FAB2(SCH_1):M_C_DQ(54)
  U5D1 AD29 DDR2_DQ<54> SKX_EXT_B_BGA1-IC,TBD   I172 @BASEBOARD_FAB2_LIB.BASEBOARD_FAB2(SCH_1):PAGE25
  J4G3  269 DQ<55> SCONN288_H44441004_PIP-SCONN,HA   I111 @BASEBOARD_FAB2_LIB.BASEBOARD_FAB2(SCH_1):PAGE47
  J6U2  124 DQ<54> SCONN288_H44441003_PIP-SCONN,HA   I111 @BASEBOARD_FAB2_LIB.BASEBOARD_FAB2(SCH_1):PAGE48

M_C_DQ<55> @BASEBOARD_FAB2_LIB.BASEBOARD_FAB2(SCH_1):M_C_DQ(55)
  U5D1 AH29 DDR2_DQ<55> SKX_EXT_B_BGA1-IC,TBD   I172 @BASEBOARD_FAB2_LIB.BASEBOARD_FAB2(SCH_1):PAGE25
  J4G3  124 DQ<54> SCONN288_H44441004_PIP-SCONN,HA   I111 @BASEBOARD_FAB2_LIB.BASEBOARD_FAB2(SCH_1):PAGE47
  J6U2  269 DQ<55> SCONN288_H44441003_PIP-SCONN,HA   I111 @BASEBOARD_FAB2_LIB.BASEBOARD_FAB2(SCH_1):PAGE48

M_C_DQ<56> @BASEBOARD_FAB2_LIB.BASEBOARD_FAB2(SCH_1):M_C_DQ(56)
  U5D1 AD25 DDR2_DQ<56> SKX_EXT_B_BGA1-IC,TBD   I172 @BASEBOARD_FAB2_LIB.BASEBOARD_FAB2(SCH_1):PAGE25
  J4G3  275 DQ<57> SCONN288_H44441004_PIP-SCONN,HA   I111 @BASEBOARD_FAB2_LIB.BASEBOARD_FAB2(SCH_1):PAGE47
  J6U2  130 DQ<56> SCONN288_H44441003_PIP-SCONN,HA   I111 @BASEBOARD_FAB2_LIB.BASEBOARD_FAB2(SCH_1):PAGE48

M_C_DQ<57> @BASEBOARD_FAB2_LIB.BASEBOARD_FAB2(SCH_1):M_C_DQ(57)
  U5D1 AH25 DDR2_DQ<57> SKX_EXT_B_BGA1-IC,TBD   I172 @BASEBOARD_FAB2_LIB.BASEBOARD_FAB2(SCH_1):PAGE25
  J4G3  130 DQ<56> SCONN288_H44441004_PIP-SCONN,HA   I111 @BASEBOARD_FAB2_LIB.BASEBOARD_FAB2(SCH_1):PAGE47
  J6U2  275 DQ<57> SCONN288_H44441003_PIP-SCONN,HA   I111 @BASEBOARD_FAB2_LIB.BASEBOARD_FAB2(SCH_1):PAGE48

M_C_DQ<58> @BASEBOARD_FAB2_LIB.BASEBOARD_FAB2(SCH_1):M_C_DQ(58)
  U5D1 AE22 DDR2_DQ<58> SKX_EXT_B_BGA1-IC,TBD   I172 @BASEBOARD_FAB2_LIB.BASEBOARD_FAB2(SCH_1):PAGE25
  J4G3  282 DQ<59> SCONN288_H44441004_PIP-SCONN,HA   I111 @BASEBOARD_FAB2_LIB.BASEBOARD_FAB2(SCH_1):PAGE47
  J6U2  137 DQ<58> SCONN288_H44441003_PIP-SCONN,HA   I111 @BASEBOARD_FAB2_LIB.BASEBOARD_FAB2(SCH_1):PAGE48

M_C_DQ<59> @BASEBOARD_FAB2_LIB.BASEBOARD_FAB2(SCH_1):M_C_DQ(59)
  U5D1 AG22 DDR2_DQ<59> SKX_EXT_B_BGA1-IC,TBD   I172 @BASEBOARD_FAB2_LIB.BASEBOARD_FAB2(SCH_1):PAGE25
  J4G3  137 DQ<58> SCONN288_H44441004_PIP-SCONN,HA   I111 @BASEBOARD_FAB2_LIB.BASEBOARD_FAB2(SCH_1):PAGE47
  J6U2  282 DQ<59> SCONN288_H44441003_PIP-SCONN,HA   I111 @BASEBOARD_FAB2_LIB.BASEBOARD_FAB2(SCH_1):PAGE48

M_C_DQ<5> @BASEBOARD_FAB2_LIB.BASEBOARD_FAB2(SCH_1):M_C_DQ(5)
  U5D1 AR74 DDR2_DQ<5> SKX_EXT_B_BGA1-IC,TBD   I172 @BASEBOARD_FAB2_LIB.BASEBOARD_FAB2(SCH_1):PAGE25
  J4G3    3  DQ<4> SCONN288_H44441004_PIP-SCONN,HA   I111 @BASEBOARD_FAB2_LIB.BASEBOARD_FAB2(SCH_1):PAGE47
  J6U2  148  DQ<5> SCONN288_H44441003_PIP-SCONN,HA   I111 @BASEBOARD_FAB2_LIB.BASEBOARD_FAB2(SCH_1):PAGE48

M_C_DQ<60> @BASEBOARD_FAB2_LIB.BASEBOARD_FAB2(SCH_1):M_C_DQ(60)
  U5D1 AE26 DDR2_DQ<60> SKX_EXT_B_BGA1-IC,TBD   I172 @BASEBOARD_FAB2_LIB.BASEBOARD_FAB2(SCH_1):PAGE25
  J4G3  273 DQ<61> SCONN288_H44441004_PIP-SCONN,HA   I111 @BASEBOARD_FAB2_LIB.BASEBOARD_FAB2(SCH_1):PAGE47
  J6U2  128 DQ<60> SCONN288_H44441003_PIP-SCONN,HA   I111 @BASEBOARD_FAB2_LIB.BASEBOARD_FAB2(SCH_1):PAGE48

M_C_DQ<61> @BASEBOARD_FAB2_LIB.BASEBOARD_FAB2(SCH_1):M_C_DQ(61)
  U5D1 AG26 DDR2_DQ<61> SKX_EXT_B_BGA1-IC,TBD   I172 @BASEBOARD_FAB2_LIB.BASEBOARD_FAB2(SCH_1):PAGE25
  J4G3  128 DQ<60> SCONN288_H44441004_PIP-SCONN,HA   I111 @BASEBOARD_FAB2_LIB.BASEBOARD_FAB2(SCH_1):PAGE47
  J6U2  273 DQ<61> SCONN288_H44441003_PIP-SCONN,HA   I111 @BASEBOARD_FAB2_LIB.BASEBOARD_FAB2(SCH_1):PAGE48

M_C_DQ<62> @BASEBOARD_FAB2_LIB.BASEBOARD_FAB2(SCH_1):M_C_DQ(62)
  U5D1 AD23 DDR2_DQ<62> SKX_EXT_B_BGA1-IC,TBD   I172 @BASEBOARD_FAB2_LIB.BASEBOARD_FAB2(SCH_1):PAGE25
  J4G3  280 DQ<63> SCONN288_H44441004_PIP-SCONN,HA   I111 @BASEBOARD_FAB2_LIB.BASEBOARD_FAB2(SCH_1):PAGE47
  J6U2  135 DQ<62> SCONN288_H44441003_PIP-SCONN,HA   I111 @BASEBOARD_FAB2_LIB.BASEBOARD_FAB2(SCH_1):PAGE48

M_C_DQ<63> @BASEBOARD_FAB2_LIB.BASEBOARD_FAB2(SCH_1):M_C_DQ(63)
  U5D1 AH23 DDR2_DQ<63> SKX_EXT_B_BGA1-IC,TBD   I172 @BASEBOARD_FAB2_LIB.BASEBOARD_FAB2(SCH_1):PAGE25
  J4G3  135 DQ<62> SCONN288_H44441004_PIP-SCONN,HA   I111 @BASEBOARD_FAB2_LIB.BASEBOARD_FAB2(SCH_1):PAGE47
  J6U2  280 DQ<63> SCONN288_H44441003_PIP-SCONN,HA   I111 @BASEBOARD_FAB2_LIB.BASEBOARD_FAB2(SCH_1):PAGE48

M_C_DQ<6> @BASEBOARD_FAB2_LIB.BASEBOARD_FAB2(SCH_1):M_C_DQ(6)
  U5D1 AM77 DDR2_DQ<6> SKX_EXT_B_BGA1-IC,TBD   I172 @BASEBOARD_FAB2_LIB.BASEBOARD_FAB2(SCH_1):PAGE25
  J4G3  155  DQ<7> SCONN288_H44441004_PIP-SCONN,HA   I111 @BASEBOARD_FAB2_LIB.BASEBOARD_FAB2(SCH_1):PAGE47
  J6U2   10  DQ<6> SCONN288_H44441003_PIP-SCONN,HA   I111 @BASEBOARD_FAB2_LIB.BASEBOARD_FAB2(SCH_1):PAGE48

M_C_DQ<7> @BASEBOARD_FAB2_LIB.BASEBOARD_FAB2(SCH_1):M_C_DQ(7)
  U5D1 AK75 DDR2_DQ<7> SKX_EXT_B_BGA1-IC,TBD   I172 @BASEBOARD_FAB2_LIB.BASEBOARD_FAB2(SCH_1):PAGE25
  J4G3   10  DQ<6> SCONN288_H44441004_PIP-SCONN,HA   I111 @BASEBOARD_FAB2_LIB.BASEBOARD_FAB2(SCH_1):PAGE47
  J6U2  155  DQ<7> SCONN288_H44441003_PIP-SCONN,HA   I111 @BASEBOARD_FAB2_LIB.BASEBOARD_FAB2(SCH_1):PAGE48

M_C_DQ<8> @BASEBOARD_FAB2_LIB.BASEBOARD_FAB2(SCH_1):M_C_DQ(8)
  U5D1 AE76 DDR2_DQ<8> SKX_EXT_B_BGA1-IC,TBD   I172 @BASEBOARD_FAB2_LIB.BASEBOARD_FAB2(SCH_1):PAGE25
  J4G3  161  DQ<9> SCONN288_H44441004_PIP-SCONN,HA   I111 @BASEBOARD_FAB2_LIB.BASEBOARD_FAB2(SCH_1):PAGE47
  J6U2   16  DQ<8> SCONN288_H44441003_PIP-SCONN,HA   I111 @BASEBOARD_FAB2_LIB.BASEBOARD_FAB2(SCH_1):PAGE48

M_C_DQ<9> @BASEBOARD_FAB2_LIB.BASEBOARD_FAB2(SCH_1):M_C_DQ(9)
  U5D1 AC74 DDR2_DQ<9> SKX_EXT_B_BGA1-IC,TBD   I172 @BASEBOARD_FAB2_LIB.BASEBOARD_FAB2(SCH_1):PAGE25
  J4G3   16  DQ<8> SCONN288_H44441004_PIP-SCONN,HA   I111 @BASEBOARD_FAB2_LIB.BASEBOARD_FAB2(SCH_1):PAGE47
  J6U2  161  DQ<9> SCONN288_H44441003_PIP-SCONN,HA   I111 @BASEBOARD_FAB2_LIB.BASEBOARD_FAB2(SCH_1):PAGE48

M_C_DQS_DN<0> @BASEBOARD_FAB2_LIB.BASEBOARD_FAB2(SCH_1):M_C_DQS_DN(0)
  U5D1 AL74 DDR2_DQS_DN<0> SKX_EXT_B_BGA1-IC,TBD   I172 @BASEBOARD_FAB2_LIB.BASEBOARD_FAB2(SCH_1):PAGE25
  J4G3  152  DQS0N SCONN288_H44441004_PIP-SCONN,HA    I61 @BASEBOARD_FAB2_LIB.BASEBOARD_FAB2(SCH_1):PAGE47
  J6U2  152  DQS0N SCONN288_H44441003_PIP-SCONN,HA    I61 @BASEBOARD_FAB2_LIB.BASEBOARD_FAB2(SCH_1):PAGE48

M_C_DQS_DN<10> @BASEBOARD_FAB2_LIB.BASEBOARD_FAB2(SCH_1):M_C_DQS_DN(10)
  U5D1 AD77 DDR2_DQS_DN<10> SKX_EXT_B_BGA1-IC,TBD   I172 @BASEBOARD_FAB2_LIB.BASEBOARD_FAB2(SCH_1):PAGE25
  J4G3   19 DQS10N SCONN288_H44441004_PIP-SCONN,HA    I61 @BASEBOARD_FAB2_LIB.BASEBOARD_FAB2(SCH_1):PAGE47
  J6U2   19 DQS10N SCONN288_H44441003_PIP-SCONN,HA    I61 @BASEBOARD_FAB2_LIB.BASEBOARD_FAB2(SCH_1):PAGE48

M_C_DQS_DN<11> @BASEBOARD_FAB2_LIB.BASEBOARD_FAB2(SCH_1):M_C_DQS_DN(11)
  U5D1  U72 DDR2_DQS_DN<11> SKX_EXT_B_BGA1-IC,TBD   I172 @BASEBOARD_FAB2_LIB.BASEBOARD_FAB2(SCH_1):PAGE25
  J4G3   30 DQS11N SCONN288_H44441004_PIP-SCONN,HA    I61 @BASEBOARD_FAB2_LIB.BASEBOARD_FAB2(SCH_1):PAGE47
  J6U2   30 DQS11N SCONN288_H44441003_PIP-SCONN,HA    I61 @BASEBOARD_FAB2_LIB.BASEBOARD_FAB2(SCH_1):PAGE48

M_C_DQS_DN<12> @BASEBOARD_FAB2_LIB.BASEBOARD_FAB2(SCH_1):M_C_DQS_DN(12)
  U5D1 AL66 DDR2_DQS_DN<12> SKX_EXT_B_BGA1-IC,TBD   I172 @BASEBOARD_FAB2_LIB.BASEBOARD_FAB2(SCH_1):PAGE25
  J4G3   41 DQS12N SCONN288_H44441004_PIP-SCONN,HA    I61 @BASEBOARD_FAB2_LIB.BASEBOARD_FAB2(SCH_1):PAGE47
  J6U2   41 DQS12N SCONN288_H44441003_PIP-SCONN,HA    I61 @BASEBOARD_FAB2_LIB.BASEBOARD_FAB2(SCH_1):PAGE48

M_C_DQS_DN<13> @BASEBOARD_FAB2_LIB.BASEBOARD_FAB2(SCH_1):M_C_DQS_DN(13)
  U5D1  T39 DDR2_DQS_DN<13> SKX_EXT_B_BGA1-IC,TBD   I172 @BASEBOARD_FAB2_LIB.BASEBOARD_FAB2(SCH_1):PAGE25
  J4G3  100 DQS13N SCONN288_H44441004_PIP-SCONN,HA    I61 @BASEBOARD_FAB2_LIB.BASEBOARD_FAB2(SCH_1):PAGE47
  J6U2  100 DQS13N SCONN288_H44441003_PIP-SCONN,HA    I61 @BASEBOARD_FAB2_LIB.BASEBOARD_FAB2(SCH_1):PAGE48

M_C_DQS_DN<14> @BASEBOARD_FAB2_LIB.BASEBOARD_FAB2(SCH_1):M_C_DQS_DN(14)
  U5D1  T33 DDR2_DQS_DN<14> SKX_EXT_B_BGA1-IC,TBD   I172 @BASEBOARD_FAB2_LIB.BASEBOARD_FAB2(SCH_1):PAGE25
  J4G3  111 DQS14N SCONN288_H44441004_PIP-SCONN,HA    I61 @BASEBOARD_FAB2_LIB.BASEBOARD_FAB2(SCH_1):PAGE47
  J6U2  111 DQS14N SCONN288_H44441003_PIP-SCONN,HA    I61 @BASEBOARD_FAB2_LIB.BASEBOARD_FAB2(SCH_1):PAGE48

M_C_DQS_DN<15> @BASEBOARD_FAB2_LIB.BASEBOARD_FAB2(SCH_1):M_C_DQS_DN(15)
  U5D1 AC30 DDR2_DQS_DN<15> SKX_EXT_B_BGA1-IC,TBD   I172 @BASEBOARD_FAB2_LIB.BASEBOARD_FAB2(SCH_1):PAGE25
  J4G3  122 DQS15N SCONN288_H44441004_PIP-SCONN,HA    I61 @BASEBOARD_FAB2_LIB.BASEBOARD_FAB2(SCH_1):PAGE47
  J6U2  122 DQS15N SCONN288_H44441003_PIP-SCONN,HA    I61 @BASEBOARD_FAB2_LIB.BASEBOARD_FAB2(SCH_1):PAGE48

M_C_DQS_DN<16> @BASEBOARD_FAB2_LIB.BASEBOARD_FAB2(SCH_1):M_C_DQS_DN(16)
  U5D1 AC24 DDR2_DQS_DN<16> SKX_EXT_B_BGA1-IC,TBD   I172 @BASEBOARD_FAB2_LIB.BASEBOARD_FAB2(SCH_1):PAGE25
  J4G3  133 DQS16N SCONN288_H44441004_PIP-SCONN,HA    I61 @BASEBOARD_FAB2_LIB.BASEBOARD_FAB2(SCH_1):PAGE47
  J6U2  133 DQS16N SCONN288_H44441003_PIP-SCONN,HA    I61 @BASEBOARD_FAB2_LIB.BASEBOARD_FAB2(SCH_1):PAGE48

M_C_DQS_DN<17> @BASEBOARD_FAB2_LIB.BASEBOARD_FAB2(SCH_1):M_C_DQS_DN(17)
  U5D1 AT71 DDR2_DQS_DN<17> SKX_EXT_B_BGA1-IC,TBD   I172 @BASEBOARD_FAB2_LIB.BASEBOARD_FAB2(SCH_1):PAGE25
  J4G3   52 DQS17N SCONN288_H44441004_PIP-SCONN,HA    I61 @BASEBOARD_FAB2_LIB.BASEBOARD_FAB2(SCH_1):PAGE47
  J6U2   52 DQS17N SCONN288_H44441003_PIP-SCONN,HA    I61 @BASEBOARD_FAB2_LIB.BASEBOARD_FAB2(SCH_1):PAGE48

M_C_DQS_DN<1> @BASEBOARD_FAB2_LIB.BASEBOARD_FAB2(SCH_1):M_C_DQS_DN(1)
  U5D1 AA74 DDR2_DQS_DN<1> SKX_EXT_B_BGA1-IC,TBD   I172 @BASEBOARD_FAB2_LIB.BASEBOARD_FAB2(SCH_1):PAGE25
  J4G3  163  DQS1N SCONN288_H44441004_PIP-SCONN,HA    I61 @BASEBOARD_FAB2_LIB.BASEBOARD_FAB2(SCH_1):PAGE47
  J6U2  163  DQS1N SCONN288_H44441003_PIP-SCONN,HA    I61 @BASEBOARD_FAB2_LIB.BASEBOARD_FAB2(SCH_1):PAGE48

M_C_DQS_DN<2> @BASEBOARD_FAB2_LIB.BASEBOARD_FAB2(SCH_1):M_C_DQS_DN(2)
  U5D1  Y69 DDR2_DQS_DN<2> SKX_EXT_B_BGA1-IC,TBD   I172 @BASEBOARD_FAB2_LIB.BASEBOARD_FAB2(SCH_1):PAGE25
  J4G3  174  DQS2N SCONN288_H44441004_PIP-SCONN,HA    I61 @BASEBOARD_FAB2_LIB.BASEBOARD_FAB2(SCH_1):PAGE47
  J6U2  174  DQS2N SCONN288_H44441003_PIP-SCONN,HA    I61 @BASEBOARD_FAB2_LIB.BASEBOARD_FAB2(SCH_1):PAGE48

M_C_DQS_DN<3> @BASEBOARD_FAB2_LIB.BASEBOARD_FAB2(SCH_1):M_C_DQS_DN(3)
  U5D1 AU66 DDR2_DQS_DN<3> SKX_EXT_B_BGA1-IC,TBD   I172 @BASEBOARD_FAB2_LIB.BASEBOARD_FAB2(SCH_1):PAGE25
  J4G3  185  DQS3N SCONN288_H44441004_PIP-SCONN,HA    I61 @BASEBOARD_FAB2_LIB.BASEBOARD_FAB2(SCH_1):PAGE47
  J6U2  185  DQS3N SCONN288_H44441003_PIP-SCONN,HA    I61 @BASEBOARD_FAB2_LIB.BASEBOARD_FAB2(SCH_1):PAGE48

M_C_DQS_DN<4> @BASEBOARD_FAB2_LIB.BASEBOARD_FAB2(SCH_1):M_C_DQS_DN(4)
  U5D1 AB39 DDR2_DQS_DN<4> SKX_EXT_B_BGA1-IC,TBD   I172 @BASEBOARD_FAB2_LIB.BASEBOARD_FAB2(SCH_1):PAGE25
  J4G3  244  DQS4N SCONN288_H44441004_PIP-SCONN,HA    I61 @BASEBOARD_FAB2_LIB.BASEBOARD_FAB2(SCH_1):PAGE47
  J6U2  244  DQS4N SCONN288_H44441003_PIP-SCONN,HA    I61 @BASEBOARD_FAB2_LIB.BASEBOARD_FAB2(SCH_1):PAGE48

M_C_DQS_DN<5> @BASEBOARD_FAB2_LIB.BASEBOARD_FAB2(SCH_1):M_C_DQS_DN(5)
  U5D1 AB33 DDR2_DQS_DN<5> SKX_EXT_B_BGA1-IC,TBD   I172 @BASEBOARD_FAB2_LIB.BASEBOARD_FAB2(SCH_1):PAGE25
  J4G3  255  DQS5N SCONN288_H44441004_PIP-SCONN,HA    I61 @BASEBOARD_FAB2_LIB.BASEBOARD_FAB2(SCH_1):PAGE47
  J6U2  255  DQS5N SCONN288_H44441003_PIP-SCONN,HA    I61 @BASEBOARD_FAB2_LIB.BASEBOARD_FAB2(SCH_1):PAGE48

M_C_DQS_DN<6> @BASEBOARD_FAB2_LIB.BASEBOARD_FAB2(SCH_1):M_C_DQS_DN(6)
  U5D1 AJ30 DDR2_DQS_DN<6> SKX_EXT_B_BGA1-IC,TBD   I172 @BASEBOARD_FAB2_LIB.BASEBOARD_FAB2(SCH_1):PAGE25
  J4G3  266  DQS6N SCONN288_H44441004_PIP-SCONN,HA    I61 @BASEBOARD_FAB2_LIB.BASEBOARD_FAB2(SCH_1):PAGE47
  J6U2  266  DQS6N SCONN288_H44441003_PIP-SCONN,HA    I61 @BASEBOARD_FAB2_LIB.BASEBOARD_FAB2(SCH_1):PAGE48

M_C_DQS_DN<7> @BASEBOARD_FAB2_LIB.BASEBOARD_FAB2(SCH_1):M_C_DQS_DN(7)
  U5D1 AJ24 DDR2_DQS_DN<7> SKX_EXT_B_BGA1-IC,TBD   I172 @BASEBOARD_FAB2_LIB.BASEBOARD_FAB2(SCH_1):PAGE25
  J4G3  277  DQS7N SCONN288_H44441004_PIP-SCONN,HA    I61 @BASEBOARD_FAB2_LIB.BASEBOARD_FAB2(SCH_1):PAGE47
  J6U2  277  DQS7N SCONN288_H44441003_PIP-SCONN,HA    I61 @BASEBOARD_FAB2_LIB.BASEBOARD_FAB2(SCH_1):PAGE48

M_C_DQS_DN<8> @BASEBOARD_FAB2_LIB.BASEBOARD_FAB2(SCH_1):M_C_DQS_DN(8)
  U5D1 BB71 DDR2_DQS_DN<8> SKX_EXT_B_BGA1-IC,TBD   I172 @BASEBOARD_FAB2_LIB.BASEBOARD_FAB2(SCH_1):PAGE25
  J4G3  196  DQS8N SCONN288_H44441004_PIP-SCONN,HA    I61 @BASEBOARD_FAB2_LIB.BASEBOARD_FAB2(SCH_1):PAGE47
  J6U2  196  DQS8N SCONN288_H44441003_PIP-SCONN,HA    I61 @BASEBOARD_FAB2_LIB.BASEBOARD_FAB2(SCH_1):PAGE48

M_C_DQS_DN<9> @BASEBOARD_FAB2_LIB.BASEBOARD_FAB2(SCH_1):M_C_DQS_DN(9)
  U5D1 AP77 DDR2_DQS_DN<9> SKX_EXT_B_BGA1-IC,TBD   I172 @BASEBOARD_FAB2_LIB.BASEBOARD_FAB2(SCH_1):PAGE25
  J4G3    8  DQS9N SCONN288_H44441004_PIP-SCONN,HA    I61 @BASEBOARD_FAB2_LIB.BASEBOARD_FAB2(SCH_1):PAGE47
  J6U2    8  DQS9N SCONN288_H44441003_PIP-SCONN,HA    I61 @BASEBOARD_FAB2_LIB.BASEBOARD_FAB2(SCH_1):PAGE48

M_C_DQS_DP<0> @BASEBOARD_FAB2_LIB.BASEBOARD_FAB2(SCH_1):M_C_DQS_DP(0)
  U5D1 AM75 DDR2_DQS_DP<0> SKX_EXT_B_BGA1-IC,TBD   I172 @BASEBOARD_FAB2_LIB.BASEBOARD_FAB2(SCH_1):PAGE25
  J4G3  153  DQS0P SCONN288_H44441004_PIP-SCONN,HA    I61 @BASEBOARD_FAB2_LIB.BASEBOARD_FAB2(SCH_1):PAGE47
  J6U2  153  DQS0P SCONN288_H44441003_PIP-SCONN,HA    I61 @BASEBOARD_FAB2_LIB.BASEBOARD_FAB2(SCH_1):PAGE48

M_C_DQS_DP<10> @BASEBOARD_FAB2_LIB.BASEBOARD_FAB2(SCH_1):M_C_DQS_DP(10)
  U5D1 AC76 DDR2_DQS_DP<10> SKX_EXT_B_BGA1-IC,TBD   I172 @BASEBOARD_FAB2_LIB.BASEBOARD_FAB2(SCH_1):PAGE25
  J4G3   18 DQS10P SCONN288_H44441004_PIP-SCONN,HA    I61 @BASEBOARD_FAB2_LIB.BASEBOARD_FAB2(SCH_1):PAGE47
  J6U2   18 DQS10P SCONN288_H44441003_PIP-SCONN,HA    I61 @BASEBOARD_FAB2_LIB.BASEBOARD_FAB2(SCH_1):PAGE48

M_C_DQS_DP<11> @BASEBOARD_FAB2_LIB.BASEBOARD_FAB2(SCH_1):M_C_DQS_DP(11)
  U5D1  V71 DDR2_DQS_DP<11> SKX_EXT_B_BGA1-IC,TBD   I172 @BASEBOARD_FAB2_LIB.BASEBOARD_FAB2(SCH_1):PAGE25
  J4G3   29 DQS11P SCONN288_H44441004_PIP-SCONN,HA    I61 @BASEBOARD_FAB2_LIB.BASEBOARD_FAB2(SCH_1):PAGE47
  J6U2   29 DQS11P SCONN288_H44441003_PIP-SCONN,HA    I61 @BASEBOARD_FAB2_LIB.BASEBOARD_FAB2(SCH_1):PAGE48

M_C_DQS_DP<12> @BASEBOARD_FAB2_LIB.BASEBOARD_FAB2(SCH_1):M_C_DQS_DP(12)
  U5D1 AN66 DDR2_DQS_DP<12> SKX_EXT_B_BGA1-IC,TBD   I172 @BASEBOARD_FAB2_LIB.BASEBOARD_FAB2(SCH_1):PAGE25
  J4G3   40 DQS12P SCONN288_H44441004_PIP-SCONN,HA    I61 @BASEBOARD_FAB2_LIB.BASEBOARD_FAB2(SCH_1):PAGE47
  J6U2   40 DQS12P SCONN288_H44441003_PIP-SCONN,HA    I61 @BASEBOARD_FAB2_LIB.BASEBOARD_FAB2(SCH_1):PAGE48

M_C_DQS_DP<13> @BASEBOARD_FAB2_LIB.BASEBOARD_FAB2(SCH_1):M_C_DQS_DP(13)
  U5D1  V39 DDR2_DQS_DP<13> SKX_EXT_B_BGA1-IC,TBD   I172 @BASEBOARD_FAB2_LIB.BASEBOARD_FAB2(SCH_1):PAGE25
  J4G3   99 DQS13P SCONN288_H44441004_PIP-SCONN,HA    I61 @BASEBOARD_FAB2_LIB.BASEBOARD_FAB2(SCH_1):PAGE47
  J6U2   99 DQS13P SCONN288_H44441003_PIP-SCONN,HA    I61 @BASEBOARD_FAB2_LIB.BASEBOARD_FAB2(SCH_1):PAGE48

M_C_DQS_DP<14> @BASEBOARD_FAB2_LIB.BASEBOARD_FAB2(SCH_1):M_C_DQS_DP(14)
  U5D1  V33 DDR2_DQS_DP<14> SKX_EXT_B_BGA1-IC,TBD   I172 @BASEBOARD_FAB2_LIB.BASEBOARD_FAB2(SCH_1):PAGE25
  J4G3  110 DQS14P SCONN288_H44441004_PIP-SCONN,HA    I61 @BASEBOARD_FAB2_LIB.BASEBOARD_FAB2(SCH_1):PAGE47
  J6U2  110 DQS14P SCONN288_H44441003_PIP-SCONN,HA    I61 @BASEBOARD_FAB2_LIB.BASEBOARD_FAB2(SCH_1):PAGE48

M_C_DQS_DP<15> @BASEBOARD_FAB2_LIB.BASEBOARD_FAB2(SCH_1):M_C_DQS_DP(15)
  U5D1 AE30 DDR2_DQS_DP<15> SKX_EXT_B_BGA1-IC,TBD   I172 @BASEBOARD_FAB2_LIB.BASEBOARD_FAB2(SCH_1):PAGE25
  J4G3  121 DQS15P SCONN288_H44441004_PIP-SCONN,HA    I61 @BASEBOARD_FAB2_LIB.BASEBOARD_FAB2(SCH_1):PAGE47
  J6U2  121 DQS15P SCONN288_H44441003_PIP-SCONN,HA    I61 @BASEBOARD_FAB2_LIB.BASEBOARD_FAB2(SCH_1):PAGE48

M_C_DQS_DP<16> @BASEBOARD_FAB2_LIB.BASEBOARD_FAB2(SCH_1):M_C_DQS_DP(16)
  U5D1 AE24 DDR2_DQS_DP<16> SKX_EXT_B_BGA1-IC,TBD   I172 @BASEBOARD_FAB2_LIB.BASEBOARD_FAB2(SCH_1):PAGE25
  J4G3  132 DQS16P SCONN288_H44441004_PIP-SCONN,HA    I61 @BASEBOARD_FAB2_LIB.BASEBOARD_FAB2(SCH_1):PAGE47
  J6U2  132 DQS16P SCONN288_H44441003_PIP-SCONN,HA    I61 @BASEBOARD_FAB2_LIB.BASEBOARD_FAB2(SCH_1):PAGE48

M_C_DQS_DP<17> @BASEBOARD_FAB2_LIB.BASEBOARD_FAB2(SCH_1):M_C_DQS_DP(17)
  U5D1 AV71 DDR2_DQS_DP<17> SKX_EXT_B_BGA1-IC,TBD   I172 @BASEBOARD_FAB2_LIB.BASEBOARD_FAB2(SCH_1):PAGE25
  J4G3   51 DQS17P SCONN288_H44441004_PIP-SCONN,HA    I61 @BASEBOARD_FAB2_LIB.BASEBOARD_FAB2(SCH_1):PAGE47
  J6U2   51 DQS17P SCONN288_H44441003_PIP-SCONN,HA    I61 @BASEBOARD_FAB2_LIB.BASEBOARD_FAB2(SCH_1):PAGE48

M_C_DQS_DP<1> @BASEBOARD_FAB2_LIB.BASEBOARD_FAB2(SCH_1):M_C_DQS_DP(1)
  U5D1 AB75 DDR2_DQS_DP<1> SKX_EXT_B_BGA1-IC,TBD   I172 @BASEBOARD_FAB2_LIB.BASEBOARD_FAB2(SCH_1):PAGE25
  J4G3  164  DQS1P SCONN288_H44441004_PIP-SCONN,HA    I61 @BASEBOARD_FAB2_LIB.BASEBOARD_FAB2(SCH_1):PAGE47
  J6U2  164  DQS1P SCONN288_H44441003_PIP-SCONN,HA    I61 @BASEBOARD_FAB2_LIB.BASEBOARD_FAB2(SCH_1):PAGE48

M_C_DQS_DP<2> @BASEBOARD_FAB2_LIB.BASEBOARD_FAB2(SCH_1):M_C_DQS_DP(2)
  U5D1  W70 DDR2_DQS_DP<2> SKX_EXT_B_BGA1-IC,TBD   I172 @BASEBOARD_FAB2_LIB.BASEBOARD_FAB2(SCH_1):PAGE25
  J4G3  175  DQS2P SCONN288_H44441004_PIP-SCONN,HA    I61 @BASEBOARD_FAB2_LIB.BASEBOARD_FAB2(SCH_1):PAGE47
  J6U2  175  DQS2P SCONN288_H44441003_PIP-SCONN,HA    I61 @BASEBOARD_FAB2_LIB.BASEBOARD_FAB2(SCH_1):PAGE48

M_C_DQS_DP<3> @BASEBOARD_FAB2_LIB.BASEBOARD_FAB2(SCH_1):M_C_DQS_DP(3)
  U5D1 AR66 DDR2_DQS_DP<3> SKX_EXT_B_BGA1-IC,TBD   I172 @BASEBOARD_FAB2_LIB.BASEBOARD_FAB2(SCH_1):PAGE25
  J4G3  186  DQS3P SCONN288_H44441004_PIP-SCONN,HA    I61 @BASEBOARD_FAB2_LIB.BASEBOARD_FAB2(SCH_1):PAGE47
  J6U2  186  DQS3P SCONN288_H44441003_PIP-SCONN,HA    I61 @BASEBOARD_FAB2_LIB.BASEBOARD_FAB2(SCH_1):PAGE48

M_C_DQS_DP<4> @BASEBOARD_FAB2_LIB.BASEBOARD_FAB2(SCH_1):M_C_DQS_DP(4)
  U5D1  Y39 DDR2_DQS_DP<4> SKX_EXT_B_BGA1-IC,TBD   I172 @BASEBOARD_FAB2_LIB.BASEBOARD_FAB2(SCH_1):PAGE25
  J4G3  245  DQS4P SCONN288_H44441004_PIP-SCONN,HA    I61 @BASEBOARD_FAB2_LIB.BASEBOARD_FAB2(SCH_1):PAGE47
  J6U2  245  DQS4P SCONN288_H44441003_PIP-SCONN,HA    I61 @BASEBOARD_FAB2_LIB.BASEBOARD_FAB2(SCH_1):PAGE48

M_C_DQS_DP<5> @BASEBOARD_FAB2_LIB.BASEBOARD_FAB2(SCH_1):M_C_DQS_DP(5)
  U5D1  Y33 DDR2_DQS_DP<5> SKX_EXT_B_BGA1-IC,TBD   I172 @BASEBOARD_FAB2_LIB.BASEBOARD_FAB2(SCH_1):PAGE25
  J4G3  256  DQS5P SCONN288_H44441004_PIP-SCONN,HA    I61 @BASEBOARD_FAB2_LIB.BASEBOARD_FAB2(SCH_1):PAGE47
  J6U2  256  DQS5P SCONN288_H44441003_PIP-SCONN,HA    I61 @BASEBOARD_FAB2_LIB.BASEBOARD_FAB2(SCH_1):PAGE48

M_C_DQS_DP<6> @BASEBOARD_FAB2_LIB.BASEBOARD_FAB2(SCH_1):M_C_DQS_DP(6)
  U5D1 AG30 DDR2_DQS_DP<6> SKX_EXT_B_BGA1-IC,TBD   I172 @BASEBOARD_FAB2_LIB.BASEBOARD_FAB2(SCH_1):PAGE25
  J4G3  267  DQS6P SCONN288_H44441004_PIP-SCONN,HA    I61 @BASEBOARD_FAB2_LIB.BASEBOARD_FAB2(SCH_1):PAGE47
  J6U2  267  DQS6P SCONN288_H44441003_PIP-SCONN,HA    I61 @BASEBOARD_FAB2_LIB.BASEBOARD_FAB2(SCH_1):PAGE48

M_C_DQS_DP<7> @BASEBOARD_FAB2_LIB.BASEBOARD_FAB2(SCH_1):M_C_DQS_DP(7)
  U5D1 AG24 DDR2_DQS_DP<7> SKX_EXT_B_BGA1-IC,TBD   I172 @BASEBOARD_FAB2_LIB.BASEBOARD_FAB2(SCH_1):PAGE25
  J4G3  278  DQS7P SCONN288_H44441004_PIP-SCONN,HA    I61 @BASEBOARD_FAB2_LIB.BASEBOARD_FAB2(SCH_1):PAGE47
  J6U2  278  DQS7P SCONN288_H44441003_PIP-SCONN,HA    I61 @BASEBOARD_FAB2_LIB.BASEBOARD_FAB2(SCH_1):PAGE48

M_C_DQS_DP<8> @BASEBOARD_FAB2_LIB.BASEBOARD_FAB2(SCH_1):M_C_DQS_DP(8)
  U5D1 AY71 DDR2_DQS_DP<8> SKX_EXT_B_BGA1-IC,TBD   I172 @BASEBOARD_FAB2_LIB.BASEBOARD_FAB2(SCH_1):PAGE25
  J4G3  197  DQS8P SCONN288_H44441004_PIP-SCONN,HA    I61 @BASEBOARD_FAB2_LIB.BASEBOARD_FAB2(SCH_1):PAGE47
  J6U2  197  DQS8P SCONN288_H44441003_PIP-SCONN,HA    I61 @BASEBOARD_FAB2_LIB.BASEBOARD_FAB2(SCH_1):PAGE48

M_C_DQS_DP<9> @BASEBOARD_FAB2_LIB.BASEBOARD_FAB2(SCH_1):M_C_DQS_DP(9)
  U5D1 AN76 DDR2_DQS_DP<9> SKX_EXT_B_BGA1-IC,TBD   I172 @BASEBOARD_FAB2_LIB.BASEBOARD_FAB2(SCH_1):PAGE25
  J4G3    7  DQS9P SCONN288_H44441004_PIP-SCONN,HA    I61 @BASEBOARD_FAB2_LIB.BASEBOARD_FAB2(SCH_1):PAGE47
  J6U2    7  DQS9P SCONN288_H44441003_PIP-SCONN,HA    I61 @BASEBOARD_FAB2_LIB.BASEBOARD_FAB2(SCH_1):PAGE48

M_C_ECC<0> @BASEBOARD_FAB2_LIB.BASEBOARD_FAB2(SCH_1):M_C_ECC(0)
  U5D1 AU72 DDR2_ECC<0> SKX_EXT_B_BGA1-IC,TBD   I172 @BASEBOARD_FAB2_LIB.BASEBOARD_FAB2(SCH_1):PAGE25
  J4G3  194  CB<1> SCONN288_H44441004_PIP-SCONN,HA   I111 @BASEBOARD_FAB2_LIB.BASEBOARD_FAB2(SCH_1):PAGE47
  J6U2   49  CB<0> SCONN288_H44441003_PIP-SCONN,HA   I111 @BASEBOARD_FAB2_LIB.BASEBOARD_FAB2(SCH_1):PAGE48

M_C_ECC<1> @BASEBOARD_FAB2_LIB.BASEBOARD_FAB2(SCH_1):M_C_ECC(1)
  U5D1 BA72 DDR2_ECC<1> SKX_EXT_B_BGA1-IC,TBD   I172 @BASEBOARD_FAB2_LIB.BASEBOARD_FAB2(SCH_1):PAGE25
  J4G3   49  CB<0> SCONN288_H44441004_PIP-SCONN,HA   I111 @BASEBOARD_FAB2_LIB.BASEBOARD_FAB2(SCH_1):PAGE47
  J6U2  194  CB<1> SCONN288_H44441003_PIP-SCONN,HA   I111 @BASEBOARD_FAB2_LIB.BASEBOARD_FAB2(SCH_1):PAGE48

M_C_ECC<2> @BASEBOARD_FAB2_LIB.BASEBOARD_FAB2(SCH_1):M_C_ECC(2)
  U5D1 AV69 DDR2_ECC<2> SKX_EXT_B_BGA1-IC,TBD   I172 @BASEBOARD_FAB2_LIB.BASEBOARD_FAB2(SCH_1):PAGE25
  J4G3  201  CB<3> SCONN288_H44441004_PIP-SCONN,HA   I111 @BASEBOARD_FAB2_LIB.BASEBOARD_FAB2(SCH_1):PAGE47
  J6U2   56  CB<2> SCONN288_H44441003_PIP-SCONN,HA   I111 @BASEBOARD_FAB2_LIB.BASEBOARD_FAB2(SCH_1):PAGE48

M_C_ECC<3> @BASEBOARD_FAB2_LIB.BASEBOARD_FAB2(SCH_1):M_C_ECC(3)
  U5D1 AY69 DDR2_ECC<3> SKX_EXT_B_BGA1-IC,TBD   I172 @BASEBOARD_FAB2_LIB.BASEBOARD_FAB2(SCH_1):PAGE25
  J4G3   56  CB<2> SCONN288_H44441004_PIP-SCONN,HA   I111 @BASEBOARD_FAB2_LIB.BASEBOARD_FAB2(SCH_1):PAGE47
  J6U2  201  CB<3> SCONN288_H44441003_PIP-SCONN,HA   I111 @BASEBOARD_FAB2_LIB.BASEBOARD_FAB2(SCH_1):PAGE48

M_C_ECC<4> @BASEBOARD_FAB2_LIB.BASEBOARD_FAB2(SCH_1):M_C_ECC(4)
  U5D1 AV73 DDR2_ECC<4> SKX_EXT_B_BGA1-IC,TBD   I172 @BASEBOARD_FAB2_LIB.BASEBOARD_FAB2(SCH_1):PAGE25
  J4G3  192  CB<5> SCONN288_H44441004_PIP-SCONN,HA   I111 @BASEBOARD_FAB2_LIB.BASEBOARD_FAB2(SCH_1):PAGE47
  J6U2   47  CB<4> SCONN288_H44441003_PIP-SCONN,HA   I111 @BASEBOARD_FAB2_LIB.BASEBOARD_FAB2(SCH_1):PAGE48

M_C_ECC<5> @BASEBOARD_FAB2_LIB.BASEBOARD_FAB2(SCH_1):M_C_ECC(5)
  U5D1 AY73 DDR2_ECC<5> SKX_EXT_B_BGA1-IC,TBD   I172 @BASEBOARD_FAB2_LIB.BASEBOARD_FAB2(SCH_1):PAGE25
  J4G3   47  CB<4> SCONN288_H44441004_PIP-SCONN,HA   I111 @BASEBOARD_FAB2_LIB.BASEBOARD_FAB2(SCH_1):PAGE47
  J6U2  192  CB<5> SCONN288_H44441003_PIP-SCONN,HA   I111 @BASEBOARD_FAB2_LIB.BASEBOARD_FAB2(SCH_1):PAGE48

M_C_ECC<6> @BASEBOARD_FAB2_LIB.BASEBOARD_FAB2(SCH_1):M_C_ECC(6)
  U5D1 AU70 DDR2_ECC<6> SKX_EXT_B_BGA1-IC,TBD   I172 @BASEBOARD_FAB2_LIB.BASEBOARD_FAB2(SCH_1):PAGE25
  J4G3  199  CB<7> SCONN288_H44441004_PIP-SCONN,HA   I111 @BASEBOARD_FAB2_LIB.BASEBOARD_FAB2(SCH_1):PAGE47
  J6U2   54  CB<6> SCONN288_H44441003_PIP-SCONN,HA   I111 @BASEBOARD_FAB2_LIB.BASEBOARD_FAB2(SCH_1):PAGE48

M_C_ECC<7> @BASEBOARD_FAB2_LIB.BASEBOARD_FAB2(SCH_1):M_C_ECC(7)
  U5D1 BA70 DDR2_ECC<7> SKX_EXT_B_BGA1-IC,TBD   I172 @BASEBOARD_FAB2_LIB.BASEBOARD_FAB2(SCH_1):PAGE25
  J4G3   54  CB<6> SCONN288_H44441004_PIP-SCONN,HA   I111 @BASEBOARD_FAB2_LIB.BASEBOARD_FAB2(SCH_1):PAGE47
  J6U2  199  CB<7> SCONN288_H44441003_PIP-SCONN,HA   I111 @BASEBOARD_FAB2_LIB.BASEBOARD_FAB2(SCH_1):PAGE48

M_C_MA<0> @BASEBOARD_FAB2_LIB.BASEBOARD_FAB2(SCH_1):M_C_MA(0)
  U5D1 AB53 DDR2_MA<0> SKX_EXT_B_BGA1-IC,TBD   I172 @BASEBOARD_FAB2_LIB.BASEBOARD_FAB2(SCH_1):PAGE25
  J4G3   79     A0 SCONN288_H44441004_PIP-SCONN,HA   I111 @BASEBOARD_FAB2_LIB.BASEBOARD_FAB2(SCH_1):PAGE47
  J6U2   79     A0 SCONN288_H44441003_PIP-SCONN,HA   I111 @BASEBOARD_FAB2_LIB.BASEBOARD_FAB2(SCH_1):PAGE48

M_C_MA<10> @BASEBOARD_FAB2_LIB.BASEBOARD_FAB2(SCH_1):M_C_MA(10)
  U5D1 AD55 DDR2_MA<10> SKX_EXT_B_BGA1-IC,TBD   I172 @BASEBOARD_FAB2_LIB.BASEBOARD_FAB2(SCH_1):PAGE25
  J4G3  225    A10 SCONN288_H44441004_PIP-SCONN,HA   I111 @BASEBOARD_FAB2_LIB.BASEBOARD_FAB2(SCH_1):PAGE47
  J6U2  225    A10 SCONN288_H44441003_PIP-SCONN,HA   I111 @BASEBOARD_FAB2_LIB.BASEBOARD_FAB2(SCH_1):PAGE48

M_C_MA<11> @BASEBOARD_FAB2_LIB.BASEBOARD_FAB2(SCH_1):M_C_MA(11)
  U5D1 AG60 DDR2_MA<11> SKX_EXT_B_BGA1-IC,TBD   I172 @BASEBOARD_FAB2_LIB.BASEBOARD_FAB2(SCH_1):PAGE25
  J4G3  210    A11 SCONN288_H44441004_PIP-SCONN,HA   I111 @BASEBOARD_FAB2_LIB.BASEBOARD_FAB2(SCH_1):PAGE47
  J6U2  210    A11 SCONN288_H44441003_PIP-SCONN,HA   I111 @BASEBOARD_FAB2_LIB.BASEBOARD_FAB2(SCH_1):PAGE48

M_C_MA<12> @BASEBOARD_FAB2_LIB.BASEBOARD_FAB2(SCH_1):M_C_MA(12)
  U5D1 AG62 DDR2_MA<12> SKX_EXT_B_BGA1-IC,TBD   I172 @BASEBOARD_FAB2_LIB.BASEBOARD_FAB2(SCH_1):PAGE25
  J4G3   65    A12 SCONN288_H44441004_PIP-SCONN,HA   I111 @BASEBOARD_FAB2_LIB.BASEBOARD_FAB2(SCH_1):PAGE47
  J6U2   65    A12 SCONN288_H44441003_PIP-SCONN,HA   I111 @BASEBOARD_FAB2_LIB.BASEBOARD_FAB2(SCH_1):PAGE48

M_C_MA<13> @BASEBOARD_FAB2_LIB.BASEBOARD_FAB2(SCH_1):M_C_MA(13)
  U5D1 AD53 DDR2_MA<13> SKX_EXT_B_BGA1-IC,TBD   I172 @BASEBOARD_FAB2_LIB.BASEBOARD_FAB2(SCH_1):PAGE25
  J4G3  232    A13 SCONN288_H44441004_PIP-SCONN,HA   I111 @BASEBOARD_FAB2_LIB.BASEBOARD_FAB2(SCH_1):PAGE47
  J6U2  232    A13 SCONN288_H44441003_PIP-SCONN,HA   I111 @BASEBOARD_FAB2_LIB.BASEBOARD_FAB2(SCH_1):PAGE48

M_C_MA<14> @BASEBOARD_FAB2_LIB.BASEBOARD_FAB2(SCH_1):M_C_MA(14)
  U5D1  W50 DDR2_MA<14> SKX_EXT_B_BGA1-IC,TBD   I172 @BASEBOARD_FAB2_LIB.BASEBOARD_FAB2(SCH_1):PAGE25
  J4G3  228 A14_WE_N SCONN288_H44441004_PIP-SCONN,HA   I111 @BASEBOARD_FAB2_LIB.BASEBOARD_FAB2(SCH_1):PAGE47
  J6U2  228 A14_WE_N SCONN288_H44441003_PIP-SCONN,HA   I111 @BASEBOARD_FAB2_LIB.BASEBOARD_FAB2(SCH_1):PAGE48

M_C_MA<15> @BASEBOARD_FAB2_LIB.BASEBOARD_FAB2(SCH_1):M_C_MA(15)
  U5D1 AE54 DDR2_MA<15> SKX_EXT_B_BGA1-IC,TBD   I172 @BASEBOARD_FAB2_LIB.BASEBOARD_FAB2(SCH_1):PAGE25
  J4G3   86 A15_CAS_N SCONN288_H44441004_PIP-SCONN,HA   I111 @BASEBOARD_FAB2_LIB.BASEBOARD_FAB2(SCH_1):PAGE47
  J6U2   86 A15_CAS_N SCONN288_H44441003_PIP-SCONN,HA   I111 @BASEBOARD_FAB2_LIB.BASEBOARD_FAB2(SCH_1):PAGE48

M_C_MA<16> @BASEBOARD_FAB2_LIB.BASEBOARD_FAB2(SCH_1):M_C_MA(16)
  U5D1 AA52 DDR2_MA<16> SKX_EXT_B_BGA1-IC,TBD   I172 @BASEBOARD_FAB2_LIB.BASEBOARD_FAB2(SCH_1):PAGE25
  J4G3   82 A16_RAS_N SCONN288_H44441004_PIP-SCONN,HA   I111 @BASEBOARD_FAB2_LIB.BASEBOARD_FAB2(SCH_1):PAGE47
  J6U2   82 A16_RAS_N SCONN288_H44441003_PIP-SCONN,HA   I111 @BASEBOARD_FAB2_LIB.BASEBOARD_FAB2(SCH_1):PAGE48

M_C_MA<17> @BASEBOARD_FAB2_LIB.BASEBOARD_FAB2(SCH_1):M_C_MA(17)
  U5D1 AC46 DDR2_MA<17> SKX_EXT_B_BGA1-IC,TBD   I172 @BASEBOARD_FAB2_LIB.BASEBOARD_FAB2(SCH_1):PAGE25
  J4G3  234    A17 SCONN288_H44441004_PIP-SCONN,HA   I111 @BASEBOARD_FAB2_LIB.BASEBOARD_FAB2(SCH_1):PAGE47
  J6U2  234    A17 SCONN288_H44441003_PIP-SCONN,HA   I111 @BASEBOARD_FAB2_LIB.BASEBOARD_FAB2(SCH_1):PAGE48

M_C_MA<1> @BASEBOARD_FAB2_LIB.BASEBOARD_FAB2(SCH_1):M_C_MA(1)
  U5D1 AE58 DDR2_MA<1> SKX_EXT_B_BGA1-IC,TBD   I172 @BASEBOARD_FAB2_LIB.BASEBOARD_FAB2(SCH_1):PAGE25
  J4G3   72     A1 SCONN288_H44441004_PIP-SCONN,HA   I111 @BASEBOARD_FAB2_LIB.BASEBOARD_FAB2(SCH_1):PAGE47
  J6U2   72     A1 SCONN288_H44441003_PIP-SCONN,HA   I111 @BASEBOARD_FAB2_LIB.BASEBOARD_FAB2(SCH_1):PAGE48

M_C_MA<2> @BASEBOARD_FAB2_LIB.BASEBOARD_FAB2(SCH_1):M_C_MA(2)
  U5D1 AD57 DDR2_MA<2> SKX_EXT_B_BGA1-IC,TBD   I172 @BASEBOARD_FAB2_LIB.BASEBOARD_FAB2(SCH_1):PAGE25
  J4G3  216     A2 SCONN288_H44441004_PIP-SCONN,HA   I111 @BASEBOARD_FAB2_LIB.BASEBOARD_FAB2(SCH_1):PAGE47
  J6U2  216     A2 SCONN288_H44441003_PIP-SCONN,HA   I111 @BASEBOARD_FAB2_LIB.BASEBOARD_FAB2(SCH_1):PAGE48

M_C_MA<3> @BASEBOARD_FAB2_LIB.BASEBOARD_FAB2(SCH_1):M_C_MA(3)
  U5D1  W58 DDR2_MA<3> SKX_EXT_B_BGA1-IC,TBD   I172 @BASEBOARD_FAB2_LIB.BASEBOARD_FAB2(SCH_1):PAGE25
  J4G3   71     A3 SCONN288_H44441004_PIP-SCONN,HA   I111 @BASEBOARD_FAB2_LIB.BASEBOARD_FAB2(SCH_1):PAGE47
  J6U2   71     A3 SCONN288_H44441003_PIP-SCONN,HA   I111 @BASEBOARD_FAB2_LIB.BASEBOARD_FAB2(SCH_1):PAGE48

M_C_MA<4> @BASEBOARD_FAB2_LIB.BASEBOARD_FAB2(SCH_1):M_C_MA(4)
  U5D1 AA58 DDR2_MA<4> SKX_EXT_B_BGA1-IC,TBD   I172 @BASEBOARD_FAB2_LIB.BASEBOARD_FAB2(SCH_1):PAGE25
  J4G3  214     A4 SCONN288_H44441004_PIP-SCONN,HA   I111 @BASEBOARD_FAB2_LIB.BASEBOARD_FAB2(SCH_1):PAGE47
  J6U2  214     A4 SCONN288_H44441003_PIP-SCONN,HA   I111 @BASEBOARD_FAB2_LIB.BASEBOARD_FAB2(SCH_1):PAGE48

M_C_MA<5> @BASEBOARD_FAB2_LIB.BASEBOARD_FAB2(SCH_1):M_C_MA(5)
  U5D1  V59 DDR2_MA<5> SKX_EXT_B_BGA1-IC,TBD   I172 @BASEBOARD_FAB2_LIB.BASEBOARD_FAB2(SCH_1):PAGE25
  J4G3  213     A5 SCONN288_H44441004_PIP-SCONN,HA   I111 @BASEBOARD_FAB2_LIB.BASEBOARD_FAB2(SCH_1):PAGE47
  J6U2  213     A5 SCONN288_H44441003_PIP-SCONN,HA   I111 @BASEBOARD_FAB2_LIB.BASEBOARD_FAB2(SCH_1):PAGE48

M_C_MA<6> @BASEBOARD_FAB2_LIB.BASEBOARD_FAB2(SCH_1):M_C_MA(6)
  U5D1 AB59 DDR2_MA<6> SKX_EXT_B_BGA1-IC,TBD   I172 @BASEBOARD_FAB2_LIB.BASEBOARD_FAB2(SCH_1):PAGE25
  J4G3   69     A6 SCONN288_H44441004_PIP-SCONN,HA   I111 @BASEBOARD_FAB2_LIB.BASEBOARD_FAB2(SCH_1):PAGE47
  J6U2   69     A6 SCONN288_H44441003_PIP-SCONN,HA   I111 @BASEBOARD_FAB2_LIB.BASEBOARD_FAB2(SCH_1):PAGE48

M_C_MA<7> @BASEBOARD_FAB2_LIB.BASEBOARD_FAB2(SCH_1):M_C_MA(7)
  U5D1 AE60 DDR2_MA<7> SKX_EXT_B_BGA1-IC,TBD   I172 @BASEBOARD_FAB2_LIB.BASEBOARD_FAB2(SCH_1):PAGE25
  J4G3  211     A7 SCONN288_H44441004_PIP-SCONN,HA   I111 @BASEBOARD_FAB2_LIB.BASEBOARD_FAB2(SCH_1):PAGE47
  J6U2  211     A7 SCONN288_H44441003_PIP-SCONN,HA   I111 @BASEBOARD_FAB2_LIB.BASEBOARD_FAB2(SCH_1):PAGE48

M_C_MA<8> @BASEBOARD_FAB2_LIB.BASEBOARD_FAB2(SCH_1):M_C_MA(8)
  U5D1 AD59 DDR2_MA<8> SKX_EXT_B_BGA1-IC,TBD   I172 @BASEBOARD_FAB2_LIB.BASEBOARD_FAB2(SCH_1):PAGE25
  J4G3   68     A8 SCONN288_H44441004_PIP-SCONN,HA   I111 @BASEBOARD_FAB2_LIB.BASEBOARD_FAB2(SCH_1):PAGE47
  J6U2   68     A8 SCONN288_H44441003_PIP-SCONN,HA   I111 @BASEBOARD_FAB2_LIB.BASEBOARD_FAB2(SCH_1):PAGE48

M_C_MA<9> @BASEBOARD_FAB2_LIB.BASEBOARD_FAB2(SCH_1):M_C_MA(9)
  U5D1 AG58 DDR2_MA<9> SKX_EXT_B_BGA1-IC,TBD   I172 @BASEBOARD_FAB2_LIB.BASEBOARD_FAB2(SCH_1):PAGE25
  J4G3   66     A9 SCONN288_H44441004_PIP-SCONN,HA   I111 @BASEBOARD_FAB2_LIB.BASEBOARD_FAB2(SCH_1):PAGE47
  J6U2   66     A9 SCONN288_H44441003_PIP-SCONN,HA   I111 @BASEBOARD_FAB2_LIB.BASEBOARD_FAB2(SCH_1):PAGE48

M_C_ODT<0> @BASEBOARD_FAB2_LIB.BASEBOARD_FAB2(SCH_1):M_C_ODT(0)
  U5D1 AA50 DDR2_ODT<0> SKX_EXT_B_BGA1-IC,TBD   I172 @BASEBOARD_FAB2_LIB.BASEBOARD_FAB2(SCH_1):PAGE25
  J4G3   87 ODT<0> SCONN288_H44441004_PIP-SCONN,HA   I111 @BASEBOARD_FAB2_LIB.BASEBOARD_FAB2(SCH_1):PAGE47

M_C_ODT<1> @BASEBOARD_FAB2_LIB.BASEBOARD_FAB2(SCH_1):M_C_ODT(1)
  U5D1 AA48 DDR2_ODT<1> SKX_EXT_B_BGA1-IC,TBD   I172 @BASEBOARD_FAB2_LIB.BASEBOARD_FAB2(SCH_1):PAGE25
  J4G3   91 ODT<1> SCONN288_H44441004_PIP-SCONN,HA   I111 @BASEBOARD_FAB2_LIB.BASEBOARD_FAB2(SCH_1):PAGE47

M_C_ODT<2> @BASEBOARD_FAB2_LIB.BASEBOARD_FAB2(SCH_1):M_C_ODT(2)
  U5D1  V49 DDR2_ODT<2> SKX_EXT_B_BGA1-IC,TBD   I172 @BASEBOARD_FAB2_LIB.BASEBOARD_FAB2(SCH_1):PAGE25
  J6U2   87 ODT<0> SCONN288_H44441003_PIP-SCONN,HA   I111 @BASEBOARD_FAB2_LIB.BASEBOARD_FAB2(SCH_1):PAGE48

M_C_ODT<3> @BASEBOARD_FAB2_LIB.BASEBOARD_FAB2(SCH_1):M_C_ODT(3)
  U5D1 AB47 DDR2_ODT<3> SKX_EXT_B_BGA1-IC,TBD   I172 @BASEBOARD_FAB2_LIB.BASEBOARD_FAB2(SCH_1):PAGE25
  J6U2   91 ODT<1> SCONN288_H44441003_PIP-SCONN,HA   I111 @BASEBOARD_FAB2_LIB.BASEBOARD_FAB2(SCH_1):PAGE48

M_C_PAR @BASEBOARD_FAB2_LIB.BASEBOARD_FAB2(SCH_1):M_C_PAR
  U5D1  V53 DDR2_PAR SKX_EXT_B_BGA1-IC,TBD   I172 @BASEBOARD_FAB2_LIB.BASEBOARD_FAB2(SCH_1):PAGE25
  J4G3  222    PAR SCONN288_H44441004_PIP-SCONN,HA   I111 @BASEBOARD_FAB2_LIB.BASEBOARD_FAB2(SCH_1):PAGE47
  J6U2  222    PAR SCONN288_H44441003_PIP-SCONN,HA   I111 @BASEBOARD_FAB2_LIB.BASEBOARD_FAB2(SCH_1):PAGE48

M_C_VREF @BASEBOARD_FAB2_LIB.BASEBOARD_FAB2(SCH_1):M_C_VREF
  J4G3  146 VREFCA SCONN288_H44441004_PIP-SCONN,HA   I111 @BASEBOARD_FAB2_LIB.BASEBOARD_FAB2(SCH_1):PAGE47
 C4G19    1      A CAP_A_0402V-0.01UF,25V,10%,X7RA   I188 @BASEBOARD_FAB2_LIB.BASEBOARD_FAB2(SCH_1):PAGE47
  J6U2  146 VREFCA SCONN288_H44441003_PIP-SCONN,HA   I111 @BASEBOARD_FAB2_LIB.BASEBOARD_FAB2(SCH_1):PAGE48
 C6U17    1      A CAP_A_0402V-0.01UF,25V,10%,X7RA   I176 @BASEBOARD_FAB2_LIB.BASEBOARD_FAB2(SCH_1):PAGE48
 R4G21    2      B RES_0402-1.00K,1%,1/16W,CHIP,GA    I46 @BASEBOARD_FAB2_LIB.BASEBOARD_FAB2(SCH_1):PAGE98
 R4G22    1      A RES_0402-1.00K,1%,1/16W,CHIP,GA    I48 @BASEBOARD_FAB2_LIB.BASEBOARD_FAB2(SCH_1):PAGE98
 R4G20    2      B RES_0402-2,1.0%,1/16W,CHIP,G21A    I50 @BASEBOARD_FAB2_LIB.BASEBOARD_FAB2(SCH_1):PAGE98

M_DEF_RST_N @BASEBOARD_FAB2_LIB.BASEBOARD_FAB2(SCH_1):M_DEF_RST_N
  U5D1 DV63 DDR345_RESET_N SKX_EXT_B_BGA1-IC,TBD   I259 @BASEBOARD_FAB2_LIB.BASEBOARD_FAB2(SCH_1):PAGE21
  J4B1   58 RESET_N SCONN288_H44441004_PIP-SCONN,HA   I111 @BASEBOARD_FAB2_LIB.BASEBOARD_FAB2(SCH_1):PAGE49
  J6M1   58 RESET_N SCONN288_H44441003_PIP-SCONN,HA   I158 @BASEBOARD_FAB2_LIB.BASEBOARD_FAB2(SCH_1):PAGE50
  J4A2   58 RESET_N SCONN288_H44441004_PIP-SCONN,HA   I111 @BASEBOARD_FAB2_LIB.BASEBOARD_FAB2(SCH_1):PAGE51
  J6L2   58 RESET_N SCONN288_H44441003_PIP-SCONN,HA    I12 @BASEBOARD_FAB2_LIB.BASEBOARD_FAB2(SCH_1):PAGE52
  J4A1   58 RESET_N SCONN288_H44441004_PIP-SCONN,HA   I111 @BASEBOARD_FAB2_LIB.BASEBOARD_FAB2(SCH_1):PAGE53
  J6L1   58 RESET_N SCONN288_H44441003_PIP-SCONN,HA   I111 @BASEBOARD_FAB2_LIB.BASEBOARD_FAB2(SCH_1):PAGE54

M_D_ACT_N @BASEBOARD_FAB2_LIB.BASEBOARD_FAB2(SCH_1):M_D_ACT_N
  U5D1 DW60 DDR3_ACT_N SKX_EXT_B_BGA1-IC,TBD   I172 @BASEBOARD_FAB2_LIB.BASEBOARD_FAB2(SCH_1):PAGE26
  J4B1   62  ACT_N SCONN288_H44441004_PIP-SCONN,HA   I111 @BASEBOARD_FAB2_LIB.BASEBOARD_FAB2(SCH_1):PAGE49
  J6M1   62  ACT_N SCONN288_H44441003_PIP-SCONN,HA   I158 @BASEBOARD_FAB2_LIB.BASEBOARD_FAB2(SCH_1):PAGE50

M_D_ALERT_N @BASEBOARD_FAB2_LIB.BASEBOARD_FAB2(SCH_1):M_D_ALERT_N
  U5D1 ED63 DDR3_ALERT_N SKX_EXT_B_BGA1-IC,TBD   I172 @BASEBOARD_FAB2_LIB.BASEBOARD_FAB2(SCH_1):PAGE26
  J4B1  208 ALERT_N SCONN288_H44441004_PIP-SCONN,HA   I111 @BASEBOARD_FAB2_LIB.BASEBOARD_FAB2(SCH_1):PAGE49
  J6M1  208 ALERT_N SCONN288_H44441003_PIP-SCONN,HA   I158 @BASEBOARD_FAB2_LIB.BASEBOARD_FAB2(SCH_1):PAGE50

M_D_BA<0> @BASEBOARD_FAB2_LIB.BASEBOARD_FAB2(SCH_1):M_D_BA(0)
  U5D1 EE52 DDR3_BA<0> SKX_EXT_B_BGA1-IC,TBD   I172 @BASEBOARD_FAB2_LIB.BASEBOARD_FAB2(SCH_1):PAGE26
  J4B1   81  BA<0> SCONN288_H44441004_PIP-SCONN,HA   I111 @BASEBOARD_FAB2_LIB.BASEBOARD_FAB2(SCH_1):PAGE49
  J6M1   81  BA<0> SCONN288_H44441003_PIP-SCONN,HA   I158 @BASEBOARD_FAB2_LIB.BASEBOARD_FAB2(SCH_1):PAGE50

M_D_BA<1> @BASEBOARD_FAB2_LIB.BASEBOARD_FAB2(SCH_1):M_D_BA(1)
  U5D1 EA54 DDR3_BA<1> SKX_EXT_B_BGA1-IC,TBD   I172 @BASEBOARD_FAB2_LIB.BASEBOARD_FAB2(SCH_1):PAGE26
  J4B1  224  BA<1> SCONN288_H44441004_PIP-SCONN,HA   I111 @BASEBOARD_FAB2_LIB.BASEBOARD_FAB2(SCH_1):PAGE49
  J6M1  224  BA<1> SCONN288_H44441003_PIP-SCONN,HA   I158 @BASEBOARD_FAB2_LIB.BASEBOARD_FAB2(SCH_1):PAGE50

M_D_BG<0> @BASEBOARD_FAB2_LIB.BASEBOARD_FAB2(SCH_1):M_D_BG(0)
  U5D1 ED61 DDR3_BG<0> SKX_EXT_B_BGA1-IC,TBD   I172 @BASEBOARD_FAB2_LIB.BASEBOARD_FAB2(SCH_1):PAGE26
  J4B1   63  BG<0> SCONN288_H44441004_PIP-SCONN,HA   I111 @BASEBOARD_FAB2_LIB.BASEBOARD_FAB2(SCH_1):PAGE49
  J6M1   63  BG<0> SCONN288_H44441003_PIP-SCONN,HA   I158 @BASEBOARD_FAB2_LIB.BASEBOARD_FAB2(SCH_1):PAGE50

M_D_BG<1> @BASEBOARD_FAB2_LIB.BASEBOARD_FAB2(SCH_1):M_D_BG(1)
  U5D1 DW62 DDR3_BG<1> SKX_EXT_B_BGA1-IC,TBD   I172 @BASEBOARD_FAB2_LIB.BASEBOARD_FAB2(SCH_1):PAGE26
  J4B1  207  BG<1> SCONN288_H44441004_PIP-SCONN,HA   I111 @BASEBOARD_FAB2_LIB.BASEBOARD_FAB2(SCH_1):PAGE49
  J6M1  207  BG<1> SCONN288_H44441003_PIP-SCONN,HA   I158 @BASEBOARD_FAB2_LIB.BASEBOARD_FAB2(SCH_1):PAGE50

M_D_C<2> @BASEBOARD_FAB2_LIB.BASEBOARD_FAB2(SCH_1):M_D_C(2)
  U5D1 DV47 DDR3_CID<2> SKX_EXT_B_BGA1-IC,TBD   I172 @BASEBOARD_FAB2_LIB.BASEBOARD_FAB2(SCH_1):PAGE26
  J4B1  235   C<2> SCONN288_H44441004_PIP-SCONN,HA   I111 @BASEBOARD_FAB2_LIB.BASEBOARD_FAB2(SCH_1):PAGE49
  J6M1  235   C<2> SCONN288_H44441003_PIP-SCONN,HA   I158 @BASEBOARD_FAB2_LIB.BASEBOARD_FAB2(SCH_1):PAGE50

M_D_CKE<0> @BASEBOARD_FAB2_LIB.BASEBOARD_FAB2(SCH_1):M_D_CKE(0)
  U5D1 EE62 DDR3_CKE<0> SKX_EXT_B_BGA1-IC,TBD   I172 @BASEBOARD_FAB2_LIB.BASEBOARD_FAB2(SCH_1):PAGE26
  J4B1   60 CKE<0> SCONN288_H44441004_PIP-SCONN,HA   I111 @BASEBOARD_FAB2_LIB.BASEBOARD_FAB2(SCH_1):PAGE49

M_D_CKE<1> @BASEBOARD_FAB2_LIB.BASEBOARD_FAB2(SCH_1):M_D_CKE(1)
  U5D1 EF63 DDR3_CKE<1> SKX_EXT_B_BGA1-IC,TBD   I172 @BASEBOARD_FAB2_LIB.BASEBOARD_FAB2(SCH_1):PAGE26
  J4B1  203 CKE<1> SCONN288_H44441004_PIP-SCONN,HA   I111 @BASEBOARD_FAB2_LIB.BASEBOARD_FAB2(SCH_1):PAGE49

M_D_CKE<2> @BASEBOARD_FAB2_LIB.BASEBOARD_FAB2(SCH_1):M_D_CKE(2)
  U5D1 EA62 DDR3_CKE<2> SKX_EXT_B_BGA1-IC,TBD   I172 @BASEBOARD_FAB2_LIB.BASEBOARD_FAB2(SCH_1):PAGE26
  J6M1   60 CKE<0> SCONN288_H44441003_PIP-SCONN,HA   I158 @BASEBOARD_FAB2_LIB.BASEBOARD_FAB2(SCH_1):PAGE50

M_D_CKE<3> @BASEBOARD_FAB2_LIB.BASEBOARD_FAB2(SCH_1):M_D_CKE(3)
  U5D1 EB63 DDR3_CKE<3> SKX_EXT_B_BGA1-IC,TBD   I172 @BASEBOARD_FAB2_LIB.BASEBOARD_FAB2(SCH_1):PAGE26
  J6M1  203 CKE<1> SCONN288_H44441003_PIP-SCONN,HA   I158 @BASEBOARD_FAB2_LIB.BASEBOARD_FAB2(SCH_1):PAGE50

M_D_CLK_DN<0> @BASEBOARD_FAB2_LIB.BASEBOARD_FAB2(SCH_1):M_D_CLK_DN(0)
  U5D1 ED55 DDR3_CLK_DN<0> SKX_EXT_B_BGA1-IC,TBD   I172 @BASEBOARD_FAB2_LIB.BASEBOARD_FAB2(SCH_1):PAGE26
  J4B1   75   CK0N SCONN288_H44441004_PIP-SCONN,HA   I111 @BASEBOARD_FAB2_LIB.BASEBOARD_FAB2(SCH_1):PAGE49

M_D_CLK_DN<1> @BASEBOARD_FAB2_LIB.BASEBOARD_FAB2(SCH_1):M_D_CLK_DN(1)
  U5D1 EF55 DDR3_CLK_DN<1> SKX_EXT_B_BGA1-IC,TBD   I172 @BASEBOARD_FAB2_LIB.BASEBOARD_FAB2(SCH_1):PAGE26
  J4B1  219   CK1N SCONN288_H44441004_PIP-SCONN,HA   I111 @BASEBOARD_FAB2_LIB.BASEBOARD_FAB2(SCH_1):PAGE49

M_D_CLK_DN<2> @BASEBOARD_FAB2_LIB.BASEBOARD_FAB2(SCH_1):M_D_CLK_DN(2)
  U5D1 DW56 DDR3_CLK_DN<2> SKX_EXT_B_BGA1-IC,TBD   I172 @BASEBOARD_FAB2_LIB.BASEBOARD_FAB2(SCH_1):PAGE26
  J6M1   75   CK0N SCONN288_H44441003_PIP-SCONN,HA   I158 @BASEBOARD_FAB2_LIB.BASEBOARD_FAB2(SCH_1):PAGE50

M_D_CLK_DN<3> @BASEBOARD_FAB2_LIB.BASEBOARD_FAB2(SCH_1):M_D_CLK_DN(3)
  U5D1 EF57 DDR3_CLK_DN<3> SKX_EXT_B_BGA1-IC,TBD   I172 @BASEBOARD_FAB2_LIB.BASEBOARD_FAB2(SCH_1):PAGE26
  J6M1  219   CK1N SCONN288_H44441003_PIP-SCONN,HA   I158 @BASEBOARD_FAB2_LIB.BASEBOARD_FAB2(SCH_1):PAGE50

M_D_CLK_DP<0> @BASEBOARD_FAB2_LIB.BASEBOARD_FAB2(SCH_1):M_D_CLK_DP(0)
  U5D1 EB55 DDR3_CLK_DP<0> SKX_EXT_B_BGA1-IC,TBD   I172 @BASEBOARD_FAB2_LIB.BASEBOARD_FAB2(SCH_1):PAGE26
  J4B1   74   CK0P SCONN288_H44441004_PIP-SCONN,HA   I111 @BASEBOARD_FAB2_LIB.BASEBOARD_FAB2(SCH_1):PAGE49

M_D_CLK_DP<1> @BASEBOARD_FAB2_LIB.BASEBOARD_FAB2(SCH_1):M_D_CLK_DP(1)
  U5D1 EE54 DDR3_CLK_DP<1> SKX_EXT_B_BGA1-IC,TBD   I172 @BASEBOARD_FAB2_LIB.BASEBOARD_FAB2(SCH_1):PAGE26
  J4B1  218   CK1P SCONN288_H44441004_PIP-SCONN,HA   I111 @BASEBOARD_FAB2_LIB.BASEBOARD_FAB2(SCH_1):PAGE49

M_D_CLK_DP<2> @BASEBOARD_FAB2_LIB.BASEBOARD_FAB2(SCH_1):M_D_CLK_DP(2)
  U5D1 EA56 DDR3_CLK_DP<2> SKX_EXT_B_BGA1-IC,TBD   I172 @BASEBOARD_FAB2_LIB.BASEBOARD_FAB2(SCH_1):PAGE26
  J6M1   74   CK0P SCONN288_H44441003_PIP-SCONN,HA   I158 @BASEBOARD_FAB2_LIB.BASEBOARD_FAB2(SCH_1):PAGE50

M_D_CLK_DP<3> @BASEBOARD_FAB2_LIB.BASEBOARD_FAB2(SCH_1):M_D_CLK_DP(3)
  U5D1 EE56 DDR3_CLK_DP<3> SKX_EXT_B_BGA1-IC,TBD   I172 @BASEBOARD_FAB2_LIB.BASEBOARD_FAB2(SCH_1):PAGE26
  J6M1  218   CK1P SCONN288_H44441003_PIP-SCONN,HA   I158 @BASEBOARD_FAB2_LIB.BASEBOARD_FAB2(SCH_1):PAGE50

M_D_CPU_VREF @BASEBOARD_FAB2_LIB.BASEBOARD_FAB2(SCH_1):M_D_CPU_VREF
  U5D1 CP61 DDR3_CAVREF SKX_EXT_B_BGA1-IC,TBD   I259 @BASEBOARD_FAB2_LIB.BASEBOARD_FAB2(SCH_1):PAGE21
  R6M2    1      A RES_0402-2,1.0%,1/16W,CHIP,G21A    I14 @BASEBOARD_FAB2_LIB.BASEBOARD_FAB2(SCH_1):PAGE98
  C6M2    1      A CAP_A_0402V-0.01UF,25V,10%,X7RA    I33 @BASEBOARD_FAB2_LIB.BASEBOARD_FAB2(SCH_1):PAGE98

M_D_CS_N<0> @BASEBOARD_FAB2_LIB.BASEBOARD_FAB2(SCH_1):M_D_CS_N(0)
  U5D1 EF51 DDR3_CS_N<0> SKX_EXT_B_BGA1-IC,TBD   I172 @BASEBOARD_FAB2_LIB.BASEBOARD_FAB2(SCH_1):PAGE26
  J4B1   84   S0_N SCONN288_H44441004_PIP-SCONN,HA   I111 @BASEBOARD_FAB2_LIB.BASEBOARD_FAB2(SCH_1):PAGE49

M_D_CS_N<1> @BASEBOARD_FAB2_LIB.BASEBOARD_FAB2(SCH_1):M_D_CS_N(1)
  U5D1 ED49 DDR3_CS_N<1> SKX_EXT_B_BGA1-IC,TBD   I172 @BASEBOARD_FAB2_LIB.BASEBOARD_FAB2(SCH_1):PAGE26
  J4B1   89   S1_N SCONN288_H44441004_PIP-SCONN,HA   I111 @BASEBOARD_FAB2_LIB.BASEBOARD_FAB2(SCH_1):PAGE49

M_D_CS_N<2> @BASEBOARD_FAB2_LIB.BASEBOARD_FAB2(SCH_1):M_D_CS_N(2)
  U5D1 ED47 DDR3_CS_N<2> SKX_EXT_B_BGA1-IC,TBD   I172 @BASEBOARD_FAB2_LIB.BASEBOARD_FAB2(SCH_1):PAGE26
  J4B1   93 S2_N_C<0> SCONN288_H44441004_PIP-SCONN,HA   I111 @BASEBOARD_FAB2_LIB.BASEBOARD_FAB2(SCH_1):PAGE49

M_D_CS_N<3> @BASEBOARD_FAB2_LIB.BASEBOARD_FAB2(SCH_1):M_D_CS_N(3)
  U5D1 EB47 DDR3_CS_N<3> SKX_EXT_B_BGA1-IC,TBD   I172 @BASEBOARD_FAB2_LIB.BASEBOARD_FAB2(SCH_1):PAGE26
  J4B1  237 S3_N_C<1> SCONN288_H44441004_PIP-SCONN,HA   I111 @BASEBOARD_FAB2_LIB.BASEBOARD_FAB2(SCH_1):PAGE49

M_D_CS_N<4> @BASEBOARD_FAB2_LIB.BASEBOARD_FAB2(SCH_1):M_D_CS_N(4)
  U5D1 EB51 DDR3_CS_N<4> SKX_EXT_B_BGA1-IC,TBD   I172 @BASEBOARD_FAB2_LIB.BASEBOARD_FAB2(SCH_1):PAGE26
  J6M1   84   S0_N SCONN288_H44441003_PIP-SCONN,HA   I158 @BASEBOARD_FAB2_LIB.BASEBOARD_FAB2(SCH_1):PAGE50

M_D_CS_N<5> @BASEBOARD_FAB2_LIB.BASEBOARD_FAB2(SCH_1):M_D_CS_N(5)
  U5D1 EB49 DDR3_CS_N<5> SKX_EXT_B_BGA1-IC,TBD   I172 @BASEBOARD_FAB2_LIB.BASEBOARD_FAB2(SCH_1):PAGE26
  J6M1   89   S1_N SCONN288_H44441003_PIP-SCONN,HA   I158 @BASEBOARD_FAB2_LIB.BASEBOARD_FAB2(SCH_1):PAGE50

M_D_CS_N<6> @BASEBOARD_FAB2_LIB.BASEBOARD_FAB2(SCH_1):M_D_CS_N(6)
  U5D1 DV45 DDR3_CS_N<6> SKX_EXT_B_BGA1-IC,TBD   I172 @BASEBOARD_FAB2_LIB.BASEBOARD_FAB2(SCH_1):PAGE26
  J6M1   93 S2_N_C<0> SCONN288_H44441003_PIP-SCONN,HA   I158 @BASEBOARD_FAB2_LIB.BASEBOARD_FAB2(SCH_1):PAGE50

M_D_CS_N<7> @BASEBOARD_FAB2_LIB.BASEBOARD_FAB2(SCH_1):M_D_CS_N(7)
  U5D1 EB45 DDR3_CS_N<7> SKX_EXT_B_BGA1-IC,TBD   I172 @BASEBOARD_FAB2_LIB.BASEBOARD_FAB2(SCH_1):PAGE26
  J6M1  237 S3_N_C<1> SCONN288_H44441003_PIP-SCONN,HA   I158 @BASEBOARD_FAB2_LIB.BASEBOARD_FAB2(SCH_1):PAGE50

M_D_DQ<0> @BASEBOARD_FAB2_LIB.BASEBOARD_FAB2(SCH_1):M_D_DQ(0)
  U5D1 CN84 DDR3_DQ<0> SKX_EXT_B_BGA1-IC,TBD   I172 @BASEBOARD_FAB2_LIB.BASEBOARD_FAB2(SCH_1):PAGE26
  J4B1  150  DQ<1> SCONN288_H44441004_PIP-SCONN,HA   I111 @BASEBOARD_FAB2_LIB.BASEBOARD_FAB2(SCH_1):PAGE49
  J6M1    5  DQ<0> SCONN288_H44441003_PIP-SCONN,HA   I158 @BASEBOARD_FAB2_LIB.BASEBOARD_FAB2(SCH_1):PAGE50

M_D_DQ<10> @BASEBOARD_FAB2_LIB.BASEBOARD_FAB2(SCH_1):M_D_DQ(10)
  U5D1 DV83 DDR3_DQ<10> SKX_EXT_B_BGA1-IC,TBD   I172 @BASEBOARD_FAB2_LIB.BASEBOARD_FAB2(SCH_1):PAGE26
  J4B1  168 DQ<11> SCONN288_H44441004_PIP-SCONN,HA   I111 @BASEBOARD_FAB2_LIB.BASEBOARD_FAB2(SCH_1):PAGE49
  J6M1   23 DQ<10> SCONN288_H44441003_PIP-SCONN,HA   I158 @BASEBOARD_FAB2_LIB.BASEBOARD_FAB2(SCH_1):PAGE50

M_D_DQ<11> @BASEBOARD_FAB2_LIB.BASEBOARD_FAB2(SCH_1):M_D_DQ(11)
  U5D1 DY83 DDR3_DQ<11> SKX_EXT_B_BGA1-IC,TBD   I172 @BASEBOARD_FAB2_LIB.BASEBOARD_FAB2(SCH_1):PAGE26
  J4B1   23 DQ<10> SCONN288_H44441004_PIP-SCONN,HA   I111 @BASEBOARD_FAB2_LIB.BASEBOARD_FAB2(SCH_1):PAGE49
  J6M1  168 DQ<11> SCONN288_H44441003_PIP-SCONN,HA   I158 @BASEBOARD_FAB2_LIB.BASEBOARD_FAB2(SCH_1):PAGE50

M_D_DQ<12> @BASEBOARD_FAB2_LIB.BASEBOARD_FAB2(SCH_1):M_D_DQ(12)
  U5D1 DD85 DDR3_DQ<12> SKX_EXT_B_BGA1-IC,TBD   I172 @BASEBOARD_FAB2_LIB.BASEBOARD_FAB2(SCH_1):PAGE26
  J4B1  159 DQ<13> SCONN288_H44441004_PIP-SCONN,HA   I111 @BASEBOARD_FAB2_LIB.BASEBOARD_FAB2(SCH_1):PAGE49
  J6M1   14 DQ<12> SCONN288_H44441003_PIP-SCONN,HA   I158 @BASEBOARD_FAB2_LIB.BASEBOARD_FAB2(SCH_1):PAGE50

M_D_DQ<13> @BASEBOARD_FAB2_LIB.BASEBOARD_FAB2(SCH_1):M_D_DQ(13)
  U5D1 DE84 DDR3_DQ<13> SKX_EXT_B_BGA1-IC,TBD   I172 @BASEBOARD_FAB2_LIB.BASEBOARD_FAB2(SCH_1):PAGE26
  J4B1   14 DQ<12> SCONN288_H44441004_PIP-SCONN,HA   I111 @BASEBOARD_FAB2_LIB.BASEBOARD_FAB2(SCH_1):PAGE49
  J6M1  159 DQ<13> SCONN288_H44441003_PIP-SCONN,HA   I158 @BASEBOARD_FAB2_LIB.BASEBOARD_FAB2(SCH_1):PAGE50

M_D_DQ<14> @BASEBOARD_FAB2_LIB.BASEBOARD_FAB2(SCH_1):M_D_DQ(14)
  U5D1 DR84 DDR3_DQ<14> SKX_EXT_B_BGA1-IC,TBD   I172 @BASEBOARD_FAB2_LIB.BASEBOARD_FAB2(SCH_1):PAGE26
  J4B1  166 DQ<15> SCONN288_H44441004_PIP-SCONN,HA   I111 @BASEBOARD_FAB2_LIB.BASEBOARD_FAB2(SCH_1):PAGE49
  J6M1   21 DQ<14> SCONN288_H44441003_PIP-SCONN,HA   I158 @BASEBOARD_FAB2_LIB.BASEBOARD_FAB2(SCH_1):PAGE50

M_D_DQ<15> @BASEBOARD_FAB2_LIB.BASEBOARD_FAB2(SCH_1):M_D_DQ(15)
  U5D1 DV85 DDR3_DQ<15> SKX_EXT_B_BGA1-IC,TBD   I172 @BASEBOARD_FAB2_LIB.BASEBOARD_FAB2(SCH_1):PAGE26
  J4B1   21 DQ<14> SCONN288_H44441004_PIP-SCONN,HA   I111 @BASEBOARD_FAB2_LIB.BASEBOARD_FAB2(SCH_1):PAGE49
  J6M1  166 DQ<15> SCONN288_H44441003_PIP-SCONN,HA   I158 @BASEBOARD_FAB2_LIB.BASEBOARD_FAB2(SCH_1):PAGE50

M_D_DQ<16> @BASEBOARD_FAB2_LIB.BASEBOARD_FAB2(SCH_1):M_D_DQ(16)
  U5D1 DM79 DDR3_DQ<16> SKX_EXT_B_BGA1-IC,TBD   I172 @BASEBOARD_FAB2_LIB.BASEBOARD_FAB2(SCH_1):PAGE26
  J4B1  172 DQ<17> SCONN288_H44441004_PIP-SCONN,HA   I111 @BASEBOARD_FAB2_LIB.BASEBOARD_FAB2(SCH_1):PAGE49
  J6M1   27 DQ<16> SCONN288_H44441003_PIP-SCONN,HA   I158 @BASEBOARD_FAB2_LIB.BASEBOARD_FAB2(SCH_1):PAGE50

M_D_DQ<17> @BASEBOARD_FAB2_LIB.BASEBOARD_FAB2(SCH_1):M_D_DQ(17)
  U5D1 DK81 DDR3_DQ<17> SKX_EXT_B_BGA1-IC,TBD   I172 @BASEBOARD_FAB2_LIB.BASEBOARD_FAB2(SCH_1):PAGE26
  J4B1   27 DQ<16> SCONN288_H44441004_PIP-SCONN,HA   I111 @BASEBOARD_FAB2_LIB.BASEBOARD_FAB2(SCH_1):PAGE49
  J6M1  172 DQ<17> SCONN288_H44441003_PIP-SCONN,HA   I158 @BASEBOARD_FAB2_LIB.BASEBOARD_FAB2(SCH_1):PAGE50

M_D_DQ<18> @BASEBOARD_FAB2_LIB.BASEBOARD_FAB2(SCH_1):M_D_DQ(18)
  U5D1 DT81 DDR3_DQ<18> SKX_EXT_B_BGA1-IC,TBD   I172 @BASEBOARD_FAB2_LIB.BASEBOARD_FAB2(SCH_1):PAGE26
  J4B1  179 DQ<19> SCONN288_H44441004_PIP-SCONN,HA   I111 @BASEBOARD_FAB2_LIB.BASEBOARD_FAB2(SCH_1):PAGE49
  J6M1   34 DQ<18> SCONN288_H44441003_PIP-SCONN,HA   I158 @BASEBOARD_FAB2_LIB.BASEBOARD_FAB2(SCH_1):PAGE50

M_D_DQ<19> @BASEBOARD_FAB2_LIB.BASEBOARD_FAB2(SCH_1):M_D_DQ(19)
  U5D1 DR82 DDR3_DQ<19> SKX_EXT_B_BGA1-IC,TBD   I172 @BASEBOARD_FAB2_LIB.BASEBOARD_FAB2(SCH_1):PAGE26
  J4B1   34 DQ<18> SCONN288_H44441004_PIP-SCONN,HA   I111 @BASEBOARD_FAB2_LIB.BASEBOARD_FAB2(SCH_1):PAGE49
  J6M1  179 DQ<19> SCONN288_H44441003_PIP-SCONN,HA   I158 @BASEBOARD_FAB2_LIB.BASEBOARD_FAB2(SCH_1):PAGE50

M_D_DQ<1> @BASEBOARD_FAB2_LIB.BASEBOARD_FAB2(SCH_1):M_D_DQ(1)
  U5D1 CN86 DDR3_DQ<1> SKX_EXT_B_BGA1-IC,TBD   I172 @BASEBOARD_FAB2_LIB.BASEBOARD_FAB2(SCH_1):PAGE26
  J4B1    5  DQ<0> SCONN288_H44441004_PIP-SCONN,HA   I111 @BASEBOARD_FAB2_LIB.BASEBOARD_FAB2(SCH_1):PAGE49
  J6M1  150  DQ<1> SCONN288_H44441003_PIP-SCONN,HA   I158 @BASEBOARD_FAB2_LIB.BASEBOARD_FAB2(SCH_1):PAGE50

M_D_DQ<20> @BASEBOARD_FAB2_LIB.BASEBOARD_FAB2(SCH_1):M_D_DQ(20)
  U5D1 DK79 DDR3_DQ<20> SKX_EXT_B_BGA1-IC,TBD   I172 @BASEBOARD_FAB2_LIB.BASEBOARD_FAB2(SCH_1):PAGE26
  J4B1  170 DQ<21> SCONN288_H44441004_PIP-SCONN,HA   I111 @BASEBOARD_FAB2_LIB.BASEBOARD_FAB2(SCH_1):PAGE49
  J6M1   25 DQ<20> SCONN288_H44441003_PIP-SCONN,HA   I158 @BASEBOARD_FAB2_LIB.BASEBOARD_FAB2(SCH_1):PAGE50

M_D_DQ<21> @BASEBOARD_FAB2_LIB.BASEBOARD_FAB2(SCH_1):M_D_DQ(21)
  U5D1 DJ80 DDR3_DQ<21> SKX_EXT_B_BGA1-IC,TBD   I172 @BASEBOARD_FAB2_LIB.BASEBOARD_FAB2(SCH_1):PAGE26
  J4B1   25 DQ<20> SCONN288_H44441004_PIP-SCONN,HA   I111 @BASEBOARD_FAB2_LIB.BASEBOARD_FAB2(SCH_1):PAGE49
  J6M1  170 DQ<21> SCONN288_H44441003_PIP-SCONN,HA   I158 @BASEBOARD_FAB2_LIB.BASEBOARD_FAB2(SCH_1):PAGE50

M_D_DQ<22> @BASEBOARD_FAB2_LIB.BASEBOARD_FAB2(SCH_1):M_D_DQ(22)
  U5D1 DR80 DDR3_DQ<22> SKX_EXT_B_BGA1-IC,TBD   I172 @BASEBOARD_FAB2_LIB.BASEBOARD_FAB2(SCH_1):PAGE26
  J4B1  177 DQ<23> SCONN288_H44441004_PIP-SCONN,HA   I111 @BASEBOARD_FAB2_LIB.BASEBOARD_FAB2(SCH_1):PAGE49
  J6M1   32 DQ<22> SCONN288_H44441003_PIP-SCONN,HA   I158 @BASEBOARD_FAB2_LIB.BASEBOARD_FAB2(SCH_1):PAGE50

M_D_DQ<23> @BASEBOARD_FAB2_LIB.BASEBOARD_FAB2(SCH_1):M_D_DQ(23)
  U5D1 DN82 DDR3_DQ<23> SKX_EXT_B_BGA1-IC,TBD   I172 @BASEBOARD_FAB2_LIB.BASEBOARD_FAB2(SCH_1):PAGE26
  J4B1   32 DQ<22> SCONN288_H44441004_PIP-SCONN,HA   I111 @BASEBOARD_FAB2_LIB.BASEBOARD_FAB2(SCH_1):PAGE49
  J6M1  177 DQ<23> SCONN288_H44441003_PIP-SCONN,HA   I158 @BASEBOARD_FAB2_LIB.BASEBOARD_FAB2(SCH_1):PAGE50

M_D_DQ<24> @BASEBOARD_FAB2_LIB.BASEBOARD_FAB2(SCH_1):M_D_DQ(24)
  U5D1 DN76 DDR3_DQ<24> SKX_EXT_B_BGA1-IC,TBD   I172 @BASEBOARD_FAB2_LIB.BASEBOARD_FAB2(SCH_1):PAGE26
  J4B1  183 DQ<25> SCONN288_H44441004_PIP-SCONN,HA   I111 @BASEBOARD_FAB2_LIB.BASEBOARD_FAB2(SCH_1):PAGE49
  J6M1   38 DQ<24> SCONN288_H44441003_PIP-SCONN,HA   I158 @BASEBOARD_FAB2_LIB.BASEBOARD_FAB2(SCH_1):PAGE50

M_D_DQ<25> @BASEBOARD_FAB2_LIB.BASEBOARD_FAB2(SCH_1):M_D_DQ(25)
  U5D1 DU76 DDR3_DQ<25> SKX_EXT_B_BGA1-IC,TBD   I172 @BASEBOARD_FAB2_LIB.BASEBOARD_FAB2(SCH_1):PAGE26
  J4B1   38 DQ<24> SCONN288_H44441004_PIP-SCONN,HA   I111 @BASEBOARD_FAB2_LIB.BASEBOARD_FAB2(SCH_1):PAGE49
  J6M1  183 DQ<25> SCONN288_H44441003_PIP-SCONN,HA   I158 @BASEBOARD_FAB2_LIB.BASEBOARD_FAB2(SCH_1):PAGE50

M_D_DQ<26> @BASEBOARD_FAB2_LIB.BASEBOARD_FAB2(SCH_1):M_D_DQ(26)
  U5D1 DP73 DDR3_DQ<26> SKX_EXT_B_BGA1-IC,TBD   I172 @BASEBOARD_FAB2_LIB.BASEBOARD_FAB2(SCH_1):PAGE26
  J4B1  190 DQ<27> SCONN288_H44441004_PIP-SCONN,HA   I111 @BASEBOARD_FAB2_LIB.BASEBOARD_FAB2(SCH_1):PAGE49
  J6M1   45 DQ<26> SCONN288_H44441003_PIP-SCONN,HA   I158 @BASEBOARD_FAB2_LIB.BASEBOARD_FAB2(SCH_1):PAGE50

M_D_DQ<27> @BASEBOARD_FAB2_LIB.BASEBOARD_FAB2(SCH_1):M_D_DQ(27)
  U5D1 DT73 DDR3_DQ<27> SKX_EXT_B_BGA1-IC,TBD   I172 @BASEBOARD_FAB2_LIB.BASEBOARD_FAB2(SCH_1):PAGE26
  J4B1   45 DQ<26> SCONN288_H44441004_PIP-SCONN,HA   I111 @BASEBOARD_FAB2_LIB.BASEBOARD_FAB2(SCH_1):PAGE49
  J6M1  190 DQ<27> SCONN288_H44441003_PIP-SCONN,HA   I158 @BASEBOARD_FAB2_LIB.BASEBOARD_FAB2(SCH_1):PAGE50

M_D_DQ<28> @BASEBOARD_FAB2_LIB.BASEBOARD_FAB2(SCH_1):M_D_DQ(28)
  U5D1 DP77 DDR3_DQ<28> SKX_EXT_B_BGA1-IC,TBD   I172 @BASEBOARD_FAB2_LIB.BASEBOARD_FAB2(SCH_1):PAGE26
  J4B1  181 DQ<29> SCONN288_H44441004_PIP-SCONN,HA   I111 @BASEBOARD_FAB2_LIB.BASEBOARD_FAB2(SCH_1):PAGE49
  J6M1   36 DQ<28> SCONN288_H44441003_PIP-SCONN,HA   I158 @BASEBOARD_FAB2_LIB.BASEBOARD_FAB2(SCH_1):PAGE50

M_D_DQ<29> @BASEBOARD_FAB2_LIB.BASEBOARD_FAB2(SCH_1):M_D_DQ(29)
  U5D1 DT77 DDR3_DQ<29> SKX_EXT_B_BGA1-IC,TBD   I172 @BASEBOARD_FAB2_LIB.BASEBOARD_FAB2(SCH_1):PAGE26
  J4B1   36 DQ<28> SCONN288_H44441004_PIP-SCONN,HA   I111 @BASEBOARD_FAB2_LIB.BASEBOARD_FAB2(SCH_1):PAGE49
  J6M1  181 DQ<29> SCONN288_H44441003_PIP-SCONN,HA   I158 @BASEBOARD_FAB2_LIB.BASEBOARD_FAB2(SCH_1):PAGE50

M_D_DQ<2> @BASEBOARD_FAB2_LIB.BASEBOARD_FAB2(SCH_1):M_D_DQ(2)
  U5D1 DA86 DDR3_DQ<2> SKX_EXT_B_BGA1-IC,TBD   I172 @BASEBOARD_FAB2_LIB.BASEBOARD_FAB2(SCH_1):PAGE26
  J4B1  157  DQ<3> SCONN288_H44441004_PIP-SCONN,HA   I111 @BASEBOARD_FAB2_LIB.BASEBOARD_FAB2(SCH_1):PAGE49
  J6M1   12  DQ<2> SCONN288_H44441003_PIP-SCONN,HA   I158 @BASEBOARD_FAB2_LIB.BASEBOARD_FAB2(SCH_1):PAGE50

M_D_DQ<30> @BASEBOARD_FAB2_LIB.BASEBOARD_FAB2(SCH_1):M_D_DQ(30)
  U5D1 DN74 DDR3_DQ<30> SKX_EXT_B_BGA1-IC,TBD   I172 @BASEBOARD_FAB2_LIB.BASEBOARD_FAB2(SCH_1):PAGE26
  J4B1  188 DQ<31> SCONN288_H44441004_PIP-SCONN,HA   I111 @BASEBOARD_FAB2_LIB.BASEBOARD_FAB2(SCH_1):PAGE49
  J6M1   43 DQ<30> SCONN288_H44441003_PIP-SCONN,HA   I158 @BASEBOARD_FAB2_LIB.BASEBOARD_FAB2(SCH_1):PAGE50

M_D_DQ<31> @BASEBOARD_FAB2_LIB.BASEBOARD_FAB2(SCH_1):M_D_DQ(31)
  U5D1 DU74 DDR3_DQ<31> SKX_EXT_B_BGA1-IC,TBD   I172 @BASEBOARD_FAB2_LIB.BASEBOARD_FAB2(SCH_1):PAGE26
  J4B1   43 DQ<30> SCONN288_H44441004_PIP-SCONN,HA   I111 @BASEBOARD_FAB2_LIB.BASEBOARD_FAB2(SCH_1):PAGE49
  J6M1  188 DQ<31> SCONN288_H44441003_PIP-SCONN,HA   I158 @BASEBOARD_FAB2_LIB.BASEBOARD_FAB2(SCH_1):PAGE50

M_D_DQ<32> @BASEBOARD_FAB2_LIB.BASEBOARD_FAB2(SCH_1):M_D_DQ(32)
  U5D1 EC40 DDR3_DQ<32> SKX_EXT_B_BGA1-IC,TBD   I172 @BASEBOARD_FAB2_LIB.BASEBOARD_FAB2(SCH_1):PAGE26
  J4B1  242 DQ<33> SCONN288_H44441004_PIP-SCONN,HA   I111 @BASEBOARD_FAB2_LIB.BASEBOARD_FAB2(SCH_1):PAGE49
  J6M1   97 DQ<32> SCONN288_H44441003_PIP-SCONN,HA   I158 @BASEBOARD_FAB2_LIB.BASEBOARD_FAB2(SCH_1):PAGE50

M_D_DQ<33> @BASEBOARD_FAB2_LIB.BASEBOARD_FAB2(SCH_1):M_D_DQ(33)
  U5D1 ED39 DDR3_DQ<33> SKX_EXT_B_BGA1-IC,TBD   I172 @BASEBOARD_FAB2_LIB.BASEBOARD_FAB2(SCH_1):PAGE26
  J4B1   97 DQ<32> SCONN288_H44441004_PIP-SCONN,HA   I111 @BASEBOARD_FAB2_LIB.BASEBOARD_FAB2(SCH_1):PAGE49
  J6M1  242 DQ<33> SCONN288_H44441003_PIP-SCONN,HA   I158 @BASEBOARD_FAB2_LIB.BASEBOARD_FAB2(SCH_1):PAGE50

M_D_DQ<34> @BASEBOARD_FAB2_LIB.BASEBOARD_FAB2(SCH_1):M_D_DQ(34)
  U5D1 EA36 DDR3_DQ<34> SKX_EXT_B_BGA1-IC,TBD   I172 @BASEBOARD_FAB2_LIB.BASEBOARD_FAB2(SCH_1):PAGE26
  J4B1  249 DQ<35> SCONN288_H44441004_PIP-SCONN,HA   I111 @BASEBOARD_FAB2_LIB.BASEBOARD_FAB2(SCH_1):PAGE49
  J6M1  104 DQ<34> SCONN288_H44441003_PIP-SCONN,HA   I158 @BASEBOARD_FAB2_LIB.BASEBOARD_FAB2(SCH_1):PAGE50

M_D_DQ<35> @BASEBOARD_FAB2_LIB.BASEBOARD_FAB2(SCH_1):M_D_DQ(35)
  U5D1 EC36 DDR3_DQ<35> SKX_EXT_B_BGA1-IC,TBD   I172 @BASEBOARD_FAB2_LIB.BASEBOARD_FAB2(SCH_1):PAGE26
  J4B1  104 DQ<34> SCONN288_H44441004_PIP-SCONN,HA   I111 @BASEBOARD_FAB2_LIB.BASEBOARD_FAB2(SCH_1):PAGE49
  J6M1  249 DQ<35> SCONN288_H44441003_PIP-SCONN,HA   I158 @BASEBOARD_FAB2_LIB.BASEBOARD_FAB2(SCH_1):PAGE50

M_D_DQ<36> @BASEBOARD_FAB2_LIB.BASEBOARD_FAB2(SCH_1):M_D_DQ(36)
  U5D1 DY39 DDR3_DQ<36> SKX_EXT_B_BGA1-IC,TBD   I172 @BASEBOARD_FAB2_LIB.BASEBOARD_FAB2(SCH_1):PAGE26
  J4B1  240 DQ<37> SCONN288_H44441004_PIP-SCONN,HA   I111 @BASEBOARD_FAB2_LIB.BASEBOARD_FAB2(SCH_1):PAGE49
  J6M1   95 DQ<36> SCONN288_H44441003_PIP-SCONN,HA   I158 @BASEBOARD_FAB2_LIB.BASEBOARD_FAB2(SCH_1):PAGE50

M_D_DQ<37> @BASEBOARD_FAB2_LIB.BASEBOARD_FAB2(SCH_1):M_D_DQ(37)
  U5D1 EA40 DDR3_DQ<37> SKX_EXT_B_BGA1-IC,TBD   I172 @BASEBOARD_FAB2_LIB.BASEBOARD_FAB2(SCH_1):PAGE26
  J4B1   95 DQ<36> SCONN288_H44441004_PIP-SCONN,HA   I111 @BASEBOARD_FAB2_LIB.BASEBOARD_FAB2(SCH_1):PAGE49
  J6M1  240 DQ<37> SCONN288_H44441003_PIP-SCONN,HA   I158 @BASEBOARD_FAB2_LIB.BASEBOARD_FAB2(SCH_1):PAGE50

M_D_DQ<38> @BASEBOARD_FAB2_LIB.BASEBOARD_FAB2(SCH_1):M_D_DQ(38)
  U5D1 DY37 DDR3_DQ<38> SKX_EXT_B_BGA1-IC,TBD   I172 @BASEBOARD_FAB2_LIB.BASEBOARD_FAB2(SCH_1):PAGE26
  J4B1  247 DQ<39> SCONN288_H44441004_PIP-SCONN,HA   I111 @BASEBOARD_FAB2_LIB.BASEBOARD_FAB2(SCH_1):PAGE49
  J6M1  102 DQ<38> SCONN288_H44441003_PIP-SCONN,HA   I158 @BASEBOARD_FAB2_LIB.BASEBOARD_FAB2(SCH_1):PAGE50

M_D_DQ<39> @BASEBOARD_FAB2_LIB.BASEBOARD_FAB2(SCH_1):M_D_DQ(39)
  U5D1 ED37 DDR3_DQ<39> SKX_EXT_B_BGA1-IC,TBD   I172 @BASEBOARD_FAB2_LIB.BASEBOARD_FAB2(SCH_1):PAGE26
  J4B1  102 DQ<38> SCONN288_H44441004_PIP-SCONN,HA   I111 @BASEBOARD_FAB2_LIB.BASEBOARD_FAB2(SCH_1):PAGE49
  J6M1  247 DQ<39> SCONN288_H44441003_PIP-SCONN,HA   I158 @BASEBOARD_FAB2_LIB.BASEBOARD_FAB2(SCH_1):PAGE50

M_D_DQ<3> @BASEBOARD_FAB2_LIB.BASEBOARD_FAB2(SCH_1):M_D_DQ(3)
  U5D1 DA84 DDR3_DQ<3> SKX_EXT_B_BGA1-IC,TBD   I172 @BASEBOARD_FAB2_LIB.BASEBOARD_FAB2(SCH_1):PAGE26
  J4B1   12  DQ<2> SCONN288_H44441004_PIP-SCONN,HA   I111 @BASEBOARD_FAB2_LIB.BASEBOARD_FAB2(SCH_1):PAGE49
  J6M1  157  DQ<3> SCONN288_H44441003_PIP-SCONN,HA   I158 @BASEBOARD_FAB2_LIB.BASEBOARD_FAB2(SCH_1):PAGE50

M_D_DQ<40> @BASEBOARD_FAB2_LIB.BASEBOARD_FAB2(SCH_1):M_D_DQ(40)
  U5D1 DN36 DDR3_DQ<40> SKX_EXT_B_BGA1-IC,TBD   I172 @BASEBOARD_FAB2_LIB.BASEBOARD_FAB2(SCH_1):PAGE26
  J4B1  253 DQ<41> SCONN288_H44441004_PIP-SCONN,HA   I111 @BASEBOARD_FAB2_LIB.BASEBOARD_FAB2(SCH_1):PAGE49
  J6M1  108 DQ<40> SCONN288_H44441003_PIP-SCONN,HA   I158 @BASEBOARD_FAB2_LIB.BASEBOARD_FAB2(SCH_1):PAGE50

M_D_DQ<41> @BASEBOARD_FAB2_LIB.BASEBOARD_FAB2(SCH_1):M_D_DQ(41)
  U5D1 DU36 DDR3_DQ<41> SKX_EXT_B_BGA1-IC,TBD   I172 @BASEBOARD_FAB2_LIB.BASEBOARD_FAB2(SCH_1):PAGE26
  J4B1  108 DQ<40> SCONN288_H44441004_PIP-SCONN,HA   I111 @BASEBOARD_FAB2_LIB.BASEBOARD_FAB2(SCH_1):PAGE49
  J6M1  253 DQ<41> SCONN288_H44441003_PIP-SCONN,HA   I158 @BASEBOARD_FAB2_LIB.BASEBOARD_FAB2(SCH_1):PAGE50

M_D_DQ<42> @BASEBOARD_FAB2_LIB.BASEBOARD_FAB2(SCH_1):M_D_DQ(42)
  U5D1 DP33 DDR3_DQ<42> SKX_EXT_B_BGA1-IC,TBD   I172 @BASEBOARD_FAB2_LIB.BASEBOARD_FAB2(SCH_1):PAGE26
  J4B1  260 DQ<43> SCONN288_H44441004_PIP-SCONN,HA   I111 @BASEBOARD_FAB2_LIB.BASEBOARD_FAB2(SCH_1):PAGE49
  J6M1  115 DQ<42> SCONN288_H44441003_PIP-SCONN,HA   I158 @BASEBOARD_FAB2_LIB.BASEBOARD_FAB2(SCH_1):PAGE50

M_D_DQ<43> @BASEBOARD_FAB2_LIB.BASEBOARD_FAB2(SCH_1):M_D_DQ(43)
  U5D1 DT33 DDR3_DQ<43> SKX_EXT_B_BGA1-IC,TBD   I172 @BASEBOARD_FAB2_LIB.BASEBOARD_FAB2(SCH_1):PAGE26
  J4B1  115 DQ<42> SCONN288_H44441004_PIP-SCONN,HA   I111 @BASEBOARD_FAB2_LIB.BASEBOARD_FAB2(SCH_1):PAGE49
  J6M1  260 DQ<43> SCONN288_H44441003_PIP-SCONN,HA   I158 @BASEBOARD_FAB2_LIB.BASEBOARD_FAB2(SCH_1):PAGE50

M_D_DQ<44> @BASEBOARD_FAB2_LIB.BASEBOARD_FAB2(SCH_1):M_D_DQ(44)
  U5D1 DP37 DDR3_DQ<44> SKX_EXT_B_BGA1-IC,TBD   I172 @BASEBOARD_FAB2_LIB.BASEBOARD_FAB2(SCH_1):PAGE26
  J4B1  251 DQ<45> SCONN288_H44441004_PIP-SCONN,HA   I111 @BASEBOARD_FAB2_LIB.BASEBOARD_FAB2(SCH_1):PAGE49
  J6M1  106 DQ<44> SCONN288_H44441003_PIP-SCONN,HA   I158 @BASEBOARD_FAB2_LIB.BASEBOARD_FAB2(SCH_1):PAGE50

M_D_DQ<45> @BASEBOARD_FAB2_LIB.BASEBOARD_FAB2(SCH_1):M_D_DQ(45)
  U5D1 DT37 DDR3_DQ<45> SKX_EXT_B_BGA1-IC,TBD   I172 @BASEBOARD_FAB2_LIB.BASEBOARD_FAB2(SCH_1):PAGE26
  J4B1  106 DQ<44> SCONN288_H44441004_PIP-SCONN,HA   I111 @BASEBOARD_FAB2_LIB.BASEBOARD_FAB2(SCH_1):PAGE49
  J6M1  251 DQ<45> SCONN288_H44441003_PIP-SCONN,HA   I158 @BASEBOARD_FAB2_LIB.BASEBOARD_FAB2(SCH_1):PAGE50

M_D_DQ<46> @BASEBOARD_FAB2_LIB.BASEBOARD_FAB2(SCH_1):M_D_DQ(46)
  U5D1 DN34 DDR3_DQ<46> SKX_EXT_B_BGA1-IC,TBD   I172 @BASEBOARD_FAB2_LIB.BASEBOARD_FAB2(SCH_1):PAGE26
  J4B1  258 DQ<47> SCONN288_H44441004_PIP-SCONN,HA   I111 @BASEBOARD_FAB2_LIB.BASEBOARD_FAB2(SCH_1):PAGE49
  J6M1  113 DQ<46> SCONN288_H44441003_PIP-SCONN,HA   I158 @BASEBOARD_FAB2_LIB.BASEBOARD_FAB2(SCH_1):PAGE50

M_D_DQ<47> @BASEBOARD_FAB2_LIB.BASEBOARD_FAB2(SCH_1):M_D_DQ(47)
  U5D1 DU34 DDR3_DQ<47> SKX_EXT_B_BGA1-IC,TBD   I172 @BASEBOARD_FAB2_LIB.BASEBOARD_FAB2(SCH_1):PAGE26
  J4B1  113 DQ<46> SCONN288_H44441004_PIP-SCONN,HA   I111 @BASEBOARD_FAB2_LIB.BASEBOARD_FAB2(SCH_1):PAGE49
  J6M1  258 DQ<47> SCONN288_H44441003_PIP-SCONN,HA   I158 @BASEBOARD_FAB2_LIB.BASEBOARD_FAB2(SCH_1):PAGE50

M_D_DQ<48> @BASEBOARD_FAB2_LIB.BASEBOARD_FAB2(SCH_1):M_D_DQ(48)
  U5D1 DN30 DDR3_DQ<48> SKX_EXT_B_BGA1-IC,TBD   I172 @BASEBOARD_FAB2_LIB.BASEBOARD_FAB2(SCH_1):PAGE26
  J4B1  264 DQ<49> SCONN288_H44441004_PIP-SCONN,HA   I111 @BASEBOARD_FAB2_LIB.BASEBOARD_FAB2(SCH_1):PAGE49
  J6M1  119 DQ<48> SCONN288_H44441003_PIP-SCONN,HA   I158 @BASEBOARD_FAB2_LIB.BASEBOARD_FAB2(SCH_1):PAGE50

M_D_DQ<49> @BASEBOARD_FAB2_LIB.BASEBOARD_FAB2(SCH_1):M_D_DQ(49)
  U5D1 DU30 DDR3_DQ<49> SKX_EXT_B_BGA1-IC,TBD   I172 @BASEBOARD_FAB2_LIB.BASEBOARD_FAB2(SCH_1):PAGE26
  J4B1  119 DQ<48> SCONN288_H44441004_PIP-SCONN,HA   I111 @BASEBOARD_FAB2_LIB.BASEBOARD_FAB2(SCH_1):PAGE49
  J6M1  264 DQ<49> SCONN288_H44441003_PIP-SCONN,HA   I158 @BASEBOARD_FAB2_LIB.BASEBOARD_FAB2(SCH_1):PAGE50

M_D_DQ<4> @BASEBOARD_FAB2_LIB.BASEBOARD_FAB2(SCH_1):M_D_DQ(4)
  U5D1 CL84 DDR3_DQ<4> SKX_EXT_B_BGA1-IC,TBD   I172 @BASEBOARD_FAB2_LIB.BASEBOARD_FAB2(SCH_1):PAGE26
  J4B1  148  DQ<5> SCONN288_H44441004_PIP-SCONN,HA   I111 @BASEBOARD_FAB2_LIB.BASEBOARD_FAB2(SCH_1):PAGE49
  J6M1    3  DQ<4> SCONN288_H44441003_PIP-SCONN,HA   I158 @BASEBOARD_FAB2_LIB.BASEBOARD_FAB2(SCH_1):PAGE50

M_D_DQ<50> @BASEBOARD_FAB2_LIB.BASEBOARD_FAB2(SCH_1):M_D_DQ(50)
  U5D1 DP27 DDR3_DQ<50> SKX_EXT_B_BGA1-IC,TBD   I172 @BASEBOARD_FAB2_LIB.BASEBOARD_FAB2(SCH_1):PAGE26
  J4B1  271 DQ<51> SCONN288_H44441004_PIP-SCONN,HA   I111 @BASEBOARD_FAB2_LIB.BASEBOARD_FAB2(SCH_1):PAGE49
  J6M1  126 DQ<50> SCONN288_H44441003_PIP-SCONN,HA   I158 @BASEBOARD_FAB2_LIB.BASEBOARD_FAB2(SCH_1):PAGE50

M_D_DQ<51> @BASEBOARD_FAB2_LIB.BASEBOARD_FAB2(SCH_1):M_D_DQ(51)
  U5D1 DT27 DDR3_DQ<51> SKX_EXT_B_BGA1-IC,TBD   I172 @BASEBOARD_FAB2_LIB.BASEBOARD_FAB2(SCH_1):PAGE26
  J4B1  126 DQ<50> SCONN288_H44441004_PIP-SCONN,HA   I111 @BASEBOARD_FAB2_LIB.BASEBOARD_FAB2(SCH_1):PAGE49
  J6M1  271 DQ<51> SCONN288_H44441003_PIP-SCONN,HA   I158 @BASEBOARD_FAB2_LIB.BASEBOARD_FAB2(SCH_1):PAGE50

M_D_DQ<52> @BASEBOARD_FAB2_LIB.BASEBOARD_FAB2(SCH_1):M_D_DQ(52)
  U5D1 DP31 DDR3_DQ<52> SKX_EXT_B_BGA1-IC,TBD   I172 @BASEBOARD_FAB2_LIB.BASEBOARD_FAB2(SCH_1):PAGE26
  J4B1  262 DQ<53> SCONN288_H44441004_PIP-SCONN,HA   I111 @BASEBOARD_FAB2_LIB.BASEBOARD_FAB2(SCH_1):PAGE49
  J6M1  117 DQ<52> SCONN288_H44441003_PIP-SCONN,HA   I158 @BASEBOARD_FAB2_LIB.BASEBOARD_FAB2(SCH_1):PAGE50

M_D_DQ<53> @BASEBOARD_FAB2_LIB.BASEBOARD_FAB2(SCH_1):M_D_DQ(53)
  U5D1 DT31 DDR3_DQ<53> SKX_EXT_B_BGA1-IC,TBD   I172 @BASEBOARD_FAB2_LIB.BASEBOARD_FAB2(SCH_1):PAGE26
  J4B1  117 DQ<52> SCONN288_H44441004_PIP-SCONN,HA   I111 @BASEBOARD_FAB2_LIB.BASEBOARD_FAB2(SCH_1):PAGE49
  J6M1  262 DQ<53> SCONN288_H44441003_PIP-SCONN,HA   I158 @BASEBOARD_FAB2_LIB.BASEBOARD_FAB2(SCH_1):PAGE50

M_D_DQ<54> @BASEBOARD_FAB2_LIB.BASEBOARD_FAB2(SCH_1):M_D_DQ(54)
  U5D1 DN28 DDR3_DQ<54> SKX_EXT_B_BGA1-IC,TBD   I172 @BASEBOARD_FAB2_LIB.BASEBOARD_FAB2(SCH_1):PAGE26
  J4B1  269 DQ<55> SCONN288_H44441004_PIP-SCONN,HA   I111 @BASEBOARD_FAB2_LIB.BASEBOARD_FAB2(SCH_1):PAGE49
  J6M1  124 DQ<54> SCONN288_H44441003_PIP-SCONN,HA   I158 @BASEBOARD_FAB2_LIB.BASEBOARD_FAB2(SCH_1):PAGE50

M_D_DQ<55> @BASEBOARD_FAB2_LIB.BASEBOARD_FAB2(SCH_1):M_D_DQ(55)
  U5D1 DU28 DDR3_DQ<55> SKX_EXT_B_BGA1-IC,TBD   I172 @BASEBOARD_FAB2_LIB.BASEBOARD_FAB2(SCH_1):PAGE26
  J4B1  124 DQ<54> SCONN288_H44441004_PIP-SCONN,HA   I111 @BASEBOARD_FAB2_LIB.BASEBOARD_FAB2(SCH_1):PAGE49
  J6M1  269 DQ<55> SCONN288_H44441003_PIP-SCONN,HA   I158 @BASEBOARD_FAB2_LIB.BASEBOARD_FAB2(SCH_1):PAGE50

M_D_DQ<56> @BASEBOARD_FAB2_LIB.BASEBOARD_FAB2(SCH_1):M_D_DQ(56)
  U5D1 DN24 DDR3_DQ<56> SKX_EXT_B_BGA1-IC,TBD   I172 @BASEBOARD_FAB2_LIB.BASEBOARD_FAB2(SCH_1):PAGE26
  J4B1  275 DQ<57> SCONN288_H44441004_PIP-SCONN,HA   I111 @BASEBOARD_FAB2_LIB.BASEBOARD_FAB2(SCH_1):PAGE49
  J6M1  130 DQ<56> SCONN288_H44441003_PIP-SCONN,HA   I158 @BASEBOARD_FAB2_LIB.BASEBOARD_FAB2(SCH_1):PAGE50

M_D_DQ<57> @BASEBOARD_FAB2_LIB.BASEBOARD_FAB2(SCH_1):M_D_DQ(57)
  U5D1 DU24 DDR3_DQ<57> SKX_EXT_B_BGA1-IC,TBD   I172 @BASEBOARD_FAB2_LIB.BASEBOARD_FAB2(SCH_1):PAGE26
  J4B1  130 DQ<56> SCONN288_H44441004_PIP-SCONN,HA   I111 @BASEBOARD_FAB2_LIB.BASEBOARD_FAB2(SCH_1):PAGE49
  J6M1  275 DQ<57> SCONN288_H44441003_PIP-SCONN,HA   I158 @BASEBOARD_FAB2_LIB.BASEBOARD_FAB2(SCH_1):PAGE50

M_D_DQ<58> @BASEBOARD_FAB2_LIB.BASEBOARD_FAB2(SCH_1):M_D_DQ(58)
  U5D1 DY21 DDR3_DQ<58> SKX_EXT_B_BGA1-IC,TBD   I172 @BASEBOARD_FAB2_LIB.BASEBOARD_FAB2(SCH_1):PAGE26
  J4B1  282 DQ<59> SCONN288_H44441004_PIP-SCONN,HA   I111 @BASEBOARD_FAB2_LIB.BASEBOARD_FAB2(SCH_1):PAGE49
  J6M1  137 DQ<58> SCONN288_H44441003_PIP-SCONN,HA   I158 @BASEBOARD_FAB2_LIB.BASEBOARD_FAB2(SCH_1):PAGE50

M_D_DQ<59> @BASEBOARD_FAB2_LIB.BASEBOARD_FAB2(SCH_1):M_D_DQ(59)
  U5D1 EB21 DDR3_DQ<59> SKX_EXT_B_BGA1-IC,TBD   I172 @BASEBOARD_FAB2_LIB.BASEBOARD_FAB2(SCH_1):PAGE26
  J4B1  137 DQ<58> SCONN288_H44441004_PIP-SCONN,HA   I111 @BASEBOARD_FAB2_LIB.BASEBOARD_FAB2(SCH_1):PAGE49
  J6M1  282 DQ<59> SCONN288_H44441003_PIP-SCONN,HA   I158 @BASEBOARD_FAB2_LIB.BASEBOARD_FAB2(SCH_1):PAGE50

M_D_DQ<5> @BASEBOARD_FAB2_LIB.BASEBOARD_FAB2(SCH_1):M_D_DQ(5)
  U5D1 CL86 DDR3_DQ<5> SKX_EXT_B_BGA1-IC,TBD   I172 @BASEBOARD_FAB2_LIB.BASEBOARD_FAB2(SCH_1):PAGE26
  J4B1    3  DQ<4> SCONN288_H44441004_PIP-SCONN,HA   I111 @BASEBOARD_FAB2_LIB.BASEBOARD_FAB2(SCH_1):PAGE49
  J6M1  148  DQ<5> SCONN288_H44441003_PIP-SCONN,HA   I158 @BASEBOARD_FAB2_LIB.BASEBOARD_FAB2(SCH_1):PAGE50

M_D_DQ<60> @BASEBOARD_FAB2_LIB.BASEBOARD_FAB2(SCH_1):M_D_DQ(60)
  U5D1 DP25 DDR3_DQ<60> SKX_EXT_B_BGA1-IC,TBD   I172 @BASEBOARD_FAB2_LIB.BASEBOARD_FAB2(SCH_1):PAGE26
  J4B1  273 DQ<61> SCONN288_H44441004_PIP-SCONN,HA   I111 @BASEBOARD_FAB2_LIB.BASEBOARD_FAB2(SCH_1):PAGE49
  J6M1  128 DQ<60> SCONN288_H44441003_PIP-SCONN,HA   I158 @BASEBOARD_FAB2_LIB.BASEBOARD_FAB2(SCH_1):PAGE50

M_D_DQ<61> @BASEBOARD_FAB2_LIB.BASEBOARD_FAB2(SCH_1):M_D_DQ(61)
  U5D1 DT25 DDR3_DQ<61> SKX_EXT_B_BGA1-IC,TBD   I172 @BASEBOARD_FAB2_LIB.BASEBOARD_FAB2(SCH_1):PAGE26
  J4B1  128 DQ<60> SCONN288_H44441004_PIP-SCONN,HA   I111 @BASEBOARD_FAB2_LIB.BASEBOARD_FAB2(SCH_1):PAGE49
  J6M1  273 DQ<61> SCONN288_H44441003_PIP-SCONN,HA   I158 @BASEBOARD_FAB2_LIB.BASEBOARD_FAB2(SCH_1):PAGE50

M_D_DQ<62> @BASEBOARD_FAB2_LIB.BASEBOARD_FAB2(SCH_1):M_D_DQ(62)
  U5D1 EC22 DDR3_DQ<62> SKX_EXT_B_BGA1-IC,TBD   I172 @BASEBOARD_FAB2_LIB.BASEBOARD_FAB2(SCH_1):PAGE26
  J4B1  280 DQ<63> SCONN288_H44441004_PIP-SCONN,HA   I111 @BASEBOARD_FAB2_LIB.BASEBOARD_FAB2(SCH_1):PAGE49
  J6M1  135 DQ<62> SCONN288_H44441003_PIP-SCONN,HA   I158 @BASEBOARD_FAB2_LIB.BASEBOARD_FAB2(SCH_1):PAGE50

M_D_DQ<63> @BASEBOARD_FAB2_LIB.BASEBOARD_FAB2(SCH_1):M_D_DQ(63)
  U5D1 DW22 DDR3_DQ<63> SKX_EXT_B_BGA1-IC,TBD   I172 @BASEBOARD_FAB2_LIB.BASEBOARD_FAB2(SCH_1):PAGE26
  J4B1  135 DQ<62> SCONN288_H44441004_PIP-SCONN,HA   I111 @BASEBOARD_FAB2_LIB.BASEBOARD_FAB2(SCH_1):PAGE49
  J6M1  280 DQ<63> SCONN288_H44441003_PIP-SCONN,HA   I158 @BASEBOARD_FAB2_LIB.BASEBOARD_FAB2(SCH_1):PAGE50

M_D_DQ<6> @BASEBOARD_FAB2_LIB.BASEBOARD_FAB2(SCH_1):M_D_DQ(6)
  U5D1 CW86 DDR3_DQ<6> SKX_EXT_B_BGA1-IC,TBD   I172 @BASEBOARD_FAB2_LIB.BASEBOARD_FAB2(SCH_1):PAGE26
  J4B1  155  DQ<7> SCONN288_H44441004_PIP-SCONN,HA   I111 @BASEBOARD_FAB2_LIB.BASEBOARD_FAB2(SCH_1):PAGE49
  J6M1   10  DQ<6> SCONN288_H44441003_PIP-SCONN,HA   I158 @BASEBOARD_FAB2_LIB.BASEBOARD_FAB2(SCH_1):PAGE50

M_D_DQ<7> @BASEBOARD_FAB2_LIB.BASEBOARD_FAB2(SCH_1):M_D_DQ(7)
  U5D1 CW84 DDR3_DQ<7> SKX_EXT_B_BGA1-IC,TBD   I172 @BASEBOARD_FAB2_LIB.BASEBOARD_FAB2(SCH_1):PAGE26
  J4B1   10  DQ<6> SCONN288_H44441004_PIP-SCONN,HA   I111 @BASEBOARD_FAB2_LIB.BASEBOARD_FAB2(SCH_1):PAGE49
  J6M1  155  DQ<7> SCONN288_H44441003_PIP-SCONN,HA   I158 @BASEBOARD_FAB2_LIB.BASEBOARD_FAB2(SCH_1):PAGE50

M_D_DQ<8> @BASEBOARD_FAB2_LIB.BASEBOARD_FAB2(SCH_1):M_D_DQ(8)
  U5D1 DG84 DDR3_DQ<8> SKX_EXT_B_BGA1-IC,TBD   I172 @BASEBOARD_FAB2_LIB.BASEBOARD_FAB2(SCH_1):PAGE26
  J4B1  161  DQ<9> SCONN288_H44441004_PIP-SCONN,HA   I111 @BASEBOARD_FAB2_LIB.BASEBOARD_FAB2(SCH_1):PAGE49
  J6M1   16  DQ<8> SCONN288_H44441003_PIP-SCONN,HA   I158 @BASEBOARD_FAB2_LIB.BASEBOARD_FAB2(SCH_1):PAGE50

M_D_DQ<9> @BASEBOARD_FAB2_LIB.BASEBOARD_FAB2(SCH_1):M_D_DQ(9)
  U5D1 DH85 DDR3_DQ<9> SKX_EXT_B_BGA1-IC,TBD   I172 @BASEBOARD_FAB2_LIB.BASEBOARD_FAB2(SCH_1):PAGE26
  J4B1   16  DQ<8> SCONN288_H44441004_PIP-SCONN,HA   I111 @BASEBOARD_FAB2_LIB.BASEBOARD_FAB2(SCH_1):PAGE49
  J6M1  161  DQ<9> SCONN288_H44441003_PIP-SCONN,HA   I158 @BASEBOARD_FAB2_LIB.BASEBOARD_FAB2(SCH_1):PAGE50

M_D_DQS_DN<0> @BASEBOARD_FAB2_LIB.BASEBOARD_FAB2(SCH_1):M_D_DQS_DN(0)
  U5D1 CU84 DDR3_DQS_DN<0> SKX_EXT_B_BGA1-IC,TBD   I172 @BASEBOARD_FAB2_LIB.BASEBOARD_FAB2(SCH_1):PAGE26
  J4B1  152  DQS0N SCONN288_H44441004_PIP-SCONN,HA    I66 @BASEBOARD_FAB2_LIB.BASEBOARD_FAB2(SCH_1):PAGE49
  J6M1  152  DQS0N SCONN288_H44441003_PIP-SCONN,HA    I46 @BASEBOARD_FAB2_LIB.BASEBOARD_FAB2(SCH_1):PAGE50

M_D_DQS_DN<10> @BASEBOARD_FAB2_LIB.BASEBOARD_FAB2(SCH_1):M_D_DQS_DN(10)
  U5D1 DM85 DDR3_DQS_DN<10> SKX_EXT_B_BGA1-IC,TBD   I172 @BASEBOARD_FAB2_LIB.BASEBOARD_FAB2(SCH_1):PAGE26
  J4B1   19 DQS10N SCONN288_H44441004_PIP-SCONN,HA    I66 @BASEBOARD_FAB2_LIB.BASEBOARD_FAB2(SCH_1):PAGE49
  J6M1   19 DQS10N SCONN288_H44441003_PIP-SCONN,HA    I46 @BASEBOARD_FAB2_LIB.BASEBOARD_FAB2(SCH_1):PAGE50

M_D_DQS_DN<11> @BASEBOARD_FAB2_LIB.BASEBOARD_FAB2(SCH_1):M_D_DQS_DN(11)
  U5D1 DN80 DDR3_DQS_DN<11> SKX_EXT_B_BGA1-IC,TBD   I172 @BASEBOARD_FAB2_LIB.BASEBOARD_FAB2(SCH_1):PAGE26
  J4B1   30 DQS11N SCONN288_H44441004_PIP-SCONN,HA    I66 @BASEBOARD_FAB2_LIB.BASEBOARD_FAB2(SCH_1):PAGE49
  J6M1   30 DQS11N SCONN288_H44441003_PIP-SCONN,HA    I46 @BASEBOARD_FAB2_LIB.BASEBOARD_FAB2(SCH_1):PAGE50

M_D_DQS_DN<12> @BASEBOARD_FAB2_LIB.BASEBOARD_FAB2(SCH_1):M_D_DQS_DN(12)
  U5D1 DP75 DDR3_DQS_DN<12> SKX_EXT_B_BGA1-IC,TBD   I172 @BASEBOARD_FAB2_LIB.BASEBOARD_FAB2(SCH_1):PAGE26
  J4B1   41 DQS12N SCONN288_H44441004_PIP-SCONN,HA    I66 @BASEBOARD_FAB2_LIB.BASEBOARD_FAB2(SCH_1):PAGE49
  J6M1   41 DQS12N SCONN288_H44441003_PIP-SCONN,HA    I46 @BASEBOARD_FAB2_LIB.BASEBOARD_FAB2(SCH_1):PAGE50

M_D_DQS_DN<13> @BASEBOARD_FAB2_LIB.BASEBOARD_FAB2(SCH_1):M_D_DQS_DN(13)
  U5D1 EA38 DDR3_DQS_DN<13> SKX_EXT_B_BGA1-IC,TBD   I172 @BASEBOARD_FAB2_LIB.BASEBOARD_FAB2(SCH_1):PAGE26
  J4B1  100 DQS13N SCONN288_H44441004_PIP-SCONN,HA    I66 @BASEBOARD_FAB2_LIB.BASEBOARD_FAB2(SCH_1):PAGE49
  J6M1  100 DQS13N SCONN288_H44441003_PIP-SCONN,HA    I46 @BASEBOARD_FAB2_LIB.BASEBOARD_FAB2(SCH_1):PAGE50

M_D_DQS_DN<14> @BASEBOARD_FAB2_LIB.BASEBOARD_FAB2(SCH_1):M_D_DQS_DN(14)
  U5D1 DP35 DDR3_DQS_DN<14> SKX_EXT_B_BGA1-IC,TBD   I172 @BASEBOARD_FAB2_LIB.BASEBOARD_FAB2(SCH_1):PAGE26
  J4B1  111 DQS14N SCONN288_H44441004_PIP-SCONN,HA    I66 @BASEBOARD_FAB2_LIB.BASEBOARD_FAB2(SCH_1):PAGE49
  J6M1  111 DQS14N SCONN288_H44441003_PIP-SCONN,HA    I46 @BASEBOARD_FAB2_LIB.BASEBOARD_FAB2(SCH_1):PAGE50

M_D_DQS_DN<15> @BASEBOARD_FAB2_LIB.BASEBOARD_FAB2(SCH_1):M_D_DQS_DN(15)
  U5D1 DM29 DDR3_DQS_DN<15> SKX_EXT_B_BGA1-IC,TBD   I172 @BASEBOARD_FAB2_LIB.BASEBOARD_FAB2(SCH_1):PAGE26
  J4B1  122 DQS15N SCONN288_H44441004_PIP-SCONN,HA    I66 @BASEBOARD_FAB2_LIB.BASEBOARD_FAB2(SCH_1):PAGE49
  J6M1  122 DQS15N SCONN288_H44441003_PIP-SCONN,HA    I46 @BASEBOARD_FAB2_LIB.BASEBOARD_FAB2(SCH_1):PAGE50

M_D_DQS_DN<16> @BASEBOARD_FAB2_LIB.BASEBOARD_FAB2(SCH_1):M_D_DQS_DN(16)
  U5D1 DM23 DDR3_DQS_DN<16> SKX_EXT_B_BGA1-IC,TBD   I172 @BASEBOARD_FAB2_LIB.BASEBOARD_FAB2(SCH_1):PAGE26
  J4B1  133 DQS16N SCONN288_H44441004_PIP-SCONN,HA    I66 @BASEBOARD_FAB2_LIB.BASEBOARD_FAB2(SCH_1):PAGE49
  J6M1  133 DQS16N SCONN288_H44441003_PIP-SCONN,HA    I46 @BASEBOARD_FAB2_LIB.BASEBOARD_FAB2(SCH_1):PAGE50

M_D_DQS_DN<17> @BASEBOARD_FAB2_LIB.BASEBOARD_FAB2(SCH_1):M_D_DQS_DN(17)
  U5D1 DB67 DDR3_DQS_DN<17> SKX_EXT_B_BGA1-IC,TBD   I172 @BASEBOARD_FAB2_LIB.BASEBOARD_FAB2(SCH_1):PAGE26
  J4B1   52 DQS17N SCONN288_H44441004_PIP-SCONN,HA    I66 @BASEBOARD_FAB2_LIB.BASEBOARD_FAB2(SCH_1):PAGE49
  J6M1   52 DQS17N SCONN288_H44441003_PIP-SCONN,HA    I46 @BASEBOARD_FAB2_LIB.BASEBOARD_FAB2(SCH_1):PAGE50

M_D_DQS_DN<1> @BASEBOARD_FAB2_LIB.BASEBOARD_FAB2(SCH_1):M_D_DQS_DN(1)
  U5D1 DN84 DDR3_DQS_DN<1> SKX_EXT_B_BGA1-IC,TBD   I172 @BASEBOARD_FAB2_LIB.BASEBOARD_FAB2(SCH_1):PAGE26
  J4B1  163  DQS1N SCONN288_H44441004_PIP-SCONN,HA    I66 @BASEBOARD_FAB2_LIB.BASEBOARD_FAB2(SCH_1):PAGE49
  J6M1  163  DQS1N SCONN288_H44441003_PIP-SCONN,HA    I46 @BASEBOARD_FAB2_LIB.BASEBOARD_FAB2(SCH_1):PAGE50

M_D_DQS_DN<2> @BASEBOARD_FAB2_LIB.BASEBOARD_FAB2(SCH_1):M_D_DQS_DN(2)
  U5D1 DL82 DDR3_DQS_DN<2> SKX_EXT_B_BGA1-IC,TBD   I172 @BASEBOARD_FAB2_LIB.BASEBOARD_FAB2(SCH_1):PAGE26
  J4B1  174  DQS2N SCONN288_H44441004_PIP-SCONN,HA    I66 @BASEBOARD_FAB2_LIB.BASEBOARD_FAB2(SCH_1):PAGE49
  J6M1  174  DQS2N SCONN288_H44441003_PIP-SCONN,HA    I46 @BASEBOARD_FAB2_LIB.BASEBOARD_FAB2(SCH_1):PAGE50

M_D_DQS_DN<3> @BASEBOARD_FAB2_LIB.BASEBOARD_FAB2(SCH_1):M_D_DQS_DN(3)
  U5D1 DV75 DDR3_DQS_DN<3> SKX_EXT_B_BGA1-IC,TBD   I172 @BASEBOARD_FAB2_LIB.BASEBOARD_FAB2(SCH_1):PAGE26
  J4B1  185  DQS3N SCONN288_H44441004_PIP-SCONN,HA    I66 @BASEBOARD_FAB2_LIB.BASEBOARD_FAB2(SCH_1):PAGE49
  J6M1  185  DQS3N SCONN288_H44441003_PIP-SCONN,HA    I46 @BASEBOARD_FAB2_LIB.BASEBOARD_FAB2(SCH_1):PAGE50

M_D_DQS_DN<4> @BASEBOARD_FAB2_LIB.BASEBOARD_FAB2(SCH_1):M_D_DQS_DN(4)
  U5D1 EE38 DDR3_DQS_DN<4> SKX_EXT_B_BGA1-IC,TBD   I172 @BASEBOARD_FAB2_LIB.BASEBOARD_FAB2(SCH_1):PAGE26
  J4B1  244  DQS4N SCONN288_H44441004_PIP-SCONN,HA    I66 @BASEBOARD_FAB2_LIB.BASEBOARD_FAB2(SCH_1):PAGE49
  J6M1  244  DQS4N SCONN288_H44441003_PIP-SCONN,HA    I46 @BASEBOARD_FAB2_LIB.BASEBOARD_FAB2(SCH_1):PAGE50

M_D_DQS_DN<5> @BASEBOARD_FAB2_LIB.BASEBOARD_FAB2(SCH_1):M_D_DQS_DN(5)
  U5D1 DV35 DDR3_DQS_DN<5> SKX_EXT_B_BGA1-IC,TBD   I172 @BASEBOARD_FAB2_LIB.BASEBOARD_FAB2(SCH_1):PAGE26
  J4B1  255  DQS5N SCONN288_H44441004_PIP-SCONN,HA    I66 @BASEBOARD_FAB2_LIB.BASEBOARD_FAB2(SCH_1):PAGE49
  J6M1  255  DQS5N SCONN288_H44441003_PIP-SCONN,HA    I46 @BASEBOARD_FAB2_LIB.BASEBOARD_FAB2(SCH_1):PAGE50

M_D_DQS_DN<6> @BASEBOARD_FAB2_LIB.BASEBOARD_FAB2(SCH_1):M_D_DQS_DN(6)
  U5D1 DV29 DDR3_DQS_DN<6> SKX_EXT_B_BGA1-IC,TBD   I172 @BASEBOARD_FAB2_LIB.BASEBOARD_FAB2(SCH_1):PAGE26
  J4B1  266  DQS6N SCONN288_H44441004_PIP-SCONN,HA    I66 @BASEBOARD_FAB2_LIB.BASEBOARD_FAB2(SCH_1):PAGE49
  J6M1  266  DQS6N SCONN288_H44441003_PIP-SCONN,HA    I46 @BASEBOARD_FAB2_LIB.BASEBOARD_FAB2(SCH_1):PAGE50

M_D_DQS_DN<7> @BASEBOARD_FAB2_LIB.BASEBOARD_FAB2(SCH_1):M_D_DQS_DN(7)
  U5D1 DV23 DDR3_DQS_DN<7> SKX_EXT_B_BGA1-IC,TBD   I172 @BASEBOARD_FAB2_LIB.BASEBOARD_FAB2(SCH_1):PAGE26
  J4B1  277  DQS7N SCONN288_H44441004_PIP-SCONN,HA    I66 @BASEBOARD_FAB2_LIB.BASEBOARD_FAB2(SCH_1):PAGE49
  J6M1  277  DQS7N SCONN288_H44441003_PIP-SCONN,HA    I46 @BASEBOARD_FAB2_LIB.BASEBOARD_FAB2(SCH_1):PAGE50

M_D_DQS_DN<8> @BASEBOARD_FAB2_LIB.BASEBOARD_FAB2(SCH_1):M_D_DQS_DN(8)
  U5D1 DF67 DDR3_DQS_DN<8> SKX_EXT_B_BGA1-IC,TBD   I172 @BASEBOARD_FAB2_LIB.BASEBOARD_FAB2(SCH_1):PAGE26
  J4B1  196  DQS8N SCONN288_H44441004_PIP-SCONN,HA    I66 @BASEBOARD_FAB2_LIB.BASEBOARD_FAB2(SCH_1):PAGE49
  J6M1  196  DQS8N SCONN288_H44441003_PIP-SCONN,HA    I46 @BASEBOARD_FAB2_LIB.BASEBOARD_FAB2(SCH_1):PAGE50

M_D_DQS_DN<9> @BASEBOARD_FAB2_LIB.BASEBOARD_FAB2(SCH_1):M_D_DQS_DN(9)
  U5D1 CR84 DDR3_DQS_DN<9> SKX_EXT_B_BGA1-IC,TBD   I172 @BASEBOARD_FAB2_LIB.BASEBOARD_FAB2(SCH_1):PAGE26
  J4B1    8  DQS9N SCONN288_H44441004_PIP-SCONN,HA    I66 @BASEBOARD_FAB2_LIB.BASEBOARD_FAB2(SCH_1):PAGE49
  J6M1    8  DQS9N SCONN288_H44441003_PIP-SCONN,HA    I46 @BASEBOARD_FAB2_LIB.BASEBOARD_FAB2(SCH_1):PAGE50

M_D_DQS_DP<0> @BASEBOARD_FAB2_LIB.BASEBOARD_FAB2(SCH_1):M_D_DQS_DP(0)
  U5D1 CV85 DDR3_DQS_DP<0> SKX_EXT_B_BGA1-IC,TBD   I172 @BASEBOARD_FAB2_LIB.BASEBOARD_FAB2(SCH_1):PAGE26
  J4B1  153  DQS0P SCONN288_H44441004_PIP-SCONN,HA    I66 @BASEBOARD_FAB2_LIB.BASEBOARD_FAB2(SCH_1):PAGE49
  J6M1  153  DQS0P SCONN288_H44441003_PIP-SCONN,HA    I46 @BASEBOARD_FAB2_LIB.BASEBOARD_FAB2(SCH_1):PAGE50

M_D_DQS_DP<10> @BASEBOARD_FAB2_LIB.BASEBOARD_FAB2(SCH_1):M_D_DQS_DP(10)
  U5D1 DL84 DDR3_DQS_DP<10> SKX_EXT_B_BGA1-IC,TBD   I172 @BASEBOARD_FAB2_LIB.BASEBOARD_FAB2(SCH_1):PAGE26
  J4B1   18 DQS10P SCONN288_H44441004_PIP-SCONN,HA    I66 @BASEBOARD_FAB2_LIB.BASEBOARD_FAB2(SCH_1):PAGE49
  J6M1   18 DQS10P SCONN288_H44441003_PIP-SCONN,HA    I46 @BASEBOARD_FAB2_LIB.BASEBOARD_FAB2(SCH_1):PAGE50

M_D_DQS_DP<11> @BASEBOARD_FAB2_LIB.BASEBOARD_FAB2(SCH_1):M_D_DQS_DP(11)
  U5D1 DP79 DDR3_DQS_DP<11> SKX_EXT_B_BGA1-IC,TBD   I172 @BASEBOARD_FAB2_LIB.BASEBOARD_FAB2(SCH_1):PAGE26
  J4B1   29 DQS11P SCONN288_H44441004_PIP-SCONN,HA    I66 @BASEBOARD_FAB2_LIB.BASEBOARD_FAB2(SCH_1):PAGE49
  J6M1   29 DQS11P SCONN288_H44441003_PIP-SCONN,HA    I46 @BASEBOARD_FAB2_LIB.BASEBOARD_FAB2(SCH_1):PAGE50

M_D_DQS_DP<12> @BASEBOARD_FAB2_LIB.BASEBOARD_FAB2(SCH_1):M_D_DQS_DP(12)
  U5D1 DM75 DDR3_DQS_DP<12> SKX_EXT_B_BGA1-IC,TBD   I172 @BASEBOARD_FAB2_LIB.BASEBOARD_FAB2(SCH_1):PAGE26
  J4B1   40 DQS12P SCONN288_H44441004_PIP-SCONN,HA    I66 @BASEBOARD_FAB2_LIB.BASEBOARD_FAB2(SCH_1):PAGE49
  J6M1   40 DQS12P SCONN288_H44441003_PIP-SCONN,HA    I46 @BASEBOARD_FAB2_LIB.BASEBOARD_FAB2(SCH_1):PAGE50

M_D_DQS_DP<13> @BASEBOARD_FAB2_LIB.BASEBOARD_FAB2(SCH_1):M_D_DQS_DP(13)
  U5D1 DW38 DDR3_DQS_DP<13> SKX_EXT_B_BGA1-IC,TBD   I172 @BASEBOARD_FAB2_LIB.BASEBOARD_FAB2(SCH_1):PAGE26
  J4B1   99 DQS13P SCONN288_H44441004_PIP-SCONN,HA    I66 @BASEBOARD_FAB2_LIB.BASEBOARD_FAB2(SCH_1):PAGE49
  J6M1   99 DQS13P SCONN288_H44441003_PIP-SCONN,HA    I46 @BASEBOARD_FAB2_LIB.BASEBOARD_FAB2(SCH_1):PAGE50

M_D_DQS_DP<14> @BASEBOARD_FAB2_LIB.BASEBOARD_FAB2(SCH_1):M_D_DQS_DP(14)
  U5D1 DM35 DDR3_DQS_DP<14> SKX_EXT_B_BGA1-IC,TBD   I172 @BASEBOARD_FAB2_LIB.BASEBOARD_FAB2(SCH_1):PAGE26
  J4B1  110 DQS14P SCONN288_H44441004_PIP-SCONN,HA    I66 @BASEBOARD_FAB2_LIB.BASEBOARD_FAB2(SCH_1):PAGE49
  J6M1  110 DQS14P SCONN288_H44441003_PIP-SCONN,HA    I46 @BASEBOARD_FAB2_LIB.BASEBOARD_FAB2(SCH_1):PAGE50

M_D_DQS_DP<15> @BASEBOARD_FAB2_LIB.BASEBOARD_FAB2(SCH_1):M_D_DQS_DP(15)
  U5D1 DP29 DDR3_DQS_DP<15> SKX_EXT_B_BGA1-IC,TBD   I172 @BASEBOARD_FAB2_LIB.BASEBOARD_FAB2(SCH_1):PAGE26
  J4B1  121 DQS15P SCONN288_H44441004_PIP-SCONN,HA    I66 @BASEBOARD_FAB2_LIB.BASEBOARD_FAB2(SCH_1):PAGE49
  J6M1  121 DQS15P SCONN288_H44441003_PIP-SCONN,HA    I46 @BASEBOARD_FAB2_LIB.BASEBOARD_FAB2(SCH_1):PAGE50

M_D_DQS_DP<16> @BASEBOARD_FAB2_LIB.BASEBOARD_FAB2(SCH_1):M_D_DQS_DP(16)
  U5D1 DP23 DDR3_DQS_DP<16> SKX_EXT_B_BGA1-IC,TBD   I172 @BASEBOARD_FAB2_LIB.BASEBOARD_FAB2(SCH_1):PAGE26
  J4B1  132 DQS16P SCONN288_H44441004_PIP-SCONN,HA    I66 @BASEBOARD_FAB2_LIB.BASEBOARD_FAB2(SCH_1):PAGE49
  J6M1  132 DQS16P SCONN288_H44441003_PIP-SCONN,HA    I46 @BASEBOARD_FAB2_LIB.BASEBOARD_FAB2(SCH_1):PAGE50

M_D_DQS_DP<17> @BASEBOARD_FAB2_LIB.BASEBOARD_FAB2(SCH_1):M_D_DQS_DP(17)
  U5D1 CY67 DDR3_DQS_DP<17> SKX_EXT_B_BGA1-IC,TBD   I172 @BASEBOARD_FAB2_LIB.BASEBOARD_FAB2(SCH_1):PAGE26
  J4B1   51 DQS17P SCONN288_H44441004_PIP-SCONN,HA    I66 @BASEBOARD_FAB2_LIB.BASEBOARD_FAB2(SCH_1):PAGE49
  J6M1   51 DQS17P SCONN288_H44441003_PIP-SCONN,HA    I46 @BASEBOARD_FAB2_LIB.BASEBOARD_FAB2(SCH_1):PAGE50

M_D_DQS_DP<1> @BASEBOARD_FAB2_LIB.BASEBOARD_FAB2(SCH_1):M_D_DQS_DP(1)
  U5D1 DP85 DDR3_DQS_DP<1> SKX_EXT_B_BGA1-IC,TBD   I172 @BASEBOARD_FAB2_LIB.BASEBOARD_FAB2(SCH_1):PAGE26
  J4B1  164  DQS1P SCONN288_H44441004_PIP-SCONN,HA    I66 @BASEBOARD_FAB2_LIB.BASEBOARD_FAB2(SCH_1):PAGE49
  J6M1  164  DQS1P SCONN288_H44441003_PIP-SCONN,HA    I46 @BASEBOARD_FAB2_LIB.BASEBOARD_FAB2(SCH_1):PAGE50

M_D_DQS_DP<2> @BASEBOARD_FAB2_LIB.BASEBOARD_FAB2(SCH_1):M_D_DQS_DP(2)
  U5D1 DM81 DDR3_DQS_DP<2> SKX_EXT_B_BGA1-IC,TBD   I172 @BASEBOARD_FAB2_LIB.BASEBOARD_FAB2(SCH_1):PAGE26
  J4B1  175  DQS2P SCONN288_H44441004_PIP-SCONN,HA    I66 @BASEBOARD_FAB2_LIB.BASEBOARD_FAB2(SCH_1):PAGE49
  J6M1  175  DQS2P SCONN288_H44441003_PIP-SCONN,HA    I46 @BASEBOARD_FAB2_LIB.BASEBOARD_FAB2(SCH_1):PAGE50

M_D_DQS_DP<3> @BASEBOARD_FAB2_LIB.BASEBOARD_FAB2(SCH_1):M_D_DQS_DP(3)
  U5D1 DT75 DDR3_DQS_DP<3> SKX_EXT_B_BGA1-IC,TBD   I172 @BASEBOARD_FAB2_LIB.BASEBOARD_FAB2(SCH_1):PAGE26
  J4B1  186  DQS3P SCONN288_H44441004_PIP-SCONN,HA    I66 @BASEBOARD_FAB2_LIB.BASEBOARD_FAB2(SCH_1):PAGE49
  J6M1  186  DQS3P SCONN288_H44441003_PIP-SCONN,HA    I46 @BASEBOARD_FAB2_LIB.BASEBOARD_FAB2(SCH_1):PAGE50

M_D_DQS_DP<4> @BASEBOARD_FAB2_LIB.BASEBOARD_FAB2(SCH_1):M_D_DQS_DP(4)
  U5D1 EC38 DDR3_DQS_DP<4> SKX_EXT_B_BGA1-IC,TBD   I172 @BASEBOARD_FAB2_LIB.BASEBOARD_FAB2(SCH_1):PAGE26
  J4B1  245  DQS4P SCONN288_H44441004_PIP-SCONN,HA    I66 @BASEBOARD_FAB2_LIB.BASEBOARD_FAB2(SCH_1):PAGE49
  J6M1  245  DQS4P SCONN288_H44441003_PIP-SCONN,HA    I46 @BASEBOARD_FAB2_LIB.BASEBOARD_FAB2(SCH_1):PAGE50

M_D_DQS_DP<5> @BASEBOARD_FAB2_LIB.BASEBOARD_FAB2(SCH_1):M_D_DQS_DP(5)
  U5D1 DT35 DDR3_DQS_DP<5> SKX_EXT_B_BGA1-IC,TBD   I172 @BASEBOARD_FAB2_LIB.BASEBOARD_FAB2(SCH_1):PAGE26
  J4B1  256  DQS5P SCONN288_H44441004_PIP-SCONN,HA    I66 @BASEBOARD_FAB2_LIB.BASEBOARD_FAB2(SCH_1):PAGE49
  J6M1  256  DQS5P SCONN288_H44441003_PIP-SCONN,HA    I46 @BASEBOARD_FAB2_LIB.BASEBOARD_FAB2(SCH_1):PAGE50

M_D_DQS_DP<6> @BASEBOARD_FAB2_LIB.BASEBOARD_FAB2(SCH_1):M_D_DQS_DP(6)
  U5D1 DT29 DDR3_DQS_DP<6> SKX_EXT_B_BGA1-IC,TBD   I172 @BASEBOARD_FAB2_LIB.BASEBOARD_FAB2(SCH_1):PAGE26
  J4B1  267  DQS6P SCONN288_H44441004_PIP-SCONN,HA    I66 @BASEBOARD_FAB2_LIB.BASEBOARD_FAB2(SCH_1):PAGE49
  J6M1  267  DQS6P SCONN288_H44441003_PIP-SCONN,HA    I46 @BASEBOARD_FAB2_LIB.BASEBOARD_FAB2(SCH_1):PAGE50

M_D_DQS_DP<7> @BASEBOARD_FAB2_LIB.BASEBOARD_FAB2(SCH_1):M_D_DQS_DP(7)
  U5D1 DT23 DDR3_DQS_DP<7> SKX_EXT_B_BGA1-IC,TBD   I172 @BASEBOARD_FAB2_LIB.BASEBOARD_FAB2(SCH_1):PAGE26
  J4B1  278  DQS7P SCONN288_H44441004_PIP-SCONN,HA    I66 @BASEBOARD_FAB2_LIB.BASEBOARD_FAB2(SCH_1):PAGE49
  J6M1  278  DQS7P SCONN288_H44441003_PIP-SCONN,HA    I46 @BASEBOARD_FAB2_LIB.BASEBOARD_FAB2(SCH_1):PAGE50

M_D_DQS_DP<8> @BASEBOARD_FAB2_LIB.BASEBOARD_FAB2(SCH_1):M_D_DQS_DP(8)
  U5D1 DD67 DDR3_DQS_DP<8> SKX_EXT_B_BGA1-IC,TBD   I172 @BASEBOARD_FAB2_LIB.BASEBOARD_FAB2(SCH_1):PAGE26
  J4B1  197  DQS8P SCONN288_H44441004_PIP-SCONN,HA    I66 @BASEBOARD_FAB2_LIB.BASEBOARD_FAB2(SCH_1):PAGE49
  J6M1  197  DQS8P SCONN288_H44441003_PIP-SCONN,HA    I46 @BASEBOARD_FAB2_LIB.BASEBOARD_FAB2(SCH_1):PAGE50

M_D_DQS_DP<9> @BASEBOARD_FAB2_LIB.BASEBOARD_FAB2(SCH_1):M_D_DQS_DP(9)
  U5D1 CP85 DDR3_DQS_DP<9> SKX_EXT_B_BGA1-IC,TBD   I172 @BASEBOARD_FAB2_LIB.BASEBOARD_FAB2(SCH_1):PAGE26
  J4B1    7  DQS9P SCONN288_H44441004_PIP-SCONN,HA    I66 @BASEBOARD_FAB2_LIB.BASEBOARD_FAB2(SCH_1):PAGE49
  J6M1    7  DQS9P SCONN288_H44441003_PIP-SCONN,HA    I46 @BASEBOARD_FAB2_LIB.BASEBOARD_FAB2(SCH_1):PAGE50

M_D_ECC<0> @BASEBOARD_FAB2_LIB.BASEBOARD_FAB2(SCH_1):M_D_ECC(0)
  U5D1 DA68 DDR3_ECC<0> SKX_EXT_B_BGA1-IC,TBD   I172 @BASEBOARD_FAB2_LIB.BASEBOARD_FAB2(SCH_1):PAGE26
  J4B1  194  CB<1> SCONN288_H44441004_PIP-SCONN,HA   I111 @BASEBOARD_FAB2_LIB.BASEBOARD_FAB2(SCH_1):PAGE49
  J6M1   49  CB<0> SCONN288_H44441003_PIP-SCONN,HA   I158 @BASEBOARD_FAB2_LIB.BASEBOARD_FAB2(SCH_1):PAGE50

M_D_ECC<1> @BASEBOARD_FAB2_LIB.BASEBOARD_FAB2(SCH_1):M_D_ECC(1)
  U5D1 DE68 DDR3_ECC<1> SKX_EXT_B_BGA1-IC,TBD   I172 @BASEBOARD_FAB2_LIB.BASEBOARD_FAB2(SCH_1):PAGE26
  J4B1   49  CB<0> SCONN288_H44441004_PIP-SCONN,HA   I111 @BASEBOARD_FAB2_LIB.BASEBOARD_FAB2(SCH_1):PAGE49
  J6M1  194  CB<1> SCONN288_H44441003_PIP-SCONN,HA   I158 @BASEBOARD_FAB2_LIB.BASEBOARD_FAB2(SCH_1):PAGE50

M_D_ECC<2> @BASEBOARD_FAB2_LIB.BASEBOARD_FAB2(SCH_1):M_D_ECC(2)
  U5D1 DB65 DDR3_ECC<2> SKX_EXT_B_BGA1-IC,TBD   I172 @BASEBOARD_FAB2_LIB.BASEBOARD_FAB2(SCH_1):PAGE26
  J4B1  201  CB<3> SCONN288_H44441004_PIP-SCONN,HA   I111 @BASEBOARD_FAB2_LIB.BASEBOARD_FAB2(SCH_1):PAGE49
  J6M1   56  CB<2> SCONN288_H44441003_PIP-SCONN,HA   I158 @BASEBOARD_FAB2_LIB.BASEBOARD_FAB2(SCH_1):PAGE50

M_D_ECC<3> @BASEBOARD_FAB2_LIB.BASEBOARD_FAB2(SCH_1):M_D_ECC(3)
  U5D1 DD65 DDR3_ECC<3> SKX_EXT_B_BGA1-IC,TBD   I172 @BASEBOARD_FAB2_LIB.BASEBOARD_FAB2(SCH_1):PAGE26
  J4B1   56  CB<2> SCONN288_H44441004_PIP-SCONN,HA   I111 @BASEBOARD_FAB2_LIB.BASEBOARD_FAB2(SCH_1):PAGE49
  J6M1  201  CB<3> SCONN288_H44441003_PIP-SCONN,HA   I158 @BASEBOARD_FAB2_LIB.BASEBOARD_FAB2(SCH_1):PAGE50

M_D_ECC<4> @BASEBOARD_FAB2_LIB.BASEBOARD_FAB2(SCH_1):M_D_ECC(4)
  U5D1 DB69 DDR3_ECC<4> SKX_EXT_B_BGA1-IC,TBD   I172 @BASEBOARD_FAB2_LIB.BASEBOARD_FAB2(SCH_1):PAGE26
  J4B1  192  CB<5> SCONN288_H44441004_PIP-SCONN,HA   I111 @BASEBOARD_FAB2_LIB.BASEBOARD_FAB2(SCH_1):PAGE49
  J6M1   47  CB<4> SCONN288_H44441003_PIP-SCONN,HA   I158 @BASEBOARD_FAB2_LIB.BASEBOARD_FAB2(SCH_1):PAGE50

M_D_ECC<5> @BASEBOARD_FAB2_LIB.BASEBOARD_FAB2(SCH_1):M_D_ECC(5)
  U5D1 DD69 DDR3_ECC<5> SKX_EXT_B_BGA1-IC,TBD   I172 @BASEBOARD_FAB2_LIB.BASEBOARD_FAB2(SCH_1):PAGE26
  J4B1   47  CB<4> SCONN288_H44441004_PIP-SCONN,HA   I111 @BASEBOARD_FAB2_LIB.BASEBOARD_FAB2(SCH_1):PAGE49
  J6M1  192  CB<5> SCONN288_H44441003_PIP-SCONN,HA   I158 @BASEBOARD_FAB2_LIB.BASEBOARD_FAB2(SCH_1):PAGE50

M_D_ECC<6> @BASEBOARD_FAB2_LIB.BASEBOARD_FAB2(SCH_1):M_D_ECC(6)
  U5D1 DA66 DDR3_ECC<6> SKX_EXT_B_BGA1-IC,TBD   I172 @BASEBOARD_FAB2_LIB.BASEBOARD_FAB2(SCH_1):PAGE26
  J4B1  199  CB<7> SCONN288_H44441004_PIP-SCONN,HA   I111 @BASEBOARD_FAB2_LIB.BASEBOARD_FAB2(SCH_1):PAGE49
  J6M1   54  CB<6> SCONN288_H44441003_PIP-SCONN,HA   I158 @BASEBOARD_FAB2_LIB.BASEBOARD_FAB2(SCH_1):PAGE50

M_D_ECC<7> @BASEBOARD_FAB2_LIB.BASEBOARD_FAB2(SCH_1):M_D_ECC(7)
  U5D1 DE66 DDR3_ECC<7> SKX_EXT_B_BGA1-IC,TBD   I172 @BASEBOARD_FAB2_LIB.BASEBOARD_FAB2(SCH_1):PAGE26
  J4B1   54  CB<6> SCONN288_H44441004_PIP-SCONN,HA   I111 @BASEBOARD_FAB2_LIB.BASEBOARD_FAB2(SCH_1):PAGE49
  J6M1  199  CB<7> SCONN288_H44441003_PIP-SCONN,HA   I158 @BASEBOARD_FAB2_LIB.BASEBOARD_FAB2(SCH_1):PAGE50

M_D_MA<0> @BASEBOARD_FAB2_LIB.BASEBOARD_FAB2(SCH_1):M_D_MA(0)
  U5D1 EB53 DDR3_MA<0> SKX_EXT_B_BGA1-IC,TBD   I172 @BASEBOARD_FAB2_LIB.BASEBOARD_FAB2(SCH_1):PAGE26
  J4B1   79     A0 SCONN288_H44441004_PIP-SCONN,HA   I111 @BASEBOARD_FAB2_LIB.BASEBOARD_FAB2(SCH_1):PAGE49
  J6M1   79     A0 SCONN288_H44441003_PIP-SCONN,HA   I158 @BASEBOARD_FAB2_LIB.BASEBOARD_FAB2(SCH_1):PAGE50

M_D_MA<10> @BASEBOARD_FAB2_LIB.BASEBOARD_FAB2(SCH_1):M_D_MA(10)
  U5D1 DW54 DDR3_MA<10> SKX_EXT_B_BGA1-IC,TBD   I172 @BASEBOARD_FAB2_LIB.BASEBOARD_FAB2(SCH_1):PAGE26
  J4B1  225    A10 SCONN288_H44441004_PIP-SCONN,HA   I111 @BASEBOARD_FAB2_LIB.BASEBOARD_FAB2(SCH_1):PAGE49
  J6M1  225    A10 SCONN288_H44441003_PIP-SCONN,HA   I158 @BASEBOARD_FAB2_LIB.BASEBOARD_FAB2(SCH_1):PAGE50

M_D_MA<11> @BASEBOARD_FAB2_LIB.BASEBOARD_FAB2(SCH_1):M_D_MA(11)
  U5D1 EB61 DDR3_MA<11> SKX_EXT_B_BGA1-IC,TBD   I172 @BASEBOARD_FAB2_LIB.BASEBOARD_FAB2(SCH_1):PAGE26
  J4B1  210    A11 SCONN288_H44441004_PIP-SCONN,HA   I111 @BASEBOARD_FAB2_LIB.BASEBOARD_FAB2(SCH_1):PAGE49
  J6M1  210    A11 SCONN288_H44441003_PIP-SCONN,HA   I158 @BASEBOARD_FAB2_LIB.BASEBOARD_FAB2(SCH_1):PAGE50

M_D_MA<12> @BASEBOARD_FAB2_LIB.BASEBOARD_FAB2(SCH_1):M_D_MA(12)
  U5D1 DT63 DDR3_MA<12> SKX_EXT_B_BGA1-IC,TBD   I172 @BASEBOARD_FAB2_LIB.BASEBOARD_FAB2(SCH_1):PAGE26
  J4B1   65    A12 SCONN288_H44441004_PIP-SCONN,HA   I111 @BASEBOARD_FAB2_LIB.BASEBOARD_FAB2(SCH_1):PAGE49
  J6M1   65    A12 SCONN288_H44441003_PIP-SCONN,HA   I158 @BASEBOARD_FAB2_LIB.BASEBOARD_FAB2(SCH_1):PAGE50

M_D_MA<13> @BASEBOARD_FAB2_LIB.BASEBOARD_FAB2(SCH_1):M_D_MA(13)
  U5D1 DW48 DDR3_MA<13> SKX_EXT_B_BGA1-IC,TBD   I172 @BASEBOARD_FAB2_LIB.BASEBOARD_FAB2(SCH_1):PAGE26
  J4B1  232    A13 SCONN288_H44441004_PIP-SCONN,HA   I111 @BASEBOARD_FAB2_LIB.BASEBOARD_FAB2(SCH_1):PAGE49
  J6M1  232    A13 SCONN288_H44441003_PIP-SCONN,HA   I158 @BASEBOARD_FAB2_LIB.BASEBOARD_FAB2(SCH_1):PAGE50

M_D_MA<14> @BASEBOARD_FAB2_LIB.BASEBOARD_FAB2(SCH_1):M_D_MA(14)
  U5D1 ED51 DDR3_MA<14> SKX_EXT_B_BGA1-IC,TBD   I172 @BASEBOARD_FAB2_LIB.BASEBOARD_FAB2(SCH_1):PAGE26
  J4B1  228 A14_WE_N SCONN288_H44441004_PIP-SCONN,HA   I111 @BASEBOARD_FAB2_LIB.BASEBOARD_FAB2(SCH_1):PAGE49
  J6M1  228 A14_WE_N SCONN288_H44441003_PIP-SCONN,HA   I158 @BASEBOARD_FAB2_LIB.BASEBOARD_FAB2(SCH_1):PAGE50

M_D_MA<15> @BASEBOARD_FAB2_LIB.BASEBOARD_FAB2(SCH_1):M_D_MA(15)
  U5D1 DV49 DDR3_MA<15> SKX_EXT_B_BGA1-IC,TBD   I172 @BASEBOARD_FAB2_LIB.BASEBOARD_FAB2(SCH_1):PAGE26
  J4B1   86 A15_CAS_N SCONN288_H44441004_PIP-SCONN,HA   I111 @BASEBOARD_FAB2_LIB.BASEBOARD_FAB2(SCH_1):PAGE49
  J6M1   86 A15_CAS_N SCONN288_H44441003_PIP-SCONN,HA   I158 @BASEBOARD_FAB2_LIB.BASEBOARD_FAB2(SCH_1):PAGE50

M_D_MA<16> @BASEBOARD_FAB2_LIB.BASEBOARD_FAB2(SCH_1):M_D_MA(16)
  U5D1 EA52 DDR3_MA<16> SKX_EXT_B_BGA1-IC,TBD   I172 @BASEBOARD_FAB2_LIB.BASEBOARD_FAB2(SCH_1):PAGE26
  J4B1   82 A16_RAS_N SCONN288_H44441004_PIP-SCONN,HA   I111 @BASEBOARD_FAB2_LIB.BASEBOARD_FAB2(SCH_1):PAGE49
  J6M1   82 A16_RAS_N SCONN288_H44441003_PIP-SCONN,HA   I158 @BASEBOARD_FAB2_LIB.BASEBOARD_FAB2(SCH_1):PAGE50

M_D_MA<17> @BASEBOARD_FAB2_LIB.BASEBOARD_FAB2(SCH_1):M_D_MA(17)
  U5D1 EA46 DDR3_MA<17> SKX_EXT_B_BGA1-IC,TBD   I172 @BASEBOARD_FAB2_LIB.BASEBOARD_FAB2(SCH_1):PAGE26
  J4B1  234    A17 SCONN288_H44441004_PIP-SCONN,HA   I111 @BASEBOARD_FAB2_LIB.BASEBOARD_FAB2(SCH_1):PAGE49
  J6M1  234    A17 SCONN288_H44441003_PIP-SCONN,HA   I158 @BASEBOARD_FAB2_LIB.BASEBOARD_FAB2(SCH_1):PAGE50

M_D_MA<1> @BASEBOARD_FAB2_LIB.BASEBOARD_FAB2(SCH_1):M_D_MA(1)
  U5D1 ED57 DDR3_MA<1> SKX_EXT_B_BGA1-IC,TBD   I172 @BASEBOARD_FAB2_LIB.BASEBOARD_FAB2(SCH_1):PAGE26
  J4B1   72     A1 SCONN288_H44441004_PIP-SCONN,HA   I111 @BASEBOARD_FAB2_LIB.BASEBOARD_FAB2(SCH_1):PAGE49
  J6M1   72     A1 SCONN288_H44441003_PIP-SCONN,HA   I158 @BASEBOARD_FAB2_LIB.BASEBOARD_FAB2(SCH_1):PAGE50

M_D_MA<2> @BASEBOARD_FAB2_LIB.BASEBOARD_FAB2(SCH_1):M_D_MA(2)
  U5D1 EE58 DDR3_MA<2> SKX_EXT_B_BGA1-IC,TBD   I172 @BASEBOARD_FAB2_LIB.BASEBOARD_FAB2(SCH_1):PAGE26
  J4B1  216     A2 SCONN288_H44441004_PIP-SCONN,HA   I111 @BASEBOARD_FAB2_LIB.BASEBOARD_FAB2(SCH_1):PAGE49
  J6M1  216     A2 SCONN288_H44441003_PIP-SCONN,HA   I158 @BASEBOARD_FAB2_LIB.BASEBOARD_FAB2(SCH_1):PAGE50

M_D_MA<3> @BASEBOARD_FAB2_LIB.BASEBOARD_FAB2(SCH_1):M_D_MA(3)
  U5D1 EB57 DDR3_MA<3> SKX_EXT_B_BGA1-IC,TBD   I172 @BASEBOARD_FAB2_LIB.BASEBOARD_FAB2(SCH_1):PAGE26
  J4B1   71     A3 SCONN288_H44441004_PIP-SCONN,HA   I111 @BASEBOARD_FAB2_LIB.BASEBOARD_FAB2(SCH_1):PAGE49
  J6M1   71     A3 SCONN288_H44441003_PIP-SCONN,HA   I158 @BASEBOARD_FAB2_LIB.BASEBOARD_FAB2(SCH_1):PAGE50

M_D_MA<4> @BASEBOARD_FAB2_LIB.BASEBOARD_FAB2(SCH_1):M_D_MA(4)
  U5D1 ED59 DDR3_MA<4> SKX_EXT_B_BGA1-IC,TBD   I172 @BASEBOARD_FAB2_LIB.BASEBOARD_FAB2(SCH_1):PAGE26
  J4B1  214     A4 SCONN288_H44441004_PIP-SCONN,HA   I111 @BASEBOARD_FAB2_LIB.BASEBOARD_FAB2(SCH_1):PAGE49
  J6M1  214     A4 SCONN288_H44441003_PIP-SCONN,HA   I158 @BASEBOARD_FAB2_LIB.BASEBOARD_FAB2(SCH_1):PAGE50

M_D_MA<5> @BASEBOARD_FAB2_LIB.BASEBOARD_FAB2(SCH_1):M_D_MA(5)
  U5D1 EA58 DDR3_MA<5> SKX_EXT_B_BGA1-IC,TBD   I172 @BASEBOARD_FAB2_LIB.BASEBOARD_FAB2(SCH_1):PAGE26
  J4B1  213     A5 SCONN288_H44441004_PIP-SCONN,HA   I111 @BASEBOARD_FAB2_LIB.BASEBOARD_FAB2(SCH_1):PAGE49
  J6M1  213     A5 SCONN288_H44441003_PIP-SCONN,HA   I158 @BASEBOARD_FAB2_LIB.BASEBOARD_FAB2(SCH_1):PAGE50

M_D_MA<6> @BASEBOARD_FAB2_LIB.BASEBOARD_FAB2(SCH_1):M_D_MA(6)
  U5D1 EE60 DDR3_MA<6> SKX_EXT_B_BGA1-IC,TBD   I172 @BASEBOARD_FAB2_LIB.BASEBOARD_FAB2(SCH_1):PAGE26
  J4B1   69     A6 SCONN288_H44441004_PIP-SCONN,HA   I111 @BASEBOARD_FAB2_LIB.BASEBOARD_FAB2(SCH_1):PAGE49
  J6M1   69     A6 SCONN288_H44441003_PIP-SCONN,HA   I158 @BASEBOARD_FAB2_LIB.BASEBOARD_FAB2(SCH_1):PAGE50

M_D_MA<7> @BASEBOARD_FAB2_LIB.BASEBOARD_FAB2(SCH_1):M_D_MA(7)
  U5D1 EA60 DDR3_MA<7> SKX_EXT_B_BGA1-IC,TBD   I172 @BASEBOARD_FAB2_LIB.BASEBOARD_FAB2(SCH_1):PAGE26
  J4B1  211     A7 SCONN288_H44441004_PIP-SCONN,HA   I111 @BASEBOARD_FAB2_LIB.BASEBOARD_FAB2(SCH_1):PAGE49
  J6M1  211     A7 SCONN288_H44441003_PIP-SCONN,HA   I158 @BASEBOARD_FAB2_LIB.BASEBOARD_FAB2(SCH_1):PAGE50

M_D_MA<8> @BASEBOARD_FAB2_LIB.BASEBOARD_FAB2(SCH_1):M_D_MA(8)
  U5D1 EB59 DDR3_MA<8> SKX_EXT_B_BGA1-IC,TBD   I172 @BASEBOARD_FAB2_LIB.BASEBOARD_FAB2(SCH_1):PAGE26
  J4B1   68     A8 SCONN288_H44441004_PIP-SCONN,HA   I111 @BASEBOARD_FAB2_LIB.BASEBOARD_FAB2(SCH_1):PAGE49
  J6M1   68     A8 SCONN288_H44441003_PIP-SCONN,HA   I158 @BASEBOARD_FAB2_LIB.BASEBOARD_FAB2(SCH_1):PAGE50

M_D_MA<9> @BASEBOARD_FAB2_LIB.BASEBOARD_FAB2(SCH_1):M_D_MA(9)
  U5D1 EF61 DDR3_MA<9> SKX_EXT_B_BGA1-IC,TBD   I172 @BASEBOARD_FAB2_LIB.BASEBOARD_FAB2(SCH_1):PAGE26
  J4B1   66     A9 SCONN288_H44441004_PIP-SCONN,HA   I111 @BASEBOARD_FAB2_LIB.BASEBOARD_FAB2(SCH_1):PAGE49
  J6M1   66     A9 SCONN288_H44441003_PIP-SCONN,HA   I158 @BASEBOARD_FAB2_LIB.BASEBOARD_FAB2(SCH_1):PAGE50

M_D_ODT<0> @BASEBOARD_FAB2_LIB.BASEBOARD_FAB2(SCH_1):M_D_ODT(0)
  U5D1 EE50 DDR3_ODT<0> SKX_EXT_B_BGA1-IC,TBD   I172 @BASEBOARD_FAB2_LIB.BASEBOARD_FAB2(SCH_1):PAGE26
  J4B1   87 ODT<0> SCONN288_H44441004_PIP-SCONN,HA   I111 @BASEBOARD_FAB2_LIB.BASEBOARD_FAB2(SCH_1):PAGE49

M_D_ODT<1> @BASEBOARD_FAB2_LIB.BASEBOARD_FAB2(SCH_1):M_D_ODT(1)
  U5D1 EE48 DDR3_ODT<1> SKX_EXT_B_BGA1-IC,TBD   I172 @BASEBOARD_FAB2_LIB.BASEBOARD_FAB2(SCH_1):PAGE26
  J4B1   91 ODT<1> SCONN288_H44441004_PIP-SCONN,HA   I111 @BASEBOARD_FAB2_LIB.BASEBOARD_FAB2(SCH_1):PAGE49

M_D_ODT<2> @BASEBOARD_FAB2_LIB.BASEBOARD_FAB2(SCH_1):M_D_ODT(2)
  U5D1 EA50 DDR3_ODT<2> SKX_EXT_B_BGA1-IC,TBD   I172 @BASEBOARD_FAB2_LIB.BASEBOARD_FAB2(SCH_1):PAGE26
  J6M1   87 ODT<0> SCONN288_H44441003_PIP-SCONN,HA   I158 @BASEBOARD_FAB2_LIB.BASEBOARD_FAB2(SCH_1):PAGE50

M_D_ODT<3> @BASEBOARD_FAB2_LIB.BASEBOARD_FAB2(SCH_1):M_D_ODT(3)
  U5D1 EA48 DDR3_ODT<3> SKX_EXT_B_BGA1-IC,TBD   I172 @BASEBOARD_FAB2_LIB.BASEBOARD_FAB2(SCH_1):PAGE26
  J6M1   91 ODT<1> SCONN288_H44441003_PIP-SCONN,HA   I158 @BASEBOARD_FAB2_LIB.BASEBOARD_FAB2(SCH_1):PAGE50

M_D_PAR @BASEBOARD_FAB2_LIB.BASEBOARD_FAB2(SCH_1):M_D_PAR
  U5D1 ED53 DDR3_PAR SKX_EXT_B_BGA1-IC,TBD   I172 @BASEBOARD_FAB2_LIB.BASEBOARD_FAB2(SCH_1):PAGE26
  J4B1  222    PAR SCONN288_H44441004_PIP-SCONN,HA   I111 @BASEBOARD_FAB2_LIB.BASEBOARD_FAB2(SCH_1):PAGE49
  J6M1  222    PAR SCONN288_H44441003_PIP-SCONN,HA   I158 @BASEBOARD_FAB2_LIB.BASEBOARD_FAB2(SCH_1):PAGE50

M_D_VREF @BASEBOARD_FAB2_LIB.BASEBOARD_FAB2(SCH_1):M_D_VREF
  J4B1  146 VREFCA SCONN288_H44441004_PIP-SCONN,HA   I111 @BASEBOARD_FAB2_LIB.BASEBOARD_FAB2(SCH_1):PAGE49
 C4B12    1      A CAP_A_0402V-0.01UF,25V,10%,X7RA   I179 @BASEBOARD_FAB2_LIB.BASEBOARD_FAB2(SCH_1):PAGE49
  J6M1  146 VREFCA SCONN288_H44441003_PIP-SCONN,HA   I158 @BASEBOARD_FAB2_LIB.BASEBOARD_FAB2(SCH_1):PAGE50
  C6M1    1      A CAP_A_0402V-0.01UF,25V,10%,X7RA   I177 @BASEBOARD_FAB2_LIB.BASEBOARD_FAB2(SCH_1):PAGE50
  R6M1    2      B RES_0402-1.00K,1%,1/16W,CHIP,GA     I9 @BASEBOARD_FAB2_LIB.BASEBOARD_FAB2(SCH_1):PAGE98
 R6L16    1      A RES_0402-1.00K,1%,1/16W,CHIP,GA    I12 @BASEBOARD_FAB2_LIB.BASEBOARD_FAB2(SCH_1):PAGE98
  R6M2    2      B RES_0402-2,1.0%,1/16W,CHIP,G21A    I14 @BASEBOARD_FAB2_LIB.BASEBOARD_FAB2(SCH_1):PAGE98

M_E_ACT_N @BASEBOARD_FAB2_LIB.BASEBOARD_FAB2(SCH_1):M_E_ACT_N
  U5D1 DR62 DDR4_ACT_N SKX_EXT_B_BGA1-IC,TBD   I172 @BASEBOARD_FAB2_LIB.BASEBOARD_FAB2(SCH_1):PAGE27
  J4A2   62  ACT_N SCONN288_H44441004_PIP-SCONN,HA   I111 @BASEBOARD_FAB2_LIB.BASEBOARD_FAB2(SCH_1):PAGE51
  J6L2   62  ACT_N SCONN288_H44441003_PIP-SCONN,HA    I12 @BASEBOARD_FAB2_LIB.BASEBOARD_FAB2(SCH_1):PAGE52

M_E_ALERT_N @BASEBOARD_FAB2_LIB.BASEBOARD_FAB2(SCH_1):M_E_ALERT_N
  U5D1 DT61 DDR4_ALERT_N SKX_EXT_B_BGA1-IC,TBD   I172 @BASEBOARD_FAB2_LIB.BASEBOARD_FAB2(SCH_1):PAGE27
  J4A2  208 ALERT_N SCONN288_H44441004_PIP-SCONN,HA   I111 @BASEBOARD_FAB2_LIB.BASEBOARD_FAB2(SCH_1):PAGE51
  J6L2  208 ALERT_N SCONN288_H44441003_PIP-SCONN,HA    I12 @BASEBOARD_FAB2_LIB.BASEBOARD_FAB2(SCH_1):PAGE52

M_E_BA<0> @BASEBOARD_FAB2_LIB.BASEBOARD_FAB2(SCH_1):M_E_BA(0)
  U5D1 DM53 DDR4_BA<0> SKX_EXT_B_BGA1-IC,TBD   I172 @BASEBOARD_FAB2_LIB.BASEBOARD_FAB2(SCH_1):PAGE27
  J4A2   81  BA<0> SCONN288_H44441004_PIP-SCONN,HA   I111 @BASEBOARD_FAB2_LIB.BASEBOARD_FAB2(SCH_1):PAGE51
  J6L2   81  BA<0> SCONN288_H44441003_PIP-SCONN,HA    I12 @BASEBOARD_FAB2_LIB.BASEBOARD_FAB2(SCH_1):PAGE52

M_E_BA<1> @BASEBOARD_FAB2_LIB.BASEBOARD_FAB2(SCH_1):M_E_BA(1)
  U5D1 DV55 DDR4_BA<1> SKX_EXT_B_BGA1-IC,TBD   I172 @BASEBOARD_FAB2_LIB.BASEBOARD_FAB2(SCH_1):PAGE27
  J4A2  224  BA<1> SCONN288_H44441004_PIP-SCONN,HA   I111 @BASEBOARD_FAB2_LIB.BASEBOARD_FAB2(SCH_1):PAGE51
  J6L2  224  BA<1> SCONN288_H44441003_PIP-SCONN,HA    I12 @BASEBOARD_FAB2_LIB.BASEBOARD_FAB2(SCH_1):PAGE52

M_E_BG<0> @BASEBOARD_FAB2_LIB.BASEBOARD_FAB2(SCH_1):M_E_BG(0)
  U5D1 DJ62 DDR4_BG<0> SKX_EXT_B_BGA1-IC,TBD   I172 @BASEBOARD_FAB2_LIB.BASEBOARD_FAB2(SCH_1):PAGE27
  J4A2   63  BG<0> SCONN288_H44441004_PIP-SCONN,HA   I111 @BASEBOARD_FAB2_LIB.BASEBOARD_FAB2(SCH_1):PAGE51
  J6L2   63  BG<0> SCONN288_H44441003_PIP-SCONN,HA    I12 @BASEBOARD_FAB2_LIB.BASEBOARD_FAB2(SCH_1):PAGE52

M_E_BG<1> @BASEBOARD_FAB2_LIB.BASEBOARD_FAB2(SCH_1):M_E_BG(1)
  U5D1 DM61 DDR4_BG<1> SKX_EXT_B_BGA1-IC,TBD   I172 @BASEBOARD_FAB2_LIB.BASEBOARD_FAB2(SCH_1):PAGE27
  J4A2  207  BG<1> SCONN288_H44441004_PIP-SCONN,HA   I111 @BASEBOARD_FAB2_LIB.BASEBOARD_FAB2(SCH_1):PAGE51
  J6L2  207  BG<1> SCONN288_H44441003_PIP-SCONN,HA    I12 @BASEBOARD_FAB2_LIB.BASEBOARD_FAB2(SCH_1):PAGE52

M_E_C<2> @BASEBOARD_FAB2_LIB.BASEBOARD_FAB2(SCH_1):M_E_C(2)
  U5D1 DT47 DDR4_CID<2> SKX_EXT_B_BGA1-IC,TBD   I172 @BASEBOARD_FAB2_LIB.BASEBOARD_FAB2(SCH_1):PAGE27
  J4A2  235   C<2> SCONN288_H44441004_PIP-SCONN,HA   I111 @BASEBOARD_FAB2_LIB.BASEBOARD_FAB2(SCH_1):PAGE51
  J6L2  235   C<2> SCONN288_H44441003_PIP-SCONN,HA    I12 @BASEBOARD_FAB2_LIB.BASEBOARD_FAB2(SCH_1):PAGE52

M_E_CKE<0> @BASEBOARD_FAB2_LIB.BASEBOARD_FAB2(SCH_1):M_E_CKE(0)
  U5D1 DM63 DDR4_CKE<0> SKX_EXT_B_BGA1-IC,TBD   I172 @BASEBOARD_FAB2_LIB.BASEBOARD_FAB2(SCH_1):PAGE27
  J4A2   60 CKE<0> SCONN288_H44441004_PIP-SCONN,HA   I111 @BASEBOARD_FAB2_LIB.BASEBOARD_FAB2(SCH_1):PAGE51

M_E_CKE<1> @BASEBOARD_FAB2_LIB.BASEBOARD_FAB2(SCH_1):M_E_CKE(1)
  U5D1 DN64 DDR4_CKE<1> SKX_EXT_B_BGA1-IC,TBD   I172 @BASEBOARD_FAB2_LIB.BASEBOARD_FAB2(SCH_1):PAGE27
  J4A2  203 CKE<1> SCONN288_H44441004_PIP-SCONN,HA   I111 @BASEBOARD_FAB2_LIB.BASEBOARD_FAB2(SCH_1):PAGE51

M_E_CKE<2> @BASEBOARD_FAB2_LIB.BASEBOARD_FAB2(SCH_1):M_E_CKE(2)
  U5D1 DL64 DDR4_CKE<2> SKX_EXT_B_BGA1-IC,TBD   I172 @BASEBOARD_FAB2_LIB.BASEBOARD_FAB2(SCH_1):PAGE27
  J6L2   60 CKE<0> SCONN288_H44441003_PIP-SCONN,HA    I12 @BASEBOARD_FAB2_LIB.BASEBOARD_FAB2(SCH_1):PAGE52

M_E_CKE<3> @BASEBOARD_FAB2_LIB.BASEBOARD_FAB2(SCH_1):M_E_CKE(3)
  U5D1 DR64 DDR4_CKE<3> SKX_EXT_B_BGA1-IC,TBD   I172 @BASEBOARD_FAB2_LIB.BASEBOARD_FAB2(SCH_1):PAGE27
  J6L2  203 CKE<1> SCONN288_H44441003_PIP-SCONN,HA    I12 @BASEBOARD_FAB2_LIB.BASEBOARD_FAB2(SCH_1):PAGE52

M_E_CLK_DN<0> @BASEBOARD_FAB2_LIB.BASEBOARD_FAB2(SCH_1):M_E_CLK_DN(0)
  U5D1 DM55 DDR4_CLK_DN<0> SKX_EXT_B_BGA1-IC,TBD   I172 @BASEBOARD_FAB2_LIB.BASEBOARD_FAB2(SCH_1):PAGE27
  J4A2   75   CK0N SCONN288_H44441004_PIP-SCONN,HA   I111 @BASEBOARD_FAB2_LIB.BASEBOARD_FAB2(SCH_1):PAGE51

M_E_CLK_DN<1> @BASEBOARD_FAB2_LIB.BASEBOARD_FAB2(SCH_1):M_E_CLK_DN(1)
  U5D1 DR54 DDR4_CLK_DN<1> SKX_EXT_B_BGA1-IC,TBD   I172 @BASEBOARD_FAB2_LIB.BASEBOARD_FAB2(SCH_1):PAGE27
  J4A2  219   CK1N SCONN288_H44441004_PIP-SCONN,HA   I111 @BASEBOARD_FAB2_LIB.BASEBOARD_FAB2(SCH_1):PAGE51

M_E_CLK_DN<2> @BASEBOARD_FAB2_LIB.BASEBOARD_FAB2(SCH_1):M_E_CLK_DN(2)
  U5D1 DM57 DDR4_CLK_DN<2> SKX_EXT_B_BGA1-IC,TBD   I172 @BASEBOARD_FAB2_LIB.BASEBOARD_FAB2(SCH_1):PAGE27
  J6L2   75   CK0N SCONN288_H44441003_PIP-SCONN,HA    I12 @BASEBOARD_FAB2_LIB.BASEBOARD_FAB2(SCH_1):PAGE52

M_E_CLK_DN<3> @BASEBOARD_FAB2_LIB.BASEBOARD_FAB2(SCH_1):M_E_CLK_DN(3)
  U5D1 DT57 DDR4_CLK_DN<3> SKX_EXT_B_BGA1-IC,TBD   I172 @BASEBOARD_FAB2_LIB.BASEBOARD_FAB2(SCH_1):PAGE27
  J6L2  219   CK1N SCONN288_H44441003_PIP-SCONN,HA    I12 @BASEBOARD_FAB2_LIB.BASEBOARD_FAB2(SCH_1):PAGE52

M_E_CLK_DP<0> @BASEBOARD_FAB2_LIB.BASEBOARD_FAB2(SCH_1):M_E_CLK_DP(0)
  U5D1 DN54 DDR4_CLK_DP<0> SKX_EXT_B_BGA1-IC,TBD   I172 @BASEBOARD_FAB2_LIB.BASEBOARD_FAB2(SCH_1):PAGE27
  J4A2   74   CK0P SCONN288_H44441004_PIP-SCONN,HA   I111 @BASEBOARD_FAB2_LIB.BASEBOARD_FAB2(SCH_1):PAGE51

M_E_CLK_DP<1> @BASEBOARD_FAB2_LIB.BASEBOARD_FAB2(SCH_1):M_E_CLK_DP(1)
  U5D1 DT53 DDR4_CLK_DP<1> SKX_EXT_B_BGA1-IC,TBD   I172 @BASEBOARD_FAB2_LIB.BASEBOARD_FAB2(SCH_1):PAGE27
  J4A2  218   CK1P SCONN288_H44441004_PIP-SCONN,HA   I111 @BASEBOARD_FAB2_LIB.BASEBOARD_FAB2(SCH_1):PAGE51

M_E_CLK_DP<2> @BASEBOARD_FAB2_LIB.BASEBOARD_FAB2(SCH_1):M_E_CLK_DP(2)
  U5D1 DN56 DDR4_CLK_DP<2> SKX_EXT_B_BGA1-IC,TBD   I172 @BASEBOARD_FAB2_LIB.BASEBOARD_FAB2(SCH_1):PAGE27
  J6L2   74   CK0P SCONN288_H44441003_PIP-SCONN,HA    I12 @BASEBOARD_FAB2_LIB.BASEBOARD_FAB2(SCH_1):PAGE52

M_E_CLK_DP<3> @BASEBOARD_FAB2_LIB.BASEBOARD_FAB2(SCH_1):M_E_CLK_DP(3)
  U5D1 DR56 DDR4_CLK_DP<3> SKX_EXT_B_BGA1-IC,TBD   I172 @BASEBOARD_FAB2_LIB.BASEBOARD_FAB2(SCH_1):PAGE27
  J6L2  218   CK1P SCONN288_H44441003_PIP-SCONN,HA    I12 @BASEBOARD_FAB2_LIB.BASEBOARD_FAB2(SCH_1):PAGE52

M_E_CPU_VREF @BASEBOARD_FAB2_LIB.BASEBOARD_FAB2(SCH_1):M_E_CPU_VREF
  U5D1 CT61 DDR4_CAVREF SKX_EXT_B_BGA1-IC,TBD   I259 @BASEBOARD_FAB2_LIB.BASEBOARD_FAB2(SCH_1):PAGE21
 R6L14    1      A RES_0402-2,1.0%,1/16W,CHIP,G21A    I58 @BASEBOARD_FAB2_LIB.BASEBOARD_FAB2(SCH_1):PAGE98
  C6L7    1      A CAP_A_0402V-0.01UF,25V,10%,X7RA    I59 @BASEBOARD_FAB2_LIB.BASEBOARD_FAB2(SCH_1):PAGE98

M_E_CS_N<0> @BASEBOARD_FAB2_LIB.BASEBOARD_FAB2(SCH_1):M_E_CS_N(0)
  U5D1 DV51 DDR4_CS_N<0> SKX_EXT_B_BGA1-IC,TBD   I172 @BASEBOARD_FAB2_LIB.BASEBOARD_FAB2(SCH_1):PAGE27
  J4A2   84   S0_N SCONN288_H44441004_PIP-SCONN,HA   I111 @BASEBOARD_FAB2_LIB.BASEBOARD_FAB2(SCH_1):PAGE51

M_E_CS_N<1> @BASEBOARD_FAB2_LIB.BASEBOARD_FAB2(SCH_1):M_E_CS_N(1)
  U5D1 DN50 DDR4_CS_N<1> SKX_EXT_B_BGA1-IC,TBD   I172 @BASEBOARD_FAB2_LIB.BASEBOARD_FAB2(SCH_1):PAGE27
  J4A2   89   S1_N SCONN288_H44441004_PIP-SCONN,HA   I111 @BASEBOARD_FAB2_LIB.BASEBOARD_FAB2(SCH_1):PAGE51

M_E_CS_N<2> @BASEBOARD_FAB2_LIB.BASEBOARD_FAB2(SCH_1):M_E_CS_N(2)
  U5D1 DR46 DDR4_CS_N<2> SKX_EXT_B_BGA1-IC,TBD   I172 @BASEBOARD_FAB2_LIB.BASEBOARD_FAB2(SCH_1):PAGE27
  J4A2   93 S2_N_C<0> SCONN288_H44441004_PIP-SCONN,HA   I111 @BASEBOARD_FAB2_LIB.BASEBOARD_FAB2(SCH_1):PAGE51

M_E_CS_N<3> @BASEBOARD_FAB2_LIB.BASEBOARD_FAB2(SCH_1):M_E_CS_N(3)
  U5D1 DK47 DDR4_CS_N<3> SKX_EXT_B_BGA1-IC,TBD   I172 @BASEBOARD_FAB2_LIB.BASEBOARD_FAB2(SCH_1):PAGE27
  J4A2  237 S3_N_C<1> SCONN288_H44441004_PIP-SCONN,HA   I111 @BASEBOARD_FAB2_LIB.BASEBOARD_FAB2(SCH_1):PAGE51

M_E_CS_N<4> @BASEBOARD_FAB2_LIB.BASEBOARD_FAB2(SCH_1):M_E_CS_N(4)
  U5D1 DW50 DDR4_CS_N<4> SKX_EXT_B_BGA1-IC,TBD   I172 @BASEBOARD_FAB2_LIB.BASEBOARD_FAB2(SCH_1):PAGE27
  J6L2   84   S0_N SCONN288_H44441003_PIP-SCONN,HA    I12 @BASEBOARD_FAB2_LIB.BASEBOARD_FAB2(SCH_1):PAGE52

M_E_CS_N<5> @BASEBOARD_FAB2_LIB.BASEBOARD_FAB2(SCH_1):M_E_CS_N(5)
  U5D1 DM49 DDR4_CS_N<5> SKX_EXT_B_BGA1-IC,TBD   I172 @BASEBOARD_FAB2_LIB.BASEBOARD_FAB2(SCH_1):PAGE27
  J6L2   89   S1_N SCONN288_H44441003_PIP-SCONN,HA    I12 @BASEBOARD_FAB2_LIB.BASEBOARD_FAB2(SCH_1):PAGE52

M_E_CS_N<6> @BASEBOARD_FAB2_LIB.BASEBOARD_FAB2(SCH_1):M_E_CS_N(6)
  U5D1 DT45 DDR4_CS_N<6> SKX_EXT_B_BGA1-IC,TBD   I172 @BASEBOARD_FAB2_LIB.BASEBOARD_FAB2(SCH_1):PAGE27
  J6L2   93 S2_N_C<0> SCONN288_H44441003_PIP-SCONN,HA    I12 @BASEBOARD_FAB2_LIB.BASEBOARD_FAB2(SCH_1):PAGE52

M_E_CS_N<7> @BASEBOARD_FAB2_LIB.BASEBOARD_FAB2(SCH_1):M_E_CS_N(7)
  U5D1 DN46 DDR4_CS_N<7> SKX_EXT_B_BGA1-IC,TBD   I172 @BASEBOARD_FAB2_LIB.BASEBOARD_FAB2(SCH_1):PAGE27
  J6L2  237 S3_N_C<1> SCONN288_H44441003_PIP-SCONN,HA    I12 @BASEBOARD_FAB2_LIB.BASEBOARD_FAB2(SCH_1):PAGE52

M_E_DQ<0> @BASEBOARD_FAB2_LIB.BASEBOARD_FAB2(SCH_1):M_E_DQ(0)
  U5D1 CM79 DDR4_DQ<0> SKX_EXT_B_BGA1-IC,TBD   I172 @BASEBOARD_FAB2_LIB.BASEBOARD_FAB2(SCH_1):PAGE27
  J4A2  150  DQ<1> SCONN288_H44441004_PIP-SCONN,HA   I111 @BASEBOARD_FAB2_LIB.BASEBOARD_FAB2(SCH_1):PAGE51
  J6L2    5  DQ<0> SCONN288_H44441003_PIP-SCONN,HA    I12 @BASEBOARD_FAB2_LIB.BASEBOARD_FAB2(SCH_1):PAGE52

M_E_DQ<10> @BASEBOARD_FAB2_LIB.BASEBOARD_FAB2(SCH_1):M_E_DQ(10)
  U5D1 DE80 DDR4_DQ<10> SKX_EXT_B_BGA1-IC,TBD   I172 @BASEBOARD_FAB2_LIB.BASEBOARD_FAB2(SCH_1):PAGE27
  J4A2  168 DQ<11> SCONN288_H44441004_PIP-SCONN,HA   I111 @BASEBOARD_FAB2_LIB.BASEBOARD_FAB2(SCH_1):PAGE51
  J6L2   23 DQ<10> SCONN288_H44441003_PIP-SCONN,HA    I12 @BASEBOARD_FAB2_LIB.BASEBOARD_FAB2(SCH_1):PAGE52

M_E_DQ<11> @BASEBOARD_FAB2_LIB.BASEBOARD_FAB2(SCH_1):M_E_DQ(11)
  U5D1 DF81 DDR4_DQ<11> SKX_EXT_B_BGA1-IC,TBD   I172 @BASEBOARD_FAB2_LIB.BASEBOARD_FAB2(SCH_1):PAGE27
  J4A2   23 DQ<10> SCONN288_H44441004_PIP-SCONN,HA   I111 @BASEBOARD_FAB2_LIB.BASEBOARD_FAB2(SCH_1):PAGE51
  J6L2  168 DQ<11> SCONN288_H44441003_PIP-SCONN,HA    I12 @BASEBOARD_FAB2_LIB.BASEBOARD_FAB2(SCH_1):PAGE52

M_E_DQ<12> @BASEBOARD_FAB2_LIB.BASEBOARD_FAB2(SCH_1):M_E_DQ(12)
  U5D1 CY79 DDR4_DQ<12> SKX_EXT_B_BGA1-IC,TBD   I172 @BASEBOARD_FAB2_LIB.BASEBOARD_FAB2(SCH_1):PAGE27
  J4A2  159 DQ<13> SCONN288_H44441004_PIP-SCONN,HA   I111 @BASEBOARD_FAB2_LIB.BASEBOARD_FAB2(SCH_1):PAGE51
  J6L2   14 DQ<12> SCONN288_H44441003_PIP-SCONN,HA    I12 @BASEBOARD_FAB2_LIB.BASEBOARD_FAB2(SCH_1):PAGE52

M_E_DQ<13> @BASEBOARD_FAB2_LIB.BASEBOARD_FAB2(SCH_1):M_E_DQ(13)
  U5D1 CW80 DDR4_DQ<13> SKX_EXT_B_BGA1-IC,TBD   I172 @BASEBOARD_FAB2_LIB.BASEBOARD_FAB2(SCH_1):PAGE27
  J4A2   14 DQ<12> SCONN288_H44441004_PIP-SCONN,HA   I111 @BASEBOARD_FAB2_LIB.BASEBOARD_FAB2(SCH_1):PAGE51
  J6L2  159 DQ<13> SCONN288_H44441003_PIP-SCONN,HA    I12 @BASEBOARD_FAB2_LIB.BASEBOARD_FAB2(SCH_1):PAGE52

M_E_DQ<14> @BASEBOARD_FAB2_LIB.BASEBOARD_FAB2(SCH_1):M_E_DQ(14)
  U5D1 DC82 DDR4_DQ<14> SKX_EXT_B_BGA1-IC,TBD   I172 @BASEBOARD_FAB2_LIB.BASEBOARD_FAB2(SCH_1):PAGE27
  J4A2  166 DQ<15> SCONN288_H44441004_PIP-SCONN,HA   I111 @BASEBOARD_FAB2_LIB.BASEBOARD_FAB2(SCH_1):PAGE51
  J6L2   21 DQ<14> SCONN288_H44441003_PIP-SCONN,HA    I12 @BASEBOARD_FAB2_LIB.BASEBOARD_FAB2(SCH_1):PAGE52

M_E_DQ<15> @BASEBOARD_FAB2_LIB.BASEBOARD_FAB2(SCH_1):M_E_DQ(15)
  U5D1 DE82 DDR4_DQ<15> SKX_EXT_B_BGA1-IC,TBD   I172 @BASEBOARD_FAB2_LIB.BASEBOARD_FAB2(SCH_1):PAGE27
  J4A2   21 DQ<14> SCONN288_H44441004_PIP-SCONN,HA   I111 @BASEBOARD_FAB2_LIB.BASEBOARD_FAB2(SCH_1):PAGE51
  J6L2  166 DQ<15> SCONN288_H44441003_PIP-SCONN,HA    I12 @BASEBOARD_FAB2_LIB.BASEBOARD_FAB2(SCH_1):PAGE52

M_E_DQ<16> @BASEBOARD_FAB2_LIB.BASEBOARD_FAB2(SCH_1):M_E_DQ(16)
  U5D1 DW80 DDR4_DQ<16> SKX_EXT_B_BGA1-IC,TBD   I172 @BASEBOARD_FAB2_LIB.BASEBOARD_FAB2(SCH_1):PAGE27
  J4A2  172 DQ<17> SCONN288_H44441004_PIP-SCONN,HA   I111 @BASEBOARD_FAB2_LIB.BASEBOARD_FAB2(SCH_1):PAGE51
  J6L2   27 DQ<16> SCONN288_H44441003_PIP-SCONN,HA    I12 @BASEBOARD_FAB2_LIB.BASEBOARD_FAB2(SCH_1):PAGE52

M_E_DQ<17> @BASEBOARD_FAB2_LIB.BASEBOARD_FAB2(SCH_1):M_E_DQ(17)
  U5D1 EC80 DDR4_DQ<17> SKX_EXT_B_BGA1-IC,TBD   I172 @BASEBOARD_FAB2_LIB.BASEBOARD_FAB2(SCH_1):PAGE27
  J4A2   27 DQ<16> SCONN288_H44441004_PIP-SCONN,HA   I111 @BASEBOARD_FAB2_LIB.BASEBOARD_FAB2(SCH_1):PAGE51
  J6L2  172 DQ<17> SCONN288_H44441003_PIP-SCONN,HA    I12 @BASEBOARD_FAB2_LIB.BASEBOARD_FAB2(SCH_1):PAGE52

M_E_DQ<18> @BASEBOARD_FAB2_LIB.BASEBOARD_FAB2(SCH_1):M_E_DQ(18)
  U5D1 DY77 DDR4_DQ<18> SKX_EXT_B_BGA1-IC,TBD   I172 @BASEBOARD_FAB2_LIB.BASEBOARD_FAB2(SCH_1):PAGE27
  J4A2  179 DQ<19> SCONN288_H44441004_PIP-SCONN,HA   I111 @BASEBOARD_FAB2_LIB.BASEBOARD_FAB2(SCH_1):PAGE51
  J6L2   34 DQ<18> SCONN288_H44441003_PIP-SCONN,HA    I12 @BASEBOARD_FAB2_LIB.BASEBOARD_FAB2(SCH_1):PAGE52

M_E_DQ<19> @BASEBOARD_FAB2_LIB.BASEBOARD_FAB2(SCH_1):M_E_DQ(19)
  U5D1 EB77 DDR4_DQ<19> SKX_EXT_B_BGA1-IC,TBD   I172 @BASEBOARD_FAB2_LIB.BASEBOARD_FAB2(SCH_1):PAGE27
  J4A2   34 DQ<18> SCONN288_H44441004_PIP-SCONN,HA   I111 @BASEBOARD_FAB2_LIB.BASEBOARD_FAB2(SCH_1):PAGE51
  J6L2  179 DQ<19> SCONN288_H44441003_PIP-SCONN,HA    I12 @BASEBOARD_FAB2_LIB.BASEBOARD_FAB2(SCH_1):PAGE52

M_E_DQ<1> @BASEBOARD_FAB2_LIB.BASEBOARD_FAB2(SCH_1):M_E_DQ(1)
  U5D1 CK81 DDR4_DQ<1> SKX_EXT_B_BGA1-IC,TBD   I172 @BASEBOARD_FAB2_LIB.BASEBOARD_FAB2(SCH_1):PAGE27
  J4A2    5  DQ<0> SCONN288_H44441004_PIP-SCONN,HA   I111 @BASEBOARD_FAB2_LIB.BASEBOARD_FAB2(SCH_1):PAGE51
  J6L2  150  DQ<1> SCONN288_H44441003_PIP-SCONN,HA    I12 @BASEBOARD_FAB2_LIB.BASEBOARD_FAB2(SCH_1):PAGE52

M_E_DQ<20> @BASEBOARD_FAB2_LIB.BASEBOARD_FAB2(SCH_1):M_E_DQ(20)
  U5D1 DY81 DDR4_DQ<20> SKX_EXT_B_BGA1-IC,TBD   I172 @BASEBOARD_FAB2_LIB.BASEBOARD_FAB2(SCH_1):PAGE27
  J4A2  170 DQ<21> SCONN288_H44441004_PIP-SCONN,HA   I111 @BASEBOARD_FAB2_LIB.BASEBOARD_FAB2(SCH_1):PAGE51
  J6L2   25 DQ<20> SCONN288_H44441003_PIP-SCONN,HA    I12 @BASEBOARD_FAB2_LIB.BASEBOARD_FAB2(SCH_1):PAGE52

M_E_DQ<21> @BASEBOARD_FAB2_LIB.BASEBOARD_FAB2(SCH_1):M_E_DQ(21)
  U5D1 EB81 DDR4_DQ<21> SKX_EXT_B_BGA1-IC,TBD   I172 @BASEBOARD_FAB2_LIB.BASEBOARD_FAB2(SCH_1):PAGE27
  J4A2   25 DQ<20> SCONN288_H44441004_PIP-SCONN,HA   I111 @BASEBOARD_FAB2_LIB.BASEBOARD_FAB2(SCH_1):PAGE51
  J6L2  170 DQ<21> SCONN288_H44441003_PIP-SCONN,HA    I12 @BASEBOARD_FAB2_LIB.BASEBOARD_FAB2(SCH_1):PAGE52

M_E_DQ<22> @BASEBOARD_FAB2_LIB.BASEBOARD_FAB2(SCH_1):M_E_DQ(22)
  U5D1 DW78 DDR4_DQ<22> SKX_EXT_B_BGA1-IC,TBD   I172 @BASEBOARD_FAB2_LIB.BASEBOARD_FAB2(SCH_1):PAGE27
  J4A2  177 DQ<23> SCONN288_H44441004_PIP-SCONN,HA   I111 @BASEBOARD_FAB2_LIB.BASEBOARD_FAB2(SCH_1):PAGE51
  J6L2   32 DQ<22> SCONN288_H44441003_PIP-SCONN,HA    I12 @BASEBOARD_FAB2_LIB.BASEBOARD_FAB2(SCH_1):PAGE52

M_E_DQ<23> @BASEBOARD_FAB2_LIB.BASEBOARD_FAB2(SCH_1):M_E_DQ(23)
  U5D1 EC78 DDR4_DQ<23> SKX_EXT_B_BGA1-IC,TBD   I172 @BASEBOARD_FAB2_LIB.BASEBOARD_FAB2(SCH_1):PAGE27
  J4A2   32 DQ<22> SCONN288_H44441004_PIP-SCONN,HA   I111 @BASEBOARD_FAB2_LIB.BASEBOARD_FAB2(SCH_1):PAGE51
  J6L2  177 DQ<23> SCONN288_H44441003_PIP-SCONN,HA    I12 @BASEBOARD_FAB2_LIB.BASEBOARD_FAB2(SCH_1):PAGE52

M_E_DQ<24> @BASEBOARD_FAB2_LIB.BASEBOARD_FAB2(SCH_1):M_E_DQ(24)
  U5D1 ED75 DDR4_DQ<24> SKX_EXT_B_BGA1-IC,TBD   I172 @BASEBOARD_FAB2_LIB.BASEBOARD_FAB2(SCH_1):PAGE27
  J4A2  183 DQ<25> SCONN288_H44441004_PIP-SCONN,HA   I111 @BASEBOARD_FAB2_LIB.BASEBOARD_FAB2(SCH_1):PAGE51
  J6L2   38 DQ<24> SCONN288_H44441003_PIP-SCONN,HA    I12 @BASEBOARD_FAB2_LIB.BASEBOARD_FAB2(SCH_1):PAGE52

M_E_DQ<25> @BASEBOARD_FAB2_LIB.BASEBOARD_FAB2(SCH_1):M_E_DQ(25)
  U5D1 EE74 DDR4_DQ<25> SKX_EXT_B_BGA1-IC,TBD   I172 @BASEBOARD_FAB2_LIB.BASEBOARD_FAB2(SCH_1):PAGE27
  J4A2   38 DQ<24> SCONN288_H44441004_PIP-SCONN,HA   I111 @BASEBOARD_FAB2_LIB.BASEBOARD_FAB2(SCH_1):PAGE51
  J6L2  183 DQ<25> SCONN288_H44441003_PIP-SCONN,HA    I12 @BASEBOARD_FAB2_LIB.BASEBOARD_FAB2(SCH_1):PAGE52

M_E_DQ<26> @BASEBOARD_FAB2_LIB.BASEBOARD_FAB2(SCH_1):M_E_DQ(26)
  U5D1 EB71 DDR4_DQ<26> SKX_EXT_B_BGA1-IC,TBD   I172 @BASEBOARD_FAB2_LIB.BASEBOARD_FAB2(SCH_1):PAGE27
  J4A2  190 DQ<27> SCONN288_H44441004_PIP-SCONN,HA   I111 @BASEBOARD_FAB2_LIB.BASEBOARD_FAB2(SCH_1):PAGE51
  J6L2   45 DQ<26> SCONN288_H44441003_PIP-SCONN,HA    I12 @BASEBOARD_FAB2_LIB.BASEBOARD_FAB2(SCH_1):PAGE52

M_E_DQ<27> @BASEBOARD_FAB2_LIB.BASEBOARD_FAB2(SCH_1):M_E_DQ(27)
  U5D1 ED71 DDR4_DQ<27> SKX_EXT_B_BGA1-IC,TBD   I172 @BASEBOARD_FAB2_LIB.BASEBOARD_FAB2(SCH_1):PAGE27
  J4A2   45 DQ<26> SCONN288_H44441004_PIP-SCONN,HA   I111 @BASEBOARD_FAB2_LIB.BASEBOARD_FAB2(SCH_1):PAGE51
  J6L2  190 DQ<27> SCONN288_H44441003_PIP-SCONN,HA    I12 @BASEBOARD_FAB2_LIB.BASEBOARD_FAB2(SCH_1):PAGE52

M_E_DQ<28> @BASEBOARD_FAB2_LIB.BASEBOARD_FAB2(SCH_1):M_E_DQ(28)
  U5D1 EA74 DDR4_DQ<28> SKX_EXT_B_BGA1-IC,TBD   I172 @BASEBOARD_FAB2_LIB.BASEBOARD_FAB2(SCH_1):PAGE27
  J4A2  181 DQ<29> SCONN288_H44441004_PIP-SCONN,HA   I111 @BASEBOARD_FAB2_LIB.BASEBOARD_FAB2(SCH_1):PAGE51
  J6L2   36 DQ<28> SCONN288_H44441003_PIP-SCONN,HA    I12 @BASEBOARD_FAB2_LIB.BASEBOARD_FAB2(SCH_1):PAGE52

M_E_DQ<29> @BASEBOARD_FAB2_LIB.BASEBOARD_FAB2(SCH_1):M_E_DQ(29)
  U5D1 EB75 DDR4_DQ<29> SKX_EXT_B_BGA1-IC,TBD   I172 @BASEBOARD_FAB2_LIB.BASEBOARD_FAB2(SCH_1):PAGE27
  J4A2   36 DQ<28> SCONN288_H44441004_PIP-SCONN,HA   I111 @BASEBOARD_FAB2_LIB.BASEBOARD_FAB2(SCH_1):PAGE51
  J6L2  181 DQ<29> SCONN288_H44441003_PIP-SCONN,HA    I12 @BASEBOARD_FAB2_LIB.BASEBOARD_FAB2(SCH_1):PAGE52

M_E_DQ<2> @BASEBOARD_FAB2_LIB.BASEBOARD_FAB2(SCH_1):M_E_DQ(2)
  U5D1 CT81 DDR4_DQ<2> SKX_EXT_B_BGA1-IC,TBD   I172 @BASEBOARD_FAB2_LIB.BASEBOARD_FAB2(SCH_1):PAGE27
  J4A2  157  DQ<3> SCONN288_H44441004_PIP-SCONN,HA   I111 @BASEBOARD_FAB2_LIB.BASEBOARD_FAB2(SCH_1):PAGE51
  J6L2   12  DQ<2> SCONN288_H44441003_PIP-SCONN,HA    I12 @BASEBOARD_FAB2_LIB.BASEBOARD_FAB2(SCH_1):PAGE52

M_E_DQ<30> @BASEBOARD_FAB2_LIB.BASEBOARD_FAB2(SCH_1):M_E_DQ(30)
  U5D1 EA72 DDR4_DQ<30> SKX_EXT_B_BGA1-IC,TBD   I172 @BASEBOARD_FAB2_LIB.BASEBOARD_FAB2(SCH_1):PAGE27
  J4A2  188 DQ<31> SCONN288_H44441004_PIP-SCONN,HA   I111 @BASEBOARD_FAB2_LIB.BASEBOARD_FAB2(SCH_1):PAGE51
  J6L2   43 DQ<30> SCONN288_H44441003_PIP-SCONN,HA    I12 @BASEBOARD_FAB2_LIB.BASEBOARD_FAB2(SCH_1):PAGE52

M_E_DQ<31> @BASEBOARD_FAB2_LIB.BASEBOARD_FAB2(SCH_1):M_E_DQ(31)
  U5D1 EE72 DDR4_DQ<31> SKX_EXT_B_BGA1-IC,TBD   I172 @BASEBOARD_FAB2_LIB.BASEBOARD_FAB2(SCH_1):PAGE27
  J4A2   43 DQ<30> SCONN288_H44441004_PIP-SCONN,HA   I111 @BASEBOARD_FAB2_LIB.BASEBOARD_FAB2(SCH_1):PAGE51
  J6L2  188 DQ<31> SCONN288_H44441003_PIP-SCONN,HA    I12 @BASEBOARD_FAB2_LIB.BASEBOARD_FAB2(SCH_1):PAGE52

M_E_DQ<32> @BASEBOARD_FAB2_LIB.BASEBOARD_FAB2(SCH_1):M_E_DQ(32)
  U5D1 DU42 DDR4_DQ<32> SKX_EXT_B_BGA1-IC,TBD   I172 @BASEBOARD_FAB2_LIB.BASEBOARD_FAB2(SCH_1):PAGE27
  J4A2  242 DQ<33> SCONN288_H44441004_PIP-SCONN,HA   I111 @BASEBOARD_FAB2_LIB.BASEBOARD_FAB2(SCH_1):PAGE51
  J6L2   97 DQ<32> SCONN288_H44441003_PIP-SCONN,HA    I12 @BASEBOARD_FAB2_LIB.BASEBOARD_FAB2(SCH_1):PAGE52

M_E_DQ<33> @BASEBOARD_FAB2_LIB.BASEBOARD_FAB2(SCH_1):M_E_DQ(33)
  U5D1 DW42 DDR4_DQ<33> SKX_EXT_B_BGA1-IC,TBD   I172 @BASEBOARD_FAB2_LIB.BASEBOARD_FAB2(SCH_1):PAGE27
  J4A2   97 DQ<32> SCONN288_H44441004_PIP-SCONN,HA   I111 @BASEBOARD_FAB2_LIB.BASEBOARD_FAB2(SCH_1):PAGE51
  J6L2  242 DQ<33> SCONN288_H44441003_PIP-SCONN,HA    I12 @BASEBOARD_FAB2_LIB.BASEBOARD_FAB2(SCH_1):PAGE52

M_E_DQ<34> @BASEBOARD_FAB2_LIB.BASEBOARD_FAB2(SCH_1):M_E_DQ(34)
  U5D1 DP39 DDR4_DQ<34> SKX_EXT_B_BGA1-IC,TBD   I172 @BASEBOARD_FAB2_LIB.BASEBOARD_FAB2(SCH_1):PAGE27
  J4A2  249 DQ<35> SCONN288_H44441004_PIP-SCONN,HA   I111 @BASEBOARD_FAB2_LIB.BASEBOARD_FAB2(SCH_1):PAGE51
  J6L2  104 DQ<34> SCONN288_H44441003_PIP-SCONN,HA    I12 @BASEBOARD_FAB2_LIB.BASEBOARD_FAB2(SCH_1):PAGE52

M_E_DQ<35> @BASEBOARD_FAB2_LIB.BASEBOARD_FAB2(SCH_1):M_E_DQ(35)
  U5D1 DT39 DDR4_DQ<35> SKX_EXT_B_BGA1-IC,TBD   I172 @BASEBOARD_FAB2_LIB.BASEBOARD_FAB2(SCH_1):PAGE27
  J4A2  104 DQ<34> SCONN288_H44441004_PIP-SCONN,HA   I111 @BASEBOARD_FAB2_LIB.BASEBOARD_FAB2(SCH_1):PAGE51
  J6L2  249 DQ<35> SCONN288_H44441003_PIP-SCONN,HA    I12 @BASEBOARD_FAB2_LIB.BASEBOARD_FAB2(SCH_1):PAGE52

M_E_DQ<36> @BASEBOARD_FAB2_LIB.BASEBOARD_FAB2(SCH_1):M_E_DQ(36)
  U5D1 DL42 DDR4_DQ<36> SKX_EXT_B_BGA1-IC,TBD   I172 @BASEBOARD_FAB2_LIB.BASEBOARD_FAB2(SCH_1):PAGE27
  J4A2  240 DQ<37> SCONN288_H44441004_PIP-SCONN,HA   I111 @BASEBOARD_FAB2_LIB.BASEBOARD_FAB2(SCH_1):PAGE51
  J6L2   95 DQ<36> SCONN288_H44441003_PIP-SCONN,HA    I12 @BASEBOARD_FAB2_LIB.BASEBOARD_FAB2(SCH_1):PAGE52

M_E_DQ<37> @BASEBOARD_FAB2_LIB.BASEBOARD_FAB2(SCH_1):M_E_DQ(37)
  U5D1 DN42 DDR4_DQ<37> SKX_EXT_B_BGA1-IC,TBD   I172 @BASEBOARD_FAB2_LIB.BASEBOARD_FAB2(SCH_1):PAGE27
  J4A2   95 DQ<36> SCONN288_H44441004_PIP-SCONN,HA   I111 @BASEBOARD_FAB2_LIB.BASEBOARD_FAB2(SCH_1):PAGE51
  J6L2  240 DQ<37> SCONN288_H44441003_PIP-SCONN,HA    I12 @BASEBOARD_FAB2_LIB.BASEBOARD_FAB2(SCH_1):PAGE52

M_E_DQ<38> @BASEBOARD_FAB2_LIB.BASEBOARD_FAB2(SCH_1):M_E_DQ(38)
  U5D1 DN40 DDR4_DQ<38> SKX_EXT_B_BGA1-IC,TBD   I172 @BASEBOARD_FAB2_LIB.BASEBOARD_FAB2(SCH_1):PAGE27
  J4A2  247 DQ<39> SCONN288_H44441004_PIP-SCONN,HA   I111 @BASEBOARD_FAB2_LIB.BASEBOARD_FAB2(SCH_1):PAGE51
  J6L2  102 DQ<38> SCONN288_H44441003_PIP-SCONN,HA    I12 @BASEBOARD_FAB2_LIB.BASEBOARD_FAB2(SCH_1):PAGE52

M_E_DQ<39> @BASEBOARD_FAB2_LIB.BASEBOARD_FAB2(SCH_1):M_E_DQ(39)
  U5D1 DU40 DDR4_DQ<39> SKX_EXT_B_BGA1-IC,TBD   I172 @BASEBOARD_FAB2_LIB.BASEBOARD_FAB2(SCH_1):PAGE27
  J4A2  102 DQ<38> SCONN288_H44441004_PIP-SCONN,HA   I111 @BASEBOARD_FAB2_LIB.BASEBOARD_FAB2(SCH_1):PAGE51
  J6L2  247 DQ<39> SCONN288_H44441003_PIP-SCONN,HA    I12 @BASEBOARD_FAB2_LIB.BASEBOARD_FAB2(SCH_1):PAGE52

M_E_DQ<3> @BASEBOARD_FAB2_LIB.BASEBOARD_FAB2(SCH_1):M_E_DQ(3)
  U5D1 CR82 DDR4_DQ<3> SKX_EXT_B_BGA1-IC,TBD   I172 @BASEBOARD_FAB2_LIB.BASEBOARD_FAB2(SCH_1):PAGE27
  J4A2   12  DQ<2> SCONN288_H44441004_PIP-SCONN,HA   I111 @BASEBOARD_FAB2_LIB.BASEBOARD_FAB2(SCH_1):PAGE51
  J6L2  157  DQ<3> SCONN288_H44441003_PIP-SCONN,HA    I12 @BASEBOARD_FAB2_LIB.BASEBOARD_FAB2(SCH_1):PAGE52

M_E_DQ<40> @BASEBOARD_FAB2_LIB.BASEBOARD_FAB2(SCH_1):M_E_DQ(40)
  U5D1 EC34 DDR4_DQ<40> SKX_EXT_B_BGA1-IC,TBD   I172 @BASEBOARD_FAB2_LIB.BASEBOARD_FAB2(SCH_1):PAGE27
  J4A2  253 DQ<41> SCONN288_H44441004_PIP-SCONN,HA   I111 @BASEBOARD_FAB2_LIB.BASEBOARD_FAB2(SCH_1):PAGE51
  J6L2  108 DQ<40> SCONN288_H44441003_PIP-SCONN,HA    I12 @BASEBOARD_FAB2_LIB.BASEBOARD_FAB2(SCH_1):PAGE52

M_E_DQ<41> @BASEBOARD_FAB2_LIB.BASEBOARD_FAB2(SCH_1):M_E_DQ(41)
  U5D1 ED33 DDR4_DQ<41> SKX_EXT_B_BGA1-IC,TBD   I172 @BASEBOARD_FAB2_LIB.BASEBOARD_FAB2(SCH_1):PAGE27
  J4A2  108 DQ<40> SCONN288_H44441004_PIP-SCONN,HA   I111 @BASEBOARD_FAB2_LIB.BASEBOARD_FAB2(SCH_1):PAGE51
  J6L2  253 DQ<41> SCONN288_H44441003_PIP-SCONN,HA    I12 @BASEBOARD_FAB2_LIB.BASEBOARD_FAB2(SCH_1):PAGE52

M_E_DQ<42> @BASEBOARD_FAB2_LIB.BASEBOARD_FAB2(SCH_1):M_E_DQ(42)
  U5D1 EA30 DDR4_DQ<42> SKX_EXT_B_BGA1-IC,TBD   I172 @BASEBOARD_FAB2_LIB.BASEBOARD_FAB2(SCH_1):PAGE27
  J4A2  260 DQ<43> SCONN288_H44441004_PIP-SCONN,HA   I111 @BASEBOARD_FAB2_LIB.BASEBOARD_FAB2(SCH_1):PAGE51
  J6L2  115 DQ<42> SCONN288_H44441003_PIP-SCONN,HA    I12 @BASEBOARD_FAB2_LIB.BASEBOARD_FAB2(SCH_1):PAGE52

M_E_DQ<43> @BASEBOARD_FAB2_LIB.BASEBOARD_FAB2(SCH_1):M_E_DQ(43)
  U5D1 EC30 DDR4_DQ<43> SKX_EXT_B_BGA1-IC,TBD   I172 @BASEBOARD_FAB2_LIB.BASEBOARD_FAB2(SCH_1):PAGE27
  J4A2  115 DQ<42> SCONN288_H44441004_PIP-SCONN,HA   I111 @BASEBOARD_FAB2_LIB.BASEBOARD_FAB2(SCH_1):PAGE51
  J6L2  260 DQ<43> SCONN288_H44441003_PIP-SCONN,HA    I12 @BASEBOARD_FAB2_LIB.BASEBOARD_FAB2(SCH_1):PAGE52

M_E_DQ<44> @BASEBOARD_FAB2_LIB.BASEBOARD_FAB2(SCH_1):M_E_DQ(44)
  U5D1 DY33 DDR4_DQ<44> SKX_EXT_B_BGA1-IC,TBD   I172 @BASEBOARD_FAB2_LIB.BASEBOARD_FAB2(SCH_1):PAGE27
  J4A2  251 DQ<45> SCONN288_H44441004_PIP-SCONN,HA   I111 @BASEBOARD_FAB2_LIB.BASEBOARD_FAB2(SCH_1):PAGE51
  J6L2  106 DQ<44> SCONN288_H44441003_PIP-SCONN,HA    I12 @BASEBOARD_FAB2_LIB.BASEBOARD_FAB2(SCH_1):PAGE52

M_E_DQ<45> @BASEBOARD_FAB2_LIB.BASEBOARD_FAB2(SCH_1):M_E_DQ(45)
  U5D1 EA34 DDR4_DQ<45> SKX_EXT_B_BGA1-IC,TBD   I172 @BASEBOARD_FAB2_LIB.BASEBOARD_FAB2(SCH_1):PAGE27
  J4A2  106 DQ<44> SCONN288_H44441004_PIP-SCONN,HA   I111 @BASEBOARD_FAB2_LIB.BASEBOARD_FAB2(SCH_1):PAGE51
  J6L2  251 DQ<45> SCONN288_H44441003_PIP-SCONN,HA    I12 @BASEBOARD_FAB2_LIB.BASEBOARD_FAB2(SCH_1):PAGE52

M_E_DQ<46> @BASEBOARD_FAB2_LIB.BASEBOARD_FAB2(SCH_1):M_E_DQ(46)
  U5D1 DY31 DDR4_DQ<46> SKX_EXT_B_BGA1-IC,TBD   I172 @BASEBOARD_FAB2_LIB.BASEBOARD_FAB2(SCH_1):PAGE27
  J4A2  258 DQ<47> SCONN288_H44441004_PIP-SCONN,HA   I111 @BASEBOARD_FAB2_LIB.BASEBOARD_FAB2(SCH_1):PAGE51
  J6L2  113 DQ<46> SCONN288_H44441003_PIP-SCONN,HA    I12 @BASEBOARD_FAB2_LIB.BASEBOARD_FAB2(SCH_1):PAGE52

M_E_DQ<47> @BASEBOARD_FAB2_LIB.BASEBOARD_FAB2(SCH_1):M_E_DQ(47)
  U5D1 ED31 DDR4_DQ<47> SKX_EXT_B_BGA1-IC,TBD   I172 @BASEBOARD_FAB2_LIB.BASEBOARD_FAB2(SCH_1):PAGE27
  J4A2  113 DQ<46> SCONN288_H44441004_PIP-SCONN,HA   I111 @BASEBOARD_FAB2_LIB.BASEBOARD_FAB2(SCH_1):PAGE51
  J6L2  258 DQ<47> SCONN288_H44441003_PIP-SCONN,HA    I12 @BASEBOARD_FAB2_LIB.BASEBOARD_FAB2(SCH_1):PAGE52

M_E_DQ<48> @BASEBOARD_FAB2_LIB.BASEBOARD_FAB2(SCH_1):M_E_DQ(48)
  U5D1 EC28 DDR4_DQ<48> SKX_EXT_B_BGA1-IC,TBD   I172 @BASEBOARD_FAB2_LIB.BASEBOARD_FAB2(SCH_1):PAGE27
  J4A2  264 DQ<49> SCONN288_H44441004_PIP-SCONN,HA   I111 @BASEBOARD_FAB2_LIB.BASEBOARD_FAB2(SCH_1):PAGE51
  J6L2  119 DQ<48> SCONN288_H44441003_PIP-SCONN,HA    I12 @BASEBOARD_FAB2_LIB.BASEBOARD_FAB2(SCH_1):PAGE52

M_E_DQ<49> @BASEBOARD_FAB2_LIB.BASEBOARD_FAB2(SCH_1):M_E_DQ(49)
  U5D1 ED27 DDR4_DQ<49> SKX_EXT_B_BGA1-IC,TBD   I172 @BASEBOARD_FAB2_LIB.BASEBOARD_FAB2(SCH_1):PAGE27
  J4A2  119 DQ<48> SCONN288_H44441004_PIP-SCONN,HA   I111 @BASEBOARD_FAB2_LIB.BASEBOARD_FAB2(SCH_1):PAGE51
  J6L2  264 DQ<49> SCONN288_H44441003_PIP-SCONN,HA    I12 @BASEBOARD_FAB2_LIB.BASEBOARD_FAB2(SCH_1):PAGE52

M_E_DQ<4> @BASEBOARD_FAB2_LIB.BASEBOARD_FAB2(SCH_1):M_E_DQ(4)
  U5D1 CK79 DDR4_DQ<4> SKX_EXT_B_BGA1-IC,TBD   I172 @BASEBOARD_FAB2_LIB.BASEBOARD_FAB2(SCH_1):PAGE27
  J4A2  148  DQ<5> SCONN288_H44441004_PIP-SCONN,HA   I111 @BASEBOARD_FAB2_LIB.BASEBOARD_FAB2(SCH_1):PAGE51
  J6L2    3  DQ<4> SCONN288_H44441003_PIP-SCONN,HA    I12 @BASEBOARD_FAB2_LIB.BASEBOARD_FAB2(SCH_1):PAGE52

M_E_DQ<50> @BASEBOARD_FAB2_LIB.BASEBOARD_FAB2(SCH_1):M_E_DQ(50)
  U5D1 EA24 DDR4_DQ<50> SKX_EXT_B_BGA1-IC,TBD   I172 @BASEBOARD_FAB2_LIB.BASEBOARD_FAB2(SCH_1):PAGE27
  J4A2  271 DQ<51> SCONN288_H44441004_PIP-SCONN,HA   I111 @BASEBOARD_FAB2_LIB.BASEBOARD_FAB2(SCH_1):PAGE51
  J6L2  126 DQ<50> SCONN288_H44441003_PIP-SCONN,HA    I12 @BASEBOARD_FAB2_LIB.BASEBOARD_FAB2(SCH_1):PAGE52

M_E_DQ<51> @BASEBOARD_FAB2_LIB.BASEBOARD_FAB2(SCH_1):M_E_DQ(51)
  U5D1 EC24 DDR4_DQ<51> SKX_EXT_B_BGA1-IC,TBD   I172 @BASEBOARD_FAB2_LIB.BASEBOARD_FAB2(SCH_1):PAGE27
  J4A2  126 DQ<50> SCONN288_H44441004_PIP-SCONN,HA   I111 @BASEBOARD_FAB2_LIB.BASEBOARD_FAB2(SCH_1):PAGE51
  J6L2  271 DQ<51> SCONN288_H44441003_PIP-SCONN,HA    I12 @BASEBOARD_FAB2_LIB.BASEBOARD_FAB2(SCH_1):PAGE52

M_E_DQ<52> @BASEBOARD_FAB2_LIB.BASEBOARD_FAB2(SCH_1):M_E_DQ(52)
  U5D1 DY27 DDR4_DQ<52> SKX_EXT_B_BGA1-IC,TBD   I172 @BASEBOARD_FAB2_LIB.BASEBOARD_FAB2(SCH_1):PAGE27
  J4A2  262 DQ<53> SCONN288_H44441004_PIP-SCONN,HA   I111 @BASEBOARD_FAB2_LIB.BASEBOARD_FAB2(SCH_1):PAGE51
  J6L2  117 DQ<52> SCONN288_H44441003_PIP-SCONN,HA    I12 @BASEBOARD_FAB2_LIB.BASEBOARD_FAB2(SCH_1):PAGE52

M_E_DQ<53> @BASEBOARD_FAB2_LIB.BASEBOARD_FAB2(SCH_1):M_E_DQ(53)
  U5D1 EA28 DDR4_DQ<53> SKX_EXT_B_BGA1-IC,TBD   I172 @BASEBOARD_FAB2_LIB.BASEBOARD_FAB2(SCH_1):PAGE27
  J4A2  117 DQ<52> SCONN288_H44441004_PIP-SCONN,HA   I111 @BASEBOARD_FAB2_LIB.BASEBOARD_FAB2(SCH_1):PAGE51
  J6L2  262 DQ<53> SCONN288_H44441003_PIP-SCONN,HA    I12 @BASEBOARD_FAB2_LIB.BASEBOARD_FAB2(SCH_1):PAGE52

M_E_DQ<54> @BASEBOARD_FAB2_LIB.BASEBOARD_FAB2(SCH_1):M_E_DQ(54)
  U5D1 DY25 DDR4_DQ<54> SKX_EXT_B_BGA1-IC,TBD   I172 @BASEBOARD_FAB2_LIB.BASEBOARD_FAB2(SCH_1):PAGE27
  J4A2  269 DQ<55> SCONN288_H44441004_PIP-SCONN,HA   I111 @BASEBOARD_FAB2_LIB.BASEBOARD_FAB2(SCH_1):PAGE51
  J6L2  124 DQ<54> SCONN288_H44441003_PIP-SCONN,HA    I12 @BASEBOARD_FAB2_LIB.BASEBOARD_FAB2(SCH_1):PAGE52

M_E_DQ<55> @BASEBOARD_FAB2_LIB.BASEBOARD_FAB2(SCH_1):M_E_DQ(55)
  U5D1 ED25 DDR4_DQ<55> SKX_EXT_B_BGA1-IC,TBD   I172 @BASEBOARD_FAB2_LIB.BASEBOARD_FAB2(SCH_1):PAGE27
  J4A2  124 DQ<54> SCONN288_H44441004_PIP-SCONN,HA   I111 @BASEBOARD_FAB2_LIB.BASEBOARD_FAB2(SCH_1):PAGE51
  J6L2  269 DQ<55> SCONN288_H44441003_PIP-SCONN,HA    I12 @BASEBOARD_FAB2_LIB.BASEBOARD_FAB2(SCH_1):PAGE52

M_E_DQ<56> @BASEBOARD_FAB2_LIB.BASEBOARD_FAB2(SCH_1):M_E_DQ(56)
  U5D1 DF27 DDR4_DQ<56> SKX_EXT_B_BGA1-IC,TBD   I172 @BASEBOARD_FAB2_LIB.BASEBOARD_FAB2(SCH_1):PAGE27
  J4A2  275 DQ<57> SCONN288_H44441004_PIP-SCONN,HA   I111 @BASEBOARD_FAB2_LIB.BASEBOARD_FAB2(SCH_1):PAGE51
  J6L2  130 DQ<56> SCONN288_H44441003_PIP-SCONN,HA    I12 @BASEBOARD_FAB2_LIB.BASEBOARD_FAB2(SCH_1):PAGE52

M_E_DQ<57> @BASEBOARD_FAB2_LIB.BASEBOARD_FAB2(SCH_1):M_E_DQ(57)
  U5D1 DK27 DDR4_DQ<57> SKX_EXT_B_BGA1-IC,TBD   I172 @BASEBOARD_FAB2_LIB.BASEBOARD_FAB2(SCH_1):PAGE27
  J4A2  130 DQ<56> SCONN288_H44441004_PIP-SCONN,HA   I111 @BASEBOARD_FAB2_LIB.BASEBOARD_FAB2(SCH_1):PAGE51
  J6L2  275 DQ<57> SCONN288_H44441003_PIP-SCONN,HA    I12 @BASEBOARD_FAB2_LIB.BASEBOARD_FAB2(SCH_1):PAGE52

M_E_DQ<58> @BASEBOARD_FAB2_LIB.BASEBOARD_FAB2(SCH_1):M_E_DQ(58)
  U5D1 DD25 DDR4_DQ<58> SKX_EXT_B_BGA1-IC,TBD   I172 @BASEBOARD_FAB2_LIB.BASEBOARD_FAB2(SCH_1):PAGE27
  J4A2  282 DQ<59> SCONN288_H44441004_PIP-SCONN,HA   I111 @BASEBOARD_FAB2_LIB.BASEBOARD_FAB2(SCH_1):PAGE51
  J6L2  137 DQ<58> SCONN288_H44441003_PIP-SCONN,HA    I12 @BASEBOARD_FAB2_LIB.BASEBOARD_FAB2(SCH_1):PAGE52

M_E_DQ<59> @BASEBOARD_FAB2_LIB.BASEBOARD_FAB2(SCH_1):M_E_DQ(59)
  U5D1 DJ24 DDR4_DQ<59> SKX_EXT_B_BGA1-IC,TBD   I172 @BASEBOARD_FAB2_LIB.BASEBOARD_FAB2(SCH_1):PAGE27
  J4A2  137 DQ<58> SCONN288_H44441004_PIP-SCONN,HA   I111 @BASEBOARD_FAB2_LIB.BASEBOARD_FAB2(SCH_1):PAGE51
  J6L2  282 DQ<59> SCONN288_H44441003_PIP-SCONN,HA    I12 @BASEBOARD_FAB2_LIB.BASEBOARD_FAB2(SCH_1):PAGE52

M_E_DQ<5> @BASEBOARD_FAB2_LIB.BASEBOARD_FAB2(SCH_1):M_E_DQ(5)
  U5D1 CJ80 DDR4_DQ<5> SKX_EXT_B_BGA1-IC,TBD   I172 @BASEBOARD_FAB2_LIB.BASEBOARD_FAB2(SCH_1):PAGE27
  J4A2    3  DQ<4> SCONN288_H44441004_PIP-SCONN,HA   I111 @BASEBOARD_FAB2_LIB.BASEBOARD_FAB2(SCH_1):PAGE51
  J6L2  148  DQ<5> SCONN288_H44441003_PIP-SCONN,HA    I12 @BASEBOARD_FAB2_LIB.BASEBOARD_FAB2(SCH_1):PAGE52

M_E_DQ<60> @BASEBOARD_FAB2_LIB.BASEBOARD_FAB2(SCH_1):M_E_DQ(60)
  U5D1 DG28 DDR4_DQ<60> SKX_EXT_B_BGA1-IC,TBD   I172 @BASEBOARD_FAB2_LIB.BASEBOARD_FAB2(SCH_1):PAGE27
  J4A2  273 DQ<61> SCONN288_H44441004_PIP-SCONN,HA   I111 @BASEBOARD_FAB2_LIB.BASEBOARD_FAB2(SCH_1):PAGE51
  J6L2  128 DQ<60> SCONN288_H44441003_PIP-SCONN,HA    I12 @BASEBOARD_FAB2_LIB.BASEBOARD_FAB2(SCH_1):PAGE52

M_E_DQ<61> @BASEBOARD_FAB2_LIB.BASEBOARD_FAB2(SCH_1):M_E_DQ(61)
  U5D1 DJ28 DDR4_DQ<61> SKX_EXT_B_BGA1-IC,TBD   I172 @BASEBOARD_FAB2_LIB.BASEBOARD_FAB2(SCH_1):PAGE27
  J4A2  128 DQ<60> SCONN288_H44441004_PIP-SCONN,HA   I111 @BASEBOARD_FAB2_LIB.BASEBOARD_FAB2(SCH_1):PAGE51
  J6L2  273 DQ<61> SCONN288_H44441003_PIP-SCONN,HA    I12 @BASEBOARD_FAB2_LIB.BASEBOARD_FAB2(SCH_1):PAGE52

M_E_DQ<62> @BASEBOARD_FAB2_LIB.BASEBOARD_FAB2(SCH_1):M_E_DQ(62)
  U5D1 DF25 DDR4_DQ<62> SKX_EXT_B_BGA1-IC,TBD   I172 @BASEBOARD_FAB2_LIB.BASEBOARD_FAB2(SCH_1):PAGE27
  J4A2  280 DQ<63> SCONN288_H44441004_PIP-SCONN,HA   I111 @BASEBOARD_FAB2_LIB.BASEBOARD_FAB2(SCH_1):PAGE51
  J6L2  135 DQ<62> SCONN288_H44441003_PIP-SCONN,HA    I12 @BASEBOARD_FAB2_LIB.BASEBOARD_FAB2(SCH_1):PAGE52

M_E_DQ<63> @BASEBOARD_FAB2_LIB.BASEBOARD_FAB2(SCH_1):M_E_DQ(63)
  U5D1 DK25 DDR4_DQ<63> SKX_EXT_B_BGA1-IC,TBD   I172 @BASEBOARD_FAB2_LIB.BASEBOARD_FAB2(SCH_1):PAGE27
  J4A2  135 DQ<62> SCONN288_H44441004_PIP-SCONN,HA   I111 @BASEBOARD_FAB2_LIB.BASEBOARD_FAB2(SCH_1):PAGE51
  J6L2  280 DQ<63> SCONN288_H44441003_PIP-SCONN,HA    I12 @BASEBOARD_FAB2_LIB.BASEBOARD_FAB2(SCH_1):PAGE52

M_E_DQ<6> @BASEBOARD_FAB2_LIB.BASEBOARD_FAB2(SCH_1):M_E_DQ(6)
  U5D1 CR80 DDR4_DQ<6> SKX_EXT_B_BGA1-IC,TBD   I172 @BASEBOARD_FAB2_LIB.BASEBOARD_FAB2(SCH_1):PAGE27
  J4A2  155  DQ<7> SCONN288_H44441004_PIP-SCONN,HA   I111 @BASEBOARD_FAB2_LIB.BASEBOARD_FAB2(SCH_1):PAGE51
  J6L2   10  DQ<6> SCONN288_H44441003_PIP-SCONN,HA    I12 @BASEBOARD_FAB2_LIB.BASEBOARD_FAB2(SCH_1):PAGE52

M_E_DQ<7> @BASEBOARD_FAB2_LIB.BASEBOARD_FAB2(SCH_1):M_E_DQ(7)
  U5D1 CN82 DDR4_DQ<7> SKX_EXT_B_BGA1-IC,TBD   I172 @BASEBOARD_FAB2_LIB.BASEBOARD_FAB2(SCH_1):PAGE27
  J4A2   10  DQ<6> SCONN288_H44441004_PIP-SCONN,HA   I111 @BASEBOARD_FAB2_LIB.BASEBOARD_FAB2(SCH_1):PAGE51
  J6L2  155  DQ<7> SCONN288_H44441003_PIP-SCONN,HA    I12 @BASEBOARD_FAB2_LIB.BASEBOARD_FAB2(SCH_1):PAGE52

M_E_DQ<8> @BASEBOARD_FAB2_LIB.BASEBOARD_FAB2(SCH_1):M_E_DQ(8)
  U5D1 DB79 DDR4_DQ<8> SKX_EXT_B_BGA1-IC,TBD   I172 @BASEBOARD_FAB2_LIB.BASEBOARD_FAB2(SCH_1):PAGE27
  J4A2  161  DQ<9> SCONN288_H44441004_PIP-SCONN,HA   I111 @BASEBOARD_FAB2_LIB.BASEBOARD_FAB2(SCH_1):PAGE51
  J6L2   16  DQ<8> SCONN288_H44441003_PIP-SCONN,HA    I12 @BASEBOARD_FAB2_LIB.BASEBOARD_FAB2(SCH_1):PAGE52

M_E_DQ<9> @BASEBOARD_FAB2_LIB.BASEBOARD_FAB2(SCH_1):M_E_DQ(9)
  U5D1 CY81 DDR4_DQ<9> SKX_EXT_B_BGA1-IC,TBD   I172 @BASEBOARD_FAB2_LIB.BASEBOARD_FAB2(SCH_1):PAGE27
  J4A2   16  DQ<8> SCONN288_H44441004_PIP-SCONN,HA   I111 @BASEBOARD_FAB2_LIB.BASEBOARD_FAB2(SCH_1):PAGE51
  J6L2  161  DQ<9> SCONN288_H44441003_PIP-SCONN,HA    I12 @BASEBOARD_FAB2_LIB.BASEBOARD_FAB2(SCH_1):PAGE52

M_E_DQS_DN<0> @BASEBOARD_FAB2_LIB.BASEBOARD_FAB2(SCH_1):M_E_DQS_DN(0)
  U5D1 CL82 DDR4_DQS_DN<0> SKX_EXT_B_BGA1-IC,TBD   I172 @BASEBOARD_FAB2_LIB.BASEBOARD_FAB2(SCH_1):PAGE27
  J4A2  152  DQS0N SCONN288_H44441004_PIP-SCONN,HA    I66 @BASEBOARD_FAB2_LIB.BASEBOARD_FAB2(SCH_1):PAGE51
  J6L2  152  DQS0N SCONN288_H44441003_PIP-SCONN,HA   I100 @BASEBOARD_FAB2_LIB.BASEBOARD_FAB2(SCH_1):PAGE52

M_E_DQS_DN<10> @BASEBOARD_FAB2_LIB.BASEBOARD_FAB2(SCH_1):M_E_DQS_DN(10)
  U5D1 DC80 DDR4_DQS_DN<10> SKX_EXT_B_BGA1-IC,TBD   I172 @BASEBOARD_FAB2_LIB.BASEBOARD_FAB2(SCH_1):PAGE27
  J4A2   19 DQS10N SCONN288_H44441004_PIP-SCONN,HA    I66 @BASEBOARD_FAB2_LIB.BASEBOARD_FAB2(SCH_1):PAGE51
  J6L2   19 DQS10N SCONN288_H44441003_PIP-SCONN,HA   I100 @BASEBOARD_FAB2_LIB.BASEBOARD_FAB2(SCH_1):PAGE52

M_E_DQS_DN<11> @BASEBOARD_FAB2_LIB.BASEBOARD_FAB2(SCH_1):M_E_DQS_DN(11)
  U5D1 DY79 DDR4_DQS_DN<11> SKX_EXT_B_BGA1-IC,TBD   I172 @BASEBOARD_FAB2_LIB.BASEBOARD_FAB2(SCH_1):PAGE27
  J4A2   30 DQS11N SCONN288_H44441004_PIP-SCONN,HA    I66 @BASEBOARD_FAB2_LIB.BASEBOARD_FAB2(SCH_1):PAGE51
  J6L2   30 DQS11N SCONN288_H44441003_PIP-SCONN,HA   I100 @BASEBOARD_FAB2_LIB.BASEBOARD_FAB2(SCH_1):PAGE52

M_E_DQS_DN<12> @BASEBOARD_FAB2_LIB.BASEBOARD_FAB2(SCH_1):M_E_DQS_DN(12)
  U5D1 EB73 DDR4_DQS_DN<12> SKX_EXT_B_BGA1-IC,TBD   I172 @BASEBOARD_FAB2_LIB.BASEBOARD_FAB2(SCH_1):PAGE27
  J4A2   41 DQS12N SCONN288_H44441004_PIP-SCONN,HA    I66 @BASEBOARD_FAB2_LIB.BASEBOARD_FAB2(SCH_1):PAGE51
  J6L2   41 DQS12N SCONN288_H44441003_PIP-SCONN,HA   I100 @BASEBOARD_FAB2_LIB.BASEBOARD_FAB2(SCH_1):PAGE52

M_E_DQS_DN<13> @BASEBOARD_FAB2_LIB.BASEBOARD_FAB2(SCH_1):M_E_DQS_DN(13)
  U5D1 DP41 DDR4_DQS_DN<13> SKX_EXT_B_BGA1-IC,TBD   I172 @BASEBOARD_FAB2_LIB.BASEBOARD_FAB2(SCH_1):PAGE27
  J4A2  100 DQS13N SCONN288_H44441004_PIP-SCONN,HA    I66 @BASEBOARD_FAB2_LIB.BASEBOARD_FAB2(SCH_1):PAGE51
  J6L2  100 DQS13N SCONN288_H44441003_PIP-SCONN,HA   I100 @BASEBOARD_FAB2_LIB.BASEBOARD_FAB2(SCH_1):PAGE52

M_E_DQS_DN<14> @BASEBOARD_FAB2_LIB.BASEBOARD_FAB2(SCH_1):M_E_DQS_DN(14)
  U5D1 EA32 DDR4_DQS_DN<14> SKX_EXT_B_BGA1-IC,TBD   I172 @BASEBOARD_FAB2_LIB.BASEBOARD_FAB2(SCH_1):PAGE27
  J4A2  111 DQS14N SCONN288_H44441004_PIP-SCONN,HA    I66 @BASEBOARD_FAB2_LIB.BASEBOARD_FAB2(SCH_1):PAGE51
  J6L2  111 DQS14N SCONN288_H44441003_PIP-SCONN,HA   I100 @BASEBOARD_FAB2_LIB.BASEBOARD_FAB2(SCH_1):PAGE52

M_E_DQS_DN<15> @BASEBOARD_FAB2_LIB.BASEBOARD_FAB2(SCH_1):M_E_DQS_DN(15)
  U5D1 EA26 DDR4_DQS_DN<15> SKX_EXT_B_BGA1-IC,TBD   I172 @BASEBOARD_FAB2_LIB.BASEBOARD_FAB2(SCH_1):PAGE27
  J4A2  122 DQS15N SCONN288_H44441004_PIP-SCONN,HA    I66 @BASEBOARD_FAB2_LIB.BASEBOARD_FAB2(SCH_1):PAGE51
  J6L2  122 DQS15N SCONN288_H44441003_PIP-SCONN,HA   I100 @BASEBOARD_FAB2_LIB.BASEBOARD_FAB2(SCH_1):PAGE52

M_E_DQS_DN<16> @BASEBOARD_FAB2_LIB.BASEBOARD_FAB2(SCH_1):M_E_DQS_DN(16)
  U5D1 DG26 DDR4_DQS_DN<16> SKX_EXT_B_BGA1-IC,TBD   I172 @BASEBOARD_FAB2_LIB.BASEBOARD_FAB2(SCH_1):PAGE27
  J4A2  133 DQS16N SCONN288_H44441004_PIP-SCONN,HA    I66 @BASEBOARD_FAB2_LIB.BASEBOARD_FAB2(SCH_1):PAGE51
  J6L2  133 DQS16N SCONN288_H44441003_PIP-SCONN,HA   I100 @BASEBOARD_FAB2_LIB.BASEBOARD_FAB2(SCH_1):PAGE52

M_E_DQS_DN<17> @BASEBOARD_FAB2_LIB.BASEBOARD_FAB2(SCH_1):M_E_DQS_DN(17)
  U5D1 DV67 DDR4_DQS_DN<17> SKX_EXT_B_BGA1-IC,TBD   I172 @BASEBOARD_FAB2_LIB.BASEBOARD_FAB2(SCH_1):PAGE27
  J4A2   52 DQS17N SCONN288_H44441004_PIP-SCONN,HA    I66 @BASEBOARD_FAB2_LIB.BASEBOARD_FAB2(SCH_1):PAGE51
  J6L2   52 DQS17N SCONN288_H44441003_PIP-SCONN,HA   I100 @BASEBOARD_FAB2_LIB.BASEBOARD_FAB2(SCH_1):PAGE52

M_E_DQS_DN<1> @BASEBOARD_FAB2_LIB.BASEBOARD_FAB2(SCH_1):M_E_DQS_DN(1)
  U5D1 DA82 DDR4_DQS_DN<1> SKX_EXT_B_BGA1-IC,TBD   I172 @BASEBOARD_FAB2_LIB.BASEBOARD_FAB2(SCH_1):PAGE27
  J4A2  163  DQS1N SCONN288_H44441004_PIP-SCONN,HA    I66 @BASEBOARD_FAB2_LIB.BASEBOARD_FAB2(SCH_1):PAGE51
  J6L2  163  DQS1N SCONN288_H44441003_PIP-SCONN,HA   I100 @BASEBOARD_FAB2_LIB.BASEBOARD_FAB2(SCH_1):PAGE52

M_E_DQS_DN<2> @BASEBOARD_FAB2_LIB.BASEBOARD_FAB2(SCH_1):M_E_DQS_DN(2)
  U5D1 ED79 DDR4_DQS_DN<2> SKX_EXT_B_BGA1-IC,TBD   I172 @BASEBOARD_FAB2_LIB.BASEBOARD_FAB2(SCH_1):PAGE27
  J4A2  174  DQS2N SCONN288_H44441004_PIP-SCONN,HA    I66 @BASEBOARD_FAB2_LIB.BASEBOARD_FAB2(SCH_1):PAGE51
  J6L2  174  DQS2N SCONN288_H44441003_PIP-SCONN,HA   I100 @BASEBOARD_FAB2_LIB.BASEBOARD_FAB2(SCH_1):PAGE52

M_E_DQS_DN<3> @BASEBOARD_FAB2_LIB.BASEBOARD_FAB2(SCH_1):M_E_DQS_DN(3)
  U5D1 EF73 DDR4_DQS_DN<3> SKX_EXT_B_BGA1-IC,TBD   I172 @BASEBOARD_FAB2_LIB.BASEBOARD_FAB2(SCH_1):PAGE27
  J4A2  185  DQS3N SCONN288_H44441004_PIP-SCONN,HA    I66 @BASEBOARD_FAB2_LIB.BASEBOARD_FAB2(SCH_1):PAGE51
  J6L2  185  DQS3N SCONN288_H44441003_PIP-SCONN,HA   I100 @BASEBOARD_FAB2_LIB.BASEBOARD_FAB2(SCH_1):PAGE52

M_E_DQS_DN<4> @BASEBOARD_FAB2_LIB.BASEBOARD_FAB2(SCH_1):M_E_DQS_DN(4)
  U5D1 DV41 DDR4_DQS_DN<4> SKX_EXT_B_BGA1-IC,TBD   I172 @BASEBOARD_FAB2_LIB.BASEBOARD_FAB2(SCH_1):PAGE27
  J4A2  244  DQS4N SCONN288_H44441004_PIP-SCONN,HA    I66 @BASEBOARD_FAB2_LIB.BASEBOARD_FAB2(SCH_1):PAGE51
  J6L2  244  DQS4N SCONN288_H44441003_PIP-SCONN,HA   I100 @BASEBOARD_FAB2_LIB.BASEBOARD_FAB2(SCH_1):PAGE52

M_E_DQS_DN<5> @BASEBOARD_FAB2_LIB.BASEBOARD_FAB2(SCH_1):M_E_DQS_DN(5)
  U5D1 EE32 DDR4_DQS_DN<5> SKX_EXT_B_BGA1-IC,TBD   I172 @BASEBOARD_FAB2_LIB.BASEBOARD_FAB2(SCH_1):PAGE27
  J4A2  255  DQS5N SCONN288_H44441004_PIP-SCONN,HA    I66 @BASEBOARD_FAB2_LIB.BASEBOARD_FAB2(SCH_1):PAGE51
  J6L2  255  DQS5N SCONN288_H44441003_PIP-SCONN,HA   I100 @BASEBOARD_FAB2_LIB.BASEBOARD_FAB2(SCH_1):PAGE52

M_E_DQS_DN<6> @BASEBOARD_FAB2_LIB.BASEBOARD_FAB2(SCH_1):M_E_DQS_DN(6)
  U5D1 EE26 DDR4_DQS_DN<6> SKX_EXT_B_BGA1-IC,TBD   I172 @BASEBOARD_FAB2_LIB.BASEBOARD_FAB2(SCH_1):PAGE27
  J4A2  266  DQS6N SCONN288_H44441004_PIP-SCONN,HA    I66 @BASEBOARD_FAB2_LIB.BASEBOARD_FAB2(SCH_1):PAGE51
  J6L2  266  DQS6N SCONN288_H44441003_PIP-SCONN,HA   I100 @BASEBOARD_FAB2_LIB.BASEBOARD_FAB2(SCH_1):PAGE52

M_E_DQS_DN<7> @BASEBOARD_FAB2_LIB.BASEBOARD_FAB2(SCH_1):M_E_DQS_DN(7)
  U5D1 DL26 DDR4_DQS_DN<7> SKX_EXT_B_BGA1-IC,TBD   I172 @BASEBOARD_FAB2_LIB.BASEBOARD_FAB2(SCH_1):PAGE27
  J4A2  277  DQS7N SCONN288_H44441004_PIP-SCONN,HA    I66 @BASEBOARD_FAB2_LIB.BASEBOARD_FAB2(SCH_1):PAGE51
  J6L2  277  DQS7N SCONN288_H44441003_PIP-SCONN,HA   I100 @BASEBOARD_FAB2_LIB.BASEBOARD_FAB2(SCH_1):PAGE52

M_E_DQS_DN<8> @BASEBOARD_FAB2_LIB.BASEBOARD_FAB2(SCH_1):M_E_DQS_DN(8)
  U5D1 EB67 DDR4_DQS_DN<8> SKX_EXT_B_BGA1-IC,TBD   I172 @BASEBOARD_FAB2_LIB.BASEBOARD_FAB2(SCH_1):PAGE27
  J4A2  196  DQS8N SCONN288_H44441004_PIP-SCONN,HA    I66 @BASEBOARD_FAB2_LIB.BASEBOARD_FAB2(SCH_1):PAGE51
  J6L2  196  DQS8N SCONN288_H44441003_PIP-SCONN,HA   I100 @BASEBOARD_FAB2_LIB.BASEBOARD_FAB2(SCH_1):PAGE52

M_E_DQS_DN<9> @BASEBOARD_FAB2_LIB.BASEBOARD_FAB2(SCH_1):M_E_DQS_DN(9)
  U5D1 CN80 DDR4_DQS_DN<9> SKX_EXT_B_BGA1-IC,TBD   I172 @BASEBOARD_FAB2_LIB.BASEBOARD_FAB2(SCH_1):PAGE27
  J4A2    8  DQS9N SCONN288_H44441004_PIP-SCONN,HA    I66 @BASEBOARD_FAB2_LIB.BASEBOARD_FAB2(SCH_1):PAGE51
  J6L2    8  DQS9N SCONN288_H44441003_PIP-SCONN,HA   I100 @BASEBOARD_FAB2_LIB.BASEBOARD_FAB2(SCH_1):PAGE52

M_E_DQS_DP<0> @BASEBOARD_FAB2_LIB.BASEBOARD_FAB2(SCH_1):M_E_DQS_DP(0)
  U5D1 CM81 DDR4_DQS_DP<0> SKX_EXT_B_BGA1-IC,TBD   I172 @BASEBOARD_FAB2_LIB.BASEBOARD_FAB2(SCH_1):PAGE27
  J4A2  153  DQS0P SCONN288_H44441004_PIP-SCONN,HA    I66 @BASEBOARD_FAB2_LIB.BASEBOARD_FAB2(SCH_1):PAGE51
  J6L2  153  DQS0P SCONN288_H44441003_PIP-SCONN,HA   I100 @BASEBOARD_FAB2_LIB.BASEBOARD_FAB2(SCH_1):PAGE52

M_E_DQS_DP<10> @BASEBOARD_FAB2_LIB.BASEBOARD_FAB2(SCH_1):M_E_DQS_DP(10)
  U5D1 DD79 DDR4_DQS_DP<10> SKX_EXT_B_BGA1-IC,TBD   I172 @BASEBOARD_FAB2_LIB.BASEBOARD_FAB2(SCH_1):PAGE27
  J4A2   18 DQS10P SCONN288_H44441004_PIP-SCONN,HA    I66 @BASEBOARD_FAB2_LIB.BASEBOARD_FAB2(SCH_1):PAGE51
  J6L2   18 DQS10P SCONN288_H44441003_PIP-SCONN,HA   I100 @BASEBOARD_FAB2_LIB.BASEBOARD_FAB2(SCH_1):PAGE52

M_E_DQS_DP<11> @BASEBOARD_FAB2_LIB.BASEBOARD_FAB2(SCH_1):M_E_DQS_DP(11)
  U5D1 DV79 DDR4_DQS_DP<11> SKX_EXT_B_BGA1-IC,TBD   I172 @BASEBOARD_FAB2_LIB.BASEBOARD_FAB2(SCH_1):PAGE27
  J4A2   29 DQS11P SCONN288_H44441004_PIP-SCONN,HA    I66 @BASEBOARD_FAB2_LIB.BASEBOARD_FAB2(SCH_1):PAGE51
  J6L2   29 DQS11P SCONN288_H44441003_PIP-SCONN,HA   I100 @BASEBOARD_FAB2_LIB.BASEBOARD_FAB2(SCH_1):PAGE52

M_E_DQS_DP<12> @BASEBOARD_FAB2_LIB.BASEBOARD_FAB2(SCH_1):M_E_DQS_DP(12)
  U5D1 DY73 DDR4_DQS_DP<12> SKX_EXT_B_BGA1-IC,TBD   I172 @BASEBOARD_FAB2_LIB.BASEBOARD_FAB2(SCH_1):PAGE27
  J4A2   40 DQS12P SCONN288_H44441004_PIP-SCONN,HA    I66 @BASEBOARD_FAB2_LIB.BASEBOARD_FAB2(SCH_1):PAGE51
  J6L2   40 DQS12P SCONN288_H44441003_PIP-SCONN,HA   I100 @BASEBOARD_FAB2_LIB.BASEBOARD_FAB2(SCH_1):PAGE52

M_E_DQS_DP<13> @BASEBOARD_FAB2_LIB.BASEBOARD_FAB2(SCH_1):M_E_DQS_DP(13)
  U5D1 DM41 DDR4_DQS_DP<13> SKX_EXT_B_BGA1-IC,TBD   I172 @BASEBOARD_FAB2_LIB.BASEBOARD_FAB2(SCH_1):PAGE27
  J4A2   99 DQS13P SCONN288_H44441004_PIP-SCONN,HA    I66 @BASEBOARD_FAB2_LIB.BASEBOARD_FAB2(SCH_1):PAGE51
  J6L2   99 DQS13P SCONN288_H44441003_PIP-SCONN,HA   I100 @BASEBOARD_FAB2_LIB.BASEBOARD_FAB2(SCH_1):PAGE52

M_E_DQS_DP<14> @BASEBOARD_FAB2_LIB.BASEBOARD_FAB2(SCH_1):M_E_DQS_DP(14)
  U5D1 DW32 DDR4_DQS_DP<14> SKX_EXT_B_BGA1-IC,TBD   I172 @BASEBOARD_FAB2_LIB.BASEBOARD_FAB2(SCH_1):PAGE27
  J4A2  110 DQS14P SCONN288_H44441004_PIP-SCONN,HA    I66 @BASEBOARD_FAB2_LIB.BASEBOARD_FAB2(SCH_1):PAGE51
  J6L2  110 DQS14P SCONN288_H44441003_PIP-SCONN,HA   I100 @BASEBOARD_FAB2_LIB.BASEBOARD_FAB2(SCH_1):PAGE52

M_E_DQS_DP<15> @BASEBOARD_FAB2_LIB.BASEBOARD_FAB2(SCH_1):M_E_DQS_DP(15)
  U5D1 DW26 DDR4_DQS_DP<15> SKX_EXT_B_BGA1-IC,TBD   I172 @BASEBOARD_FAB2_LIB.BASEBOARD_FAB2(SCH_1):PAGE27
  J4A2  121 DQS15P SCONN288_H44441004_PIP-SCONN,HA    I66 @BASEBOARD_FAB2_LIB.BASEBOARD_FAB2(SCH_1):PAGE51
  J6L2  121 DQS15P SCONN288_H44441003_PIP-SCONN,HA   I100 @BASEBOARD_FAB2_LIB.BASEBOARD_FAB2(SCH_1):PAGE52

M_E_DQS_DP<16> @BASEBOARD_FAB2_LIB.BASEBOARD_FAB2(SCH_1):M_E_DQS_DP(16)
  U5D1 DE26 DDR4_DQS_DP<16> SKX_EXT_B_BGA1-IC,TBD   I172 @BASEBOARD_FAB2_LIB.BASEBOARD_FAB2(SCH_1):PAGE27
  J4A2  132 DQS16P SCONN288_H44441004_PIP-SCONN,HA    I66 @BASEBOARD_FAB2_LIB.BASEBOARD_FAB2(SCH_1):PAGE51
  J6L2  132 DQS16P SCONN288_H44441003_PIP-SCONN,HA   I100 @BASEBOARD_FAB2_LIB.BASEBOARD_FAB2(SCH_1):PAGE52

M_E_DQS_DP<17> @BASEBOARD_FAB2_LIB.BASEBOARD_FAB2(SCH_1):M_E_DQS_DP(17)
  U5D1 DT67 DDR4_DQS_DP<17> SKX_EXT_B_BGA1-IC,TBD   I172 @BASEBOARD_FAB2_LIB.BASEBOARD_FAB2(SCH_1):PAGE27
  J4A2   51 DQS17P SCONN288_H44441004_PIP-SCONN,HA    I66 @BASEBOARD_FAB2_LIB.BASEBOARD_FAB2(SCH_1):PAGE51
  J6L2   51 DQS17P SCONN288_H44441003_PIP-SCONN,HA   I100 @BASEBOARD_FAB2_LIB.BASEBOARD_FAB2(SCH_1):PAGE52

M_E_DQS_DP<1> @BASEBOARD_FAB2_LIB.BASEBOARD_FAB2(SCH_1):M_E_DQS_DP(1)
  U5D1 DB81 DDR4_DQS_DP<1> SKX_EXT_B_BGA1-IC,TBD   I172 @BASEBOARD_FAB2_LIB.BASEBOARD_FAB2(SCH_1):PAGE27
  J4A2  164  DQS1P SCONN288_H44441004_PIP-SCONN,HA    I66 @BASEBOARD_FAB2_LIB.BASEBOARD_FAB2(SCH_1):PAGE51
  J6L2  164  DQS1P SCONN288_H44441003_PIP-SCONN,HA   I100 @BASEBOARD_FAB2_LIB.BASEBOARD_FAB2(SCH_1):PAGE52

M_E_DQS_DP<2> @BASEBOARD_FAB2_LIB.BASEBOARD_FAB2(SCH_1):M_E_DQS_DP(2)
  U5D1 EB79 DDR4_DQS_DP<2> SKX_EXT_B_BGA1-IC,TBD   I172 @BASEBOARD_FAB2_LIB.BASEBOARD_FAB2(SCH_1):PAGE27
  J4A2  175  DQS2P SCONN288_H44441004_PIP-SCONN,HA    I66 @BASEBOARD_FAB2_LIB.BASEBOARD_FAB2(SCH_1):PAGE51
  J6L2  175  DQS2P SCONN288_H44441003_PIP-SCONN,HA   I100 @BASEBOARD_FAB2_LIB.BASEBOARD_FAB2(SCH_1):PAGE52

M_E_DQS_DP<3> @BASEBOARD_FAB2_LIB.BASEBOARD_FAB2(SCH_1):M_E_DQS_DP(3)
  U5D1 ED73 DDR4_DQS_DP<3> SKX_EXT_B_BGA1-IC,TBD   I172 @BASEBOARD_FAB2_LIB.BASEBOARD_FAB2(SCH_1):PAGE27
  J4A2  186  DQS3P SCONN288_H44441004_PIP-SCONN,HA    I66 @BASEBOARD_FAB2_LIB.BASEBOARD_FAB2(SCH_1):PAGE51
  J6L2  186  DQS3P SCONN288_H44441003_PIP-SCONN,HA   I100 @BASEBOARD_FAB2_LIB.BASEBOARD_FAB2(SCH_1):PAGE52

M_E_DQS_DP<4> @BASEBOARD_FAB2_LIB.BASEBOARD_FAB2(SCH_1):M_E_DQS_DP(4)
  U5D1 DT41 DDR4_DQS_DP<4> SKX_EXT_B_BGA1-IC,TBD   I172 @BASEBOARD_FAB2_LIB.BASEBOARD_FAB2(SCH_1):PAGE27
  J4A2  245  DQS4P SCONN288_H44441004_PIP-SCONN,HA    I66 @BASEBOARD_FAB2_LIB.BASEBOARD_FAB2(SCH_1):PAGE51
  J6L2  245  DQS4P SCONN288_H44441003_PIP-SCONN,HA   I100 @BASEBOARD_FAB2_LIB.BASEBOARD_FAB2(SCH_1):PAGE52

M_E_DQS_DP<5> @BASEBOARD_FAB2_LIB.BASEBOARD_FAB2(SCH_1):M_E_DQS_DP(5)
  U5D1 EC32 DDR4_DQS_DP<5> SKX_EXT_B_BGA1-IC,TBD   I172 @BASEBOARD_FAB2_LIB.BASEBOARD_FAB2(SCH_1):PAGE27
  J4A2  256  DQS5P SCONN288_H44441004_PIP-SCONN,HA    I66 @BASEBOARD_FAB2_LIB.BASEBOARD_FAB2(SCH_1):PAGE51
  J6L2  256  DQS5P SCONN288_H44441003_PIP-SCONN,HA   I100 @BASEBOARD_FAB2_LIB.BASEBOARD_FAB2(SCH_1):PAGE52

M_E_DQS_DP<6> @BASEBOARD_FAB2_LIB.BASEBOARD_FAB2(SCH_1):M_E_DQS_DP(6)
  U5D1 EC26 DDR4_DQS_DP<6> SKX_EXT_B_BGA1-IC,TBD   I172 @BASEBOARD_FAB2_LIB.BASEBOARD_FAB2(SCH_1):PAGE27
  J4A2  267  DQS6P SCONN288_H44441004_PIP-SCONN,HA    I66 @BASEBOARD_FAB2_LIB.BASEBOARD_FAB2(SCH_1):PAGE51
  J6L2  267  DQS6P SCONN288_H44441003_PIP-SCONN,HA   I100 @BASEBOARD_FAB2_LIB.BASEBOARD_FAB2(SCH_1):PAGE52

M_E_DQS_DP<7> @BASEBOARD_FAB2_LIB.BASEBOARD_FAB2(SCH_1):M_E_DQS_DP(7)
  U5D1 DJ26 DDR4_DQS_DP<7> SKX_EXT_B_BGA1-IC,TBD   I172 @BASEBOARD_FAB2_LIB.BASEBOARD_FAB2(SCH_1):PAGE27
  J4A2  278  DQS7P SCONN288_H44441004_PIP-SCONN,HA    I66 @BASEBOARD_FAB2_LIB.BASEBOARD_FAB2(SCH_1):PAGE51
  J6L2  278  DQS7P SCONN288_H44441003_PIP-SCONN,HA   I100 @BASEBOARD_FAB2_LIB.BASEBOARD_FAB2(SCH_1):PAGE52

M_E_DQS_DP<8> @BASEBOARD_FAB2_LIB.BASEBOARD_FAB2(SCH_1):M_E_DQS_DP(8)
  U5D1 DY67 DDR4_DQS_DP<8> SKX_EXT_B_BGA1-IC,TBD   I172 @BASEBOARD_FAB2_LIB.BASEBOARD_FAB2(SCH_1):PAGE27
  J4A2  197  DQS8P SCONN288_H44441004_PIP-SCONN,HA    I66 @BASEBOARD_FAB2_LIB.BASEBOARD_FAB2(SCH_1):PAGE51
  J6L2  197  DQS8P SCONN288_H44441003_PIP-SCONN,HA   I100 @BASEBOARD_FAB2_LIB.BASEBOARD_FAB2(SCH_1):PAGE52

M_E_DQS_DP<9> @BASEBOARD_FAB2_LIB.BASEBOARD_FAB2(SCH_1):M_E_DQS_DP(9)
  U5D1 CP79 DDR4_DQS_DP<9> SKX_EXT_B_BGA1-IC,TBD   I172 @BASEBOARD_FAB2_LIB.BASEBOARD_FAB2(SCH_1):PAGE27
  J4A2    7  DQS9P SCONN288_H44441004_PIP-SCONN,HA    I66 @BASEBOARD_FAB2_LIB.BASEBOARD_FAB2(SCH_1):PAGE51
  J6L2    7  DQS9P SCONN288_H44441003_PIP-SCONN,HA   I100 @BASEBOARD_FAB2_LIB.BASEBOARD_FAB2(SCH_1):PAGE52

M_E_ECC<0> @BASEBOARD_FAB2_LIB.BASEBOARD_FAB2(SCH_1):M_E_ECC(0)
  U5D1 DY69 DDR4_ECC<0> SKX_EXT_B_BGA1-IC,TBD   I172 @BASEBOARD_FAB2_LIB.BASEBOARD_FAB2(SCH_1):PAGE27
  J4A2  194  CB<1> SCONN288_H44441004_PIP-SCONN,HA   I111 @BASEBOARD_FAB2_LIB.BASEBOARD_FAB2(SCH_1):PAGE51
  J6L2   49  CB<0> SCONN288_H44441003_PIP-SCONN,HA    I12 @BASEBOARD_FAB2_LIB.BASEBOARD_FAB2(SCH_1):PAGE52

M_E_ECC<1> @BASEBOARD_FAB2_LIB.BASEBOARD_FAB2(SCH_1):M_E_ECC(1)
  U5D1 EA68 DDR4_ECC<1> SKX_EXT_B_BGA1-IC,TBD   I172 @BASEBOARD_FAB2_LIB.BASEBOARD_FAB2(SCH_1):PAGE27
  J4A2   49  CB<0> SCONN288_H44441004_PIP-SCONN,HA   I111 @BASEBOARD_FAB2_LIB.BASEBOARD_FAB2(SCH_1):PAGE51
  J6L2  194  CB<1> SCONN288_H44441003_PIP-SCONN,HA    I12 @BASEBOARD_FAB2_LIB.BASEBOARD_FAB2(SCH_1):PAGE52

M_E_ECC<2> @BASEBOARD_FAB2_LIB.BASEBOARD_FAB2(SCH_1):M_E_ECC(2)
  U5D1 DV65 DDR4_ECC<2> SKX_EXT_B_BGA1-IC,TBD   I172 @BASEBOARD_FAB2_LIB.BASEBOARD_FAB2(SCH_1):PAGE27
  J4A2  201  CB<3> SCONN288_H44441004_PIP-SCONN,HA   I111 @BASEBOARD_FAB2_LIB.BASEBOARD_FAB2(SCH_1):PAGE51
  J6L2   56  CB<2> SCONN288_H44441003_PIP-SCONN,HA    I12 @BASEBOARD_FAB2_LIB.BASEBOARD_FAB2(SCH_1):PAGE52

M_E_ECC<3> @BASEBOARD_FAB2_LIB.BASEBOARD_FAB2(SCH_1):M_E_ECC(3)
  U5D1 DY65 DDR4_ECC<3> SKX_EXT_B_BGA1-IC,TBD   I172 @BASEBOARD_FAB2_LIB.BASEBOARD_FAB2(SCH_1):PAGE27
  J4A2   56  CB<2> SCONN288_H44441004_PIP-SCONN,HA   I111 @BASEBOARD_FAB2_LIB.BASEBOARD_FAB2(SCH_1):PAGE51
  J6L2  201  CB<3> SCONN288_H44441003_PIP-SCONN,HA    I12 @BASEBOARD_FAB2_LIB.BASEBOARD_FAB2(SCH_1):PAGE52

M_E_ECC<4> @BASEBOARD_FAB2_LIB.BASEBOARD_FAB2(SCH_1):M_E_ECC(4)
  U5D1 DU68 DDR4_ECC<4> SKX_EXT_B_BGA1-IC,TBD   I172 @BASEBOARD_FAB2_LIB.BASEBOARD_FAB2(SCH_1):PAGE27
  J4A2  192  CB<5> SCONN288_H44441004_PIP-SCONN,HA   I111 @BASEBOARD_FAB2_LIB.BASEBOARD_FAB2(SCH_1):PAGE51
  J6L2   47  CB<4> SCONN288_H44441003_PIP-SCONN,HA    I12 @BASEBOARD_FAB2_LIB.BASEBOARD_FAB2(SCH_1):PAGE52

M_E_ECC<5> @BASEBOARD_FAB2_LIB.BASEBOARD_FAB2(SCH_1):M_E_ECC(5)
  U5D1 DV69 DDR4_ECC<5> SKX_EXT_B_BGA1-IC,TBD   I172 @BASEBOARD_FAB2_LIB.BASEBOARD_FAB2(SCH_1):PAGE27
  J4A2   47  CB<4> SCONN288_H44441004_PIP-SCONN,HA   I111 @BASEBOARD_FAB2_LIB.BASEBOARD_FAB2(SCH_1):PAGE51
  J6L2  192  CB<5> SCONN288_H44441003_PIP-SCONN,HA    I12 @BASEBOARD_FAB2_LIB.BASEBOARD_FAB2(SCH_1):PAGE52

M_E_ECC<6> @BASEBOARD_FAB2_LIB.BASEBOARD_FAB2(SCH_1):M_E_ECC(6)
  U5D1 DU66 DDR4_ECC<6> SKX_EXT_B_BGA1-IC,TBD   I172 @BASEBOARD_FAB2_LIB.BASEBOARD_FAB2(SCH_1):PAGE27
  J4A2  199  CB<7> SCONN288_H44441004_PIP-SCONN,HA   I111 @BASEBOARD_FAB2_LIB.BASEBOARD_FAB2(SCH_1):PAGE51
  J6L2   54  CB<6> SCONN288_H44441003_PIP-SCONN,HA    I12 @BASEBOARD_FAB2_LIB.BASEBOARD_FAB2(SCH_1):PAGE52

M_E_ECC<7> @BASEBOARD_FAB2_LIB.BASEBOARD_FAB2(SCH_1):M_E_ECC(7)
  U5D1 EA66 DDR4_ECC<7> SKX_EXT_B_BGA1-IC,TBD   I172 @BASEBOARD_FAB2_LIB.BASEBOARD_FAB2(SCH_1):PAGE27
  J4A2   54  CB<6> SCONN288_H44441004_PIP-SCONN,HA   I111 @BASEBOARD_FAB2_LIB.BASEBOARD_FAB2(SCH_1):PAGE51
  J6L2  199  CB<7> SCONN288_H44441003_PIP-SCONN,HA    I12 @BASEBOARD_FAB2_LIB.BASEBOARD_FAB2(SCH_1):PAGE52

M_E_MA<0> @BASEBOARD_FAB2_LIB.BASEBOARD_FAB2(SCH_1):M_E_MA(0)
  U5D1 DW52 DDR4_MA<0> SKX_EXT_B_BGA1-IC,TBD   I172 @BASEBOARD_FAB2_LIB.BASEBOARD_FAB2(SCH_1):PAGE27
  J4A2   79     A0 SCONN288_H44441004_PIP-SCONN,HA   I111 @BASEBOARD_FAB2_LIB.BASEBOARD_FAB2(SCH_1):PAGE51
  J6L2   79     A0 SCONN288_H44441003_PIP-SCONN,HA    I12 @BASEBOARD_FAB2_LIB.BASEBOARD_FAB2(SCH_1):PAGE52

M_E_MA<10> @BASEBOARD_FAB2_LIB.BASEBOARD_FAB2(SCH_1):M_E_MA(10)
  U5D1 DT55 DDR4_MA<10> SKX_EXT_B_BGA1-IC,TBD   I172 @BASEBOARD_FAB2_LIB.BASEBOARD_FAB2(SCH_1):PAGE27
  J4A2  225    A10 SCONN288_H44441004_PIP-SCONN,HA   I111 @BASEBOARD_FAB2_LIB.BASEBOARD_FAB2(SCH_1):PAGE51
  J6L2  225    A10 SCONN288_H44441003_PIP-SCONN,HA    I12 @BASEBOARD_FAB2_LIB.BASEBOARD_FAB2(SCH_1):PAGE52

M_E_MA<11> @BASEBOARD_FAB2_LIB.BASEBOARD_FAB2(SCH_1):M_E_MA(11)
  U5D1 DR60 DDR4_MA<11> SKX_EXT_B_BGA1-IC,TBD   I172 @BASEBOARD_FAB2_LIB.BASEBOARD_FAB2(SCH_1):PAGE27
  J4A2  210    A11 SCONN288_H44441004_PIP-SCONN,HA   I111 @BASEBOARD_FAB2_LIB.BASEBOARD_FAB2(SCH_1):PAGE51
  J6L2  210    A11 SCONN288_H44441003_PIP-SCONN,HA    I12 @BASEBOARD_FAB2_LIB.BASEBOARD_FAB2(SCH_1):PAGE52

M_E_MA<12> @BASEBOARD_FAB2_LIB.BASEBOARD_FAB2(SCH_1):M_E_MA(12)
  U5D1 DN60 DDR4_MA<12> SKX_EXT_B_BGA1-IC,TBD   I172 @BASEBOARD_FAB2_LIB.BASEBOARD_FAB2(SCH_1):PAGE27
  J4A2   65    A12 SCONN288_H44441004_PIP-SCONN,HA   I111 @BASEBOARD_FAB2_LIB.BASEBOARD_FAB2(SCH_1):PAGE51
  J6L2   65    A12 SCONN288_H44441003_PIP-SCONN,HA    I12 @BASEBOARD_FAB2_LIB.BASEBOARD_FAB2(SCH_1):PAGE52

M_E_MA<13> @BASEBOARD_FAB2_LIB.BASEBOARD_FAB2(SCH_1):M_E_MA(13)
  U5D1 DT51 DDR4_MA<13> SKX_EXT_B_BGA1-IC,TBD   I172 @BASEBOARD_FAB2_LIB.BASEBOARD_FAB2(SCH_1):PAGE27
  J4A2  232    A13 SCONN288_H44441004_PIP-SCONN,HA   I111 @BASEBOARD_FAB2_LIB.BASEBOARD_FAB2(SCH_1):PAGE51
  J6L2  232    A13 SCONN288_H44441003_PIP-SCONN,HA    I12 @BASEBOARD_FAB2_LIB.BASEBOARD_FAB2(SCH_1):PAGE52

M_E_MA<14> @BASEBOARD_FAB2_LIB.BASEBOARD_FAB2(SCH_1):M_E_MA(14)
  U5D1 DM51 DDR4_MA<14> SKX_EXT_B_BGA1-IC,TBD   I172 @BASEBOARD_FAB2_LIB.BASEBOARD_FAB2(SCH_1):PAGE27
  J4A2  228 A14_WE_N SCONN288_H44441004_PIP-SCONN,HA   I111 @BASEBOARD_FAB2_LIB.BASEBOARD_FAB2(SCH_1):PAGE51
  J6L2  228 A14_WE_N SCONN288_H44441003_PIP-SCONN,HA    I12 @BASEBOARD_FAB2_LIB.BASEBOARD_FAB2(SCH_1):PAGE52

M_E_MA<15> @BASEBOARD_FAB2_LIB.BASEBOARD_FAB2(SCH_1):M_E_MA(15)
  U5D1 DR52 DDR4_MA<15> SKX_EXT_B_BGA1-IC,TBD   I172 @BASEBOARD_FAB2_LIB.BASEBOARD_FAB2(SCH_1):PAGE27
  J4A2   86 A15_CAS_N SCONN288_H44441004_PIP-SCONN,HA   I111 @BASEBOARD_FAB2_LIB.BASEBOARD_FAB2(SCH_1):PAGE51
  J6L2   86 A15_CAS_N SCONN288_H44441003_PIP-SCONN,HA    I12 @BASEBOARD_FAB2_LIB.BASEBOARD_FAB2(SCH_1):PAGE52

M_E_MA<16> @BASEBOARD_FAB2_LIB.BASEBOARD_FAB2(SCH_1):M_E_MA(16)
  U5D1 DN52 DDR4_MA<16> SKX_EXT_B_BGA1-IC,TBD   I172 @BASEBOARD_FAB2_LIB.BASEBOARD_FAB2(SCH_1):PAGE27
  J4A2   82 A16_RAS_N SCONN288_H44441004_PIP-SCONN,HA   I111 @BASEBOARD_FAB2_LIB.BASEBOARD_FAB2(SCH_1):PAGE51
  J6L2   82 A16_RAS_N SCONN288_H44441003_PIP-SCONN,HA    I12 @BASEBOARD_FAB2_LIB.BASEBOARD_FAB2(SCH_1):PAGE52

M_E_MA<17> @BASEBOARD_FAB2_LIB.BASEBOARD_FAB2(SCH_1):M_E_MA(17)
  U5D1 DR48 DDR4_MA<17> SKX_EXT_B_BGA1-IC,TBD   I172 @BASEBOARD_FAB2_LIB.BASEBOARD_FAB2(SCH_1):PAGE27
  J4A2  234    A17 SCONN288_H44441004_PIP-SCONN,HA   I111 @BASEBOARD_FAB2_LIB.BASEBOARD_FAB2(SCH_1):PAGE51
  J6L2  234    A17 SCONN288_H44441003_PIP-SCONN,HA    I12 @BASEBOARD_FAB2_LIB.BASEBOARD_FAB2(SCH_1):PAGE52

M_E_MA<1> @BASEBOARD_FAB2_LIB.BASEBOARD_FAB2(SCH_1):M_E_MA(1)
  U5D1 DW58 DDR4_MA<1> SKX_EXT_B_BGA1-IC,TBD   I172 @BASEBOARD_FAB2_LIB.BASEBOARD_FAB2(SCH_1):PAGE27
  J4A2   72     A1 SCONN288_H44441004_PIP-SCONN,HA   I111 @BASEBOARD_FAB2_LIB.BASEBOARD_FAB2(SCH_1):PAGE51
  J6L2   72     A1 SCONN288_H44441003_PIP-SCONN,HA    I12 @BASEBOARD_FAB2_LIB.BASEBOARD_FAB2(SCH_1):PAGE52

M_E_MA<2> @BASEBOARD_FAB2_LIB.BASEBOARD_FAB2(SCH_1):M_E_MA(2)
  U5D1 DV57 DDR4_MA<2> SKX_EXT_B_BGA1-IC,TBD   I172 @BASEBOARD_FAB2_LIB.BASEBOARD_FAB2(SCH_1):PAGE27
  J4A2  216     A2 SCONN288_H44441004_PIP-SCONN,HA   I111 @BASEBOARD_FAB2_LIB.BASEBOARD_FAB2(SCH_1):PAGE51
  J6L2  216     A2 SCONN288_H44441003_PIP-SCONN,HA    I12 @BASEBOARD_FAB2_LIB.BASEBOARD_FAB2(SCH_1):PAGE52

M_E_MA<3> @BASEBOARD_FAB2_LIB.BASEBOARD_FAB2(SCH_1):M_E_MA(3)
  U5D1 DR58 DDR4_MA<3> SKX_EXT_B_BGA1-IC,TBD   I172 @BASEBOARD_FAB2_LIB.BASEBOARD_FAB2(SCH_1):PAGE27
  J4A2   71     A3 SCONN288_H44441004_PIP-SCONN,HA   I111 @BASEBOARD_FAB2_LIB.BASEBOARD_FAB2(SCH_1):PAGE51
  J6L2   71     A3 SCONN288_H44441003_PIP-SCONN,HA    I12 @BASEBOARD_FAB2_LIB.BASEBOARD_FAB2(SCH_1):PAGE52

M_E_MA<4> @BASEBOARD_FAB2_LIB.BASEBOARD_FAB2(SCH_1):M_E_MA(4)
  U5D1 DT59 DDR4_MA<4> SKX_EXT_B_BGA1-IC,TBD   I172 @BASEBOARD_FAB2_LIB.BASEBOARD_FAB2(SCH_1):PAGE27
  J4A2  214     A4 SCONN288_H44441004_PIP-SCONN,HA   I111 @BASEBOARD_FAB2_LIB.BASEBOARD_FAB2(SCH_1):PAGE51
  J6L2  214     A4 SCONN288_H44441003_PIP-SCONN,HA    I12 @BASEBOARD_FAB2_LIB.BASEBOARD_FAB2(SCH_1):PAGE52

M_E_MA<5> @BASEBOARD_FAB2_LIB.BASEBOARD_FAB2(SCH_1):M_E_MA(5)
  U5D1 DN58 DDR4_MA<5> SKX_EXT_B_BGA1-IC,TBD   I172 @BASEBOARD_FAB2_LIB.BASEBOARD_FAB2(SCH_1):PAGE27
  J4A2  213     A5 SCONN288_H44441004_PIP-SCONN,HA   I111 @BASEBOARD_FAB2_LIB.BASEBOARD_FAB2(SCH_1):PAGE51
  J6L2  213     A5 SCONN288_H44441003_PIP-SCONN,HA    I12 @BASEBOARD_FAB2_LIB.BASEBOARD_FAB2(SCH_1):PAGE52

M_E_MA<6> @BASEBOARD_FAB2_LIB.BASEBOARD_FAB2(SCH_1):M_E_MA(6)
  U5D1 DM59 DDR4_MA<6> SKX_EXT_B_BGA1-IC,TBD   I172 @BASEBOARD_FAB2_LIB.BASEBOARD_FAB2(SCH_1):PAGE27
  J4A2   69     A6 SCONN288_H44441004_PIP-SCONN,HA   I111 @BASEBOARD_FAB2_LIB.BASEBOARD_FAB2(SCH_1):PAGE51
  J6L2   69     A6 SCONN288_H44441003_PIP-SCONN,HA    I12 @BASEBOARD_FAB2_LIB.BASEBOARD_FAB2(SCH_1):PAGE52

M_E_MA<7> @BASEBOARD_FAB2_LIB.BASEBOARD_FAB2(SCH_1):M_E_MA(7)
  U5D1 DK61 DDR4_MA<7> SKX_EXT_B_BGA1-IC,TBD   I172 @BASEBOARD_FAB2_LIB.BASEBOARD_FAB2(SCH_1):PAGE27
  J4A2  211     A7 SCONN288_H44441004_PIP-SCONN,HA   I111 @BASEBOARD_FAB2_LIB.BASEBOARD_FAB2(SCH_1):PAGE51
  J6L2  211     A7 SCONN288_H44441003_PIP-SCONN,HA    I12 @BASEBOARD_FAB2_LIB.BASEBOARD_FAB2(SCH_1):PAGE52

M_E_MA<8> @BASEBOARD_FAB2_LIB.BASEBOARD_FAB2(SCH_1):M_E_MA(8)
  U5D1 DJ60 DDR4_MA<8> SKX_EXT_B_BGA1-IC,TBD   I172 @BASEBOARD_FAB2_LIB.BASEBOARD_FAB2(SCH_1):PAGE27
  J4A2   68     A8 SCONN288_H44441004_PIP-SCONN,HA   I111 @BASEBOARD_FAB2_LIB.BASEBOARD_FAB2(SCH_1):PAGE51
  J6L2   68     A8 SCONN288_H44441003_PIP-SCONN,HA    I12 @BASEBOARD_FAB2_LIB.BASEBOARD_FAB2(SCH_1):PAGE52

M_E_MA<9> @BASEBOARD_FAB2_LIB.BASEBOARD_FAB2(SCH_1):M_E_MA(9)
  U5D1 DV59 DDR4_MA<9> SKX_EXT_B_BGA1-IC,TBD   I172 @BASEBOARD_FAB2_LIB.BASEBOARD_FAB2(SCH_1):PAGE27
  J4A2   66     A9 SCONN288_H44441004_PIP-SCONN,HA   I111 @BASEBOARD_FAB2_LIB.BASEBOARD_FAB2(SCH_1):PAGE51
  J6L2   66     A9 SCONN288_H44441003_PIP-SCONN,HA    I12 @BASEBOARD_FAB2_LIB.BASEBOARD_FAB2(SCH_1):PAGE52

M_E_ODT<0> @BASEBOARD_FAB2_LIB.BASEBOARD_FAB2(SCH_1):M_E_ODT(0)
  U5D1 DR50 DDR4_ODT<0> SKX_EXT_B_BGA1-IC,TBD   I172 @BASEBOARD_FAB2_LIB.BASEBOARD_FAB2(SCH_1):PAGE27
  J4A2   87 ODT<0> SCONN288_H44441004_PIP-SCONN,HA   I111 @BASEBOARD_FAB2_LIB.BASEBOARD_FAB2(SCH_1):PAGE51

M_E_ODT<1> @BASEBOARD_FAB2_LIB.BASEBOARD_FAB2(SCH_1):M_E_ODT(1)
  U5D1 DN48 DDR4_ODT<1> SKX_EXT_B_BGA1-IC,TBD   I172 @BASEBOARD_FAB2_LIB.BASEBOARD_FAB2(SCH_1):PAGE27
  J4A2   91 ODT<1> SCONN288_H44441004_PIP-SCONN,HA   I111 @BASEBOARD_FAB2_LIB.BASEBOARD_FAB2(SCH_1):PAGE51

M_E_ODT<2> @BASEBOARD_FAB2_LIB.BASEBOARD_FAB2(SCH_1):M_E_ODT(2)
  U5D1 DT49 DDR4_ODT<2> SKX_EXT_B_BGA1-IC,TBD   I172 @BASEBOARD_FAB2_LIB.BASEBOARD_FAB2(SCH_1):PAGE27
  J6L2   87 ODT<0> SCONN288_H44441003_PIP-SCONN,HA    I12 @BASEBOARD_FAB2_LIB.BASEBOARD_FAB2(SCH_1):PAGE52

M_E_ODT<3> @BASEBOARD_FAB2_LIB.BASEBOARD_FAB2(SCH_1):M_E_ODT(3)
  U5D1 DM47 DDR4_ODT<3> SKX_EXT_B_BGA1-IC,TBD   I172 @BASEBOARD_FAB2_LIB.BASEBOARD_FAB2(SCH_1):PAGE27
  J6L2   91 ODT<1> SCONN288_H44441003_PIP-SCONN,HA    I12 @BASEBOARD_FAB2_LIB.BASEBOARD_FAB2(SCH_1):PAGE52

M_E_PAR @BASEBOARD_FAB2_LIB.BASEBOARD_FAB2(SCH_1):M_E_PAR
  U5D1 DV53 DDR4_PAR SKX_EXT_B_BGA1-IC,TBD   I172 @BASEBOARD_FAB2_LIB.BASEBOARD_FAB2(SCH_1):PAGE27
  J4A2  222    PAR SCONN288_H44441004_PIP-SCONN,HA   I111 @BASEBOARD_FAB2_LIB.BASEBOARD_FAB2(SCH_1):PAGE51
  J6L2  222    PAR SCONN288_H44441003_PIP-SCONN,HA    I12 @BASEBOARD_FAB2_LIB.BASEBOARD_FAB2(SCH_1):PAGE52

M_E_VREF @BASEBOARD_FAB2_LIB.BASEBOARD_FAB2(SCH_1):M_E_VREF
  J4A2  146 VREFCA SCONN288_H44441004_PIP-SCONN,HA   I111 @BASEBOARD_FAB2_LIB.BASEBOARD_FAB2(SCH_1):PAGE51
  C6L6    1      A CAP_A_0402V-0.01UF,25V,10%,X7RA   I175 @BASEBOARD_FAB2_LIB.BASEBOARD_FAB2(SCH_1):PAGE51
 C4A18    1      A CAP_A_0402V-0.01UF,25V,10%,X7RA     I3 @BASEBOARD_FAB2_LIB.BASEBOARD_FAB2(SCH_1):PAGE52
  J6L2  146 VREFCA SCONN288_H44441003_PIP-SCONN,HA    I12 @BASEBOARD_FAB2_LIB.BASEBOARD_FAB2(SCH_1):PAGE52
 R6L13    2      B RES_0402-1.00K,1%,1/16W,CHIP,GA    I54 @BASEBOARD_FAB2_LIB.BASEBOARD_FAB2(SCH_1):PAGE98
 R6L12    1      A RES_0402-1.00K,1%,1/16W,CHIP,GA    I56 @BASEBOARD_FAB2_LIB.BASEBOARD_FAB2(SCH_1):PAGE98
 R6L14    2      B RES_0402-2,1.0%,1/16W,CHIP,G21A    I58 @BASEBOARD_FAB2_LIB.BASEBOARD_FAB2(SCH_1):PAGE98

M_F_ACT_N @BASEBOARD_FAB2_LIB.BASEBOARD_FAB2(SCH_1):M_F_ACT_N
  U5D1 DC62 DDR5_ACT_N SKX_EXT_B_BGA1-IC,TBD   I172 @BASEBOARD_FAB2_LIB.BASEBOARD_FAB2(SCH_1):PAGE28
  J4A1   62  ACT_N SCONN288_H44441004_PIP-SCONN,HA   I111 @BASEBOARD_FAB2_LIB.BASEBOARD_FAB2(SCH_1):PAGE53
  J6L1   62  ACT_N SCONN288_H44441003_PIP-SCONN,HA   I111 @BASEBOARD_FAB2_LIB.BASEBOARD_FAB2(SCH_1):PAGE54

M_F_ALERT_N @BASEBOARD_FAB2_LIB.BASEBOARD_FAB2(SCH_1):M_F_ALERT_N
  U5D1 DD61 DDR5_ALERT_N SKX_EXT_B_BGA1-IC,TBD   I172 @BASEBOARD_FAB2_LIB.BASEBOARD_FAB2(SCH_1):PAGE28
  J4A1  208 ALERT_N SCONN288_H44441004_PIP-SCONN,HA   I111 @BASEBOARD_FAB2_LIB.BASEBOARD_FAB2(SCH_1):PAGE53
  J6L1  208 ALERT_N SCONN288_H44441003_PIP-SCONN,HA   I111 @BASEBOARD_FAB2_LIB.BASEBOARD_FAB2(SCH_1):PAGE54

M_F_BA<0> @BASEBOARD_FAB2_LIB.BASEBOARD_FAB2(SCH_1):M_F_BA(0)
  U5D1 DJ52 DDR5_BA<0> SKX_EXT_B_BGA1-IC,TBD   I172 @BASEBOARD_FAB2_LIB.BASEBOARD_FAB2(SCH_1):PAGE28
  J4A1   81  BA<0> SCONN288_H44441004_PIP-SCONN,HA   I111 @BASEBOARD_FAB2_LIB.BASEBOARD_FAB2(SCH_1):PAGE53
  J6L1   81  BA<0> SCONN288_H44441003_PIP-SCONN,HA   I111 @BASEBOARD_FAB2_LIB.BASEBOARD_FAB2(SCH_1):PAGE54

M_F_BA<1> @BASEBOARD_FAB2_LIB.BASEBOARD_FAB2(SCH_1):M_F_BA(1)
  U5D1 DC56 DDR5_BA<1> SKX_EXT_B_BGA1-IC,TBD   I172 @BASEBOARD_FAB2_LIB.BASEBOARD_FAB2(SCH_1):PAGE28
  J4A1  224  BA<1> SCONN288_H44441004_PIP-SCONN,HA   I111 @BASEBOARD_FAB2_LIB.BASEBOARD_FAB2(SCH_1):PAGE53
  J6L1  224  BA<1> SCONN288_H44441003_PIP-SCONN,HA   I111 @BASEBOARD_FAB2_LIB.BASEBOARD_FAB2(SCH_1):PAGE54

M_F_BG<0> @BASEBOARD_FAB2_LIB.BASEBOARD_FAB2(SCH_1):M_F_BG(0)
  U5D1 DA62 DDR5_BG<0> SKX_EXT_B_BGA1-IC,TBD   I172 @BASEBOARD_FAB2_LIB.BASEBOARD_FAB2(SCH_1):PAGE28
  J4A1   63  BG<0> SCONN288_H44441004_PIP-SCONN,HA   I111 @BASEBOARD_FAB2_LIB.BASEBOARD_FAB2(SCH_1):PAGE53
  J6L1   63  BG<0> SCONN288_H44441003_PIP-SCONN,HA   I111 @BASEBOARD_FAB2_LIB.BASEBOARD_FAB2(SCH_1):PAGE54

M_F_BG<1> @BASEBOARD_FAB2_LIB.BASEBOARD_FAB2(SCH_1):M_F_BG(1)
  U5D1 DF61 DDR5_BG<1> SKX_EXT_B_BGA1-IC,TBD   I172 @BASEBOARD_FAB2_LIB.BASEBOARD_FAB2(SCH_1):PAGE28
  J4A1  207  BG<1> SCONN288_H44441004_PIP-SCONN,HA   I111 @BASEBOARD_FAB2_LIB.BASEBOARD_FAB2(SCH_1):PAGE53
  J6L1  207  BG<1> SCONN288_H44441003_PIP-SCONN,HA   I111 @BASEBOARD_FAB2_LIB.BASEBOARD_FAB2(SCH_1):PAGE54

M_F_C<2> @BASEBOARD_FAB2_LIB.BASEBOARD_FAB2(SCH_1):M_F_C(2)
  U5D1 DF45 DDR5_CID<2> SKX_EXT_B_BGA1-IC,TBD   I172 @BASEBOARD_FAB2_LIB.BASEBOARD_FAB2(SCH_1):PAGE28
  J4A1  235   C<2> SCONN288_H44441004_PIP-SCONN,HA   I111 @BASEBOARD_FAB2_LIB.BASEBOARD_FAB2(SCH_1):PAGE53
  J6L1  235   C<2> SCONN288_H44441003_PIP-SCONN,HA   I111 @BASEBOARD_FAB2_LIB.BASEBOARD_FAB2(SCH_1):PAGE54

M_F_CKE<0> @BASEBOARD_FAB2_LIB.BASEBOARD_FAB2(SCH_1):M_F_CKE(0)
  U5D1 DG62 DDR5_CKE<0> SKX_EXT_B_BGA1-IC,TBD   I172 @BASEBOARD_FAB2_LIB.BASEBOARD_FAB2(SCH_1):PAGE28
  J4A1   60 CKE<0> SCONN288_H44441004_PIP-SCONN,HA   I111 @BASEBOARD_FAB2_LIB.BASEBOARD_FAB2(SCH_1):PAGE53

M_F_CKE<1> @BASEBOARD_FAB2_LIB.BASEBOARD_FAB2(SCH_1):M_F_CKE(1)
  U5D1 DD63 DDR5_CKE<1> SKX_EXT_B_BGA1-IC,TBD   I172 @BASEBOARD_FAB2_LIB.BASEBOARD_FAB2(SCH_1):PAGE28
  J4A1  203 CKE<1> SCONN288_H44441004_PIP-SCONN,HA   I111 @BASEBOARD_FAB2_LIB.BASEBOARD_FAB2(SCH_1):PAGE53

M_F_CKE<2> @BASEBOARD_FAB2_LIB.BASEBOARD_FAB2(SCH_1):M_F_CKE(2)
  U5D1 DK63 DDR5_CKE<2> SKX_EXT_B_BGA1-IC,TBD   I172 @BASEBOARD_FAB2_LIB.BASEBOARD_FAB2(SCH_1):PAGE28
  J6L1   60 CKE<0> SCONN288_H44441003_PIP-SCONN,HA   I111 @BASEBOARD_FAB2_LIB.BASEBOARD_FAB2(SCH_1):PAGE54

M_F_CKE<3> @BASEBOARD_FAB2_LIB.BASEBOARD_FAB2(SCH_1):M_F_CKE(3)
  U5D1 DF63 DDR5_CKE<3> SKX_EXT_B_BGA1-IC,TBD   I172 @BASEBOARD_FAB2_LIB.BASEBOARD_FAB2(SCH_1):PAGE28
  J6L1  203 CKE<1> SCONN288_H44441003_PIP-SCONN,HA   I111 @BASEBOARD_FAB2_LIB.BASEBOARD_FAB2(SCH_1):PAGE54

M_F_CLK_DN<0> @BASEBOARD_FAB2_LIB.BASEBOARD_FAB2(SCH_1):M_F_CLK_DN(0)
  U5D1 DK55 DDR5_CLK_DN<0> SKX_EXT_B_BGA1-IC,TBD   I172 @BASEBOARD_FAB2_LIB.BASEBOARD_FAB2(SCH_1):PAGE28
  J4A1   75   CK0N SCONN288_H44441004_PIP-SCONN,HA   I111 @BASEBOARD_FAB2_LIB.BASEBOARD_FAB2(SCH_1):PAGE53

M_F_CLK_DN<1> @BASEBOARD_FAB2_LIB.BASEBOARD_FAB2(SCH_1):M_F_CLK_DN(1)
  U5D1 DF55 DDR5_CLK_DN<1> SKX_EXT_B_BGA1-IC,TBD   I172 @BASEBOARD_FAB2_LIB.BASEBOARD_FAB2(SCH_1):PAGE28
  J4A1  219   CK1N SCONN288_H44441004_PIP-SCONN,HA   I111 @BASEBOARD_FAB2_LIB.BASEBOARD_FAB2(SCH_1):PAGE53

M_F_CLK_DN<2> @BASEBOARD_FAB2_LIB.BASEBOARD_FAB2(SCH_1):M_F_CLK_DN(2)
  U5D1 DK57 DDR5_CLK_DN<2> SKX_EXT_B_BGA1-IC,TBD   I172 @BASEBOARD_FAB2_LIB.BASEBOARD_FAB2(SCH_1):PAGE28
  J6L1   75   CK0N SCONN288_H44441003_PIP-SCONN,HA   I111 @BASEBOARD_FAB2_LIB.BASEBOARD_FAB2(SCH_1):PAGE54

M_F_CLK_DN<3> @BASEBOARD_FAB2_LIB.BASEBOARD_FAB2(SCH_1):M_F_CLK_DN(3)
  U5D1 DF57 DDR5_CLK_DN<3> SKX_EXT_B_BGA1-IC,TBD   I172 @BASEBOARD_FAB2_LIB.BASEBOARD_FAB2(SCH_1):PAGE28
  J6L1  219   CK1N SCONN288_H44441003_PIP-SCONN,HA   I111 @BASEBOARD_FAB2_LIB.BASEBOARD_FAB2(SCH_1):PAGE54

M_F_CLK_DP<0> @BASEBOARD_FAB2_LIB.BASEBOARD_FAB2(SCH_1):M_F_CLK_DP(0)
  U5D1 DJ54 DDR5_CLK_DP<0> SKX_EXT_B_BGA1-IC,TBD   I172 @BASEBOARD_FAB2_LIB.BASEBOARD_FAB2(SCH_1):PAGE28
  J4A1   74   CK0P SCONN288_H44441004_PIP-SCONN,HA   I111 @BASEBOARD_FAB2_LIB.BASEBOARD_FAB2(SCH_1):PAGE53

M_F_CLK_DP<1> @BASEBOARD_FAB2_LIB.BASEBOARD_FAB2(SCH_1):M_F_CLK_DP(1)
  U5D1 DG54 DDR5_CLK_DP<1> SKX_EXT_B_BGA1-IC,TBD   I172 @BASEBOARD_FAB2_LIB.BASEBOARD_FAB2(SCH_1):PAGE28
  J4A1  218   CK1P SCONN288_H44441004_PIP-SCONN,HA   I111 @BASEBOARD_FAB2_LIB.BASEBOARD_FAB2(SCH_1):PAGE53

M_F_CLK_DP<2> @BASEBOARD_FAB2_LIB.BASEBOARD_FAB2(SCH_1):M_F_CLK_DP(2)
  U5D1 DJ56 DDR5_CLK_DP<2> SKX_EXT_B_BGA1-IC,TBD   I172 @BASEBOARD_FAB2_LIB.BASEBOARD_FAB2(SCH_1):PAGE28
  J6L1   74   CK0P SCONN288_H44441003_PIP-SCONN,HA   I111 @BASEBOARD_FAB2_LIB.BASEBOARD_FAB2(SCH_1):PAGE54

M_F_CLK_DP<3> @BASEBOARD_FAB2_LIB.BASEBOARD_FAB2(SCH_1):M_F_CLK_DP(3)
  U5D1 DG56 DDR5_CLK_DP<3> SKX_EXT_B_BGA1-IC,TBD   I172 @BASEBOARD_FAB2_LIB.BASEBOARD_FAB2(SCH_1):PAGE28
  J6L1  218   CK1P SCONN288_H44441003_PIP-SCONN,HA   I111 @BASEBOARD_FAB2_LIB.BASEBOARD_FAB2(SCH_1):PAGE54

M_F_CPU_VREF @BASEBOARD_FAB2_LIB.BASEBOARD_FAB2(SCH_1):M_F_CPU_VREF
  U5D1 CV61 DDR5_CAVREF SKX_EXT_B_BGA1-IC,TBD   I259 @BASEBOARD_FAB2_LIB.BASEBOARD_FAB2(SCH_1):PAGE21
  R6L3    1      A RES_0402-2,1.0%,1/16W,CHIP,G21A    I66 @BASEBOARD_FAB2_LIB.BASEBOARD_FAB2(SCH_1):PAGE98
  C6L2    1      A CAP_A_0402V-0.01UF,25V,10%,X7RA    I67 @BASEBOARD_FAB2_LIB.BASEBOARD_FAB2(SCH_1):PAGE98

M_F_CS_N<0> @BASEBOARD_FAB2_LIB.BASEBOARD_FAB2(SCH_1):M_F_CS_N(0)
  U5D1 DK51 DDR5_CS_N<0> SKX_EXT_B_BGA1-IC,TBD   I172 @BASEBOARD_FAB2_LIB.BASEBOARD_FAB2(SCH_1):PAGE28
  J4A1   84   S0_N SCONN288_H44441004_PIP-SCONN,HA   I111 @BASEBOARD_FAB2_LIB.BASEBOARD_FAB2(SCH_1):PAGE53

M_F_CS_N<1> @BASEBOARD_FAB2_LIB.BASEBOARD_FAB2(SCH_1):M_F_CS_N(1)
  U5D1 DF49 DDR5_CS_N<1> SKX_EXT_B_BGA1-IC,TBD   I172 @BASEBOARD_FAB2_LIB.BASEBOARD_FAB2(SCH_1):PAGE28
  J4A1   89   S1_N SCONN288_H44441004_PIP-SCONN,HA   I111 @BASEBOARD_FAB2_LIB.BASEBOARD_FAB2(SCH_1):PAGE53

M_F_CS_N<2> @BASEBOARD_FAB2_LIB.BASEBOARD_FAB2(SCH_1):M_F_CS_N(2)
  U5D1 DJ46 DDR5_CS_N<2> SKX_EXT_B_BGA1-IC,TBD   I172 @BASEBOARD_FAB2_LIB.BASEBOARD_FAB2(SCH_1):PAGE28
  J4A1   93 S2_N_C<0> SCONN288_H44441004_PIP-SCONN,HA   I111 @BASEBOARD_FAB2_LIB.BASEBOARD_FAB2(SCH_1):PAGE53

M_F_CS_N<3> @BASEBOARD_FAB2_LIB.BASEBOARD_FAB2(SCH_1):M_F_CS_N(3)
  U5D1 DG46 DDR5_CS_N<3> SKX_EXT_B_BGA1-IC,TBD   I172 @BASEBOARD_FAB2_LIB.BASEBOARD_FAB2(SCH_1):PAGE28
  J4A1  237 S3_N_C<1> SCONN288_H44441004_PIP-SCONN,HA   I111 @BASEBOARD_FAB2_LIB.BASEBOARD_FAB2(SCH_1):PAGE53

M_F_CS_N<4> @BASEBOARD_FAB2_LIB.BASEBOARD_FAB2(SCH_1):M_F_CS_N(4)
  U5D1 DF51 DDR5_CS_N<4> SKX_EXT_B_BGA1-IC,TBD   I172 @BASEBOARD_FAB2_LIB.BASEBOARD_FAB2(SCH_1):PAGE28
  J6L1   84   S0_N SCONN288_H44441003_PIP-SCONN,HA   I111 @BASEBOARD_FAB2_LIB.BASEBOARD_FAB2(SCH_1):PAGE54

M_F_CS_N<5> @BASEBOARD_FAB2_LIB.BASEBOARD_FAB2(SCH_1):M_F_CS_N(5)
  U5D1 DJ48 DDR5_CS_N<5> SKX_EXT_B_BGA1-IC,TBD   I172 @BASEBOARD_FAB2_LIB.BASEBOARD_FAB2(SCH_1):PAGE28
  J6L1   89   S1_N SCONN288_H44441003_PIP-SCONN,HA   I111 @BASEBOARD_FAB2_LIB.BASEBOARD_FAB2(SCH_1):PAGE54

M_F_CS_N<6> @BASEBOARD_FAB2_LIB.BASEBOARD_FAB2(SCH_1):M_F_CS_N(6)
  U5D1 DM45 DDR5_CS_N<6> SKX_EXT_B_BGA1-IC,TBD   I172 @BASEBOARD_FAB2_LIB.BASEBOARD_FAB2(SCH_1):PAGE28
  J6L1   93 S2_N_C<0> SCONN288_H44441003_PIP-SCONN,HA   I111 @BASEBOARD_FAB2_LIB.BASEBOARD_FAB2(SCH_1):PAGE54

M_F_CS_N<7> @BASEBOARD_FAB2_LIB.BASEBOARD_FAB2(SCH_1):M_F_CS_N(7)
  U5D1 DK45 DDR5_CS_N<7> SKX_EXT_B_BGA1-IC,TBD   I172 @BASEBOARD_FAB2_LIB.BASEBOARD_FAB2(SCH_1):PAGE28
  J6L1  237 S3_N_C<1> SCONN288_H44441003_PIP-SCONN,HA   I111 @BASEBOARD_FAB2_LIB.BASEBOARD_FAB2(SCH_1):PAGE54

M_F_DQ<0> @BASEBOARD_FAB2_LIB.BASEBOARD_FAB2(SCH_1):M_F_DQ(0)
  U5D1 CR74 DDR5_DQ<0> SKX_EXT_B_BGA1-IC,TBD   I172 @BASEBOARD_FAB2_LIB.BASEBOARD_FAB2(SCH_1):PAGE28
  J4A1  150  DQ<1> SCONN288_H44441004_PIP-SCONN,HA   I111 @BASEBOARD_FAB2_LIB.BASEBOARD_FAB2(SCH_1):PAGE53
  J6L1    5  DQ<0> SCONN288_H44441003_PIP-SCONN,HA   I111 @BASEBOARD_FAB2_LIB.BASEBOARD_FAB2(SCH_1):PAGE54

M_F_DQ<10> @BASEBOARD_FAB2_LIB.BASEBOARD_FAB2(SCH_1):M_F_DQ(10)
  U5D1 DH75 DDR5_DQ<10> SKX_EXT_B_BGA1-IC,TBD   I172 @BASEBOARD_FAB2_LIB.BASEBOARD_FAB2(SCH_1):PAGE28
  J4A1  168 DQ<11> SCONN288_H44441004_PIP-SCONN,HA   I111 @BASEBOARD_FAB2_LIB.BASEBOARD_FAB2(SCH_1):PAGE53
  J6L1   23 DQ<10> SCONN288_H44441003_PIP-SCONN,HA   I111 @BASEBOARD_FAB2_LIB.BASEBOARD_FAB2(SCH_1):PAGE54

M_F_DQ<11> @BASEBOARD_FAB2_LIB.BASEBOARD_FAB2(SCH_1):M_F_DQ(11)
  U5D1 DJ76 DDR5_DQ<11> SKX_EXT_B_BGA1-IC,TBD   I172 @BASEBOARD_FAB2_LIB.BASEBOARD_FAB2(SCH_1):PAGE28
  J4A1   23 DQ<10> SCONN288_H44441004_PIP-SCONN,HA   I111 @BASEBOARD_FAB2_LIB.BASEBOARD_FAB2(SCH_1):PAGE53
  J6L1  168 DQ<11> SCONN288_H44441003_PIP-SCONN,HA   I111 @BASEBOARD_FAB2_LIB.BASEBOARD_FAB2(SCH_1):PAGE54

M_F_DQ<12> @BASEBOARD_FAB2_LIB.BASEBOARD_FAB2(SCH_1):M_F_DQ(12)
  U5D1 DC74 DDR5_DQ<12> SKX_EXT_B_BGA1-IC,TBD   I172 @BASEBOARD_FAB2_LIB.BASEBOARD_FAB2(SCH_1):PAGE28
  J4A1  159 DQ<13> SCONN288_H44441004_PIP-SCONN,HA   I111 @BASEBOARD_FAB2_LIB.BASEBOARD_FAB2(SCH_1):PAGE53
  J6L1   14 DQ<12> SCONN288_H44441003_PIP-SCONN,HA   I111 @BASEBOARD_FAB2_LIB.BASEBOARD_FAB2(SCH_1):PAGE54

M_F_DQ<13> @BASEBOARD_FAB2_LIB.BASEBOARD_FAB2(SCH_1):M_F_DQ(13)
  U5D1 DB75 DDR5_DQ<13> SKX_EXT_B_BGA1-IC,TBD   I172 @BASEBOARD_FAB2_LIB.BASEBOARD_FAB2(SCH_1):PAGE28
  J4A1   14 DQ<12> SCONN288_H44441004_PIP-SCONN,HA   I111 @BASEBOARD_FAB2_LIB.BASEBOARD_FAB2(SCH_1):PAGE53
  J6L1  159 DQ<13> SCONN288_H44441003_PIP-SCONN,HA   I111 @BASEBOARD_FAB2_LIB.BASEBOARD_FAB2(SCH_1):PAGE54

M_F_DQ<14> @BASEBOARD_FAB2_LIB.BASEBOARD_FAB2(SCH_1):M_F_DQ(14)
  U5D1 DF77 DDR5_DQ<14> SKX_EXT_B_BGA1-IC,TBD   I172 @BASEBOARD_FAB2_LIB.BASEBOARD_FAB2(SCH_1):PAGE28
  J4A1  166 DQ<15> SCONN288_H44441004_PIP-SCONN,HA   I111 @BASEBOARD_FAB2_LIB.BASEBOARD_FAB2(SCH_1):PAGE53
  J6L1   21 DQ<14> SCONN288_H44441003_PIP-SCONN,HA   I111 @BASEBOARD_FAB2_LIB.BASEBOARD_FAB2(SCH_1):PAGE54

M_F_DQ<15> @BASEBOARD_FAB2_LIB.BASEBOARD_FAB2(SCH_1):M_F_DQ(15)
  U5D1 DH77 DDR5_DQ<15> SKX_EXT_B_BGA1-IC,TBD   I172 @BASEBOARD_FAB2_LIB.BASEBOARD_FAB2(SCH_1):PAGE28
  J4A1   21 DQ<14> SCONN288_H44441004_PIP-SCONN,HA   I111 @BASEBOARD_FAB2_LIB.BASEBOARD_FAB2(SCH_1):PAGE53
  J6L1  166 DQ<15> SCONN288_H44441003_PIP-SCONN,HA   I111 @BASEBOARD_FAB2_LIB.BASEBOARD_FAB2(SCH_1):PAGE54

M_F_DQ<16> @BASEBOARD_FAB2_LIB.BASEBOARD_FAB2(SCH_1):M_F_DQ(16)
  U5D1 DG70 DDR5_DQ<16> SKX_EXT_B_BGA1-IC,TBD   I172 @BASEBOARD_FAB2_LIB.BASEBOARD_FAB2(SCH_1):PAGE28
  J4A1  172 DQ<17> SCONN288_H44441004_PIP-SCONN,HA   I111 @BASEBOARD_FAB2_LIB.BASEBOARD_FAB2(SCH_1):PAGE53
  J6L1   27 DQ<16> SCONN288_H44441003_PIP-SCONN,HA   I111 @BASEBOARD_FAB2_LIB.BASEBOARD_FAB2(SCH_1):PAGE54

M_F_DQ<17> @BASEBOARD_FAB2_LIB.BASEBOARD_FAB2(SCH_1):M_F_DQ(17)
  U5D1 DJ72 DDR5_DQ<17> SKX_EXT_B_BGA1-IC,TBD   I172 @BASEBOARD_FAB2_LIB.BASEBOARD_FAB2(SCH_1):PAGE28
  J4A1   27 DQ<16> SCONN288_H44441004_PIP-SCONN,HA   I111 @BASEBOARD_FAB2_LIB.BASEBOARD_FAB2(SCH_1):PAGE53
  J6L1  172 DQ<17> SCONN288_H44441003_PIP-SCONN,HA   I111 @BASEBOARD_FAB2_LIB.BASEBOARD_FAB2(SCH_1):PAGE54

M_F_DQ<18> @BASEBOARD_FAB2_LIB.BASEBOARD_FAB2(SCH_1):M_F_DQ(18)
  U5D1 DM69 DDR5_DQ<18> SKX_EXT_B_BGA1-IC,TBD   I172 @BASEBOARD_FAB2_LIB.BASEBOARD_FAB2(SCH_1):PAGE28
  J4A1  179 DQ<19> SCONN288_H44441004_PIP-SCONN,HA   I111 @BASEBOARD_FAB2_LIB.BASEBOARD_FAB2(SCH_1):PAGE53
  J6L1   34 DQ<18> SCONN288_H44441003_PIP-SCONN,HA   I111 @BASEBOARD_FAB2_LIB.BASEBOARD_FAB2(SCH_1):PAGE54

M_F_DQ<19> @BASEBOARD_FAB2_LIB.BASEBOARD_FAB2(SCH_1):M_F_DQ(19)
  U5D1 DN70 DDR5_DQ<19> SKX_EXT_B_BGA1-IC,TBD   I172 @BASEBOARD_FAB2_LIB.BASEBOARD_FAB2(SCH_1):PAGE28
  J4A1   34 DQ<18> SCONN288_H44441004_PIP-SCONN,HA   I111 @BASEBOARD_FAB2_LIB.BASEBOARD_FAB2(SCH_1):PAGE53
  J6L1  179 DQ<19> SCONN288_H44441003_PIP-SCONN,HA   I111 @BASEBOARD_FAB2_LIB.BASEBOARD_FAB2(SCH_1):PAGE54

M_F_DQ<1> @BASEBOARD_FAB2_LIB.BASEBOARD_FAB2(SCH_1):M_F_DQ(1)
  U5D1 CN76 DDR5_DQ<1> SKX_EXT_B_BGA1-IC,TBD   I172 @BASEBOARD_FAB2_LIB.BASEBOARD_FAB2(SCH_1):PAGE28
  J4A1    5  DQ<0> SCONN288_H44441004_PIP-SCONN,HA   I111 @BASEBOARD_FAB2_LIB.BASEBOARD_FAB2(SCH_1):PAGE53
  J6L1  150  DQ<1> SCONN288_H44441003_PIP-SCONN,HA   I111 @BASEBOARD_FAB2_LIB.BASEBOARD_FAB2(SCH_1):PAGE54

M_F_DQ<20> @BASEBOARD_FAB2_LIB.BASEBOARD_FAB2(SCH_1):M_F_DQ(20)
  U5D1 DF71 DDR5_DQ<20> SKX_EXT_B_BGA1-IC,TBD   I172 @BASEBOARD_FAB2_LIB.BASEBOARD_FAB2(SCH_1):PAGE28
  J4A1  170 DQ<21> SCONN288_H44441004_PIP-SCONN,HA   I111 @BASEBOARD_FAB2_LIB.BASEBOARD_FAB2(SCH_1):PAGE53
  J6L1   25 DQ<20> SCONN288_H44441003_PIP-SCONN,HA   I111 @BASEBOARD_FAB2_LIB.BASEBOARD_FAB2(SCH_1):PAGE54

M_F_DQ<21> @BASEBOARD_FAB2_LIB.BASEBOARD_FAB2(SCH_1):M_F_DQ(21)
  U5D1 DG72 DDR5_DQ<21> SKX_EXT_B_BGA1-IC,TBD   I172 @BASEBOARD_FAB2_LIB.BASEBOARD_FAB2(SCH_1):PAGE28
  J4A1   25 DQ<20> SCONN288_H44441004_PIP-SCONN,HA   I111 @BASEBOARD_FAB2_LIB.BASEBOARD_FAB2(SCH_1):PAGE53
  J6L1  170 DQ<21> SCONN288_H44441003_PIP-SCONN,HA   I111 @BASEBOARD_FAB2_LIB.BASEBOARD_FAB2(SCH_1):PAGE54

M_F_DQ<22> @BASEBOARD_FAB2_LIB.BASEBOARD_FAB2(SCH_1):M_F_DQ(22)
  U5D1 DK69 DDR5_DQ<22> SKX_EXT_B_BGA1-IC,TBD   I172 @BASEBOARD_FAB2_LIB.BASEBOARD_FAB2(SCH_1):PAGE28
  J4A1  177 DQ<23> SCONN288_H44441004_PIP-SCONN,HA   I111 @BASEBOARD_FAB2_LIB.BASEBOARD_FAB2(SCH_1):PAGE53
  J6L1   32 DQ<22> SCONN288_H44441003_PIP-SCONN,HA   I111 @BASEBOARD_FAB2_LIB.BASEBOARD_FAB2(SCH_1):PAGE54

M_F_DQ<23> @BASEBOARD_FAB2_LIB.BASEBOARD_FAB2(SCH_1):M_F_DQ(23)
  U5D1 DM71 DDR5_DQ<23> SKX_EXT_B_BGA1-IC,TBD   I172 @BASEBOARD_FAB2_LIB.BASEBOARD_FAB2(SCH_1):PAGE28
  J4A1   32 DQ<22> SCONN288_H44441004_PIP-SCONN,HA   I111 @BASEBOARD_FAB2_LIB.BASEBOARD_FAB2(SCH_1):PAGE53
  J6L1  177 DQ<23> SCONN288_H44441003_PIP-SCONN,HA   I111 @BASEBOARD_FAB2_LIB.BASEBOARD_FAB2(SCH_1):PAGE54

M_F_DQ<24> @BASEBOARD_FAB2_LIB.BASEBOARD_FAB2(SCH_1):M_F_DQ(24)
  U5D1 CN66 DDR5_DQ<24> SKX_EXT_B_BGA1-IC,TBD   I172 @BASEBOARD_FAB2_LIB.BASEBOARD_FAB2(SCH_1):PAGE28
  J4A1  183 DQ<25> SCONN288_H44441004_PIP-SCONN,HA   I111 @BASEBOARD_FAB2_LIB.BASEBOARD_FAB2(SCH_1):PAGE53
  J6L1   38 DQ<24> SCONN288_H44441003_PIP-SCONN,HA   I111 @BASEBOARD_FAB2_LIB.BASEBOARD_FAB2(SCH_1):PAGE54

M_F_DQ<25> @BASEBOARD_FAB2_LIB.BASEBOARD_FAB2(SCH_1):M_F_DQ(25)
  U5D1 CU66 DDR5_DQ<25> SKX_EXT_B_BGA1-IC,TBD   I172 @BASEBOARD_FAB2_LIB.BASEBOARD_FAB2(SCH_1):PAGE28
  J4A1   38 DQ<24> SCONN288_H44441004_PIP-SCONN,HA   I111 @BASEBOARD_FAB2_LIB.BASEBOARD_FAB2(SCH_1):PAGE53
  J6L1  183 DQ<25> SCONN288_H44441003_PIP-SCONN,HA   I111 @BASEBOARD_FAB2_LIB.BASEBOARD_FAB2(SCH_1):PAGE54

M_F_DQ<26> @BASEBOARD_FAB2_LIB.BASEBOARD_FAB2(SCH_1):M_F_DQ(26)
  U5D1 CP63 DDR5_DQ<26> SKX_EXT_B_BGA1-IC,TBD   I172 @BASEBOARD_FAB2_LIB.BASEBOARD_FAB2(SCH_1):PAGE28
  J4A1  190 DQ<27> SCONN288_H44441004_PIP-SCONN,HA   I111 @BASEBOARD_FAB2_LIB.BASEBOARD_FAB2(SCH_1):PAGE53
  J6L1   45 DQ<26> SCONN288_H44441003_PIP-SCONN,HA   I111 @BASEBOARD_FAB2_LIB.BASEBOARD_FAB2(SCH_1):PAGE54

M_F_DQ<27> @BASEBOARD_FAB2_LIB.BASEBOARD_FAB2(SCH_1):M_F_DQ(27)
  U5D1 CT63 DDR5_DQ<27> SKX_EXT_B_BGA1-IC,TBD   I172 @BASEBOARD_FAB2_LIB.BASEBOARD_FAB2(SCH_1):PAGE28
  J4A1   45 DQ<26> SCONN288_H44441004_PIP-SCONN,HA   I111 @BASEBOARD_FAB2_LIB.BASEBOARD_FAB2(SCH_1):PAGE53
  J6L1  190 DQ<27> SCONN288_H44441003_PIP-SCONN,HA   I111 @BASEBOARD_FAB2_LIB.BASEBOARD_FAB2(SCH_1):PAGE54

M_F_DQ<28> @BASEBOARD_FAB2_LIB.BASEBOARD_FAB2(SCH_1):M_F_DQ(28)
  U5D1 CP67 DDR5_DQ<28> SKX_EXT_B_BGA1-IC,TBD   I172 @BASEBOARD_FAB2_LIB.BASEBOARD_FAB2(SCH_1):PAGE28
  J4A1  181 DQ<29> SCONN288_H44441004_PIP-SCONN,HA   I111 @BASEBOARD_FAB2_LIB.BASEBOARD_FAB2(SCH_1):PAGE53
  J6L1   36 DQ<28> SCONN288_H44441003_PIP-SCONN,HA   I111 @BASEBOARD_FAB2_LIB.BASEBOARD_FAB2(SCH_1):PAGE54

M_F_DQ<29> @BASEBOARD_FAB2_LIB.BASEBOARD_FAB2(SCH_1):M_F_DQ(29)
  U5D1 CT67 DDR5_DQ<29> SKX_EXT_B_BGA1-IC,TBD   I172 @BASEBOARD_FAB2_LIB.BASEBOARD_FAB2(SCH_1):PAGE28
  J4A1   36 DQ<28> SCONN288_H44441004_PIP-SCONN,HA   I111 @BASEBOARD_FAB2_LIB.BASEBOARD_FAB2(SCH_1):PAGE53
  J6L1  181 DQ<29> SCONN288_H44441003_PIP-SCONN,HA   I111 @BASEBOARD_FAB2_LIB.BASEBOARD_FAB2(SCH_1):PAGE54

M_F_DQ<2> @BASEBOARD_FAB2_LIB.BASEBOARD_FAB2(SCH_1):M_F_DQ(2)
  U5D1 CW76 DDR5_DQ<2> SKX_EXT_B_BGA1-IC,TBD   I172 @BASEBOARD_FAB2_LIB.BASEBOARD_FAB2(SCH_1):PAGE28
  J4A1  157  DQ<3> SCONN288_H44441004_PIP-SCONN,HA   I111 @BASEBOARD_FAB2_LIB.BASEBOARD_FAB2(SCH_1):PAGE53
  J6L1   12  DQ<2> SCONN288_H44441003_PIP-SCONN,HA   I111 @BASEBOARD_FAB2_LIB.BASEBOARD_FAB2(SCH_1):PAGE54

M_F_DQ<30> @BASEBOARD_FAB2_LIB.BASEBOARD_FAB2(SCH_1):M_F_DQ(30)
  U5D1 CN64 DDR5_DQ<30> SKX_EXT_B_BGA1-IC,TBD   I172 @BASEBOARD_FAB2_LIB.BASEBOARD_FAB2(SCH_1):PAGE28
  J4A1  188 DQ<31> SCONN288_H44441004_PIP-SCONN,HA   I111 @BASEBOARD_FAB2_LIB.BASEBOARD_FAB2(SCH_1):PAGE53
  J6L1   43 DQ<30> SCONN288_H44441003_PIP-SCONN,HA   I111 @BASEBOARD_FAB2_LIB.BASEBOARD_FAB2(SCH_1):PAGE54

M_F_DQ<31> @BASEBOARD_FAB2_LIB.BASEBOARD_FAB2(SCH_1):M_F_DQ(31)
  U5D1 CU64 DDR5_DQ<31> SKX_EXT_B_BGA1-IC,TBD   I172 @BASEBOARD_FAB2_LIB.BASEBOARD_FAB2(SCH_1):PAGE28
  J4A1   43 DQ<30> SCONN288_H44441004_PIP-SCONN,HA   I111 @BASEBOARD_FAB2_LIB.BASEBOARD_FAB2(SCH_1):PAGE53
  J6L1  188 DQ<31> SCONN288_H44441003_PIP-SCONN,HA   I111 @BASEBOARD_FAB2_LIB.BASEBOARD_FAB2(SCH_1):PAGE54

M_F_DQ<32> @BASEBOARD_FAB2_LIB.BASEBOARD_FAB2(SCH_1):M_F_DQ(32)
  U5D1 DD41 DDR5_DQ<32> SKX_EXT_B_BGA1-IC,TBD   I172 @BASEBOARD_FAB2_LIB.BASEBOARD_FAB2(SCH_1):PAGE28
  J4A1  242 DQ<33> SCONN288_H44441004_PIP-SCONN,HA   I111 @BASEBOARD_FAB2_LIB.BASEBOARD_FAB2(SCH_1):PAGE53
  J6L1   97 DQ<32> SCONN288_H44441003_PIP-SCONN,HA   I111 @BASEBOARD_FAB2_LIB.BASEBOARD_FAB2(SCH_1):PAGE54

M_F_DQ<33> @BASEBOARD_FAB2_LIB.BASEBOARD_FAB2(SCH_1):M_F_DQ(33)
  U5D1 DG42 DDR5_DQ<33> SKX_EXT_B_BGA1-IC,TBD   I172 @BASEBOARD_FAB2_LIB.BASEBOARD_FAB2(SCH_1):PAGE28
  J4A1   97 DQ<32> SCONN288_H44441004_PIP-SCONN,HA   I111 @BASEBOARD_FAB2_LIB.BASEBOARD_FAB2(SCH_1):PAGE53
  J6L1  242 DQ<33> SCONN288_H44441003_PIP-SCONN,HA   I111 @BASEBOARD_FAB2_LIB.BASEBOARD_FAB2(SCH_1):PAGE54

M_F_DQ<34> @BASEBOARD_FAB2_LIB.BASEBOARD_FAB2(SCH_1):M_F_DQ(34)
  U5D1 DE38 DDR5_DQ<34> SKX_EXT_B_BGA1-IC,TBD   I172 @BASEBOARD_FAB2_LIB.BASEBOARD_FAB2(SCH_1):PAGE28
  J4A1  249 DQ<35> SCONN288_H44441004_PIP-SCONN,HA   I111 @BASEBOARD_FAB2_LIB.BASEBOARD_FAB2(SCH_1):PAGE53
  J6L1  104 DQ<34> SCONN288_H44441003_PIP-SCONN,HA   I111 @BASEBOARD_FAB2_LIB.BASEBOARD_FAB2(SCH_1):PAGE54

M_F_DQ<35> @BASEBOARD_FAB2_LIB.BASEBOARD_FAB2(SCH_1):M_F_DQ(35)
  U5D1 DG38 DDR5_DQ<35> SKX_EXT_B_BGA1-IC,TBD   I172 @BASEBOARD_FAB2_LIB.BASEBOARD_FAB2(SCH_1):PAGE28
  J4A1  104 DQ<34> SCONN288_H44441004_PIP-SCONN,HA   I111 @BASEBOARD_FAB2_LIB.BASEBOARD_FAB2(SCH_1):PAGE53
  J6L1  249 DQ<35> SCONN288_H44441003_PIP-SCONN,HA   I111 @BASEBOARD_FAB2_LIB.BASEBOARD_FAB2(SCH_1):PAGE54

M_F_DQ<36> @BASEBOARD_FAB2_LIB.BASEBOARD_FAB2(SCH_1):M_F_DQ(36)
  U5D1 DA42 DDR5_DQ<36> SKX_EXT_B_BGA1-IC,TBD   I172 @BASEBOARD_FAB2_LIB.BASEBOARD_FAB2(SCH_1):PAGE28
  J4A1  240 DQ<37> SCONN288_H44441004_PIP-SCONN,HA   I111 @BASEBOARD_FAB2_LIB.BASEBOARD_FAB2(SCH_1):PAGE53
  J6L1   95 DQ<36> SCONN288_H44441003_PIP-SCONN,HA   I111 @BASEBOARD_FAB2_LIB.BASEBOARD_FAB2(SCH_1):PAGE54

M_F_DQ<37> @BASEBOARD_FAB2_LIB.BASEBOARD_FAB2(SCH_1):M_F_DQ(37)
  U5D1 DE42 DDR5_DQ<37> SKX_EXT_B_BGA1-IC,TBD   I172 @BASEBOARD_FAB2_LIB.BASEBOARD_FAB2(SCH_1):PAGE28
  J4A1   95 DQ<36> SCONN288_H44441004_PIP-SCONN,HA   I111 @BASEBOARD_FAB2_LIB.BASEBOARD_FAB2(SCH_1):PAGE53
  J6L1  240 DQ<37> SCONN288_H44441003_PIP-SCONN,HA   I111 @BASEBOARD_FAB2_LIB.BASEBOARD_FAB2(SCH_1):PAGE54

M_F_DQ<38> @BASEBOARD_FAB2_LIB.BASEBOARD_FAB2(SCH_1):M_F_DQ(38)
  U5D1 DD39 DDR5_DQ<38> SKX_EXT_B_BGA1-IC,TBD   I172 @BASEBOARD_FAB2_LIB.BASEBOARD_FAB2(SCH_1):PAGE28
  J4A1  247 DQ<39> SCONN288_H44441004_PIP-SCONN,HA   I111 @BASEBOARD_FAB2_LIB.BASEBOARD_FAB2(SCH_1):PAGE53
  J6L1  102 DQ<38> SCONN288_H44441003_PIP-SCONN,HA   I111 @BASEBOARD_FAB2_LIB.BASEBOARD_FAB2(SCH_1):PAGE54

M_F_DQ<39> @BASEBOARD_FAB2_LIB.BASEBOARD_FAB2(SCH_1):M_F_DQ(39)
  U5D1 DH39 DDR5_DQ<39> SKX_EXT_B_BGA1-IC,TBD   I172 @BASEBOARD_FAB2_LIB.BASEBOARD_FAB2(SCH_1):PAGE28
  J4A1  102 DQ<38> SCONN288_H44441004_PIP-SCONN,HA   I111 @BASEBOARD_FAB2_LIB.BASEBOARD_FAB2(SCH_1):PAGE53
  J6L1  247 DQ<39> SCONN288_H44441003_PIP-SCONN,HA   I111 @BASEBOARD_FAB2_LIB.BASEBOARD_FAB2(SCH_1):PAGE54

M_F_DQ<3> @BASEBOARD_FAB2_LIB.BASEBOARD_FAB2(SCH_1):M_F_DQ(3)
  U5D1 CV77 DDR5_DQ<3> SKX_EXT_B_BGA1-IC,TBD   I172 @BASEBOARD_FAB2_LIB.BASEBOARD_FAB2(SCH_1):PAGE28
  J4A1   12  DQ<2> SCONN288_H44441004_PIP-SCONN,HA   I111 @BASEBOARD_FAB2_LIB.BASEBOARD_FAB2(SCH_1):PAGE53
  J6L1  157  DQ<3> SCONN288_H44441003_PIP-SCONN,HA   I111 @BASEBOARD_FAB2_LIB.BASEBOARD_FAB2(SCH_1):PAGE54

M_F_DQ<40> @BASEBOARD_FAB2_LIB.BASEBOARD_FAB2(SCH_1):M_F_DQ(40)
  U5D1 DF33 DDR5_DQ<40> SKX_EXT_B_BGA1-IC,TBD   I172 @BASEBOARD_FAB2_LIB.BASEBOARD_FAB2(SCH_1):PAGE28
  J4A1  253 DQ<41> SCONN288_H44441004_PIP-SCONN,HA   I111 @BASEBOARD_FAB2_LIB.BASEBOARD_FAB2(SCH_1):PAGE53
  J6L1  108 DQ<40> SCONN288_H44441003_PIP-SCONN,HA   I111 @BASEBOARD_FAB2_LIB.BASEBOARD_FAB2(SCH_1):PAGE54

M_F_DQ<41> @BASEBOARD_FAB2_LIB.BASEBOARD_FAB2(SCH_1):M_F_DQ(41)
  U5D1 DK33 DDR5_DQ<41> SKX_EXT_B_BGA1-IC,TBD   I172 @BASEBOARD_FAB2_LIB.BASEBOARD_FAB2(SCH_1):PAGE28
  J4A1  108 DQ<40> SCONN288_H44441004_PIP-SCONN,HA   I111 @BASEBOARD_FAB2_LIB.BASEBOARD_FAB2(SCH_1):PAGE53
  J6L1  253 DQ<41> SCONN288_H44441003_PIP-SCONN,HA   I111 @BASEBOARD_FAB2_LIB.BASEBOARD_FAB2(SCH_1):PAGE54

M_F_DQ<42> @BASEBOARD_FAB2_LIB.BASEBOARD_FAB2(SCH_1):M_F_DQ(42)
  U5D1 DG30 DDR5_DQ<42> SKX_EXT_B_BGA1-IC,TBD   I172 @BASEBOARD_FAB2_LIB.BASEBOARD_FAB2(SCH_1):PAGE28
  J4A1  260 DQ<43> SCONN288_H44441004_PIP-SCONN,HA   I111 @BASEBOARD_FAB2_LIB.BASEBOARD_FAB2(SCH_1):PAGE53
  J6L1  115 DQ<42> SCONN288_H44441003_PIP-SCONN,HA   I111 @BASEBOARD_FAB2_LIB.BASEBOARD_FAB2(SCH_1):PAGE54

M_F_DQ<43> @BASEBOARD_FAB2_LIB.BASEBOARD_FAB2(SCH_1):M_F_DQ(43)
  U5D1 DJ30 DDR5_DQ<43> SKX_EXT_B_BGA1-IC,TBD   I172 @BASEBOARD_FAB2_LIB.BASEBOARD_FAB2(SCH_1):PAGE28
  J4A1  115 DQ<42> SCONN288_H44441004_PIP-SCONN,HA   I111 @BASEBOARD_FAB2_LIB.BASEBOARD_FAB2(SCH_1):PAGE53
  J6L1  260 DQ<43> SCONN288_H44441003_PIP-SCONN,HA   I111 @BASEBOARD_FAB2_LIB.BASEBOARD_FAB2(SCH_1):PAGE54

M_F_DQ<44> @BASEBOARD_FAB2_LIB.BASEBOARD_FAB2(SCH_1):M_F_DQ(44)
  U5D1 DG34 DDR5_DQ<44> SKX_EXT_B_BGA1-IC,TBD   I172 @BASEBOARD_FAB2_LIB.BASEBOARD_FAB2(SCH_1):PAGE28
  J4A1  251 DQ<45> SCONN288_H44441004_PIP-SCONN,HA   I111 @BASEBOARD_FAB2_LIB.BASEBOARD_FAB2(SCH_1):PAGE53
  J6L1  106 DQ<44> SCONN288_H44441003_PIP-SCONN,HA   I111 @BASEBOARD_FAB2_LIB.BASEBOARD_FAB2(SCH_1):PAGE54

M_F_DQ<45> @BASEBOARD_FAB2_LIB.BASEBOARD_FAB2(SCH_1):M_F_DQ(45)
  U5D1 DJ34 DDR5_DQ<45> SKX_EXT_B_BGA1-IC,TBD   I172 @BASEBOARD_FAB2_LIB.BASEBOARD_FAB2(SCH_1):PAGE28
  J4A1  106 DQ<44> SCONN288_H44441004_PIP-SCONN,HA   I111 @BASEBOARD_FAB2_LIB.BASEBOARD_FAB2(SCH_1):PAGE53
  J6L1  251 DQ<45> SCONN288_H44441003_PIP-SCONN,HA   I111 @BASEBOARD_FAB2_LIB.BASEBOARD_FAB2(SCH_1):PAGE54

M_F_DQ<46> @BASEBOARD_FAB2_LIB.BASEBOARD_FAB2(SCH_1):M_F_DQ(46)
  U5D1 DF31 DDR5_DQ<46> SKX_EXT_B_BGA1-IC,TBD   I172 @BASEBOARD_FAB2_LIB.BASEBOARD_FAB2(SCH_1):PAGE28
  J4A1  258 DQ<47> SCONN288_H44441004_PIP-SCONN,HA   I111 @BASEBOARD_FAB2_LIB.BASEBOARD_FAB2(SCH_1):PAGE53
  J6L1  113 DQ<46> SCONN288_H44441003_PIP-SCONN,HA   I111 @BASEBOARD_FAB2_LIB.BASEBOARD_FAB2(SCH_1):PAGE54

M_F_DQ<47> @BASEBOARD_FAB2_LIB.BASEBOARD_FAB2(SCH_1):M_F_DQ(47)
  U5D1 DK31 DDR5_DQ<47> SKX_EXT_B_BGA1-IC,TBD   I172 @BASEBOARD_FAB2_LIB.BASEBOARD_FAB2(SCH_1):PAGE28
  J4A1  113 DQ<46> SCONN288_H44441004_PIP-SCONN,HA   I111 @BASEBOARD_FAB2_LIB.BASEBOARD_FAB2(SCH_1):PAGE53
  J6L1  258 DQ<47> SCONN288_H44441003_PIP-SCONN,HA   I111 @BASEBOARD_FAB2_LIB.BASEBOARD_FAB2(SCH_1):PAGE54

M_F_DQ<48> @BASEBOARD_FAB2_LIB.BASEBOARD_FAB2(SCH_1):M_F_DQ(48)
  U5D1 CW36 DDR5_DQ<48> SKX_EXT_B_BGA1-IC,TBD   I172 @BASEBOARD_FAB2_LIB.BASEBOARD_FAB2(SCH_1):PAGE28
  J4A1  264 DQ<49> SCONN288_H44441004_PIP-SCONN,HA   I111 @BASEBOARD_FAB2_LIB.BASEBOARD_FAB2(SCH_1):PAGE53
  J6L1  119 DQ<48> SCONN288_H44441003_PIP-SCONN,HA   I111 @BASEBOARD_FAB2_LIB.BASEBOARD_FAB2(SCH_1):PAGE54

M_F_DQ<49> @BASEBOARD_FAB2_LIB.BASEBOARD_FAB2(SCH_1):M_F_DQ(49)
  U5D1 DC36 DDR5_DQ<49> SKX_EXT_B_BGA1-IC,TBD   I172 @BASEBOARD_FAB2_LIB.BASEBOARD_FAB2(SCH_1):PAGE28
  J4A1  119 DQ<48> SCONN288_H44441004_PIP-SCONN,HA   I111 @BASEBOARD_FAB2_LIB.BASEBOARD_FAB2(SCH_1):PAGE53
  J6L1  264 DQ<49> SCONN288_H44441003_PIP-SCONN,HA   I111 @BASEBOARD_FAB2_LIB.BASEBOARD_FAB2(SCH_1):PAGE54

M_F_DQ<4> @BASEBOARD_FAB2_LIB.BASEBOARD_FAB2(SCH_1):M_F_DQ(4)
  U5D1 CN74 DDR5_DQ<4> SKX_EXT_B_BGA1-IC,TBD   I172 @BASEBOARD_FAB2_LIB.BASEBOARD_FAB2(SCH_1):PAGE28
  J4A1  148  DQ<5> SCONN288_H44441004_PIP-SCONN,HA   I111 @BASEBOARD_FAB2_LIB.BASEBOARD_FAB2(SCH_1):PAGE53
  J6L1    3  DQ<4> SCONN288_H44441003_PIP-SCONN,HA   I111 @BASEBOARD_FAB2_LIB.BASEBOARD_FAB2(SCH_1):PAGE54

M_F_DQ<50> @BASEBOARD_FAB2_LIB.BASEBOARD_FAB2(SCH_1):M_F_DQ(50)
  U5D1 CY33 DDR5_DQ<50> SKX_EXT_B_BGA1-IC,TBD   I172 @BASEBOARD_FAB2_LIB.BASEBOARD_FAB2(SCH_1):PAGE28
  J4A1  271 DQ<51> SCONN288_H44441004_PIP-SCONN,HA   I111 @BASEBOARD_FAB2_LIB.BASEBOARD_FAB2(SCH_1):PAGE53
  J6L1  126 DQ<50> SCONN288_H44441003_PIP-SCONN,HA   I111 @BASEBOARD_FAB2_LIB.BASEBOARD_FAB2(SCH_1):PAGE54

M_F_DQ<51> @BASEBOARD_FAB2_LIB.BASEBOARD_FAB2(SCH_1):M_F_DQ(51)
  U5D1 DB33 DDR5_DQ<51> SKX_EXT_B_BGA1-IC,TBD   I172 @BASEBOARD_FAB2_LIB.BASEBOARD_FAB2(SCH_1):PAGE28
  J4A1  126 DQ<50> SCONN288_H44441004_PIP-SCONN,HA   I111 @BASEBOARD_FAB2_LIB.BASEBOARD_FAB2(SCH_1):PAGE53
  J6L1  271 DQ<51> SCONN288_H44441003_PIP-SCONN,HA   I111 @BASEBOARD_FAB2_LIB.BASEBOARD_FAB2(SCH_1):PAGE54

M_F_DQ<52> @BASEBOARD_FAB2_LIB.BASEBOARD_FAB2(SCH_1):M_F_DQ(52)
  U5D1 CY37 DDR5_DQ<52> SKX_EXT_B_BGA1-IC,TBD   I172 @BASEBOARD_FAB2_LIB.BASEBOARD_FAB2(SCH_1):PAGE28
  J4A1  262 DQ<53> SCONN288_H44441004_PIP-SCONN,HA   I111 @BASEBOARD_FAB2_LIB.BASEBOARD_FAB2(SCH_1):PAGE53
  J6L1  117 DQ<52> SCONN288_H44441003_PIP-SCONN,HA   I111 @BASEBOARD_FAB2_LIB.BASEBOARD_FAB2(SCH_1):PAGE54

M_F_DQ<53> @BASEBOARD_FAB2_LIB.BASEBOARD_FAB2(SCH_1):M_F_DQ(53)
  U5D1 DB37 DDR5_DQ<53> SKX_EXT_B_BGA1-IC,TBD   I172 @BASEBOARD_FAB2_LIB.BASEBOARD_FAB2(SCH_1):PAGE28
  J4A1  117 DQ<52> SCONN288_H44441004_PIP-SCONN,HA   I111 @BASEBOARD_FAB2_LIB.BASEBOARD_FAB2(SCH_1):PAGE53
  J6L1  262 DQ<53> SCONN288_H44441003_PIP-SCONN,HA   I111 @BASEBOARD_FAB2_LIB.BASEBOARD_FAB2(SCH_1):PAGE54

M_F_DQ<54> @BASEBOARD_FAB2_LIB.BASEBOARD_FAB2(SCH_1):M_F_DQ(54)
  U5D1 CW34 DDR5_DQ<54> SKX_EXT_B_BGA1-IC,TBD   I172 @BASEBOARD_FAB2_LIB.BASEBOARD_FAB2(SCH_1):PAGE28
  J4A1  269 DQ<55> SCONN288_H44441004_PIP-SCONN,HA   I111 @BASEBOARD_FAB2_LIB.BASEBOARD_FAB2(SCH_1):PAGE53
  J6L1  124 DQ<54> SCONN288_H44441003_PIP-SCONN,HA   I111 @BASEBOARD_FAB2_LIB.BASEBOARD_FAB2(SCH_1):PAGE54

M_F_DQ<55> @BASEBOARD_FAB2_LIB.BASEBOARD_FAB2(SCH_1):M_F_DQ(55)
  U5D1 DC34 DDR5_DQ<55> SKX_EXT_B_BGA1-IC,TBD   I172 @BASEBOARD_FAB2_LIB.BASEBOARD_FAB2(SCH_1):PAGE28
  J4A1  124 DQ<54> SCONN288_H44441004_PIP-SCONN,HA   I111 @BASEBOARD_FAB2_LIB.BASEBOARD_FAB2(SCH_1):PAGE53
  J6L1  269 DQ<55> SCONN288_H44441003_PIP-SCONN,HA   I111 @BASEBOARD_FAB2_LIB.BASEBOARD_FAB2(SCH_1):PAGE54

M_F_DQ<56> @BASEBOARD_FAB2_LIB.BASEBOARD_FAB2(SCH_1):M_F_DQ(56)
  U5D1 CW30 DDR5_DQ<56> SKX_EXT_B_BGA1-IC,TBD   I172 @BASEBOARD_FAB2_LIB.BASEBOARD_FAB2(SCH_1):PAGE28
  J4A1  275 DQ<57> SCONN288_H44441004_PIP-SCONN,HA   I111 @BASEBOARD_FAB2_LIB.BASEBOARD_FAB2(SCH_1):PAGE53
  J6L1  130 DQ<56> SCONN288_H44441003_PIP-SCONN,HA   I111 @BASEBOARD_FAB2_LIB.BASEBOARD_FAB2(SCH_1):PAGE54

M_F_DQ<57> @BASEBOARD_FAB2_LIB.BASEBOARD_FAB2(SCH_1):M_F_DQ(57)
  U5D1 DC30 DDR5_DQ<57> SKX_EXT_B_BGA1-IC,TBD   I172 @BASEBOARD_FAB2_LIB.BASEBOARD_FAB2(SCH_1):PAGE28
  J4A1  130 DQ<56> SCONN288_H44441004_PIP-SCONN,HA   I111 @BASEBOARD_FAB2_LIB.BASEBOARD_FAB2(SCH_1):PAGE53
  J6L1  275 DQ<57> SCONN288_H44441003_PIP-SCONN,HA   I111 @BASEBOARD_FAB2_LIB.BASEBOARD_FAB2(SCH_1):PAGE54

M_F_DQ<58> @BASEBOARD_FAB2_LIB.BASEBOARD_FAB2(SCH_1):M_F_DQ(58)
  U5D1 CY27 DDR5_DQ<58> SKX_EXT_B_BGA1-IC,TBD   I172 @BASEBOARD_FAB2_LIB.BASEBOARD_FAB2(SCH_1):PAGE28
  J4A1  282 DQ<59> SCONN288_H44441004_PIP-SCONN,HA   I111 @BASEBOARD_FAB2_LIB.BASEBOARD_FAB2(SCH_1):PAGE53
  J6L1  137 DQ<58> SCONN288_H44441003_PIP-SCONN,HA   I111 @BASEBOARD_FAB2_LIB.BASEBOARD_FAB2(SCH_1):PAGE54

M_F_DQ<59> @BASEBOARD_FAB2_LIB.BASEBOARD_FAB2(SCH_1):M_F_DQ(59)
  U5D1 DB27 DDR5_DQ<59> SKX_EXT_B_BGA1-IC,TBD   I172 @BASEBOARD_FAB2_LIB.BASEBOARD_FAB2(SCH_1):PAGE28
  J4A1  137 DQ<58> SCONN288_H44441004_PIP-SCONN,HA   I111 @BASEBOARD_FAB2_LIB.BASEBOARD_FAB2(SCH_1):PAGE53
  J6L1  282 DQ<59> SCONN288_H44441003_PIP-SCONN,HA   I111 @BASEBOARD_FAB2_LIB.BASEBOARD_FAB2(SCH_1):PAGE54

M_F_DQ<5> @BASEBOARD_FAB2_LIB.BASEBOARD_FAB2(SCH_1):M_F_DQ(5)
  U5D1 CM75 DDR5_DQ<5> SKX_EXT_B_BGA1-IC,TBD   I172 @BASEBOARD_FAB2_LIB.BASEBOARD_FAB2(SCH_1):PAGE28
  J4A1    3  DQ<4> SCONN288_H44441004_PIP-SCONN,HA   I111 @BASEBOARD_FAB2_LIB.BASEBOARD_FAB2(SCH_1):PAGE53
  J6L1  148  DQ<5> SCONN288_H44441003_PIP-SCONN,HA   I111 @BASEBOARD_FAB2_LIB.BASEBOARD_FAB2(SCH_1):PAGE54

M_F_DQ<60> @BASEBOARD_FAB2_LIB.BASEBOARD_FAB2(SCH_1):M_F_DQ(60)
  U5D1 CY31 DDR5_DQ<60> SKX_EXT_B_BGA1-IC,TBD   I172 @BASEBOARD_FAB2_LIB.BASEBOARD_FAB2(SCH_1):PAGE28
  J4A1  273 DQ<61> SCONN288_H44441004_PIP-SCONN,HA   I111 @BASEBOARD_FAB2_LIB.BASEBOARD_FAB2(SCH_1):PAGE53
  J6L1  128 DQ<60> SCONN288_H44441003_PIP-SCONN,HA   I111 @BASEBOARD_FAB2_LIB.BASEBOARD_FAB2(SCH_1):PAGE54

M_F_DQ<61> @BASEBOARD_FAB2_LIB.BASEBOARD_FAB2(SCH_1):M_F_DQ(61)
  U5D1 DB31 DDR5_DQ<61> SKX_EXT_B_BGA1-IC,TBD   I172 @BASEBOARD_FAB2_LIB.BASEBOARD_FAB2(SCH_1):PAGE28
  J4A1  128 DQ<60> SCONN288_H44441004_PIP-SCONN,HA   I111 @BASEBOARD_FAB2_LIB.BASEBOARD_FAB2(SCH_1):PAGE53
  J6L1  273 DQ<61> SCONN288_H44441003_PIP-SCONN,HA   I111 @BASEBOARD_FAB2_LIB.BASEBOARD_FAB2(SCH_1):PAGE54

M_F_DQ<62> @BASEBOARD_FAB2_LIB.BASEBOARD_FAB2(SCH_1):M_F_DQ(62)
  U5D1 CW28 DDR5_DQ<62> SKX_EXT_B_BGA1-IC,TBD   I172 @BASEBOARD_FAB2_LIB.BASEBOARD_FAB2(SCH_1):PAGE28
  J4A1  280 DQ<63> SCONN288_H44441004_PIP-SCONN,HA   I111 @BASEBOARD_FAB2_LIB.BASEBOARD_FAB2(SCH_1):PAGE53
  J6L1  135 DQ<62> SCONN288_H44441003_PIP-SCONN,HA   I111 @BASEBOARD_FAB2_LIB.BASEBOARD_FAB2(SCH_1):PAGE54

M_F_DQ<63> @BASEBOARD_FAB2_LIB.BASEBOARD_FAB2(SCH_1):M_F_DQ(63)
  U5D1 DC28 DDR5_DQ<63> SKX_EXT_B_BGA1-IC,TBD   I172 @BASEBOARD_FAB2_LIB.BASEBOARD_FAB2(SCH_1):PAGE28
  J4A1  135 DQ<62> SCONN288_H44441004_PIP-SCONN,HA   I111 @BASEBOARD_FAB2_LIB.BASEBOARD_FAB2(SCH_1):PAGE53
  J6L1  280 DQ<63> SCONN288_H44441003_PIP-SCONN,HA   I111 @BASEBOARD_FAB2_LIB.BASEBOARD_FAB2(SCH_1):PAGE54

M_F_DQ<6> @BASEBOARD_FAB2_LIB.BASEBOARD_FAB2(SCH_1):M_F_DQ(6)
  U5D1 CV75 DDR5_DQ<6> SKX_EXT_B_BGA1-IC,TBD   I172 @BASEBOARD_FAB2_LIB.BASEBOARD_FAB2(SCH_1):PAGE28
  J4A1  155  DQ<7> SCONN288_H44441004_PIP-SCONN,HA   I111 @BASEBOARD_FAB2_LIB.BASEBOARD_FAB2(SCH_1):PAGE53
  J6L1   10  DQ<6> SCONN288_H44441003_PIP-SCONN,HA   I111 @BASEBOARD_FAB2_LIB.BASEBOARD_FAB2(SCH_1):PAGE54

M_F_DQ<7> @BASEBOARD_FAB2_LIB.BASEBOARD_FAB2(SCH_1):M_F_DQ(7)
  U5D1 CT77 DDR5_DQ<7> SKX_EXT_B_BGA1-IC,TBD   I172 @BASEBOARD_FAB2_LIB.BASEBOARD_FAB2(SCH_1):PAGE28
  J4A1   10  DQ<6> SCONN288_H44441004_PIP-SCONN,HA   I111 @BASEBOARD_FAB2_LIB.BASEBOARD_FAB2(SCH_1):PAGE53
  J6L1  155  DQ<7> SCONN288_H44441003_PIP-SCONN,HA   I111 @BASEBOARD_FAB2_LIB.BASEBOARD_FAB2(SCH_1):PAGE54

M_F_DQ<8> @BASEBOARD_FAB2_LIB.BASEBOARD_FAB2(SCH_1):M_F_DQ(8)
  U5D1 DE74 DDR5_DQ<8> SKX_EXT_B_BGA1-IC,TBD   I172 @BASEBOARD_FAB2_LIB.BASEBOARD_FAB2(SCH_1):PAGE28
  J4A1  161  DQ<9> SCONN288_H44441004_PIP-SCONN,HA   I111 @BASEBOARD_FAB2_LIB.BASEBOARD_FAB2(SCH_1):PAGE53
  J6L1   16  DQ<8> SCONN288_H44441003_PIP-SCONN,HA   I111 @BASEBOARD_FAB2_LIB.BASEBOARD_FAB2(SCH_1):PAGE54

M_F_DQ<9> @BASEBOARD_FAB2_LIB.BASEBOARD_FAB2(SCH_1):M_F_DQ(9)
  U5D1 DC76 DDR5_DQ<9> SKX_EXT_B_BGA1-IC,TBD   I172 @BASEBOARD_FAB2_LIB.BASEBOARD_FAB2(SCH_1):PAGE28
  J4A1   16  DQ<8> SCONN288_H44441004_PIP-SCONN,HA   I111 @BASEBOARD_FAB2_LIB.BASEBOARD_FAB2(SCH_1):PAGE53
  J6L1  161  DQ<9> SCONN288_H44441003_PIP-SCONN,HA   I111 @BASEBOARD_FAB2_LIB.BASEBOARD_FAB2(SCH_1):PAGE54

M_F_DQS_DN<0> @BASEBOARD_FAB2_LIB.BASEBOARD_FAB2(SCH_1):M_F_DQS_DN(0)
  U5D1 CP77 DDR5_DQS_DN<0> SKX_EXT_B_BGA1-IC,TBD   I172 @BASEBOARD_FAB2_LIB.BASEBOARD_FAB2(SCH_1):PAGE28
  J4A1  152  DQS0N SCONN288_H44441004_PIP-SCONN,HA    I66 @BASEBOARD_FAB2_LIB.BASEBOARD_FAB2(SCH_1):PAGE53
  J6L1  152  DQS0N SCONN288_H44441003_PIP-SCONN,HA    I66 @BASEBOARD_FAB2_LIB.BASEBOARD_FAB2(SCH_1):PAGE54

M_F_DQS_DN<10> @BASEBOARD_FAB2_LIB.BASEBOARD_FAB2(SCH_1):M_F_DQS_DN(10)
  U5D1 DF75 DDR5_DQS_DN<10> SKX_EXT_B_BGA1-IC,TBD   I172 @BASEBOARD_FAB2_LIB.BASEBOARD_FAB2(SCH_1):PAGE28
  J4A1   19 DQS10N SCONN288_H44441004_PIP-SCONN,HA    I66 @BASEBOARD_FAB2_LIB.BASEBOARD_FAB2(SCH_1):PAGE53
  J6L1   19 DQS10N SCONN288_H44441003_PIP-SCONN,HA    I66 @BASEBOARD_FAB2_LIB.BASEBOARD_FAB2(SCH_1):PAGE54

M_F_DQS_DN<11> @BASEBOARD_FAB2_LIB.BASEBOARD_FAB2(SCH_1):M_F_DQS_DN(11)
  U5D1 DJ70 DDR5_DQS_DN<11> SKX_EXT_B_BGA1-IC,TBD   I172 @BASEBOARD_FAB2_LIB.BASEBOARD_FAB2(SCH_1):PAGE28
  J4A1   30 DQS11N SCONN288_H44441004_PIP-SCONN,HA    I66 @BASEBOARD_FAB2_LIB.BASEBOARD_FAB2(SCH_1):PAGE53
  J6L1   30 DQS11N SCONN288_H44441003_PIP-SCONN,HA    I66 @BASEBOARD_FAB2_LIB.BASEBOARD_FAB2(SCH_1):PAGE54

M_F_DQS_DN<12> @BASEBOARD_FAB2_LIB.BASEBOARD_FAB2(SCH_1):M_F_DQS_DN(12)
  U5D1 CP65 DDR5_DQS_DN<12> SKX_EXT_B_BGA1-IC,TBD   I172 @BASEBOARD_FAB2_LIB.BASEBOARD_FAB2(SCH_1):PAGE28
  J4A1   41 DQS12N SCONN288_H44441004_PIP-SCONN,HA    I66 @BASEBOARD_FAB2_LIB.BASEBOARD_FAB2(SCH_1):PAGE53
  J6L1   41 DQS12N SCONN288_H44441003_PIP-SCONN,HA    I66 @BASEBOARD_FAB2_LIB.BASEBOARD_FAB2(SCH_1):PAGE54

M_F_DQS_DN<13> @BASEBOARD_FAB2_LIB.BASEBOARD_FAB2(SCH_1):M_F_DQS_DN(13)
  U5D1 DE40 DDR5_DQS_DN<13> SKX_EXT_B_BGA1-IC,TBD   I172 @BASEBOARD_FAB2_LIB.BASEBOARD_FAB2(SCH_1):PAGE28
  J4A1  100 DQS13N SCONN288_H44441004_PIP-SCONN,HA    I66 @BASEBOARD_FAB2_LIB.BASEBOARD_FAB2(SCH_1):PAGE53
  J6L1  100 DQS13N SCONN288_H44441003_PIP-SCONN,HA    I66 @BASEBOARD_FAB2_LIB.BASEBOARD_FAB2(SCH_1):PAGE54

M_F_DQS_DN<14> @BASEBOARD_FAB2_LIB.BASEBOARD_FAB2(SCH_1):M_F_DQS_DN(14)
  U5D1 DG32 DDR5_DQS_DN<14> SKX_EXT_B_BGA1-IC,TBD   I172 @BASEBOARD_FAB2_LIB.BASEBOARD_FAB2(SCH_1):PAGE28
  J4A1  111 DQS14N SCONN288_H44441004_PIP-SCONN,HA    I66 @BASEBOARD_FAB2_LIB.BASEBOARD_FAB2(SCH_1):PAGE53
  J6L1  111 DQS14N SCONN288_H44441003_PIP-SCONN,HA    I66 @BASEBOARD_FAB2_LIB.BASEBOARD_FAB2(SCH_1):PAGE54

M_F_DQS_DN<15> @BASEBOARD_FAB2_LIB.BASEBOARD_FAB2(SCH_1):M_F_DQS_DN(15)
  U5D1 CY35 DDR5_DQS_DN<15> SKX_EXT_B_BGA1-IC,TBD   I172 @BASEBOARD_FAB2_LIB.BASEBOARD_FAB2(SCH_1):PAGE28
  J4A1  122 DQS15N SCONN288_H44441004_PIP-SCONN,HA    I66 @BASEBOARD_FAB2_LIB.BASEBOARD_FAB2(SCH_1):PAGE53
  J6L1  122 DQS15N SCONN288_H44441003_PIP-SCONN,HA    I66 @BASEBOARD_FAB2_LIB.BASEBOARD_FAB2(SCH_1):PAGE54

M_F_DQS_DN<16> @BASEBOARD_FAB2_LIB.BASEBOARD_FAB2(SCH_1):M_F_DQS_DN(16)
  U5D1 CY29 DDR5_DQS_DN<16> SKX_EXT_B_BGA1-IC,TBD   I172 @BASEBOARD_FAB2_LIB.BASEBOARD_FAB2(SCH_1):PAGE28
  J4A1  133 DQS16N SCONN288_H44441004_PIP-SCONN,HA    I66 @BASEBOARD_FAB2_LIB.BASEBOARD_FAB2(SCH_1):PAGE53
  J6L1  133 DQS16N SCONN288_H44441003_PIP-SCONN,HA    I66 @BASEBOARD_FAB2_LIB.BASEBOARD_FAB2(SCH_1):PAGE54

M_F_DQS_DN<17> @BASEBOARD_FAB2_LIB.BASEBOARD_FAB2(SCH_1):M_F_DQS_DN(17)
  U5D1 CJ70 DDR5_DQS_DN<17> SKX_EXT_B_BGA1-IC,TBD   I172 @BASEBOARD_FAB2_LIB.BASEBOARD_FAB2(SCH_1):PAGE28
  J4A1   52 DQS17N SCONN288_H44441004_PIP-SCONN,HA    I66 @BASEBOARD_FAB2_LIB.BASEBOARD_FAB2(SCH_1):PAGE53
  J6L1   52 DQS17N SCONN288_H44441003_PIP-SCONN,HA    I66 @BASEBOARD_FAB2_LIB.BASEBOARD_FAB2(SCH_1):PAGE54

M_F_DQS_DN<1> @BASEBOARD_FAB2_LIB.BASEBOARD_FAB2(SCH_1):M_F_DQS_DN(1)
  U5D1 DD77 DDR5_DQS_DN<1> SKX_EXT_B_BGA1-IC,TBD   I172 @BASEBOARD_FAB2_LIB.BASEBOARD_FAB2(SCH_1):PAGE28
  J4A1  163  DQS1N SCONN288_H44441004_PIP-SCONN,HA    I66 @BASEBOARD_FAB2_LIB.BASEBOARD_FAB2(SCH_1):PAGE53
  J6L1  163  DQS1N SCONN288_H44441003_PIP-SCONN,HA    I66 @BASEBOARD_FAB2_LIB.BASEBOARD_FAB2(SCH_1):PAGE54

M_F_DQS_DN<2> @BASEBOARD_FAB2_LIB.BASEBOARD_FAB2(SCH_1):M_F_DQS_DN(2)
  U5D1 DL72 DDR5_DQS_DN<2> SKX_EXT_B_BGA1-IC,TBD   I172 @BASEBOARD_FAB2_LIB.BASEBOARD_FAB2(SCH_1):PAGE28
  J4A1  174  DQS2N SCONN288_H44441004_PIP-SCONN,HA    I66 @BASEBOARD_FAB2_LIB.BASEBOARD_FAB2(SCH_1):PAGE53
  J6L1  174  DQS2N SCONN288_H44441003_PIP-SCONN,HA    I66 @BASEBOARD_FAB2_LIB.BASEBOARD_FAB2(SCH_1):PAGE54

M_F_DQS_DN<3> @BASEBOARD_FAB2_LIB.BASEBOARD_FAB2(SCH_1):M_F_DQS_DN(3)
  U5D1 CV65 DDR5_DQS_DN<3> SKX_EXT_B_BGA1-IC,TBD   I172 @BASEBOARD_FAB2_LIB.BASEBOARD_FAB2(SCH_1):PAGE28
  J4A1  185  DQS3N SCONN288_H44441004_PIP-SCONN,HA    I66 @BASEBOARD_FAB2_LIB.BASEBOARD_FAB2(SCH_1):PAGE53
  J6L1  185  DQS3N SCONN288_H44441003_PIP-SCONN,HA    I66 @BASEBOARD_FAB2_LIB.BASEBOARD_FAB2(SCH_1):PAGE54

M_F_DQS_DN<4> @BASEBOARD_FAB2_LIB.BASEBOARD_FAB2(SCH_1):M_F_DQS_DN(4)
  U5D1 DG40 DDR5_DQS_DN<4> SKX_EXT_B_BGA1-IC,TBD   I172 @BASEBOARD_FAB2_LIB.BASEBOARD_FAB2(SCH_1):PAGE28
  J4A1  244  DQS4N SCONN288_H44441004_PIP-SCONN,HA    I66 @BASEBOARD_FAB2_LIB.BASEBOARD_FAB2(SCH_1):PAGE53
  J6L1  244  DQS4N SCONN288_H44441003_PIP-SCONN,HA    I66 @BASEBOARD_FAB2_LIB.BASEBOARD_FAB2(SCH_1):PAGE54

M_F_DQS_DN<5> @BASEBOARD_FAB2_LIB.BASEBOARD_FAB2(SCH_1):M_F_DQS_DN(5)
  U5D1 DL32 DDR5_DQS_DN<5> SKX_EXT_B_BGA1-IC,TBD   I172 @BASEBOARD_FAB2_LIB.BASEBOARD_FAB2(SCH_1):PAGE28
  J4A1  255  DQS5N SCONN288_H44441004_PIP-SCONN,HA    I66 @BASEBOARD_FAB2_LIB.BASEBOARD_FAB2(SCH_1):PAGE53
  J6L1  255  DQS5N SCONN288_H44441003_PIP-SCONN,HA    I66 @BASEBOARD_FAB2_LIB.BASEBOARD_FAB2(SCH_1):PAGE54

M_F_DQS_DN<6> @BASEBOARD_FAB2_LIB.BASEBOARD_FAB2(SCH_1):M_F_DQS_DN(6)
  U5D1 DD35 DDR5_DQS_DN<6> SKX_EXT_B_BGA1-IC,TBD   I172 @BASEBOARD_FAB2_LIB.BASEBOARD_FAB2(SCH_1):PAGE28
  J4A1  266  DQS6N SCONN288_H44441004_PIP-SCONN,HA    I66 @BASEBOARD_FAB2_LIB.BASEBOARD_FAB2(SCH_1):PAGE53
  J6L1  266  DQS6N SCONN288_H44441003_PIP-SCONN,HA    I66 @BASEBOARD_FAB2_LIB.BASEBOARD_FAB2(SCH_1):PAGE54

M_F_DQS_DN<7> @BASEBOARD_FAB2_LIB.BASEBOARD_FAB2(SCH_1):M_F_DQS_DN(7)
  U5D1 DD29 DDR5_DQS_DN<7> SKX_EXT_B_BGA1-IC,TBD   I172 @BASEBOARD_FAB2_LIB.BASEBOARD_FAB2(SCH_1):PAGE28
  J4A1  277  DQS7N SCONN288_H44441004_PIP-SCONN,HA    I66 @BASEBOARD_FAB2_LIB.BASEBOARD_FAB2(SCH_1):PAGE53
  J6L1  277  DQS7N SCONN288_H44441003_PIP-SCONN,HA    I66 @BASEBOARD_FAB2_LIB.BASEBOARD_FAB2(SCH_1):PAGE54

M_F_DQS_DN<8> @BASEBOARD_FAB2_LIB.BASEBOARD_FAB2(SCH_1):M_F_DQS_DN(8)
  U5D1 CN70 DDR5_DQS_DN<8> SKX_EXT_B_BGA1-IC,TBD   I172 @BASEBOARD_FAB2_LIB.BASEBOARD_FAB2(SCH_1):PAGE28
  J4A1  196  DQS8N SCONN288_H44441004_PIP-SCONN,HA    I66 @BASEBOARD_FAB2_LIB.BASEBOARD_FAB2(SCH_1):PAGE53
  J6L1  196  DQS8N SCONN288_H44441003_PIP-SCONN,HA    I66 @BASEBOARD_FAB2_LIB.BASEBOARD_FAB2(SCH_1):PAGE54

M_F_DQS_DN<9> @BASEBOARD_FAB2_LIB.BASEBOARD_FAB2(SCH_1):M_F_DQS_DN(9)
  U5D1 CT75 DDR5_DQS_DN<9> SKX_EXT_B_BGA1-IC,TBD   I172 @BASEBOARD_FAB2_LIB.BASEBOARD_FAB2(SCH_1):PAGE28
  J4A1    8  DQS9N SCONN288_H44441004_PIP-SCONN,HA    I66 @BASEBOARD_FAB2_LIB.BASEBOARD_FAB2(SCH_1):PAGE53
  J6L1    8  DQS9N SCONN288_H44441003_PIP-SCONN,HA    I66 @BASEBOARD_FAB2_LIB.BASEBOARD_FAB2(SCH_1):PAGE54

M_F_DQS_DP<0> @BASEBOARD_FAB2_LIB.BASEBOARD_FAB2(SCH_1):M_F_DQS_DP(0)
  U5D1 CR76 DDR5_DQS_DP<0> SKX_EXT_B_BGA1-IC,TBD   I172 @BASEBOARD_FAB2_LIB.BASEBOARD_FAB2(SCH_1):PAGE28
  J4A1  153  DQS0P SCONN288_H44441004_PIP-SCONN,HA    I66 @BASEBOARD_FAB2_LIB.BASEBOARD_FAB2(SCH_1):PAGE53
  J6L1  153  DQS0P SCONN288_H44441003_PIP-SCONN,HA    I66 @BASEBOARD_FAB2_LIB.BASEBOARD_FAB2(SCH_1):PAGE54

M_F_DQS_DP<10> @BASEBOARD_FAB2_LIB.BASEBOARD_FAB2(SCH_1):M_F_DQS_DP(10)
  U5D1 DG74 DDR5_DQS_DP<10> SKX_EXT_B_BGA1-IC,TBD   I172 @BASEBOARD_FAB2_LIB.BASEBOARD_FAB2(SCH_1):PAGE28
  J4A1   18 DQS10P SCONN288_H44441004_PIP-SCONN,HA    I66 @BASEBOARD_FAB2_LIB.BASEBOARD_FAB2(SCH_1):PAGE53
  J6L1   18 DQS10P SCONN288_H44441003_PIP-SCONN,HA    I66 @BASEBOARD_FAB2_LIB.BASEBOARD_FAB2(SCH_1):PAGE54

M_F_DQS_DP<11> @BASEBOARD_FAB2_LIB.BASEBOARD_FAB2(SCH_1):M_F_DQS_DP(11)
  U5D1 DH69 DDR5_DQS_DP<11> SKX_EXT_B_BGA1-IC,TBD   I172 @BASEBOARD_FAB2_LIB.BASEBOARD_FAB2(SCH_1):PAGE28
  J4A1   29 DQS11P SCONN288_H44441004_PIP-SCONN,HA    I66 @BASEBOARD_FAB2_LIB.BASEBOARD_FAB2(SCH_1):PAGE53
  J6L1   29 DQS11P SCONN288_H44441003_PIP-SCONN,HA    I66 @BASEBOARD_FAB2_LIB.BASEBOARD_FAB2(SCH_1):PAGE54

M_F_DQS_DP<12> @BASEBOARD_FAB2_LIB.BASEBOARD_FAB2(SCH_1):M_F_DQS_DP(12)
  U5D1 CM65 DDR5_DQS_DP<12> SKX_EXT_B_BGA1-IC,TBD   I172 @BASEBOARD_FAB2_LIB.BASEBOARD_FAB2(SCH_1):PAGE28
  J4A1   40 DQS12P SCONN288_H44441004_PIP-SCONN,HA    I66 @BASEBOARD_FAB2_LIB.BASEBOARD_FAB2(SCH_1):PAGE53
  J6L1   40 DQS12P SCONN288_H44441003_PIP-SCONN,HA    I66 @BASEBOARD_FAB2_LIB.BASEBOARD_FAB2(SCH_1):PAGE54

M_F_DQS_DP<13> @BASEBOARD_FAB2_LIB.BASEBOARD_FAB2(SCH_1):M_F_DQS_DP(13)
  U5D1 DC40 DDR5_DQS_DP<13> SKX_EXT_B_BGA1-IC,TBD   I172 @BASEBOARD_FAB2_LIB.BASEBOARD_FAB2(SCH_1):PAGE28
  J4A1   99 DQS13P SCONN288_H44441004_PIP-SCONN,HA    I66 @BASEBOARD_FAB2_LIB.BASEBOARD_FAB2(SCH_1):PAGE53
  J6L1   99 DQS13P SCONN288_H44441003_PIP-SCONN,HA    I66 @BASEBOARD_FAB2_LIB.BASEBOARD_FAB2(SCH_1):PAGE54

M_F_DQS_DP<14> @BASEBOARD_FAB2_LIB.BASEBOARD_FAB2(SCH_1):M_F_DQS_DP(14)
  U5D1 DE32 DDR5_DQS_DP<14> SKX_EXT_B_BGA1-IC,TBD   I172 @BASEBOARD_FAB2_LIB.BASEBOARD_FAB2(SCH_1):PAGE28
  J4A1  110 DQS14P SCONN288_H44441004_PIP-SCONN,HA    I66 @BASEBOARD_FAB2_LIB.BASEBOARD_FAB2(SCH_1):PAGE53
  J6L1  110 DQS14P SCONN288_H44441003_PIP-SCONN,HA    I66 @BASEBOARD_FAB2_LIB.BASEBOARD_FAB2(SCH_1):PAGE54

M_F_DQS_DP<15> @BASEBOARD_FAB2_LIB.BASEBOARD_FAB2(SCH_1):M_F_DQS_DP(15)
  U5D1 CV35 DDR5_DQS_DP<15> SKX_EXT_B_BGA1-IC,TBD   I172 @BASEBOARD_FAB2_LIB.BASEBOARD_FAB2(SCH_1):PAGE28
  J4A1  121 DQS15P SCONN288_H44441004_PIP-SCONN,HA    I66 @BASEBOARD_FAB2_LIB.BASEBOARD_FAB2(SCH_1):PAGE53
  J6L1  121 DQS15P SCONN288_H44441003_PIP-SCONN,HA    I66 @BASEBOARD_FAB2_LIB.BASEBOARD_FAB2(SCH_1):PAGE54

M_F_DQS_DP<16> @BASEBOARD_FAB2_LIB.BASEBOARD_FAB2(SCH_1):M_F_DQS_DP(16)
  U5D1 CV29 DDR5_DQS_DP<16> SKX_EXT_B_BGA1-IC,TBD   I172 @BASEBOARD_FAB2_LIB.BASEBOARD_FAB2(SCH_1):PAGE28
  J4A1  132 DQS16P SCONN288_H44441004_PIP-SCONN,HA    I66 @BASEBOARD_FAB2_LIB.BASEBOARD_FAB2(SCH_1):PAGE53
  J6L1  132 DQS16P SCONN288_H44441003_PIP-SCONN,HA    I66 @BASEBOARD_FAB2_LIB.BASEBOARD_FAB2(SCH_1):PAGE54

M_F_DQS_DP<17> @BASEBOARD_FAB2_LIB.BASEBOARD_FAB2(SCH_1):M_F_DQS_DP(17)
  U5D1 CG70 DDR5_DQS_DP<17> SKX_EXT_B_BGA1-IC,TBD   I172 @BASEBOARD_FAB2_LIB.BASEBOARD_FAB2(SCH_1):PAGE28
  J4A1   51 DQS17P SCONN288_H44441004_PIP-SCONN,HA    I66 @BASEBOARD_FAB2_LIB.BASEBOARD_FAB2(SCH_1):PAGE53
  J6L1   51 DQS17P SCONN288_H44441003_PIP-SCONN,HA    I66 @BASEBOARD_FAB2_LIB.BASEBOARD_FAB2(SCH_1):PAGE54

M_F_DQS_DP<1> @BASEBOARD_FAB2_LIB.BASEBOARD_FAB2(SCH_1):M_F_DQS_DP(1)
  U5D1 DE76 DDR5_DQS_DP<1> SKX_EXT_B_BGA1-IC,TBD   I172 @BASEBOARD_FAB2_LIB.BASEBOARD_FAB2(SCH_1):PAGE28
  J4A1  164  DQS1P SCONN288_H44441004_PIP-SCONN,HA    I66 @BASEBOARD_FAB2_LIB.BASEBOARD_FAB2(SCH_1):PAGE53
  J6L1  164  DQS1P SCONN288_H44441003_PIP-SCONN,HA    I66 @BASEBOARD_FAB2_LIB.BASEBOARD_FAB2(SCH_1):PAGE54

M_F_DQS_DP<2> @BASEBOARD_FAB2_LIB.BASEBOARD_FAB2(SCH_1):M_F_DQS_DP(2)
  U5D1 DK71 DDR5_DQS_DP<2> SKX_EXT_B_BGA1-IC,TBD   I172 @BASEBOARD_FAB2_LIB.BASEBOARD_FAB2(SCH_1):PAGE28
  J4A1  175  DQS2P SCONN288_H44441004_PIP-SCONN,HA    I66 @BASEBOARD_FAB2_LIB.BASEBOARD_FAB2(SCH_1):PAGE53
  J6L1  175  DQS2P SCONN288_H44441003_PIP-SCONN,HA    I66 @BASEBOARD_FAB2_LIB.BASEBOARD_FAB2(SCH_1):PAGE54

M_F_DQS_DP<3> @BASEBOARD_FAB2_LIB.BASEBOARD_FAB2(SCH_1):M_F_DQS_DP(3)
  U5D1 CT65 DDR5_DQS_DP<3> SKX_EXT_B_BGA1-IC,TBD   I172 @BASEBOARD_FAB2_LIB.BASEBOARD_FAB2(SCH_1):PAGE28
  J4A1  186  DQS3P SCONN288_H44441004_PIP-SCONN,HA    I66 @BASEBOARD_FAB2_LIB.BASEBOARD_FAB2(SCH_1):PAGE53
  J6L1  186  DQS3P SCONN288_H44441003_PIP-SCONN,HA    I66 @BASEBOARD_FAB2_LIB.BASEBOARD_FAB2(SCH_1):PAGE54

M_F_DQS_DP<4> @BASEBOARD_FAB2_LIB.BASEBOARD_FAB2(SCH_1):M_F_DQS_DP(4)
  U5D1 DJ40 DDR5_DQS_DP<4> SKX_EXT_B_BGA1-IC,TBD   I172 @BASEBOARD_FAB2_LIB.BASEBOARD_FAB2(SCH_1):PAGE28
  J4A1  245  DQS4P SCONN288_H44441004_PIP-SCONN,HA    I66 @BASEBOARD_FAB2_LIB.BASEBOARD_FAB2(SCH_1):PAGE53
  J6L1  245  DQS4P SCONN288_H44441003_PIP-SCONN,HA    I66 @BASEBOARD_FAB2_LIB.BASEBOARD_FAB2(SCH_1):PAGE54

M_F_DQS_DP<5> @BASEBOARD_FAB2_LIB.BASEBOARD_FAB2(SCH_1):M_F_DQS_DP(5)
  U5D1 DJ32 DDR5_DQS_DP<5> SKX_EXT_B_BGA1-IC,TBD   I172 @BASEBOARD_FAB2_LIB.BASEBOARD_FAB2(SCH_1):PAGE28
  J4A1  256  DQS5P SCONN288_H44441004_PIP-SCONN,HA    I66 @BASEBOARD_FAB2_LIB.BASEBOARD_FAB2(SCH_1):PAGE53
  J6L1  256  DQS5P SCONN288_H44441003_PIP-SCONN,HA    I66 @BASEBOARD_FAB2_LIB.BASEBOARD_FAB2(SCH_1):PAGE54

M_F_DQS_DP<6> @BASEBOARD_FAB2_LIB.BASEBOARD_FAB2(SCH_1):M_F_DQS_DP(6)
  U5D1 DB35 DDR5_DQS_DP<6> SKX_EXT_B_BGA1-IC,TBD   I172 @BASEBOARD_FAB2_LIB.BASEBOARD_FAB2(SCH_1):PAGE28
  J4A1  267  DQS6P SCONN288_H44441004_PIP-SCONN,HA    I66 @BASEBOARD_FAB2_LIB.BASEBOARD_FAB2(SCH_1):PAGE53
  J6L1  267  DQS6P SCONN288_H44441003_PIP-SCONN,HA    I66 @BASEBOARD_FAB2_LIB.BASEBOARD_FAB2(SCH_1):PAGE54

M_F_DQS_DP<7> @BASEBOARD_FAB2_LIB.BASEBOARD_FAB2(SCH_1):M_F_DQS_DP(7)
  U5D1 DB29 DDR5_DQS_DP<7> SKX_EXT_B_BGA1-IC,TBD   I172 @BASEBOARD_FAB2_LIB.BASEBOARD_FAB2(SCH_1):PAGE28
  J4A1  278  DQS7P SCONN288_H44441004_PIP-SCONN,HA    I66 @BASEBOARD_FAB2_LIB.BASEBOARD_FAB2(SCH_1):PAGE53
  J6L1  278  DQS7P SCONN288_H44441003_PIP-SCONN,HA    I66 @BASEBOARD_FAB2_LIB.BASEBOARD_FAB2(SCH_1):PAGE54

M_F_DQS_DP<8> @BASEBOARD_FAB2_LIB.BASEBOARD_FAB2(SCH_1):M_F_DQS_DP(8)
  U5D1 CL70 DDR5_DQS_DP<8> SKX_EXT_B_BGA1-IC,TBD   I172 @BASEBOARD_FAB2_LIB.BASEBOARD_FAB2(SCH_1):PAGE28
  J4A1  197  DQS8P SCONN288_H44441004_PIP-SCONN,HA    I66 @BASEBOARD_FAB2_LIB.BASEBOARD_FAB2(SCH_1):PAGE53
  J6L1  197  DQS8P SCONN288_H44441003_PIP-SCONN,HA    I66 @BASEBOARD_FAB2_LIB.BASEBOARD_FAB2(SCH_1):PAGE54

M_F_DQS_DP<9> @BASEBOARD_FAB2_LIB.BASEBOARD_FAB2(SCH_1):M_F_DQS_DP(9)
  U5D1 CU74 DDR5_DQS_DP<9> SKX_EXT_B_BGA1-IC,TBD   I172 @BASEBOARD_FAB2_LIB.BASEBOARD_FAB2(SCH_1):PAGE28
  J4A1    7  DQS9P SCONN288_H44441004_PIP-SCONN,HA    I66 @BASEBOARD_FAB2_LIB.BASEBOARD_FAB2(SCH_1):PAGE53
  J6L1    7  DQS9P SCONN288_H44441003_PIP-SCONN,HA    I66 @BASEBOARD_FAB2_LIB.BASEBOARD_FAB2(SCH_1):PAGE54

M_F_ECC<0> @BASEBOARD_FAB2_LIB.BASEBOARD_FAB2(SCH_1):M_F_ECC(0)
  U5D1 CH71 DDR5_ECC<0> SKX_EXT_B_BGA1-IC,TBD   I172 @BASEBOARD_FAB2_LIB.BASEBOARD_FAB2(SCH_1):PAGE28
  J4A1  194  CB<1> SCONN288_H44441004_PIP-SCONN,HA   I111 @BASEBOARD_FAB2_LIB.BASEBOARD_FAB2(SCH_1):PAGE53
  J6L1   49  CB<0> SCONN288_H44441003_PIP-SCONN,HA   I111 @BASEBOARD_FAB2_LIB.BASEBOARD_FAB2(SCH_1):PAGE54

M_F_ECC<1> @BASEBOARD_FAB2_LIB.BASEBOARD_FAB2(SCH_1):M_F_ECC(1)
  U5D1 CM71 DDR5_ECC<1> SKX_EXT_B_BGA1-IC,TBD   I172 @BASEBOARD_FAB2_LIB.BASEBOARD_FAB2(SCH_1):PAGE28
  J4A1   49  CB<0> SCONN288_H44441004_PIP-SCONN,HA   I111 @BASEBOARD_FAB2_LIB.BASEBOARD_FAB2(SCH_1):PAGE53
  J6L1  194  CB<1> SCONN288_H44441003_PIP-SCONN,HA   I111 @BASEBOARD_FAB2_LIB.BASEBOARD_FAB2(SCH_1):PAGE54

M_F_ECC<2> @BASEBOARD_FAB2_LIB.BASEBOARD_FAB2(SCH_1):M_F_ECC(2)
  U5D1 CJ68 DDR5_ECC<2> SKX_EXT_B_BGA1-IC,TBD   I172 @BASEBOARD_FAB2_LIB.BASEBOARD_FAB2(SCH_1):PAGE28
  J4A1  201  CB<3> SCONN288_H44441004_PIP-SCONN,HA   I111 @BASEBOARD_FAB2_LIB.BASEBOARD_FAB2(SCH_1):PAGE53
  J6L1   56  CB<2> SCONN288_H44441003_PIP-SCONN,HA   I111 @BASEBOARD_FAB2_LIB.BASEBOARD_FAB2(SCH_1):PAGE54

M_F_ECC<3> @BASEBOARD_FAB2_LIB.BASEBOARD_FAB2(SCH_1):M_F_ECC(3)
  U5D1 CL68 DDR5_ECC<3> SKX_EXT_B_BGA1-IC,TBD   I172 @BASEBOARD_FAB2_LIB.BASEBOARD_FAB2(SCH_1):PAGE28
  J4A1   56  CB<2> SCONN288_H44441004_PIP-SCONN,HA   I111 @BASEBOARD_FAB2_LIB.BASEBOARD_FAB2(SCH_1):PAGE53
  J6L1  201  CB<3> SCONN288_H44441003_PIP-SCONN,HA   I111 @BASEBOARD_FAB2_LIB.BASEBOARD_FAB2(SCH_1):PAGE54

M_F_ECC<4> @BASEBOARD_FAB2_LIB.BASEBOARD_FAB2(SCH_1):M_F_ECC(4)
  U5D1 CJ72 DDR5_ECC<4> SKX_EXT_B_BGA1-IC,TBD   I172 @BASEBOARD_FAB2_LIB.BASEBOARD_FAB2(SCH_1):PAGE28
  J4A1  192  CB<5> SCONN288_H44441004_PIP-SCONN,HA   I111 @BASEBOARD_FAB2_LIB.BASEBOARD_FAB2(SCH_1):PAGE53
  J6L1   47  CB<4> SCONN288_H44441003_PIP-SCONN,HA   I111 @BASEBOARD_FAB2_LIB.BASEBOARD_FAB2(SCH_1):PAGE54

M_F_ECC<5> @BASEBOARD_FAB2_LIB.BASEBOARD_FAB2(SCH_1):M_F_ECC(5)
  U5D1 CL72 DDR5_ECC<5> SKX_EXT_B_BGA1-IC,TBD   I172 @BASEBOARD_FAB2_LIB.BASEBOARD_FAB2(SCH_1):PAGE28
  J4A1   47  CB<4> SCONN288_H44441004_PIP-SCONN,HA   I111 @BASEBOARD_FAB2_LIB.BASEBOARD_FAB2(SCH_1):PAGE53
  J6L1  192  CB<5> SCONN288_H44441003_PIP-SCONN,HA   I111 @BASEBOARD_FAB2_LIB.BASEBOARD_FAB2(SCH_1):PAGE54

M_F_ECC<6> @BASEBOARD_FAB2_LIB.BASEBOARD_FAB2(SCH_1):M_F_ECC(6)
  U5D1 CH69 DDR5_ECC<6> SKX_EXT_B_BGA1-IC,TBD   I172 @BASEBOARD_FAB2_LIB.BASEBOARD_FAB2(SCH_1):PAGE28
  J4A1  199  CB<7> SCONN288_H44441004_PIP-SCONN,HA   I111 @BASEBOARD_FAB2_LIB.BASEBOARD_FAB2(SCH_1):PAGE53
  J6L1   54  CB<6> SCONN288_H44441003_PIP-SCONN,HA   I111 @BASEBOARD_FAB2_LIB.BASEBOARD_FAB2(SCH_1):PAGE54

M_F_ECC<7> @BASEBOARD_FAB2_LIB.BASEBOARD_FAB2(SCH_1):M_F_ECC(7)
  U5D1 CM69 DDR5_ECC<7> SKX_EXT_B_BGA1-IC,TBD   I172 @BASEBOARD_FAB2_LIB.BASEBOARD_FAB2(SCH_1):PAGE28
  J4A1   54  CB<6> SCONN288_H44441004_PIP-SCONN,HA   I111 @BASEBOARD_FAB2_LIB.BASEBOARD_FAB2(SCH_1):PAGE53
  J6L1  199  CB<7> SCONN288_H44441003_PIP-SCONN,HA   I111 @BASEBOARD_FAB2_LIB.BASEBOARD_FAB2(SCH_1):PAGE54

M_F_MA<0> @BASEBOARD_FAB2_LIB.BASEBOARD_FAB2(SCH_1):M_F_MA(0)
  U5D1 DF53 DDR5_MA<0> SKX_EXT_B_BGA1-IC,TBD   I172 @BASEBOARD_FAB2_LIB.BASEBOARD_FAB2(SCH_1):PAGE28
  J4A1   79     A0 SCONN288_H44441004_PIP-SCONN,HA   I111 @BASEBOARD_FAB2_LIB.BASEBOARD_FAB2(SCH_1):PAGE53
  J6L1   79     A0 SCONN288_H44441003_PIP-SCONN,HA   I111 @BASEBOARD_FAB2_LIB.BASEBOARD_FAB2(SCH_1):PAGE54

M_F_MA<10> @BASEBOARD_FAB2_LIB.BASEBOARD_FAB2(SCH_1):M_F_MA(10)
  U5D1 DD55 DDR5_MA<10> SKX_EXT_B_BGA1-IC,TBD   I172 @BASEBOARD_FAB2_LIB.BASEBOARD_FAB2(SCH_1):PAGE28
  J4A1  225    A10 SCONN288_H44441004_PIP-SCONN,HA   I111 @BASEBOARD_FAB2_LIB.BASEBOARD_FAB2(SCH_1):PAGE53
  J6L1  225    A10 SCONN288_H44441003_PIP-SCONN,HA   I111 @BASEBOARD_FAB2_LIB.BASEBOARD_FAB2(SCH_1):PAGE54

M_F_MA<11> @BASEBOARD_FAB2_LIB.BASEBOARD_FAB2(SCH_1):M_F_MA(11)
  U5D1 DA60 DDR5_MA<11> SKX_EXT_B_BGA1-IC,TBD   I172 @BASEBOARD_FAB2_LIB.BASEBOARD_FAB2(SCH_1):PAGE28
  J4A1  210    A11 SCONN288_H44441004_PIP-SCONN,HA   I111 @BASEBOARD_FAB2_LIB.BASEBOARD_FAB2(SCH_1):PAGE53
  J6L1  210    A11 SCONN288_H44441003_PIP-SCONN,HA   I111 @BASEBOARD_FAB2_LIB.BASEBOARD_FAB2(SCH_1):PAGE54

M_F_MA<12> @BASEBOARD_FAB2_LIB.BASEBOARD_FAB2(SCH_1):M_F_MA(12)
  U5D1 DG60 DDR5_MA<12> SKX_EXT_B_BGA1-IC,TBD   I172 @BASEBOARD_FAB2_LIB.BASEBOARD_FAB2(SCH_1):PAGE28
  J4A1   65    A12 SCONN288_H44441004_PIP-SCONN,HA   I111 @BASEBOARD_FAB2_LIB.BASEBOARD_FAB2(SCH_1):PAGE53
  J6L1   65    A12 SCONN288_H44441003_PIP-SCONN,HA   I111 @BASEBOARD_FAB2_LIB.BASEBOARD_FAB2(SCH_1):PAGE54

M_F_MA<13> @BASEBOARD_FAB2_LIB.BASEBOARD_FAB2(SCH_1):M_F_MA(13)
  U5D1 DD53 DDR5_MA<13> SKX_EXT_B_BGA1-IC,TBD   I172 @BASEBOARD_FAB2_LIB.BASEBOARD_FAB2(SCH_1):PAGE28
  J4A1  232    A13 SCONN288_H44441004_PIP-SCONN,HA   I111 @BASEBOARD_FAB2_LIB.BASEBOARD_FAB2(SCH_1):PAGE53
  J6L1  232    A13 SCONN288_H44441003_PIP-SCONN,HA   I111 @BASEBOARD_FAB2_LIB.BASEBOARD_FAB2(SCH_1):PAGE54

M_F_MA<14> @BASEBOARD_FAB2_LIB.BASEBOARD_FAB2(SCH_1):M_F_MA(14)
  U5D1 DJ50 DDR5_MA<14> SKX_EXT_B_BGA1-IC,TBD   I172 @BASEBOARD_FAB2_LIB.BASEBOARD_FAB2(SCH_1):PAGE28
  J4A1  228 A14_WE_N SCONN288_H44441004_PIP-SCONN,HA   I111 @BASEBOARD_FAB2_LIB.BASEBOARD_FAB2(SCH_1):PAGE53
  J6L1  228 A14_WE_N SCONN288_H44441003_PIP-SCONN,HA   I111 @BASEBOARD_FAB2_LIB.BASEBOARD_FAB2(SCH_1):PAGE54

M_F_MA<15> @BASEBOARD_FAB2_LIB.BASEBOARD_FAB2(SCH_1):M_F_MA(15)
  U5D1 DC54 DDR5_MA<15> SKX_EXT_B_BGA1-IC,TBD   I172 @BASEBOARD_FAB2_LIB.BASEBOARD_FAB2(SCH_1):PAGE28
  J4A1   86 A15_CAS_N SCONN288_H44441004_PIP-SCONN,HA   I111 @BASEBOARD_FAB2_LIB.BASEBOARD_FAB2(SCH_1):PAGE53
  J6L1   86 A15_CAS_N SCONN288_H44441003_PIP-SCONN,HA   I111 @BASEBOARD_FAB2_LIB.BASEBOARD_FAB2(SCH_1):PAGE54

M_F_MA<16> @BASEBOARD_FAB2_LIB.BASEBOARD_FAB2(SCH_1):M_F_MA(16)
  U5D1 DG52 DDR5_MA<16> SKX_EXT_B_BGA1-IC,TBD   I172 @BASEBOARD_FAB2_LIB.BASEBOARD_FAB2(SCH_1):PAGE28
  J4A1   82 A16_RAS_N SCONN288_H44441004_PIP-SCONN,HA   I111 @BASEBOARD_FAB2_LIB.BASEBOARD_FAB2(SCH_1):PAGE53
  J6L1   82 A16_RAS_N SCONN288_H44441003_PIP-SCONN,HA   I111 @BASEBOARD_FAB2_LIB.BASEBOARD_FAB2(SCH_1):PAGE54

M_F_MA<17> @BASEBOARD_FAB2_LIB.BASEBOARD_FAB2(SCH_1):M_F_MA(17)
  U5D1 DE46 DDR5_MA<17> SKX_EXT_B_BGA1-IC,TBD   I172 @BASEBOARD_FAB2_LIB.BASEBOARD_FAB2(SCH_1):PAGE28
  J4A1  234    A17 SCONN288_H44441004_PIP-SCONN,HA   I111 @BASEBOARD_FAB2_LIB.BASEBOARD_FAB2(SCH_1):PAGE53
  J6L1  234    A17 SCONN288_H44441003_PIP-SCONN,HA   I111 @BASEBOARD_FAB2_LIB.BASEBOARD_FAB2(SCH_1):PAGE54

M_F_MA<1> @BASEBOARD_FAB2_LIB.BASEBOARD_FAB2(SCH_1):M_F_MA(1)
  U5D1 DC58 DDR5_MA<1> SKX_EXT_B_BGA1-IC,TBD   I172 @BASEBOARD_FAB2_LIB.BASEBOARD_FAB2(SCH_1):PAGE28
  J4A1   72     A1 SCONN288_H44441004_PIP-SCONN,HA   I111 @BASEBOARD_FAB2_LIB.BASEBOARD_FAB2(SCH_1):PAGE53
  J6L1   72     A1 SCONN288_H44441003_PIP-SCONN,HA   I111 @BASEBOARD_FAB2_LIB.BASEBOARD_FAB2(SCH_1):PAGE54

M_F_MA<2> @BASEBOARD_FAB2_LIB.BASEBOARD_FAB2(SCH_1):M_F_MA(2)
  U5D1 DD57 DDR5_MA<2> SKX_EXT_B_BGA1-IC,TBD   I172 @BASEBOARD_FAB2_LIB.BASEBOARD_FAB2(SCH_1):PAGE28
  J4A1  216     A2 SCONN288_H44441004_PIP-SCONN,HA   I111 @BASEBOARD_FAB2_LIB.BASEBOARD_FAB2(SCH_1):PAGE53
  J6L1  216     A2 SCONN288_H44441003_PIP-SCONN,HA   I111 @BASEBOARD_FAB2_LIB.BASEBOARD_FAB2(SCH_1):PAGE54

M_F_MA<3> @BASEBOARD_FAB2_LIB.BASEBOARD_FAB2(SCH_1):M_F_MA(3)
  U5D1 DG58 DDR5_MA<3> SKX_EXT_B_BGA1-IC,TBD   I172 @BASEBOARD_FAB2_LIB.BASEBOARD_FAB2(SCH_1):PAGE28
  J4A1   71     A3 SCONN288_H44441004_PIP-SCONN,HA   I111 @BASEBOARD_FAB2_LIB.BASEBOARD_FAB2(SCH_1):PAGE53
  J6L1   71     A3 SCONN288_H44441003_PIP-SCONN,HA   I111 @BASEBOARD_FAB2_LIB.BASEBOARD_FAB2(SCH_1):PAGE54

M_F_MA<4> @BASEBOARD_FAB2_LIB.BASEBOARD_FAB2(SCH_1):M_F_MA(4)
  U5D1 DJ58 DDR5_MA<4> SKX_EXT_B_BGA1-IC,TBD   I172 @BASEBOARD_FAB2_LIB.BASEBOARD_FAB2(SCH_1):PAGE28
  J4A1  214     A4 SCONN288_H44441004_PIP-SCONN,HA   I111 @BASEBOARD_FAB2_LIB.BASEBOARD_FAB2(SCH_1):PAGE53
  J6L1  214     A4 SCONN288_H44441003_PIP-SCONN,HA   I111 @BASEBOARD_FAB2_LIB.BASEBOARD_FAB2(SCH_1):PAGE54

M_F_MA<5> @BASEBOARD_FAB2_LIB.BASEBOARD_FAB2(SCH_1):M_F_MA(5)
  U5D1 DF59 DDR5_MA<5> SKX_EXT_B_BGA1-IC,TBD   I172 @BASEBOARD_FAB2_LIB.BASEBOARD_FAB2(SCH_1):PAGE28
  J4A1  213     A5 SCONN288_H44441004_PIP-SCONN,HA   I111 @BASEBOARD_FAB2_LIB.BASEBOARD_FAB2(SCH_1):PAGE53
  J6L1  213     A5 SCONN288_H44441003_PIP-SCONN,HA   I111 @BASEBOARD_FAB2_LIB.BASEBOARD_FAB2(SCH_1):PAGE54

M_F_MA<6> @BASEBOARD_FAB2_LIB.BASEBOARD_FAB2(SCH_1):M_F_MA(6)
  U5D1 DK59 DDR5_MA<6> SKX_EXT_B_BGA1-IC,TBD   I172 @BASEBOARD_FAB2_LIB.BASEBOARD_FAB2(SCH_1):PAGE28
  J4A1   69     A6 SCONN288_H44441004_PIP-SCONN,HA   I111 @BASEBOARD_FAB2_LIB.BASEBOARD_FAB2(SCH_1):PAGE53
  J6L1   69     A6 SCONN288_H44441003_PIP-SCONN,HA   I111 @BASEBOARD_FAB2_LIB.BASEBOARD_FAB2(SCH_1):PAGE54

M_F_MA<7> @BASEBOARD_FAB2_LIB.BASEBOARD_FAB2(SCH_1):M_F_MA(7)
  U5D1 DC60 DDR5_MA<7> SKX_EXT_B_BGA1-IC,TBD   I172 @BASEBOARD_FAB2_LIB.BASEBOARD_FAB2(SCH_1):PAGE28
  J4A1  211     A7 SCONN288_H44441004_PIP-SCONN,HA   I111 @BASEBOARD_FAB2_LIB.BASEBOARD_FAB2(SCH_1):PAGE53
  J6L1  211     A7 SCONN288_H44441003_PIP-SCONN,HA   I111 @BASEBOARD_FAB2_LIB.BASEBOARD_FAB2(SCH_1):PAGE54

M_F_MA<8> @BASEBOARD_FAB2_LIB.BASEBOARD_FAB2(SCH_1):M_F_MA(8)
  U5D1 DD59 DDR5_MA<8> SKX_EXT_B_BGA1-IC,TBD   I172 @BASEBOARD_FAB2_LIB.BASEBOARD_FAB2(SCH_1):PAGE28
  J4A1   68     A8 SCONN288_H44441004_PIP-SCONN,HA   I111 @BASEBOARD_FAB2_LIB.BASEBOARD_FAB2(SCH_1):PAGE53
  J6L1   68     A8 SCONN288_H44441003_PIP-SCONN,HA   I111 @BASEBOARD_FAB2_LIB.BASEBOARD_FAB2(SCH_1):PAGE54

M_F_MA<9> @BASEBOARD_FAB2_LIB.BASEBOARD_FAB2(SCH_1):M_F_MA(9)
  U5D1 DA58 DDR5_MA<9> SKX_EXT_B_BGA1-IC,TBD   I172 @BASEBOARD_FAB2_LIB.BASEBOARD_FAB2(SCH_1):PAGE28
  J4A1   66     A9 SCONN288_H44441004_PIP-SCONN,HA   I111 @BASEBOARD_FAB2_LIB.BASEBOARD_FAB2(SCH_1):PAGE53
  J6L1   66     A9 SCONN288_H44441003_PIP-SCONN,HA   I111 @BASEBOARD_FAB2_LIB.BASEBOARD_FAB2(SCH_1):PAGE54

M_F_ODT<0> @BASEBOARD_FAB2_LIB.BASEBOARD_FAB2(SCH_1):M_F_ODT(0)
  U5D1 DG50 DDR5_ODT<0> SKX_EXT_B_BGA1-IC,TBD   I172 @BASEBOARD_FAB2_LIB.BASEBOARD_FAB2(SCH_1):PAGE28
  J4A1   87 ODT<0> SCONN288_H44441004_PIP-SCONN,HA   I111 @BASEBOARD_FAB2_LIB.BASEBOARD_FAB2(SCH_1):PAGE53

M_F_ODT<1> @BASEBOARD_FAB2_LIB.BASEBOARD_FAB2(SCH_1):M_F_ODT(1)
  U5D1 DG48 DDR5_ODT<1> SKX_EXT_B_BGA1-IC,TBD   I172 @BASEBOARD_FAB2_LIB.BASEBOARD_FAB2(SCH_1):PAGE28
  J4A1   91 ODT<1> SCONN288_H44441004_PIP-SCONN,HA   I111 @BASEBOARD_FAB2_LIB.BASEBOARD_FAB2(SCH_1):PAGE53

M_F_ODT<2> @BASEBOARD_FAB2_LIB.BASEBOARD_FAB2(SCH_1):M_F_ODT(2)
  U5D1 DK49 DDR5_ODT<2> SKX_EXT_B_BGA1-IC,TBD   I172 @BASEBOARD_FAB2_LIB.BASEBOARD_FAB2(SCH_1):PAGE28
  J6L1   87 ODT<0> SCONN288_H44441003_PIP-SCONN,HA   I111 @BASEBOARD_FAB2_LIB.BASEBOARD_FAB2(SCH_1):PAGE54

M_F_ODT<3> @BASEBOARD_FAB2_LIB.BASEBOARD_FAB2(SCH_1):M_F_ODT(3)
  U5D1 DF47 DDR5_ODT<3> SKX_EXT_B_BGA1-IC,TBD   I172 @BASEBOARD_FAB2_LIB.BASEBOARD_FAB2(SCH_1):PAGE28
  J6L1   91 ODT<1> SCONN288_H44441003_PIP-SCONN,HA   I111 @BASEBOARD_FAB2_LIB.BASEBOARD_FAB2(SCH_1):PAGE54

M_F_PAR @BASEBOARD_FAB2_LIB.BASEBOARD_FAB2(SCH_1):M_F_PAR
  U5D1 DK53 DDR5_PAR SKX_EXT_B_BGA1-IC,TBD   I172 @BASEBOARD_FAB2_LIB.BASEBOARD_FAB2(SCH_1):PAGE28
  J4A1  222    PAR SCONN288_H44441004_PIP-SCONN,HA   I111 @BASEBOARD_FAB2_LIB.BASEBOARD_FAB2(SCH_1):PAGE53
  J6L1  222    PAR SCONN288_H44441003_PIP-SCONN,HA   I111 @BASEBOARD_FAB2_LIB.BASEBOARD_FAB2(SCH_1):PAGE54

M_F_VREF @BASEBOARD_FAB2_LIB.BASEBOARD_FAB2(SCH_1):M_F_VREF
  J4A1  146 VREFCA SCONN288_H44441004_PIP-SCONN,HA   I111 @BASEBOARD_FAB2_LIB.BASEBOARD_FAB2(SCH_1):PAGE53
  C6L1    1      A CAP_A_0402V-0.01UF,25V,10%,X7RA   I178 @BASEBOARD_FAB2_LIB.BASEBOARD_FAB2(SCH_1):PAGE53
  J6L1  146 VREFCA SCONN288_H44441003_PIP-SCONN,HA   I111 @BASEBOARD_FAB2_LIB.BASEBOARD_FAB2(SCH_1):PAGE54
  C4A5    1      A CAP_A_0402V-0.01UF,25V,10%,X7RA   I179 @BASEBOARD_FAB2_LIB.BASEBOARD_FAB2(SCH_1):PAGE54
  R6L2    2      B RES_0402-1.00K,1%,1/16W,CHIP,GA    I62 @BASEBOARD_FAB2_LIB.BASEBOARD_FAB2(SCH_1):PAGE98
  R6L1    1      A RES_0402-1.00K,1%,1/16W,CHIP,GA    I64 @BASEBOARD_FAB2_LIB.BASEBOARD_FAB2(SCH_1):PAGE98
  R6L3    2      B RES_0402-2,1.0%,1/16W,CHIP,G21A    I66 @BASEBOARD_FAB2_LIB.BASEBOARD_FAB2(SCH_1):PAGE98

M_GHJ_RST_N @BASEBOARD_FAB2_LIB.BASEBOARD_FAB2(SCH_1):M_GHJ_RST_N
  U2D1  U64 DDR012_RESET_N SKX_EXT_B_BGA1-IC,TBD   I172 @BASEBOARD_FAB2_LIB.BASEBOARD_FAB2(SCH_1):PAGE55
  J1G1   58 RESET_N SCONN288_H44441004_PIP-SCONN,HA   I111 @BASEBOARD_FAB2_LIB.BASEBOARD_FAB2(SCH_1):PAGE77
  J9T1   58 RESET_N SCONN288_H44441003_PIP-SCONN,HA    I13 @BASEBOARD_FAB2_LIB.BASEBOARD_FAB2(SCH_1):PAGE78
  J1G2   58 RESET_N SCONN288_H44441004_PIP-SCONN,HA   I111 @BASEBOARD_FAB2_LIB.BASEBOARD_FAB2(SCH_1):PAGE79
  J9U1   58 RESET_N SCONN288_H44441003_PIP-SCONN,HA    I24 @BASEBOARD_FAB2_LIB.BASEBOARD_FAB2(SCH_1):PAGE80
  J1G3   58 RESET_N SCONN288_H44441004_PIP-SCONN,HA   I186 @BASEBOARD_FAB2_LIB.BASEBOARD_FAB2(SCH_1):PAGE81
  J9U2   58 RESET_N SCONN288_H44441003_PIP-SCONN,HA   I187 @BASEBOARD_FAB2_LIB.BASEBOARD_FAB2(SCH_1):PAGE82

M_G_ACT_N @BASEBOARD_FAB2_LIB.BASEBOARD_FAB2(SCH_1):M_G_ACT_N
  U2D1  J60 DDR0_ACT_N SKX_EXT_B_BGA1-IC,TBD   I172 @BASEBOARD_FAB2_LIB.BASEBOARD_FAB2(SCH_1):PAGE57
  J1G1   62  ACT_N SCONN288_H44441004_PIP-SCONN,HA   I111 @BASEBOARD_FAB2_LIB.BASEBOARD_FAB2(SCH_1):PAGE77
  J9T1   62  ACT_N SCONN288_H44441003_PIP-SCONN,HA    I13 @BASEBOARD_FAB2_LIB.BASEBOARD_FAB2(SCH_1):PAGE78

M_G_ALERT_N @BASEBOARD_FAB2_LIB.BASEBOARD_FAB2(SCH_1):M_G_ALERT_N
  U2D1  B61 DDR0_ALERT_N SKX_EXT_B_BGA1-IC,TBD   I172 @BASEBOARD_FAB2_LIB.BASEBOARD_FAB2(SCH_1):PAGE57
  J1G1  208 ALERT_N SCONN288_H44441004_PIP-SCONN,HA   I111 @BASEBOARD_FAB2_LIB.BASEBOARD_FAB2(SCH_1):PAGE77
  J9T1  208 ALERT_N SCONN288_H44441003_PIP-SCONN,HA    I13 @BASEBOARD_FAB2_LIB.BASEBOARD_FAB2(SCH_1):PAGE78

M_G_BA<0> @BASEBOARD_FAB2_LIB.BASEBOARD_FAB2(SCH_1):M_G_BA(0)
  U2D1  C52 DDR0_BA<0> SKX_EXT_B_BGA1-IC,TBD   I172 @BASEBOARD_FAB2_LIB.BASEBOARD_FAB2(SCH_1):PAGE57
  J1G1   81  BA<0> SCONN288_H44441004_PIP-SCONN,HA   I111 @BASEBOARD_FAB2_LIB.BASEBOARD_FAB2(SCH_1):PAGE77
  J9T1   81  BA<0> SCONN288_H44441003_PIP-SCONN,HA    I13 @BASEBOARD_FAB2_LIB.BASEBOARD_FAB2(SCH_1):PAGE78

M_G_BA<1> @BASEBOARD_FAB2_LIB.BASEBOARD_FAB2(SCH_1):M_G_BA(1)
  U2D1  G54 DDR0_BA<1> SKX_EXT_B_BGA1-IC,TBD   I172 @BASEBOARD_FAB2_LIB.BASEBOARD_FAB2(SCH_1):PAGE57
  J1G1  224  BA<1> SCONN288_H44441004_PIP-SCONN,HA   I111 @BASEBOARD_FAB2_LIB.BASEBOARD_FAB2(SCH_1):PAGE77
  J9T1  224  BA<1> SCONN288_H44441003_PIP-SCONN,HA    I13 @BASEBOARD_FAB2_LIB.BASEBOARD_FAB2(SCH_1):PAGE78

M_G_BG<0> @BASEBOARD_FAB2_LIB.BASEBOARD_FAB2(SCH_1):M_G_BG(0)
  U2D1  D61 DDR0_BG<0> SKX_EXT_B_BGA1-IC,TBD   I172 @BASEBOARD_FAB2_LIB.BASEBOARD_FAB2(SCH_1):PAGE57
  J1G1   63  BG<0> SCONN288_H44441004_PIP-SCONN,HA   I111 @BASEBOARD_FAB2_LIB.BASEBOARD_FAB2(SCH_1):PAGE77
  J9T1   63  BG<0> SCONN288_H44441003_PIP-SCONN,HA    I13 @BASEBOARD_FAB2_LIB.BASEBOARD_FAB2(SCH_1):PAGE78

M_G_BG<1> @BASEBOARD_FAB2_LIB.BASEBOARD_FAB2(SCH_1):M_G_BG(1)
  U2D1  F63 DDR0_BG<1> SKX_EXT_B_BGA1-IC,TBD   I172 @BASEBOARD_FAB2_LIB.BASEBOARD_FAB2(SCH_1):PAGE57
  J1G1  207  BG<1> SCONN288_H44441004_PIP-SCONN,HA   I111 @BASEBOARD_FAB2_LIB.BASEBOARD_FAB2(SCH_1):PAGE77
  J9T1  207  BG<1> SCONN288_H44441003_PIP-SCONN,HA    I13 @BASEBOARD_FAB2_LIB.BASEBOARD_FAB2(SCH_1):PAGE78

M_G_C<2> @BASEBOARD_FAB2_LIB.BASEBOARD_FAB2(SCH_1):M_G_C(2)
  U2D1  G46 DDR0_CID<2> SKX_EXT_B_BGA1-IC,TBD   I172 @BASEBOARD_FAB2_LIB.BASEBOARD_FAB2(SCH_1):PAGE57
  J1G1  235   C<2> SCONN288_H44441004_PIP-SCONN,HA   I111 @BASEBOARD_FAB2_LIB.BASEBOARD_FAB2(SCH_1):PAGE77
  J9T1  235   C<2> SCONN288_H44441003_PIP-SCONN,HA    I13 @BASEBOARD_FAB2_LIB.BASEBOARD_FAB2(SCH_1):PAGE78

M_G_CKE<0> @BASEBOARD_FAB2_LIB.BASEBOARD_FAB2(SCH_1):M_G_CKE(0)
  U2D1  C62 DDR0_CKE<0> SKX_EXT_B_BGA1-IC,TBD   I172 @BASEBOARD_FAB2_LIB.BASEBOARD_FAB2(SCH_1):PAGE57
  J1G1   60 CKE<0> SCONN288_H44441004_PIP-SCONN,HA   I111 @BASEBOARD_FAB2_LIB.BASEBOARD_FAB2(SCH_1):PAGE77

M_G_CKE<1> @BASEBOARD_FAB2_LIB.BASEBOARD_FAB2(SCH_1):M_G_CKE(1)
  U2D1  C64 DDR0_CKE<1> SKX_EXT_B_BGA1-IC,TBD   I172 @BASEBOARD_FAB2_LIB.BASEBOARD_FAB2(SCH_1):PAGE57
  J1G1  203 CKE<1> SCONN288_H44441004_PIP-SCONN,HA   I111 @BASEBOARD_FAB2_LIB.BASEBOARD_FAB2(SCH_1):PAGE77

M_G_CKE<2> @BASEBOARD_FAB2_LIB.BASEBOARD_FAB2(SCH_1):M_G_CKE(2)
  U2D1  B63 DDR0_CKE<2> SKX_EXT_B_BGA1-IC,TBD   I172 @BASEBOARD_FAB2_LIB.BASEBOARD_FAB2(SCH_1):PAGE57
  J9T1   60 CKE<0> SCONN288_H44441003_PIP-SCONN,HA    I13 @BASEBOARD_FAB2_LIB.BASEBOARD_FAB2(SCH_1):PAGE78

M_G_CKE<3> @BASEBOARD_FAB2_LIB.BASEBOARD_FAB2(SCH_1):M_G_CKE(3)
  U2D1  D63 DDR0_CKE<3> SKX_EXT_B_BGA1-IC,TBD   I172 @BASEBOARD_FAB2_LIB.BASEBOARD_FAB2(SCH_1):PAGE57
  J9T1  203 CKE<1> SCONN288_H44441003_PIP-SCONN,HA    I13 @BASEBOARD_FAB2_LIB.BASEBOARD_FAB2(SCH_1):PAGE78

M_G_CLK_DN<0> @BASEBOARD_FAB2_LIB.BASEBOARD_FAB2(SCH_1):M_G_CLK_DN(0)
  U2D1  F55 DDR0_CLK_DN<0> SKX_EXT_B_BGA1-IC,TBD   I172 @BASEBOARD_FAB2_LIB.BASEBOARD_FAB2(SCH_1):PAGE57
  J1G1   75   CK0N SCONN288_H44441004_PIP-SCONN,HA   I111 @BASEBOARD_FAB2_LIB.BASEBOARD_FAB2(SCH_1):PAGE77

M_G_CLK_DN<1> @BASEBOARD_FAB2_LIB.BASEBOARD_FAB2(SCH_1):M_G_CLK_DN(1)
  U2D1  C54 DDR0_CLK_DN<1> SKX_EXT_B_BGA1-IC,TBD   I172 @BASEBOARD_FAB2_LIB.BASEBOARD_FAB2(SCH_1):PAGE57
  J1G1  219   CK1N SCONN288_H44441004_PIP-SCONN,HA   I111 @BASEBOARD_FAB2_LIB.BASEBOARD_FAB2(SCH_1):PAGE77

M_G_CLK_DN<2> @BASEBOARD_FAB2_LIB.BASEBOARD_FAB2(SCH_1):M_G_CLK_DN(2)
  U2D1  J56 DDR0_CLK_DN<2> SKX_EXT_B_BGA1-IC,TBD   I172 @BASEBOARD_FAB2_LIB.BASEBOARD_FAB2(SCH_1):PAGE57
  J9T1   75   CK0N SCONN288_H44441003_PIP-SCONN,HA    I13 @BASEBOARD_FAB2_LIB.BASEBOARD_FAB2(SCH_1):PAGE78

M_G_CLK_DN<3> @BASEBOARD_FAB2_LIB.BASEBOARD_FAB2(SCH_1):M_G_CLK_DN(3)
  U2D1  C56 DDR0_CLK_DN<3> SKX_EXT_B_BGA1-IC,TBD   I172 @BASEBOARD_FAB2_LIB.BASEBOARD_FAB2(SCH_1):PAGE57
  J9T1  219   CK1N SCONN288_H44441003_PIP-SCONN,HA    I13 @BASEBOARD_FAB2_LIB.BASEBOARD_FAB2(SCH_1):PAGE78

M_G_CLK_DP<0> @BASEBOARD_FAB2_LIB.BASEBOARD_FAB2(SCH_1):M_G_CLK_DP(0)
  U2D1  D55 DDR0_CLK_DP<0> SKX_EXT_B_BGA1-IC,TBD   I172 @BASEBOARD_FAB2_LIB.BASEBOARD_FAB2(SCH_1):PAGE57
  J1G1   74   CK0P SCONN288_H44441004_PIP-SCONN,HA   I111 @BASEBOARD_FAB2_LIB.BASEBOARD_FAB2(SCH_1):PAGE77

M_G_CLK_DP<1> @BASEBOARD_FAB2_LIB.BASEBOARD_FAB2(SCH_1):M_G_CLK_DP(1)
  U2D1  B55 DDR0_CLK_DP<1> SKX_EXT_B_BGA1-IC,TBD   I172 @BASEBOARD_FAB2_LIB.BASEBOARD_FAB2(SCH_1):PAGE57
  J1G1  218   CK1P SCONN288_H44441004_PIP-SCONN,HA   I111 @BASEBOARD_FAB2_LIB.BASEBOARD_FAB2(SCH_1):PAGE77

M_G_CLK_DP<2> @BASEBOARD_FAB2_LIB.BASEBOARD_FAB2(SCH_1):M_G_CLK_DP(2)
  U2D1  G56 DDR0_CLK_DP<2> SKX_EXT_B_BGA1-IC,TBD   I172 @BASEBOARD_FAB2_LIB.BASEBOARD_FAB2(SCH_1):PAGE57
  J9T1   74   CK0P SCONN288_H44441003_PIP-SCONN,HA    I13 @BASEBOARD_FAB2_LIB.BASEBOARD_FAB2(SCH_1):PAGE78

M_G_CLK_DP<3> @BASEBOARD_FAB2_LIB.BASEBOARD_FAB2(SCH_1):M_G_CLK_DP(3)
  U2D1  B57 DDR0_CLK_DP<3> SKX_EXT_B_BGA1-IC,TBD   I172 @BASEBOARD_FAB2_LIB.BASEBOARD_FAB2(SCH_1):PAGE57
  J9T1  218   CK1P SCONN288_H44441003_PIP-SCONN,HA    I13 @BASEBOARD_FAB2_LIB.BASEBOARD_FAB2(SCH_1):PAGE78

M_G_CPU_VREF @BASEBOARD_FAB2_LIB.BASEBOARD_FAB2(SCH_1):M_G_CPU_VREF
  U2D1 AJ64 DDR0_CAVREF SKX_EXT_B_BGA1-IC,TBD   I172 @BASEBOARD_FAB2_LIB.BASEBOARD_FAB2(SCH_1):PAGE55
  R1F4    1      A RES_0402-2,1.0%,1/16W,CHIP,G21A     I7 @BASEBOARD_FAB2_LIB.BASEBOARD_FAB2(SCH_1):PAGE100
 C1F19    1      A CAP_A_0402V-0.01UF,25V,10%,X7RA     I8 @BASEBOARD_FAB2_LIB.BASEBOARD_FAB2(SCH_1):PAGE100

M_G_CS_N<0> @BASEBOARD_FAB2_LIB.BASEBOARD_FAB2(SCH_1):M_G_CS_N(0)
  U2D1  G52 DDR0_CS_N<0> SKX_EXT_B_BGA1-IC,TBD   I172 @BASEBOARD_FAB2_LIB.BASEBOARD_FAB2(SCH_1):PAGE57
  J1G1   84   S0_N SCONN288_H44441004_PIP-SCONN,HA   I111 @BASEBOARD_FAB2_LIB.BASEBOARD_FAB2(SCH_1):PAGE77

M_G_CS_N<1> @BASEBOARD_FAB2_LIB.BASEBOARD_FAB2(SCH_1):M_G_CS_N(1)
  U2D1  F49 DDR0_CS_N<1> SKX_EXT_B_BGA1-IC,TBD   I172 @BASEBOARD_FAB2_LIB.BASEBOARD_FAB2(SCH_1):PAGE57
  J1G1   89   S1_N SCONN288_H44441004_PIP-SCONN,HA   I111 @BASEBOARD_FAB2_LIB.BASEBOARD_FAB2(SCH_1):PAGE77

M_G_CS_N<2> @BASEBOARD_FAB2_LIB.BASEBOARD_FAB2(SCH_1):M_G_CS_N(2)
  U2D1  D47 DDR0_CS_N<2> SKX_EXT_B_BGA1-IC,TBD   I172 @BASEBOARD_FAB2_LIB.BASEBOARD_FAB2(SCH_1):PAGE57
  J1G1   93 S2_N_C<0> SCONN288_H44441004_PIP-SCONN,HA   I111 @BASEBOARD_FAB2_LIB.BASEBOARD_FAB2(SCH_1):PAGE77

M_G_CS_N<3> @BASEBOARD_FAB2_LIB.BASEBOARD_FAB2(SCH_1):M_G_CS_N(3)
  U2D1  F47 DDR0_CS_N<3> SKX_EXT_B_BGA1-IC,TBD   I172 @BASEBOARD_FAB2_LIB.BASEBOARD_FAB2(SCH_1):PAGE57
  J1G1  237 S3_N_C<1> SCONN288_H44441004_PIP-SCONN,HA   I111 @BASEBOARD_FAB2_LIB.BASEBOARD_FAB2(SCH_1):PAGE77

M_G_CS_N<4> @BASEBOARD_FAB2_LIB.BASEBOARD_FAB2(SCH_1):M_G_CS_N(4)
  U2D1  B51 DDR0_CS_N<4> SKX_EXT_B_BGA1-IC,TBD   I172 @BASEBOARD_FAB2_LIB.BASEBOARD_FAB2(SCH_1):PAGE57
  J9T1   84   S0_N SCONN288_H44441003_PIP-SCONN,HA    I13 @BASEBOARD_FAB2_LIB.BASEBOARD_FAB2(SCH_1):PAGE78

M_G_CS_N<5> @BASEBOARD_FAB2_LIB.BASEBOARD_FAB2(SCH_1):M_G_CS_N(5)
  U2D1  D49 DDR0_CS_N<5> SKX_EXT_B_BGA1-IC,TBD   I172 @BASEBOARD_FAB2_LIB.BASEBOARD_FAB2(SCH_1):PAGE57
  J9T1   89   S1_N SCONN288_H44441003_PIP-SCONN,HA    I13 @BASEBOARD_FAB2_LIB.BASEBOARD_FAB2(SCH_1):PAGE78

M_G_CS_N<6> @BASEBOARD_FAB2_LIB.BASEBOARD_FAB2(SCH_1):M_G_CS_N(6)
  U2D1  F45 DDR0_CS_N<6> SKX_EXT_B_BGA1-IC,TBD   I172 @BASEBOARD_FAB2_LIB.BASEBOARD_FAB2(SCH_1):PAGE57
  J9T1   93 S2_N_C<0> SCONN288_H44441003_PIP-SCONN,HA    I13 @BASEBOARD_FAB2_LIB.BASEBOARD_FAB2(SCH_1):PAGE78

M_G_CS_N<7> @BASEBOARD_FAB2_LIB.BASEBOARD_FAB2(SCH_1):M_G_CS_N(7)
  U2D1  K45 DDR0_CS_N<7> SKX_EXT_B_BGA1-IC,TBD   I172 @BASEBOARD_FAB2_LIB.BASEBOARD_FAB2(SCH_1):PAGE57
  J9T1  237 S3_N_C<1> SCONN288_H44441003_PIP-SCONN,HA    I13 @BASEBOARD_FAB2_LIB.BASEBOARD_FAB2(SCH_1):PAGE78

M_G_DQ<0> @BASEBOARD_FAB2_LIB.BASEBOARD_FAB2(SCH_1):M_G_DQ(0)
  U2D1 AN86 DDR0_DQ<0> SKX_EXT_B_BGA1-IC,TBD   I172 @BASEBOARD_FAB2_LIB.BASEBOARD_FAB2(SCH_1):PAGE57
  J1G1  150  DQ<1> SCONN288_H44441004_PIP-SCONN,HA   I111 @BASEBOARD_FAB2_LIB.BASEBOARD_FAB2(SCH_1):PAGE77
  J9T1    5  DQ<0> SCONN288_H44441003_PIP-SCONN,HA    I13 @BASEBOARD_FAB2_LIB.BASEBOARD_FAB2(SCH_1):PAGE78

M_G_DQ<10> @BASEBOARD_FAB2_LIB.BASEBOARD_FAB2(SCH_1):M_G_DQ(10)
  U2D1  L86 DDR0_DQ<10> SKX_EXT_B_BGA1-IC,TBD   I172 @BASEBOARD_FAB2_LIB.BASEBOARD_FAB2(SCH_1):PAGE57
  J1G1  168 DQ<11> SCONN288_H44441004_PIP-SCONN,HA   I111 @BASEBOARD_FAB2_LIB.BASEBOARD_FAB2(SCH_1):PAGE77
  J9T1   23 DQ<10> SCONN288_H44441003_PIP-SCONN,HA    I13 @BASEBOARD_FAB2_LIB.BASEBOARD_FAB2(SCH_1):PAGE78

M_G_DQ<11> @BASEBOARD_FAB2_LIB.BASEBOARD_FAB2(SCH_1):M_G_DQ(11)
  U2D1  L84 DDR0_DQ<11> SKX_EXT_B_BGA1-IC,TBD   I172 @BASEBOARD_FAB2_LIB.BASEBOARD_FAB2(SCH_1):PAGE57
  J1G1   23 DQ<10> SCONN288_H44441004_PIP-SCONN,HA   I111 @BASEBOARD_FAB2_LIB.BASEBOARD_FAB2(SCH_1):PAGE77
  J9T1  168 DQ<11> SCONN288_H44441003_PIP-SCONN,HA    I13 @BASEBOARD_FAB2_LIB.BASEBOARD_FAB2(SCH_1):PAGE78

M_G_DQ<12> @BASEBOARD_FAB2_LIB.BASEBOARD_FAB2(SCH_1):M_G_DQ(12)
  U2D1 AA86 DDR0_DQ<12> SKX_EXT_B_BGA1-IC,TBD   I172 @BASEBOARD_FAB2_LIB.BASEBOARD_FAB2(SCH_1):PAGE57
  J1G1  159 DQ<13> SCONN288_H44441004_PIP-SCONN,HA   I111 @BASEBOARD_FAB2_LIB.BASEBOARD_FAB2(SCH_1):PAGE77
  J9T1   14 DQ<12> SCONN288_H44441003_PIP-SCONN,HA    I13 @BASEBOARD_FAB2_LIB.BASEBOARD_FAB2(SCH_1):PAGE78

M_G_DQ<13> @BASEBOARD_FAB2_LIB.BASEBOARD_FAB2(SCH_1):M_G_DQ(13)
  U2D1 AA84 DDR0_DQ<13> SKX_EXT_B_BGA1-IC,TBD   I172 @BASEBOARD_FAB2_LIB.BASEBOARD_FAB2(SCH_1):PAGE57
  J1G1   14 DQ<12> SCONN288_H44441004_PIP-SCONN,HA   I111 @BASEBOARD_FAB2_LIB.BASEBOARD_FAB2(SCH_1):PAGE77
  J9T1  159 DQ<13> SCONN288_H44441003_PIP-SCONN,HA    I13 @BASEBOARD_FAB2_LIB.BASEBOARD_FAB2(SCH_1):PAGE78

M_G_DQ<14> @BASEBOARD_FAB2_LIB.BASEBOARD_FAB2(SCH_1):M_G_DQ(14)
  U2D1  N86 DDR0_DQ<14> SKX_EXT_B_BGA1-IC,TBD   I172 @BASEBOARD_FAB2_LIB.BASEBOARD_FAB2(SCH_1):PAGE57
  J1G1  166 DQ<15> SCONN288_H44441004_PIP-SCONN,HA   I111 @BASEBOARD_FAB2_LIB.BASEBOARD_FAB2(SCH_1):PAGE77
  J9T1   21 DQ<14> SCONN288_H44441003_PIP-SCONN,HA    I13 @BASEBOARD_FAB2_LIB.BASEBOARD_FAB2(SCH_1):PAGE78

M_G_DQ<15> @BASEBOARD_FAB2_LIB.BASEBOARD_FAB2(SCH_1):M_G_DQ(15)
  U2D1  N84 DDR0_DQ<15> SKX_EXT_B_BGA1-IC,TBD   I172 @BASEBOARD_FAB2_LIB.BASEBOARD_FAB2(SCH_1):PAGE57
  J1G1   21 DQ<14> SCONN288_H44441004_PIP-SCONN,HA   I111 @BASEBOARD_FAB2_LIB.BASEBOARD_FAB2(SCH_1):PAGE77
  J9T1  166 DQ<15> SCONN288_H44441003_PIP-SCONN,HA    I13 @BASEBOARD_FAB2_LIB.BASEBOARD_FAB2(SCH_1):PAGE78

M_G_DQ<16> @BASEBOARD_FAB2_LIB.BASEBOARD_FAB2(SCH_1):M_G_DQ(16)
  U2D1  V81 DDR0_DQ<16> SKX_EXT_B_BGA1-IC,TBD   I172 @BASEBOARD_FAB2_LIB.BASEBOARD_FAB2(SCH_1):PAGE57
  J1G1  172 DQ<17> SCONN288_H44441004_PIP-SCONN,HA   I111 @BASEBOARD_FAB2_LIB.BASEBOARD_FAB2(SCH_1):PAGE77
  J9T1   27 DQ<16> SCONN288_H44441003_PIP-SCONN,HA    I13 @BASEBOARD_FAB2_LIB.BASEBOARD_FAB2(SCH_1):PAGE78

M_G_DQ<17> @BASEBOARD_FAB2_LIB.BASEBOARD_FAB2(SCH_1):M_G_DQ(17)
  U2D1  T79 DDR0_DQ<17> SKX_EXT_B_BGA1-IC,TBD   I172 @BASEBOARD_FAB2_LIB.BASEBOARD_FAB2(SCH_1):PAGE57
  J1G1   27 DQ<16> SCONN288_H44441004_PIP-SCONN,HA   I111 @BASEBOARD_FAB2_LIB.BASEBOARD_FAB2(SCH_1):PAGE77
  J9T1  172 DQ<17> SCONN288_H44441003_PIP-SCONN,HA    I13 @BASEBOARD_FAB2_LIB.BASEBOARD_FAB2(SCH_1):PAGE78

M_G_DQ<18> @BASEBOARD_FAB2_LIB.BASEBOARD_FAB2(SCH_1):M_G_DQ(18)
  U2D1  N82 DDR0_DQ<18> SKX_EXT_B_BGA1-IC,TBD   I172 @BASEBOARD_FAB2_LIB.BASEBOARD_FAB2(SCH_1):PAGE57
  J1G1  179 DQ<19> SCONN288_H44441004_PIP-SCONN,HA   I111 @BASEBOARD_FAB2_LIB.BASEBOARD_FAB2(SCH_1):PAGE77
  J9T1   34 DQ<18> SCONN288_H44441003_PIP-SCONN,HA    I13 @BASEBOARD_FAB2_LIB.BASEBOARD_FAB2(SCH_1):PAGE78

M_G_DQ<19> @BASEBOARD_FAB2_LIB.BASEBOARD_FAB2(SCH_1):M_G_DQ(19)
  U2D1  M81 DDR0_DQ<19> SKX_EXT_B_BGA1-IC,TBD   I172 @BASEBOARD_FAB2_LIB.BASEBOARD_FAB2(SCH_1):PAGE57
  J1G1   34 DQ<18> SCONN288_H44441004_PIP-SCONN,HA   I111 @BASEBOARD_FAB2_LIB.BASEBOARD_FAB2(SCH_1):PAGE77
  J9T1  179 DQ<19> SCONN288_H44441003_PIP-SCONN,HA    I13 @BASEBOARD_FAB2_LIB.BASEBOARD_FAB2(SCH_1):PAGE78

M_G_DQ<1> @BASEBOARD_FAB2_LIB.BASEBOARD_FAB2(SCH_1):M_G_DQ(1)
  U2D1 AN84 DDR0_DQ<1> SKX_EXT_B_BGA1-IC,TBD   I172 @BASEBOARD_FAB2_LIB.BASEBOARD_FAB2(SCH_1):PAGE57
  J1G1    5  DQ<0> SCONN288_H44441004_PIP-SCONN,HA   I111 @BASEBOARD_FAB2_LIB.BASEBOARD_FAB2(SCH_1):PAGE77
  J9T1  150  DQ<1> SCONN288_H44441003_PIP-SCONN,HA    I13 @BASEBOARD_FAB2_LIB.BASEBOARD_FAB2(SCH_1):PAGE78

M_G_DQ<20> @BASEBOARD_FAB2_LIB.BASEBOARD_FAB2(SCH_1):M_G_DQ(20)
  U2D1  W80 DDR0_DQ<20> SKX_EXT_B_BGA1-IC,TBD   I172 @BASEBOARD_FAB2_LIB.BASEBOARD_FAB2(SCH_1):PAGE57
  J1G1  170 DQ<21> SCONN288_H44441004_PIP-SCONN,HA   I111 @BASEBOARD_FAB2_LIB.BASEBOARD_FAB2(SCH_1):PAGE77
  J9T1   25 DQ<20> SCONN288_H44441003_PIP-SCONN,HA    I13 @BASEBOARD_FAB2_LIB.BASEBOARD_FAB2(SCH_1):PAGE78

M_G_DQ<21> @BASEBOARD_FAB2_LIB.BASEBOARD_FAB2(SCH_1):M_G_DQ(21)
  U2D1  V79 DDR0_DQ<21> SKX_EXT_B_BGA1-IC,TBD   I172 @BASEBOARD_FAB2_LIB.BASEBOARD_FAB2(SCH_1):PAGE57
  J1G1   25 DQ<20> SCONN288_H44441004_PIP-SCONN,HA   I111 @BASEBOARD_FAB2_LIB.BASEBOARD_FAB2(SCH_1):PAGE77
  J9T1  170 DQ<21> SCONN288_H44441003_PIP-SCONN,HA    I13 @BASEBOARD_FAB2_LIB.BASEBOARD_FAB2(SCH_1):PAGE78

M_G_DQ<22> @BASEBOARD_FAB2_LIB.BASEBOARD_FAB2(SCH_1):M_G_DQ(22)
  U2D1  R82 DDR0_DQ<22> SKX_EXT_B_BGA1-IC,TBD   I172 @BASEBOARD_FAB2_LIB.BASEBOARD_FAB2(SCH_1):PAGE57
  J1G1  177 DQ<23> SCONN288_H44441004_PIP-SCONN,HA   I111 @BASEBOARD_FAB2_LIB.BASEBOARD_FAB2(SCH_1):PAGE77
  J9T1   32 DQ<22> SCONN288_H44441003_PIP-SCONN,HA    I13 @BASEBOARD_FAB2_LIB.BASEBOARD_FAB2(SCH_1):PAGE78

M_G_DQ<23> @BASEBOARD_FAB2_LIB.BASEBOARD_FAB2(SCH_1):M_G_DQ(23)
  U2D1  N80 DDR0_DQ<23> SKX_EXT_B_BGA1-IC,TBD   I172 @BASEBOARD_FAB2_LIB.BASEBOARD_FAB2(SCH_1):PAGE57
  J1G1   32 DQ<22> SCONN288_H44441004_PIP-SCONN,HA   I111 @BASEBOARD_FAB2_LIB.BASEBOARD_FAB2(SCH_1):PAGE77
  J9T1  177 DQ<23> SCONN288_H44441003_PIP-SCONN,HA    I13 @BASEBOARD_FAB2_LIB.BASEBOARD_FAB2(SCH_1):PAGE78

M_G_DQ<24> @BASEBOARD_FAB2_LIB.BASEBOARD_FAB2(SCH_1):M_G_DQ(24)
  U2D1  L76 DDR0_DQ<24> SKX_EXT_B_BGA1-IC,TBD   I172 @BASEBOARD_FAB2_LIB.BASEBOARD_FAB2(SCH_1):PAGE57
  J1G1  183 DQ<25> SCONN288_H44441004_PIP-SCONN,HA   I111 @BASEBOARD_FAB2_LIB.BASEBOARD_FAB2(SCH_1):PAGE77
  J9T1   38 DQ<24> SCONN288_H44441003_PIP-SCONN,HA    I13 @BASEBOARD_FAB2_LIB.BASEBOARD_FAB2(SCH_1):PAGE78

M_G_DQ<25> @BASEBOARD_FAB2_LIB.BASEBOARD_FAB2(SCH_1):M_G_DQ(25)
  U2D1  R76 DDR0_DQ<25> SKX_EXT_B_BGA1-IC,TBD   I172 @BASEBOARD_FAB2_LIB.BASEBOARD_FAB2(SCH_1):PAGE57
  J1G1   38 DQ<24> SCONN288_H44441004_PIP-SCONN,HA   I111 @BASEBOARD_FAB2_LIB.BASEBOARD_FAB2(SCH_1):PAGE77
  J9T1  183 DQ<25> SCONN288_H44441003_PIP-SCONN,HA    I13 @BASEBOARD_FAB2_LIB.BASEBOARD_FAB2(SCH_1):PAGE78

M_G_DQ<26> @BASEBOARD_FAB2_LIB.BASEBOARD_FAB2(SCH_1):M_G_DQ(26)
  U2D1  M73 DDR0_DQ<26> SKX_EXT_B_BGA1-IC,TBD   I172 @BASEBOARD_FAB2_LIB.BASEBOARD_FAB2(SCH_1):PAGE57
  J1G1  190 DQ<27> SCONN288_H44441004_PIP-SCONN,HA   I111 @BASEBOARD_FAB2_LIB.BASEBOARD_FAB2(SCH_1):PAGE77
  J9T1   45 DQ<26> SCONN288_H44441003_PIP-SCONN,HA    I13 @BASEBOARD_FAB2_LIB.BASEBOARD_FAB2(SCH_1):PAGE78

M_G_DQ<27> @BASEBOARD_FAB2_LIB.BASEBOARD_FAB2(SCH_1):M_G_DQ(27)
  U2D1  P73 DDR0_DQ<27> SKX_EXT_B_BGA1-IC,TBD   I172 @BASEBOARD_FAB2_LIB.BASEBOARD_FAB2(SCH_1):PAGE57
  J1G1   45 DQ<26> SCONN288_H44441004_PIP-SCONN,HA   I111 @BASEBOARD_FAB2_LIB.BASEBOARD_FAB2(SCH_1):PAGE77
  J9T1  190 DQ<27> SCONN288_H44441003_PIP-SCONN,HA    I13 @BASEBOARD_FAB2_LIB.BASEBOARD_FAB2(SCH_1):PAGE78

M_G_DQ<28> @BASEBOARD_FAB2_LIB.BASEBOARD_FAB2(SCH_1):M_G_DQ(28)
  U2D1  M77 DDR0_DQ<28> SKX_EXT_B_BGA1-IC,TBD   I172 @BASEBOARD_FAB2_LIB.BASEBOARD_FAB2(SCH_1):PAGE57
  J1G1  181 DQ<29> SCONN288_H44441004_PIP-SCONN,HA   I111 @BASEBOARD_FAB2_LIB.BASEBOARD_FAB2(SCH_1):PAGE77
  J9T1   36 DQ<28> SCONN288_H44441003_PIP-SCONN,HA    I13 @BASEBOARD_FAB2_LIB.BASEBOARD_FAB2(SCH_1):PAGE78

M_G_DQ<29> @BASEBOARD_FAB2_LIB.BASEBOARD_FAB2(SCH_1):M_G_DQ(29)
  U2D1  P77 DDR0_DQ<29> SKX_EXT_B_BGA1-IC,TBD   I172 @BASEBOARD_FAB2_LIB.BASEBOARD_FAB2(SCH_1):PAGE57
  J1G1   36 DQ<28> SCONN288_H44441004_PIP-SCONN,HA   I111 @BASEBOARD_FAB2_LIB.BASEBOARD_FAB2(SCH_1):PAGE77
  J9T1  181 DQ<29> SCONN288_H44441003_PIP-SCONN,HA    I13 @BASEBOARD_FAB2_LIB.BASEBOARD_FAB2(SCH_1):PAGE78

M_G_DQ<2> @BASEBOARD_FAB2_LIB.BASEBOARD_FAB2(SCH_1):M_G_DQ(2)
  U2D1 AE86 DDR0_DQ<2> SKX_EXT_B_BGA1-IC,TBD   I172 @BASEBOARD_FAB2_LIB.BASEBOARD_FAB2(SCH_1):PAGE57
  J1G1  157  DQ<3> SCONN288_H44441004_PIP-SCONN,HA   I111 @BASEBOARD_FAB2_LIB.BASEBOARD_FAB2(SCH_1):PAGE77
  J9T1   12  DQ<2> SCONN288_H44441003_PIP-SCONN,HA    I13 @BASEBOARD_FAB2_LIB.BASEBOARD_FAB2(SCH_1):PAGE78

M_G_DQ<30> @BASEBOARD_FAB2_LIB.BASEBOARD_FAB2(SCH_1):M_G_DQ(30)
  U2D1  L74 DDR0_DQ<30> SKX_EXT_B_BGA1-IC,TBD   I172 @BASEBOARD_FAB2_LIB.BASEBOARD_FAB2(SCH_1):PAGE57
  J1G1  188 DQ<31> SCONN288_H44441004_PIP-SCONN,HA   I111 @BASEBOARD_FAB2_LIB.BASEBOARD_FAB2(SCH_1):PAGE77
  J9T1   43 DQ<30> SCONN288_H44441003_PIP-SCONN,HA    I13 @BASEBOARD_FAB2_LIB.BASEBOARD_FAB2(SCH_1):PAGE78

M_G_DQ<31> @BASEBOARD_FAB2_LIB.BASEBOARD_FAB2(SCH_1):M_G_DQ(31)
  U2D1  R74 DDR0_DQ<31> SKX_EXT_B_BGA1-IC,TBD   I172 @BASEBOARD_FAB2_LIB.BASEBOARD_FAB2(SCH_1):PAGE57
  J1G1   43 DQ<30> SCONN288_H44441004_PIP-SCONN,HA   I111 @BASEBOARD_FAB2_LIB.BASEBOARD_FAB2(SCH_1):PAGE77
  J9T1  188 DQ<31> SCONN288_H44441003_PIP-SCONN,HA    I13 @BASEBOARD_FAB2_LIB.BASEBOARD_FAB2(SCH_1):PAGE78

M_G_DQ<32> @BASEBOARD_FAB2_LIB.BASEBOARD_FAB2(SCH_1):M_G_DQ(32)
  U2D1  C42 DDR0_DQ<32> SKX_EXT_B_BGA1-IC,TBD   I172 @BASEBOARD_FAB2_LIB.BASEBOARD_FAB2(SCH_1):PAGE57
  J1G1  242 DQ<33> SCONN288_H44441004_PIP-SCONN,HA   I111 @BASEBOARD_FAB2_LIB.BASEBOARD_FAB2(SCH_1):PAGE77
  J9T1   97 DQ<32> SCONN288_H44441003_PIP-SCONN,HA    I13 @BASEBOARD_FAB2_LIB.BASEBOARD_FAB2(SCH_1):PAGE78

M_G_DQ<33> @BASEBOARD_FAB2_LIB.BASEBOARD_FAB2(SCH_1):M_G_DQ(33)
  U2D1  B41 DDR0_DQ<33> SKX_EXT_B_BGA1-IC,TBD   I172 @BASEBOARD_FAB2_LIB.BASEBOARD_FAB2(SCH_1):PAGE57
  J1G1   97 DQ<32> SCONN288_H44441004_PIP-SCONN,HA   I111 @BASEBOARD_FAB2_LIB.BASEBOARD_FAB2(SCH_1):PAGE77
  J9T1  242 DQ<33> SCONN288_H44441003_PIP-SCONN,HA    I13 @BASEBOARD_FAB2_LIB.BASEBOARD_FAB2(SCH_1):PAGE78

M_G_DQ<34> @BASEBOARD_FAB2_LIB.BASEBOARD_FAB2(SCH_1):M_G_DQ(34)
  U2D1  C38 DDR0_DQ<34> SKX_EXT_B_BGA1-IC,TBD   I172 @BASEBOARD_FAB2_LIB.BASEBOARD_FAB2(SCH_1):PAGE57
  J1G1  249 DQ<35> SCONN288_H44441004_PIP-SCONN,HA   I111 @BASEBOARD_FAB2_LIB.BASEBOARD_FAB2(SCH_1):PAGE77
  J9T1  104 DQ<34> SCONN288_H44441003_PIP-SCONN,HA    I13 @BASEBOARD_FAB2_LIB.BASEBOARD_FAB2(SCH_1):PAGE78

M_G_DQ<35> @BASEBOARD_FAB2_LIB.BASEBOARD_FAB2(SCH_1):M_G_DQ(35)
  U2D1  E38 DDR0_DQ<35> SKX_EXT_B_BGA1-IC,TBD   I172 @BASEBOARD_FAB2_LIB.BASEBOARD_FAB2(SCH_1):PAGE57
  J1G1  104 DQ<34> SCONN288_H44441004_PIP-SCONN,HA   I111 @BASEBOARD_FAB2_LIB.BASEBOARD_FAB2(SCH_1):PAGE77
  J9T1  249 DQ<35> SCONN288_H44441003_PIP-SCONN,HA    I13 @BASEBOARD_FAB2_LIB.BASEBOARD_FAB2(SCH_1):PAGE78

M_G_DQ<36> @BASEBOARD_FAB2_LIB.BASEBOARD_FAB2(SCH_1):M_G_DQ(36)
  U2D1  E42 DDR0_DQ<36> SKX_EXT_B_BGA1-IC,TBD   I172 @BASEBOARD_FAB2_LIB.BASEBOARD_FAB2(SCH_1):PAGE57
  J1G1  240 DQ<37> SCONN288_H44441004_PIP-SCONN,HA   I111 @BASEBOARD_FAB2_LIB.BASEBOARD_FAB2(SCH_1):PAGE77
  J9T1   95 DQ<36> SCONN288_H44441003_PIP-SCONN,HA    I13 @BASEBOARD_FAB2_LIB.BASEBOARD_FAB2(SCH_1):PAGE78

M_G_DQ<37> @BASEBOARD_FAB2_LIB.BASEBOARD_FAB2(SCH_1):M_G_DQ(37)
  U2D1  F41 DDR0_DQ<37> SKX_EXT_B_BGA1-IC,TBD   I172 @BASEBOARD_FAB2_LIB.BASEBOARD_FAB2(SCH_1):PAGE57
  J1G1   95 DQ<36> SCONN288_H44441004_PIP-SCONN,HA   I111 @BASEBOARD_FAB2_LIB.BASEBOARD_FAB2(SCH_1):PAGE77
  J9T1  240 DQ<37> SCONN288_H44441003_PIP-SCONN,HA    I13 @BASEBOARD_FAB2_LIB.BASEBOARD_FAB2(SCH_1):PAGE78

M_G_DQ<38> @BASEBOARD_FAB2_LIB.BASEBOARD_FAB2(SCH_1):M_G_DQ(38)
  U2D1  B39 DDR0_DQ<38> SKX_EXT_B_BGA1-IC,TBD   I172 @BASEBOARD_FAB2_LIB.BASEBOARD_FAB2(SCH_1):PAGE57
  J1G1  247 DQ<39> SCONN288_H44441004_PIP-SCONN,HA   I111 @BASEBOARD_FAB2_LIB.BASEBOARD_FAB2(SCH_1):PAGE77
  J9T1  102 DQ<38> SCONN288_H44441003_PIP-SCONN,HA    I13 @BASEBOARD_FAB2_LIB.BASEBOARD_FAB2(SCH_1):PAGE78

M_G_DQ<39> @BASEBOARD_FAB2_LIB.BASEBOARD_FAB2(SCH_1):M_G_DQ(39)
  U2D1  F39 DDR0_DQ<39> SKX_EXT_B_BGA1-IC,TBD   I172 @BASEBOARD_FAB2_LIB.BASEBOARD_FAB2(SCH_1):PAGE57
  J1G1  102 DQ<38> SCONN288_H44441004_PIP-SCONN,HA   I111 @BASEBOARD_FAB2_LIB.BASEBOARD_FAB2(SCH_1):PAGE77
  J9T1  247 DQ<39> SCONN288_H44441003_PIP-SCONN,HA    I13 @BASEBOARD_FAB2_LIB.BASEBOARD_FAB2(SCH_1):PAGE78

M_G_DQ<3> @BASEBOARD_FAB2_LIB.BASEBOARD_FAB2(SCH_1):M_G_DQ(3)
  U2D1 AE84 DDR0_DQ<3> SKX_EXT_B_BGA1-IC,TBD   I172 @BASEBOARD_FAB2_LIB.BASEBOARD_FAB2(SCH_1):PAGE57
  J1G1   12  DQ<2> SCONN288_H44441004_PIP-SCONN,HA   I111 @BASEBOARD_FAB2_LIB.BASEBOARD_FAB2(SCH_1):PAGE77
  J9T1  157  DQ<3> SCONN288_H44441003_PIP-SCONN,HA    I13 @BASEBOARD_FAB2_LIB.BASEBOARD_FAB2(SCH_1):PAGE78

M_G_DQ<40> @BASEBOARD_FAB2_LIB.BASEBOARD_FAB2(SCH_1):M_G_DQ(40)
  U2D1  K37 DDR0_DQ<40> SKX_EXT_B_BGA1-IC,TBD   I172 @BASEBOARD_FAB2_LIB.BASEBOARD_FAB2(SCH_1):PAGE57
  J1G1  253 DQ<41> SCONN288_H44441004_PIP-SCONN,HA   I111 @BASEBOARD_FAB2_LIB.BASEBOARD_FAB2(SCH_1):PAGE77
  J9T1  108 DQ<40> SCONN288_H44441003_PIP-SCONN,HA    I13 @BASEBOARD_FAB2_LIB.BASEBOARD_FAB2(SCH_1):PAGE78

M_G_DQ<41> @BASEBOARD_FAB2_LIB.BASEBOARD_FAB2(SCH_1):M_G_DQ(41)
  U2D1  P37 DDR0_DQ<41> SKX_EXT_B_BGA1-IC,TBD   I172 @BASEBOARD_FAB2_LIB.BASEBOARD_FAB2(SCH_1):PAGE57
  J1G1  108 DQ<40> SCONN288_H44441004_PIP-SCONN,HA   I111 @BASEBOARD_FAB2_LIB.BASEBOARD_FAB2(SCH_1):PAGE77
  J9T1  253 DQ<41> SCONN288_H44441003_PIP-SCONN,HA    I13 @BASEBOARD_FAB2_LIB.BASEBOARD_FAB2(SCH_1):PAGE78

M_G_DQ<42> @BASEBOARD_FAB2_LIB.BASEBOARD_FAB2(SCH_1):M_G_DQ(42)
  U2D1  L34 DDR0_DQ<42> SKX_EXT_B_BGA1-IC,TBD   I172 @BASEBOARD_FAB2_LIB.BASEBOARD_FAB2(SCH_1):PAGE57
  J1G1  260 DQ<43> SCONN288_H44441004_PIP-SCONN,HA   I111 @BASEBOARD_FAB2_LIB.BASEBOARD_FAB2(SCH_1):PAGE77
  J9T1  115 DQ<42> SCONN288_H44441003_PIP-SCONN,HA    I13 @BASEBOARD_FAB2_LIB.BASEBOARD_FAB2(SCH_1):PAGE78

M_G_DQ<43> @BASEBOARD_FAB2_LIB.BASEBOARD_FAB2(SCH_1):M_G_DQ(43)
  U2D1  N34 DDR0_DQ<43> SKX_EXT_B_BGA1-IC,TBD   I172 @BASEBOARD_FAB2_LIB.BASEBOARD_FAB2(SCH_1):PAGE57
  J1G1  115 DQ<42> SCONN288_H44441004_PIP-SCONN,HA   I111 @BASEBOARD_FAB2_LIB.BASEBOARD_FAB2(SCH_1):PAGE77
  J9T1  260 DQ<43> SCONN288_H44441003_PIP-SCONN,HA    I13 @BASEBOARD_FAB2_LIB.BASEBOARD_FAB2(SCH_1):PAGE78

M_G_DQ<44> @BASEBOARD_FAB2_LIB.BASEBOARD_FAB2(SCH_1):M_G_DQ(44)
  U2D1  L38 DDR0_DQ<44> SKX_EXT_B_BGA1-IC,TBD   I172 @BASEBOARD_FAB2_LIB.BASEBOARD_FAB2(SCH_1):PAGE57
  J1G1  251 DQ<45> SCONN288_H44441004_PIP-SCONN,HA   I111 @BASEBOARD_FAB2_LIB.BASEBOARD_FAB2(SCH_1):PAGE77
  J9T1  106 DQ<44> SCONN288_H44441003_PIP-SCONN,HA    I13 @BASEBOARD_FAB2_LIB.BASEBOARD_FAB2(SCH_1):PAGE78

M_G_DQ<45> @BASEBOARD_FAB2_LIB.BASEBOARD_FAB2(SCH_1):M_G_DQ(45)
  U2D1  N38 DDR0_DQ<45> SKX_EXT_B_BGA1-IC,TBD   I172 @BASEBOARD_FAB2_LIB.BASEBOARD_FAB2(SCH_1):PAGE57
  J1G1  106 DQ<44> SCONN288_H44441004_PIP-SCONN,HA   I111 @BASEBOARD_FAB2_LIB.BASEBOARD_FAB2(SCH_1):PAGE77
  J9T1  251 DQ<45> SCONN288_H44441003_PIP-SCONN,HA    I13 @BASEBOARD_FAB2_LIB.BASEBOARD_FAB2(SCH_1):PAGE78

M_G_DQ<46> @BASEBOARD_FAB2_LIB.BASEBOARD_FAB2(SCH_1):M_G_DQ(46)
  U2D1  K35 DDR0_DQ<46> SKX_EXT_B_BGA1-IC,TBD   I172 @BASEBOARD_FAB2_LIB.BASEBOARD_FAB2(SCH_1):PAGE57
  J1G1  258 DQ<47> SCONN288_H44441004_PIP-SCONN,HA   I111 @BASEBOARD_FAB2_LIB.BASEBOARD_FAB2(SCH_1):PAGE77
  J9T1  113 DQ<46> SCONN288_H44441003_PIP-SCONN,HA    I13 @BASEBOARD_FAB2_LIB.BASEBOARD_FAB2(SCH_1):PAGE78

M_G_DQ<47> @BASEBOARD_FAB2_LIB.BASEBOARD_FAB2(SCH_1):M_G_DQ(47)
  U2D1  P35 DDR0_DQ<47> SKX_EXT_B_BGA1-IC,TBD   I172 @BASEBOARD_FAB2_LIB.BASEBOARD_FAB2(SCH_1):PAGE57
  J1G1  113 DQ<46> SCONN288_H44441004_PIP-SCONN,HA   I111 @BASEBOARD_FAB2_LIB.BASEBOARD_FAB2(SCH_1):PAGE77
  J9T1  258 DQ<47> SCONN288_H44441003_PIP-SCONN,HA    I13 @BASEBOARD_FAB2_LIB.BASEBOARD_FAB2(SCH_1):PAGE78

M_G_DQ<48> @BASEBOARD_FAB2_LIB.BASEBOARD_FAB2(SCH_1):M_G_DQ(48)
  U2D1  K31 DDR0_DQ<48> SKX_EXT_B_BGA1-IC,TBD   I172 @BASEBOARD_FAB2_LIB.BASEBOARD_FAB2(SCH_1):PAGE57
  J1G1  264 DQ<49> SCONN288_H44441004_PIP-SCONN,HA   I111 @BASEBOARD_FAB2_LIB.BASEBOARD_FAB2(SCH_1):PAGE77
  J9T1  119 DQ<48> SCONN288_H44441003_PIP-SCONN,HA    I13 @BASEBOARD_FAB2_LIB.BASEBOARD_FAB2(SCH_1):PAGE78

M_G_DQ<49> @BASEBOARD_FAB2_LIB.BASEBOARD_FAB2(SCH_1):M_G_DQ(49)
  U2D1  P31 DDR0_DQ<49> SKX_EXT_B_BGA1-IC,TBD   I172 @BASEBOARD_FAB2_LIB.BASEBOARD_FAB2(SCH_1):PAGE57
  J1G1  119 DQ<48> SCONN288_H44441004_PIP-SCONN,HA   I111 @BASEBOARD_FAB2_LIB.BASEBOARD_FAB2(SCH_1):PAGE77
  J9T1  264 DQ<49> SCONN288_H44441003_PIP-SCONN,HA    I13 @BASEBOARD_FAB2_LIB.BASEBOARD_FAB2(SCH_1):PAGE78

M_G_DQ<4> @BASEBOARD_FAB2_LIB.BASEBOARD_FAB2(SCH_1):M_G_DQ(4)
  U2D1 AR86 DDR0_DQ<4> SKX_EXT_B_BGA1-IC,TBD   I172 @BASEBOARD_FAB2_LIB.BASEBOARD_FAB2(SCH_1):PAGE57
  J1G1  148  DQ<5> SCONN288_H44441004_PIP-SCONN,HA   I111 @BASEBOARD_FAB2_LIB.BASEBOARD_FAB2(SCH_1):PAGE77
  J9T1    3  DQ<4> SCONN288_H44441003_PIP-SCONN,HA    I13 @BASEBOARD_FAB2_LIB.BASEBOARD_FAB2(SCH_1):PAGE78

M_G_DQ<50> @BASEBOARD_FAB2_LIB.BASEBOARD_FAB2(SCH_1):M_G_DQ(50)
  U2D1  L28 DDR0_DQ<50> SKX_EXT_B_BGA1-IC,TBD   I172 @BASEBOARD_FAB2_LIB.BASEBOARD_FAB2(SCH_1):PAGE57
  J1G1  271 DQ<51> SCONN288_H44441004_PIP-SCONN,HA   I111 @BASEBOARD_FAB2_LIB.BASEBOARD_FAB2(SCH_1):PAGE77
  J9T1  126 DQ<50> SCONN288_H44441003_PIP-SCONN,HA    I13 @BASEBOARD_FAB2_LIB.BASEBOARD_FAB2(SCH_1):PAGE78

M_G_DQ<51> @BASEBOARD_FAB2_LIB.BASEBOARD_FAB2(SCH_1):M_G_DQ(51)
  U2D1  N28 DDR0_DQ<51> SKX_EXT_B_BGA1-IC,TBD   I172 @BASEBOARD_FAB2_LIB.BASEBOARD_FAB2(SCH_1):PAGE57
  J1G1  126 DQ<50> SCONN288_H44441004_PIP-SCONN,HA   I111 @BASEBOARD_FAB2_LIB.BASEBOARD_FAB2(SCH_1):PAGE77
  J9T1  271 DQ<51> SCONN288_H44441003_PIP-SCONN,HA    I13 @BASEBOARD_FAB2_LIB.BASEBOARD_FAB2(SCH_1):PAGE78

M_G_DQ<52> @BASEBOARD_FAB2_LIB.BASEBOARD_FAB2(SCH_1):M_G_DQ(52)
  U2D1  L32 DDR0_DQ<52> SKX_EXT_B_BGA1-IC,TBD   I172 @BASEBOARD_FAB2_LIB.BASEBOARD_FAB2(SCH_1):PAGE57
  J1G1  262 DQ<53> SCONN288_H44441004_PIP-SCONN,HA   I111 @BASEBOARD_FAB2_LIB.BASEBOARD_FAB2(SCH_1):PAGE77
  J9T1  117 DQ<52> SCONN288_H44441003_PIP-SCONN,HA    I13 @BASEBOARD_FAB2_LIB.BASEBOARD_FAB2(SCH_1):PAGE78

M_G_DQ<53> @BASEBOARD_FAB2_LIB.BASEBOARD_FAB2(SCH_1):M_G_DQ(53)
  U2D1  N32 DDR0_DQ<53> SKX_EXT_B_BGA1-IC,TBD   I172 @BASEBOARD_FAB2_LIB.BASEBOARD_FAB2(SCH_1):PAGE57
  J1G1  117 DQ<52> SCONN288_H44441004_PIP-SCONN,HA   I111 @BASEBOARD_FAB2_LIB.BASEBOARD_FAB2(SCH_1):PAGE77
  J9T1  262 DQ<53> SCONN288_H44441003_PIP-SCONN,HA    I13 @BASEBOARD_FAB2_LIB.BASEBOARD_FAB2(SCH_1):PAGE78

M_G_DQ<54> @BASEBOARD_FAB2_LIB.BASEBOARD_FAB2(SCH_1):M_G_DQ(54)
  U2D1  K29 DDR0_DQ<54> SKX_EXT_B_BGA1-IC,TBD   I172 @BASEBOARD_FAB2_LIB.BASEBOARD_FAB2(SCH_1):PAGE57
  J1G1  269 DQ<55> SCONN288_H44441004_PIP-SCONN,HA   I111 @BASEBOARD_FAB2_LIB.BASEBOARD_FAB2(SCH_1):PAGE77
  J9T1  124 DQ<54> SCONN288_H44441003_PIP-SCONN,HA    I13 @BASEBOARD_FAB2_LIB.BASEBOARD_FAB2(SCH_1):PAGE78

M_G_DQ<55> @BASEBOARD_FAB2_LIB.BASEBOARD_FAB2(SCH_1):M_G_DQ(55)
  U2D1  P29 DDR0_DQ<55> SKX_EXT_B_BGA1-IC,TBD   I172 @BASEBOARD_FAB2_LIB.BASEBOARD_FAB2(SCH_1):PAGE57
  J1G1  124 DQ<54> SCONN288_H44441004_PIP-SCONN,HA   I111 @BASEBOARD_FAB2_LIB.BASEBOARD_FAB2(SCH_1):PAGE77
  J9T1  269 DQ<55> SCONN288_H44441003_PIP-SCONN,HA    I13 @BASEBOARD_FAB2_LIB.BASEBOARD_FAB2(SCH_1):PAGE78

M_G_DQ<56> @BASEBOARD_FAB2_LIB.BASEBOARD_FAB2(SCH_1):M_G_DQ(56)
  U2D1  K25 DDR0_DQ<56> SKX_EXT_B_BGA1-IC,TBD   I172 @BASEBOARD_FAB2_LIB.BASEBOARD_FAB2(SCH_1):PAGE57
  J1G1  275 DQ<57> SCONN288_H44441004_PIP-SCONN,HA   I111 @BASEBOARD_FAB2_LIB.BASEBOARD_FAB2(SCH_1):PAGE77
  J9T1  130 DQ<56> SCONN288_H44441003_PIP-SCONN,HA    I13 @BASEBOARD_FAB2_LIB.BASEBOARD_FAB2(SCH_1):PAGE78

M_G_DQ<57> @BASEBOARD_FAB2_LIB.BASEBOARD_FAB2(SCH_1):M_G_DQ(57)
  U2D1  P25 DDR0_DQ<57> SKX_EXT_B_BGA1-IC,TBD   I172 @BASEBOARD_FAB2_LIB.BASEBOARD_FAB2(SCH_1):PAGE57
  J1G1  130 DQ<56> SCONN288_H44441004_PIP-SCONN,HA   I111 @BASEBOARD_FAB2_LIB.BASEBOARD_FAB2(SCH_1):PAGE77
  J9T1  275 DQ<57> SCONN288_H44441003_PIP-SCONN,HA    I13 @BASEBOARD_FAB2_LIB.BASEBOARD_FAB2(SCH_1):PAGE78

M_G_DQ<58> @BASEBOARD_FAB2_LIB.BASEBOARD_FAB2(SCH_1):M_G_DQ(58)
  U2D1  P23 DDR0_DQ<58> SKX_EXT_B_BGA1-IC,TBD   I172 @BASEBOARD_FAB2_LIB.BASEBOARD_FAB2(SCH_1):PAGE57
  J1G1  282 DQ<59> SCONN288_H44441004_PIP-SCONN,HA   I111 @BASEBOARD_FAB2_LIB.BASEBOARD_FAB2(SCH_1):PAGE77
  J9T1  137 DQ<58> SCONN288_H44441003_PIP-SCONN,HA    I13 @BASEBOARD_FAB2_LIB.BASEBOARD_FAB2(SCH_1):PAGE78

M_G_DQ<59> @BASEBOARD_FAB2_LIB.BASEBOARD_FAB2(SCH_1):M_G_DQ(59)
  U2D1  T23 DDR0_DQ<59> SKX_EXT_B_BGA1-IC,TBD   I172 @BASEBOARD_FAB2_LIB.BASEBOARD_FAB2(SCH_1):PAGE57
  J1G1  137 DQ<58> SCONN288_H44441004_PIP-SCONN,HA   I111 @BASEBOARD_FAB2_LIB.BASEBOARD_FAB2(SCH_1):PAGE77
  J9T1  282 DQ<59> SCONN288_H44441003_PIP-SCONN,HA    I13 @BASEBOARD_FAB2_LIB.BASEBOARD_FAB2(SCH_1):PAGE78

M_G_DQ<5> @BASEBOARD_FAB2_LIB.BASEBOARD_FAB2(SCH_1):M_G_DQ(5)
  U2D1 AR84 DDR0_DQ<5> SKX_EXT_B_BGA1-IC,TBD   I172 @BASEBOARD_FAB2_LIB.BASEBOARD_FAB2(SCH_1):PAGE57
  J1G1    3  DQ<4> SCONN288_H44441004_PIP-SCONN,HA   I111 @BASEBOARD_FAB2_LIB.BASEBOARD_FAB2(SCH_1):PAGE77
  J9T1  148  DQ<5> SCONN288_H44441003_PIP-SCONN,HA    I13 @BASEBOARD_FAB2_LIB.BASEBOARD_FAB2(SCH_1):PAGE78

M_G_DQ<60> @BASEBOARD_FAB2_LIB.BASEBOARD_FAB2(SCH_1):M_G_DQ(60)
  U2D1  L26 DDR0_DQ<60> SKX_EXT_B_BGA1-IC,TBD   I172 @BASEBOARD_FAB2_LIB.BASEBOARD_FAB2(SCH_1):PAGE57
  J1G1  273 DQ<61> SCONN288_H44441004_PIP-SCONN,HA   I111 @BASEBOARD_FAB2_LIB.BASEBOARD_FAB2(SCH_1):PAGE77
  J9T1  128 DQ<60> SCONN288_H44441003_PIP-SCONN,HA    I13 @BASEBOARD_FAB2_LIB.BASEBOARD_FAB2(SCH_1):PAGE78

M_G_DQ<61> @BASEBOARD_FAB2_LIB.BASEBOARD_FAB2(SCH_1):M_G_DQ(61)
  U2D1  N26 DDR0_DQ<61> SKX_EXT_B_BGA1-IC,TBD   I172 @BASEBOARD_FAB2_LIB.BASEBOARD_FAB2(SCH_1):PAGE57
  J1G1  128 DQ<60> SCONN288_H44441004_PIP-SCONN,HA   I111 @BASEBOARD_FAB2_LIB.BASEBOARD_FAB2(SCH_1):PAGE77
  J9T1  273 DQ<61> SCONN288_H44441003_PIP-SCONN,HA    I13 @BASEBOARD_FAB2_LIB.BASEBOARD_FAB2(SCH_1):PAGE78

M_G_DQ<62> @BASEBOARD_FAB2_LIB.BASEBOARD_FAB2(SCH_1):M_G_DQ(62)
  U2D1  H23 DDR0_DQ<62> SKX_EXT_B_BGA1-IC,TBD   I172 @BASEBOARD_FAB2_LIB.BASEBOARD_FAB2(SCH_1):PAGE57
  J1G1  280 DQ<63> SCONN288_H44441004_PIP-SCONN,HA   I111 @BASEBOARD_FAB2_LIB.BASEBOARD_FAB2(SCH_1):PAGE77
  J9T1  135 DQ<62> SCONN288_H44441003_PIP-SCONN,HA    I13 @BASEBOARD_FAB2_LIB.BASEBOARD_FAB2(SCH_1):PAGE78

M_G_DQ<63> @BASEBOARD_FAB2_LIB.BASEBOARD_FAB2(SCH_1):M_G_DQ(63)
  U2D1  K23 DDR0_DQ<63> SKX_EXT_B_BGA1-IC,TBD   I172 @BASEBOARD_FAB2_LIB.BASEBOARD_FAB2(SCH_1):PAGE57
  J1G1  135 DQ<62> SCONN288_H44441004_PIP-SCONN,HA   I111 @BASEBOARD_FAB2_LIB.BASEBOARD_FAB2(SCH_1):PAGE77
  J9T1  280 DQ<63> SCONN288_H44441003_PIP-SCONN,HA    I13 @BASEBOARD_FAB2_LIB.BASEBOARD_FAB2(SCH_1):PAGE78

M_G_DQ<6> @BASEBOARD_FAB2_LIB.BASEBOARD_FAB2(SCH_1):M_G_DQ(6)
  U2D1 AG86 DDR0_DQ<6> SKX_EXT_B_BGA1-IC,TBD   I172 @BASEBOARD_FAB2_LIB.BASEBOARD_FAB2(SCH_1):PAGE57
  J1G1  155  DQ<7> SCONN288_H44441004_PIP-SCONN,HA   I111 @BASEBOARD_FAB2_LIB.BASEBOARD_FAB2(SCH_1):PAGE77
  J9T1   10  DQ<6> SCONN288_H44441003_PIP-SCONN,HA    I13 @BASEBOARD_FAB2_LIB.BASEBOARD_FAB2(SCH_1):PAGE78

M_G_DQ<7> @BASEBOARD_FAB2_LIB.BASEBOARD_FAB2(SCH_1):M_G_DQ(7)
  U2D1 AG84 DDR0_DQ<7> SKX_EXT_B_BGA1-IC,TBD   I172 @BASEBOARD_FAB2_LIB.BASEBOARD_FAB2(SCH_1):PAGE57
  J1G1   10  DQ<6> SCONN288_H44441004_PIP-SCONN,HA   I111 @BASEBOARD_FAB2_LIB.BASEBOARD_FAB2(SCH_1):PAGE77
  J9T1  155  DQ<7> SCONN288_H44441003_PIP-SCONN,HA    I13 @BASEBOARD_FAB2_LIB.BASEBOARD_FAB2(SCH_1):PAGE78

M_G_DQ<8> @BASEBOARD_FAB2_LIB.BASEBOARD_FAB2(SCH_1):M_G_DQ(8)
  U2D1  W86 DDR0_DQ<8> SKX_EXT_B_BGA1-IC,TBD   I172 @BASEBOARD_FAB2_LIB.BASEBOARD_FAB2(SCH_1):PAGE57
  J1G1  161  DQ<9> SCONN288_H44441004_PIP-SCONN,HA   I111 @BASEBOARD_FAB2_LIB.BASEBOARD_FAB2(SCH_1):PAGE77
  J9T1   16  DQ<8> SCONN288_H44441003_PIP-SCONN,HA    I13 @BASEBOARD_FAB2_LIB.BASEBOARD_FAB2(SCH_1):PAGE78

M_G_DQ<9> @BASEBOARD_FAB2_LIB.BASEBOARD_FAB2(SCH_1):M_G_DQ(9)
  U2D1  W84 DDR0_DQ<9> SKX_EXT_B_BGA1-IC,TBD   I172 @BASEBOARD_FAB2_LIB.BASEBOARD_FAB2(SCH_1):PAGE57
  J1G1   16  DQ<8> SCONN288_H44441004_PIP-SCONN,HA   I111 @BASEBOARD_FAB2_LIB.BASEBOARD_FAB2(SCH_1):PAGE77
  J9T1  161  DQ<9> SCONN288_H44441003_PIP-SCONN,HA    I13 @BASEBOARD_FAB2_LIB.BASEBOARD_FAB2(SCH_1):PAGE78

M_G_DQS_DN<0> @BASEBOARD_FAB2_LIB.BASEBOARD_FAB2(SCH_1):M_G_DQS_DN(0)
  U2D1 AJ84 DDR0_DQS_DN<0> SKX_EXT_B_BGA1-IC,TBD   I172 @BASEBOARD_FAB2_LIB.BASEBOARD_FAB2(SCH_1):PAGE57
  J1G1  152  DQS0N SCONN288_H44441004_PIP-SCONN,HA    I66 @BASEBOARD_FAB2_LIB.BASEBOARD_FAB2(SCH_1):PAGE77
  J9T1  152  DQS0N SCONN288_H44441003_PIP-SCONN,HA   I120 @BASEBOARD_FAB2_LIB.BASEBOARD_FAB2(SCH_1):PAGE78

M_G_DQS_DN<10> @BASEBOARD_FAB2_LIB.BASEBOARD_FAB2(SCH_1):M_G_DQS_DN(10)
  U2D1  U84 DDR0_DQS_DN<10> SKX_EXT_B_BGA1-IC,TBD   I172 @BASEBOARD_FAB2_LIB.BASEBOARD_FAB2(SCH_1):PAGE57
  J1G1   19 DQS10N SCONN288_H44441004_PIP-SCONN,HA    I66 @BASEBOARD_FAB2_LIB.BASEBOARD_FAB2(SCH_1):PAGE77
  J9T1   19 DQS10N SCONN288_H44441003_PIP-SCONN,HA   I120 @BASEBOARD_FAB2_LIB.BASEBOARD_FAB2(SCH_1):PAGE78

M_G_DQS_DN<11> @BASEBOARD_FAB2_LIB.BASEBOARD_FAB2(SCH_1):M_G_DQS_DN(11)
  U2D1  U82 DDR0_DQS_DN<11> SKX_EXT_B_BGA1-IC,TBD   I172 @BASEBOARD_FAB2_LIB.BASEBOARD_FAB2(SCH_1):PAGE57
  J1G1   30 DQS11N SCONN288_H44441004_PIP-SCONN,HA    I66 @BASEBOARD_FAB2_LIB.BASEBOARD_FAB2(SCH_1):PAGE77
  J9T1   30 DQS11N SCONN288_H44441003_PIP-SCONN,HA   I120 @BASEBOARD_FAB2_LIB.BASEBOARD_FAB2(SCH_1):PAGE78

M_G_DQS_DN<12> @BASEBOARD_FAB2_LIB.BASEBOARD_FAB2(SCH_1):M_G_DQS_DN(12)
  U2D1  K75 DDR0_DQS_DN<12> SKX_EXT_B_BGA1-IC,TBD   I172 @BASEBOARD_FAB2_LIB.BASEBOARD_FAB2(SCH_1):PAGE57
  J1G1   41 DQS12N SCONN288_H44441004_PIP-SCONN,HA    I66 @BASEBOARD_FAB2_LIB.BASEBOARD_FAB2(SCH_1):PAGE77
  J9T1   41 DQS12N SCONN288_H44441003_PIP-SCONN,HA   I120 @BASEBOARD_FAB2_LIB.BASEBOARD_FAB2(SCH_1):PAGE78

M_G_DQS_DN<13> @BASEBOARD_FAB2_LIB.BASEBOARD_FAB2(SCH_1):M_G_DQS_DN(13)
  U2D1  A40 DDR0_DQS_DN<13> SKX_EXT_B_BGA1-IC,TBD   I172 @BASEBOARD_FAB2_LIB.BASEBOARD_FAB2(SCH_1):PAGE57
  J1G1  100 DQS13N SCONN288_H44441004_PIP-SCONN,HA    I66 @BASEBOARD_FAB2_LIB.BASEBOARD_FAB2(SCH_1):PAGE77
  J9T1  100 DQS13N SCONN288_H44441003_PIP-SCONN,HA   I120 @BASEBOARD_FAB2_LIB.BASEBOARD_FAB2(SCH_1):PAGE78

M_G_DQS_DN<14> @BASEBOARD_FAB2_LIB.BASEBOARD_FAB2(SCH_1):M_G_DQS_DN(14)
  U2D1  J36 DDR0_DQS_DN<14> SKX_EXT_B_BGA1-IC,TBD   I172 @BASEBOARD_FAB2_LIB.BASEBOARD_FAB2(SCH_1):PAGE57
  J1G1  111 DQS14N SCONN288_H44441004_PIP-SCONN,HA    I66 @BASEBOARD_FAB2_LIB.BASEBOARD_FAB2(SCH_1):PAGE77
  J9T1  111 DQS14N SCONN288_H44441003_PIP-SCONN,HA   I120 @BASEBOARD_FAB2_LIB.BASEBOARD_FAB2(SCH_1):PAGE78

M_G_DQS_DN<15> @BASEBOARD_FAB2_LIB.BASEBOARD_FAB2(SCH_1):M_G_DQS_DN(15)
  U2D1  J30 DDR0_DQS_DN<15> SKX_EXT_B_BGA1-IC,TBD   I172 @BASEBOARD_FAB2_LIB.BASEBOARD_FAB2(SCH_1):PAGE57
  J1G1  122 DQS15N SCONN288_H44441004_PIP-SCONN,HA    I66 @BASEBOARD_FAB2_LIB.BASEBOARD_FAB2(SCH_1):PAGE77
  J9T1  122 DQS15N SCONN288_H44441003_PIP-SCONN,HA   I120 @BASEBOARD_FAB2_LIB.BASEBOARD_FAB2(SCH_1):PAGE78

M_G_DQS_DN<16> @BASEBOARD_FAB2_LIB.BASEBOARD_FAB2(SCH_1):M_G_DQS_DN(16)
  U2D1  J24 DDR0_DQS_DN<16> SKX_EXT_B_BGA1-IC,TBD   I172 @BASEBOARD_FAB2_LIB.BASEBOARD_FAB2(SCH_1):PAGE57
  J1G1  133 DQS16N SCONN288_H44441004_PIP-SCONN,HA    I66 @BASEBOARD_FAB2_LIB.BASEBOARD_FAB2(SCH_1):PAGE77
  J9T1  133 DQS16N SCONN288_H44441003_PIP-SCONN,HA   I120 @BASEBOARD_FAB2_LIB.BASEBOARD_FAB2(SCH_1):PAGE78

M_G_DQS_DN<17> @BASEBOARD_FAB2_LIB.BASEBOARD_FAB2(SCH_1):M_G_DQS_DN(17)
  U2D1 AB67 DDR0_DQS_DN<17> SKX_EXT_B_BGA1-IC,TBD   I172 @BASEBOARD_FAB2_LIB.BASEBOARD_FAB2(SCH_1):PAGE57
  J1G1   52 DQS17N SCONN288_H44441004_PIP-SCONN,HA    I66 @BASEBOARD_FAB2_LIB.BASEBOARD_FAB2(SCH_1):PAGE77
  J9T1   52 DQS17N SCONN288_H44441003_PIP-SCONN,HA   I120 @BASEBOARD_FAB2_LIB.BASEBOARD_FAB2(SCH_1):PAGE78

M_G_DQS_DN<1> @BASEBOARD_FAB2_LIB.BASEBOARD_FAB2(SCH_1):M_G_DQS_DN(1)
  U2D1  R84 DDR0_DQS_DN<1> SKX_EXT_B_BGA1-IC,TBD   I172 @BASEBOARD_FAB2_LIB.BASEBOARD_FAB2(SCH_1):PAGE57
  J1G1  163  DQS1N SCONN288_H44441004_PIP-SCONN,HA    I66 @BASEBOARD_FAB2_LIB.BASEBOARD_FAB2(SCH_1):PAGE77
  J9T1  163  DQS1N SCONN288_H44441003_PIP-SCONN,HA   I120 @BASEBOARD_FAB2_LIB.BASEBOARD_FAB2(SCH_1):PAGE78

M_G_DQS_DN<2> @BASEBOARD_FAB2_LIB.BASEBOARD_FAB2(SCH_1):M_G_DQS_DN(2)
  U2D1  P79 DDR0_DQS_DN<2> SKX_EXT_B_BGA1-IC,TBD   I172 @BASEBOARD_FAB2_LIB.BASEBOARD_FAB2(SCH_1):PAGE57
  J1G1  174  DQS2N SCONN288_H44441004_PIP-SCONN,HA    I66 @BASEBOARD_FAB2_LIB.BASEBOARD_FAB2(SCH_1):PAGE77
  J9T1  174  DQS2N SCONN288_H44441003_PIP-SCONN,HA   I120 @BASEBOARD_FAB2_LIB.BASEBOARD_FAB2(SCH_1):PAGE78

M_G_DQS_DN<3> @BASEBOARD_FAB2_LIB.BASEBOARD_FAB2(SCH_1):M_G_DQS_DN(3)
  U2D1  T75 DDR0_DQS_DN<3> SKX_EXT_B_BGA1-IC,TBD   I172 @BASEBOARD_FAB2_LIB.BASEBOARD_FAB2(SCH_1):PAGE57
  J1G1  185  DQS3N SCONN288_H44441004_PIP-SCONN,HA    I66 @BASEBOARD_FAB2_LIB.BASEBOARD_FAB2(SCH_1):PAGE77
  J9T1  185  DQS3N SCONN288_H44441003_PIP-SCONN,HA   I120 @BASEBOARD_FAB2_LIB.BASEBOARD_FAB2(SCH_1):PAGE78

M_G_DQS_DN<4> @BASEBOARD_FAB2_LIB.BASEBOARD_FAB2(SCH_1):M_G_DQS_DN(4)
  U2D1  G40 DDR0_DQS_DN<4> SKX_EXT_B_BGA1-IC,TBD   I172 @BASEBOARD_FAB2_LIB.BASEBOARD_FAB2(SCH_1):PAGE57
  J1G1  244  DQS4N SCONN288_H44441004_PIP-SCONN,HA    I66 @BASEBOARD_FAB2_LIB.BASEBOARD_FAB2(SCH_1):PAGE77
  J9T1  244  DQS4N SCONN288_H44441003_PIP-SCONN,HA   I120 @BASEBOARD_FAB2_LIB.BASEBOARD_FAB2(SCH_1):PAGE78

M_G_DQS_DN<5> @BASEBOARD_FAB2_LIB.BASEBOARD_FAB2(SCH_1):M_G_DQS_DN(5)
  U2D1  R36 DDR0_DQS_DN<5> SKX_EXT_B_BGA1-IC,TBD   I172 @BASEBOARD_FAB2_LIB.BASEBOARD_FAB2(SCH_1):PAGE57
  J1G1  255  DQS5N SCONN288_H44441004_PIP-SCONN,HA    I66 @BASEBOARD_FAB2_LIB.BASEBOARD_FAB2(SCH_1):PAGE77
  J9T1  255  DQS5N SCONN288_H44441003_PIP-SCONN,HA   I120 @BASEBOARD_FAB2_LIB.BASEBOARD_FAB2(SCH_1):PAGE78

M_G_DQS_DN<6> @BASEBOARD_FAB2_LIB.BASEBOARD_FAB2(SCH_1):M_G_DQS_DN(6)
  U2D1  R30 DDR0_DQS_DN<6> SKX_EXT_B_BGA1-IC,TBD   I172 @BASEBOARD_FAB2_LIB.BASEBOARD_FAB2(SCH_1):PAGE57
  J1G1  266  DQS6N SCONN288_H44441004_PIP-SCONN,HA    I66 @BASEBOARD_FAB2_LIB.BASEBOARD_FAB2(SCH_1):PAGE77
  J9T1  266  DQS6N SCONN288_H44441003_PIP-SCONN,HA   I120 @BASEBOARD_FAB2_LIB.BASEBOARD_FAB2(SCH_1):PAGE78

M_G_DQS_DN<7> @BASEBOARD_FAB2_LIB.BASEBOARD_FAB2(SCH_1):M_G_DQS_DN(7)
  U2D1  N24 DDR0_DQS_DN<7> SKX_EXT_B_BGA1-IC,TBD   I172 @BASEBOARD_FAB2_LIB.BASEBOARD_FAB2(SCH_1):PAGE57
  J1G1  277  DQS7N SCONN288_H44441004_PIP-SCONN,HA    I66 @BASEBOARD_FAB2_LIB.BASEBOARD_FAB2(SCH_1):PAGE77
  J9T1  277  DQS7N SCONN288_H44441003_PIP-SCONN,HA   I120 @BASEBOARD_FAB2_LIB.BASEBOARD_FAB2(SCH_1):PAGE78

M_G_DQS_DN<8> @BASEBOARD_FAB2_LIB.BASEBOARD_FAB2(SCH_1):M_G_DQS_DN(8)
  U2D1 AH67 DDR0_DQS_DN<8> SKX_EXT_B_BGA1-IC,TBD   I172 @BASEBOARD_FAB2_LIB.BASEBOARD_FAB2(SCH_1):PAGE57
  J1G1  196  DQS8N SCONN288_H44441004_PIP-SCONN,HA    I66 @BASEBOARD_FAB2_LIB.BASEBOARD_FAB2(SCH_1):PAGE77
  J9T1  196  DQS8N SCONN288_H44441003_PIP-SCONN,HA   I120 @BASEBOARD_FAB2_LIB.BASEBOARD_FAB2(SCH_1):PAGE78

M_G_DQS_DN<9> @BASEBOARD_FAB2_LIB.BASEBOARD_FAB2(SCH_1):M_G_DQS_DN(9)
  U2D1 AL84 DDR0_DQS_DN<9> SKX_EXT_B_BGA1-IC,TBD   I172 @BASEBOARD_FAB2_LIB.BASEBOARD_FAB2(SCH_1):PAGE57
  J1G1    8  DQS9N SCONN288_H44441004_PIP-SCONN,HA    I66 @BASEBOARD_FAB2_LIB.BASEBOARD_FAB2(SCH_1):PAGE77
  J9T1    8  DQS9N SCONN288_H44441003_PIP-SCONN,HA   I120 @BASEBOARD_FAB2_LIB.BASEBOARD_FAB2(SCH_1):PAGE78

M_G_DQS_DP<0> @BASEBOARD_FAB2_LIB.BASEBOARD_FAB2(SCH_1):M_G_DQS_DP(0)
  U2D1 AH85 DDR0_DQS_DP<0> SKX_EXT_B_BGA1-IC,TBD   I172 @BASEBOARD_FAB2_LIB.BASEBOARD_FAB2(SCH_1):PAGE57
  J1G1  153  DQS0P SCONN288_H44441004_PIP-SCONN,HA    I66 @BASEBOARD_FAB2_LIB.BASEBOARD_FAB2(SCH_1):PAGE77
  J9T1  153  DQS0P SCONN288_H44441003_PIP-SCONN,HA   I120 @BASEBOARD_FAB2_LIB.BASEBOARD_FAB2(SCH_1):PAGE78

M_G_DQS_DP<10> @BASEBOARD_FAB2_LIB.BASEBOARD_FAB2(SCH_1):M_G_DQS_DP(10)
  U2D1  V85 DDR0_DQS_DP<10> SKX_EXT_B_BGA1-IC,TBD   I172 @BASEBOARD_FAB2_LIB.BASEBOARD_FAB2(SCH_1):PAGE57
  J1G1   18 DQS10P SCONN288_H44441004_PIP-SCONN,HA    I66 @BASEBOARD_FAB2_LIB.BASEBOARD_FAB2(SCH_1):PAGE77
  J9T1   18 DQS10P SCONN288_H44441003_PIP-SCONN,HA   I120 @BASEBOARD_FAB2_LIB.BASEBOARD_FAB2(SCH_1):PAGE78

M_G_DQS_DP<11> @BASEBOARD_FAB2_LIB.BASEBOARD_FAB2(SCH_1):M_G_DQS_DP(11)
  U2D1  T81 DDR0_DQS_DP<11> SKX_EXT_B_BGA1-IC,TBD   I172 @BASEBOARD_FAB2_LIB.BASEBOARD_FAB2(SCH_1):PAGE57
  J1G1   29 DQS11P SCONN288_H44441004_PIP-SCONN,HA    I66 @BASEBOARD_FAB2_LIB.BASEBOARD_FAB2(SCH_1):PAGE77
  J9T1   29 DQS11P SCONN288_H44441003_PIP-SCONN,HA   I120 @BASEBOARD_FAB2_LIB.BASEBOARD_FAB2(SCH_1):PAGE78

M_G_DQS_DP<12> @BASEBOARD_FAB2_LIB.BASEBOARD_FAB2(SCH_1):M_G_DQS_DP(12)
  U2D1  M75 DDR0_DQS_DP<12> SKX_EXT_B_BGA1-IC,TBD   I172 @BASEBOARD_FAB2_LIB.BASEBOARD_FAB2(SCH_1):PAGE57
  J1G1   40 DQS12P SCONN288_H44441004_PIP-SCONN,HA    I66 @BASEBOARD_FAB2_LIB.BASEBOARD_FAB2(SCH_1):PAGE77
  J9T1   40 DQS12P SCONN288_H44441003_PIP-SCONN,HA   I120 @BASEBOARD_FAB2_LIB.BASEBOARD_FAB2(SCH_1):PAGE78

M_G_DQS_DP<13> @BASEBOARD_FAB2_LIB.BASEBOARD_FAB2(SCH_1):M_G_DQS_DP(13)
  U2D1  C40 DDR0_DQS_DP<13> SKX_EXT_B_BGA1-IC,TBD   I172 @BASEBOARD_FAB2_LIB.BASEBOARD_FAB2(SCH_1):PAGE57
  J1G1   99 DQS13P SCONN288_H44441004_PIP-SCONN,HA    I66 @BASEBOARD_FAB2_LIB.BASEBOARD_FAB2(SCH_1):PAGE77
  J9T1   99 DQS13P SCONN288_H44441003_PIP-SCONN,HA   I120 @BASEBOARD_FAB2_LIB.BASEBOARD_FAB2(SCH_1):PAGE78

M_G_DQS_DP<14> @BASEBOARD_FAB2_LIB.BASEBOARD_FAB2(SCH_1):M_G_DQS_DP(14)
  U2D1  L36 DDR0_DQS_DP<14> SKX_EXT_B_BGA1-IC,TBD   I172 @BASEBOARD_FAB2_LIB.BASEBOARD_FAB2(SCH_1):PAGE57
  J1G1  110 DQS14P SCONN288_H44441004_PIP-SCONN,HA    I66 @BASEBOARD_FAB2_LIB.BASEBOARD_FAB2(SCH_1):PAGE77
  J9T1  110 DQS14P SCONN288_H44441003_PIP-SCONN,HA   I120 @BASEBOARD_FAB2_LIB.BASEBOARD_FAB2(SCH_1):PAGE78

M_G_DQS_DP<15> @BASEBOARD_FAB2_LIB.BASEBOARD_FAB2(SCH_1):M_G_DQS_DP(15)
  U2D1  L30 DDR0_DQS_DP<15> SKX_EXT_B_BGA1-IC,TBD   I172 @BASEBOARD_FAB2_LIB.BASEBOARD_FAB2(SCH_1):PAGE57
  J1G1  121 DQS15P SCONN288_H44441004_PIP-SCONN,HA    I66 @BASEBOARD_FAB2_LIB.BASEBOARD_FAB2(SCH_1):PAGE77
  J9T1  121 DQS15P SCONN288_H44441003_PIP-SCONN,HA   I120 @BASEBOARD_FAB2_LIB.BASEBOARD_FAB2(SCH_1):PAGE78

M_G_DQS_DP<16> @BASEBOARD_FAB2_LIB.BASEBOARD_FAB2(SCH_1):M_G_DQS_DP(16)
  U2D1  L24 DDR0_DQS_DP<16> SKX_EXT_B_BGA1-IC,TBD   I172 @BASEBOARD_FAB2_LIB.BASEBOARD_FAB2(SCH_1):PAGE57
  J1G1  132 DQS16P SCONN288_H44441004_PIP-SCONN,HA    I66 @BASEBOARD_FAB2_LIB.BASEBOARD_FAB2(SCH_1):PAGE77
  J9T1  132 DQS16P SCONN288_H44441003_PIP-SCONN,HA   I120 @BASEBOARD_FAB2_LIB.BASEBOARD_FAB2(SCH_1):PAGE78

M_G_DQS_DP<17> @BASEBOARD_FAB2_LIB.BASEBOARD_FAB2(SCH_1):M_G_DQS_DP(17)
  U2D1 AD67 DDR0_DQS_DP<17> SKX_EXT_B_BGA1-IC,TBD   I172 @BASEBOARD_FAB2_LIB.BASEBOARD_FAB2(SCH_1):PAGE57
  J1G1   51 DQS17P SCONN288_H44441004_PIP-SCONN,HA    I66 @BASEBOARD_FAB2_LIB.BASEBOARD_FAB2(SCH_1):PAGE77
  J9T1   51 DQS17P SCONN288_H44441003_PIP-SCONN,HA   I120 @BASEBOARD_FAB2_LIB.BASEBOARD_FAB2(SCH_1):PAGE78

M_G_DQS_DP<1> @BASEBOARD_FAB2_LIB.BASEBOARD_FAB2(SCH_1):M_G_DQS_DP(1)
  U2D1  P85 DDR0_DQS_DP<1> SKX_EXT_B_BGA1-IC,TBD   I172 @BASEBOARD_FAB2_LIB.BASEBOARD_FAB2(SCH_1):PAGE57
  J1G1  164  DQS1P SCONN288_H44441004_PIP-SCONN,HA    I66 @BASEBOARD_FAB2_LIB.BASEBOARD_FAB2(SCH_1):PAGE77
  J9T1  164  DQS1P SCONN288_H44441003_PIP-SCONN,HA   I120 @BASEBOARD_FAB2_LIB.BASEBOARD_FAB2(SCH_1):PAGE78

M_G_DQS_DP<2> @BASEBOARD_FAB2_LIB.BASEBOARD_FAB2(SCH_1):M_G_DQS_DP(2)
  U2D1  R80 DDR0_DQS_DP<2> SKX_EXT_B_BGA1-IC,TBD   I172 @BASEBOARD_FAB2_LIB.BASEBOARD_FAB2(SCH_1):PAGE57
  J1G1  175  DQS2P SCONN288_H44441004_PIP-SCONN,HA    I66 @BASEBOARD_FAB2_LIB.BASEBOARD_FAB2(SCH_1):PAGE77
  J9T1  175  DQS2P SCONN288_H44441003_PIP-SCONN,HA   I120 @BASEBOARD_FAB2_LIB.BASEBOARD_FAB2(SCH_1):PAGE78

M_G_DQS_DP<3> @BASEBOARD_FAB2_LIB.BASEBOARD_FAB2(SCH_1):M_G_DQS_DP(3)
  U2D1  P75 DDR0_DQS_DP<3> SKX_EXT_B_BGA1-IC,TBD   I172 @BASEBOARD_FAB2_LIB.BASEBOARD_FAB2(SCH_1):PAGE57
  J1G1  186  DQS3P SCONN288_H44441004_PIP-SCONN,HA    I66 @BASEBOARD_FAB2_LIB.BASEBOARD_FAB2(SCH_1):PAGE77
  J9T1  186  DQS3P SCONN288_H44441003_PIP-SCONN,HA   I120 @BASEBOARD_FAB2_LIB.BASEBOARD_FAB2(SCH_1):PAGE78

M_G_DQS_DP<4> @BASEBOARD_FAB2_LIB.BASEBOARD_FAB2(SCH_1):M_G_DQS_DP(4)
  U2D1  E40 DDR0_DQS_DP<4> SKX_EXT_B_BGA1-IC,TBD   I172 @BASEBOARD_FAB2_LIB.BASEBOARD_FAB2(SCH_1):PAGE57
  J1G1  245  DQS4P SCONN288_H44441004_PIP-SCONN,HA    I66 @BASEBOARD_FAB2_LIB.BASEBOARD_FAB2(SCH_1):PAGE77
  J9T1  245  DQS4P SCONN288_H44441003_PIP-SCONN,HA   I120 @BASEBOARD_FAB2_LIB.BASEBOARD_FAB2(SCH_1):PAGE78

M_G_DQS_DP<5> @BASEBOARD_FAB2_LIB.BASEBOARD_FAB2(SCH_1):M_G_DQS_DP(5)
  U2D1  N36 DDR0_DQS_DP<5> SKX_EXT_B_BGA1-IC,TBD   I172 @BASEBOARD_FAB2_LIB.BASEBOARD_FAB2(SCH_1):PAGE57
  J1G1  256  DQS5P SCONN288_H44441004_PIP-SCONN,HA    I66 @BASEBOARD_FAB2_LIB.BASEBOARD_FAB2(SCH_1):PAGE77
  J9T1  256  DQS5P SCONN288_H44441003_PIP-SCONN,HA   I120 @BASEBOARD_FAB2_LIB.BASEBOARD_FAB2(SCH_1):PAGE78

M_G_DQS_DP<6> @BASEBOARD_FAB2_LIB.BASEBOARD_FAB2(SCH_1):M_G_DQS_DP(6)
  U2D1  N30 DDR0_DQS_DP<6> SKX_EXT_B_BGA1-IC,TBD   I172 @BASEBOARD_FAB2_LIB.BASEBOARD_FAB2(SCH_1):PAGE57
  J1G1  267  DQS6P SCONN288_H44441004_PIP-SCONN,HA    I66 @BASEBOARD_FAB2_LIB.BASEBOARD_FAB2(SCH_1):PAGE77
  J9T1  267  DQS6P SCONN288_H44441003_PIP-SCONN,HA   I120 @BASEBOARD_FAB2_LIB.BASEBOARD_FAB2(SCH_1):PAGE78

M_G_DQS_DP<7> @BASEBOARD_FAB2_LIB.BASEBOARD_FAB2(SCH_1):M_G_DQS_DP(7)
  U2D1  R24 DDR0_DQS_DP<7> SKX_EXT_B_BGA1-IC,TBD   I172 @BASEBOARD_FAB2_LIB.BASEBOARD_FAB2(SCH_1):PAGE57
  J1G1  278  DQS7P SCONN288_H44441004_PIP-SCONN,HA    I66 @BASEBOARD_FAB2_LIB.BASEBOARD_FAB2(SCH_1):PAGE77
  J9T1  278  DQS7P SCONN288_H44441003_PIP-SCONN,HA   I120 @BASEBOARD_FAB2_LIB.BASEBOARD_FAB2(SCH_1):PAGE78

M_G_DQS_DP<8> @BASEBOARD_FAB2_LIB.BASEBOARD_FAB2(SCH_1):M_G_DQS_DP(8)
  U2D1 AF67 DDR0_DQS_DP<8> SKX_EXT_B_BGA1-IC,TBD   I172 @BASEBOARD_FAB2_LIB.BASEBOARD_FAB2(SCH_1):PAGE57
  J1G1  197  DQS8P SCONN288_H44441004_PIP-SCONN,HA    I66 @BASEBOARD_FAB2_LIB.BASEBOARD_FAB2(SCH_1):PAGE77
  J9T1  197  DQS8P SCONN288_H44441003_PIP-SCONN,HA   I120 @BASEBOARD_FAB2_LIB.BASEBOARD_FAB2(SCH_1):PAGE78

M_G_DQS_DP<9> @BASEBOARD_FAB2_LIB.BASEBOARD_FAB2(SCH_1):M_G_DQS_DP(9)
  U2D1 AM85 DDR0_DQS_DP<9> SKX_EXT_B_BGA1-IC,TBD   I172 @BASEBOARD_FAB2_LIB.BASEBOARD_FAB2(SCH_1):PAGE57
  J1G1    7  DQS9P SCONN288_H44441004_PIP-SCONN,HA    I66 @BASEBOARD_FAB2_LIB.BASEBOARD_FAB2(SCH_1):PAGE77
  J9T1    7  DQS9P SCONN288_H44441003_PIP-SCONN,HA   I120 @BASEBOARD_FAB2_LIB.BASEBOARD_FAB2(SCH_1):PAGE78

M_G_ECC<0> @BASEBOARD_FAB2_LIB.BASEBOARD_FAB2(SCH_1):M_G_ECC(0)
  U2D1 AC68 DDR0_ECC<0> SKX_EXT_B_BGA1-IC,TBD   I172 @BASEBOARD_FAB2_LIB.BASEBOARD_FAB2(SCH_1):PAGE57
  J1G1  194  CB<1> SCONN288_H44441004_PIP-SCONN,HA   I111 @BASEBOARD_FAB2_LIB.BASEBOARD_FAB2(SCH_1):PAGE77
  J9T1   49  CB<0> SCONN288_H44441003_PIP-SCONN,HA    I13 @BASEBOARD_FAB2_LIB.BASEBOARD_FAB2(SCH_1):PAGE78

M_G_ECC<1> @BASEBOARD_FAB2_LIB.BASEBOARD_FAB2(SCH_1):M_G_ECC(1)
  U2D1 AG68 DDR0_ECC<1> SKX_EXT_B_BGA1-IC,TBD   I172 @BASEBOARD_FAB2_LIB.BASEBOARD_FAB2(SCH_1):PAGE57
  J1G1   49  CB<0> SCONN288_H44441004_PIP-SCONN,HA   I111 @BASEBOARD_FAB2_LIB.BASEBOARD_FAB2(SCH_1):PAGE77
  J9T1  194  CB<1> SCONN288_H44441003_PIP-SCONN,HA    I13 @BASEBOARD_FAB2_LIB.BASEBOARD_FAB2(SCH_1):PAGE78

M_G_ECC<2> @BASEBOARD_FAB2_LIB.BASEBOARD_FAB2(SCH_1):M_G_ECC(2)
  U2D1 AD65 DDR0_ECC<2> SKX_EXT_B_BGA1-IC,TBD   I172 @BASEBOARD_FAB2_LIB.BASEBOARD_FAB2(SCH_1):PAGE57
  J1G1  201  CB<3> SCONN288_H44441004_PIP-SCONN,HA   I111 @BASEBOARD_FAB2_LIB.BASEBOARD_FAB2(SCH_1):PAGE77
  J9T1   56  CB<2> SCONN288_H44441003_PIP-SCONN,HA    I13 @BASEBOARD_FAB2_LIB.BASEBOARD_FAB2(SCH_1):PAGE78

M_G_ECC<3> @BASEBOARD_FAB2_LIB.BASEBOARD_FAB2(SCH_1):M_G_ECC(3)
  U2D1 AF65 DDR0_ECC<3> SKX_EXT_B_BGA1-IC,TBD   I172 @BASEBOARD_FAB2_LIB.BASEBOARD_FAB2(SCH_1):PAGE57
  J1G1   56  CB<2> SCONN288_H44441004_PIP-SCONN,HA   I111 @BASEBOARD_FAB2_LIB.BASEBOARD_FAB2(SCH_1):PAGE77
  J9T1  201  CB<3> SCONN288_H44441003_PIP-SCONN,HA    I13 @BASEBOARD_FAB2_LIB.BASEBOARD_FAB2(SCH_1):PAGE78

M_G_ECC<4> @BASEBOARD_FAB2_LIB.BASEBOARD_FAB2(SCH_1):M_G_ECC(4)
  U2D1 AD69 DDR0_ECC<4> SKX_EXT_B_BGA1-IC,TBD   I172 @BASEBOARD_FAB2_LIB.BASEBOARD_FAB2(SCH_1):PAGE57
  J1G1  192  CB<5> SCONN288_H44441004_PIP-SCONN,HA   I111 @BASEBOARD_FAB2_LIB.BASEBOARD_FAB2(SCH_1):PAGE77
  J9T1   47  CB<4> SCONN288_H44441003_PIP-SCONN,HA    I13 @BASEBOARD_FAB2_LIB.BASEBOARD_FAB2(SCH_1):PAGE78

M_G_ECC<5> @BASEBOARD_FAB2_LIB.BASEBOARD_FAB2(SCH_1):M_G_ECC(5)
  U2D1 AF69 DDR0_ECC<5> SKX_EXT_B_BGA1-IC,TBD   I172 @BASEBOARD_FAB2_LIB.BASEBOARD_FAB2(SCH_1):PAGE57
  J1G1   47  CB<4> SCONN288_H44441004_PIP-SCONN,HA   I111 @BASEBOARD_FAB2_LIB.BASEBOARD_FAB2(SCH_1):PAGE77
  J9T1  192  CB<5> SCONN288_H44441003_PIP-SCONN,HA    I13 @BASEBOARD_FAB2_LIB.BASEBOARD_FAB2(SCH_1):PAGE78

M_G_ECC<6> @BASEBOARD_FAB2_LIB.BASEBOARD_FAB2(SCH_1):M_G_ECC(6)
  U2D1 AC66 DDR0_ECC<6> SKX_EXT_B_BGA1-IC,TBD   I172 @BASEBOARD_FAB2_LIB.BASEBOARD_FAB2(SCH_1):PAGE57
  J1G1  199  CB<7> SCONN288_H44441004_PIP-SCONN,HA   I111 @BASEBOARD_FAB2_LIB.BASEBOARD_FAB2(SCH_1):PAGE77
  J9T1   54  CB<6> SCONN288_H44441003_PIP-SCONN,HA    I13 @BASEBOARD_FAB2_LIB.BASEBOARD_FAB2(SCH_1):PAGE78

M_G_ECC<7> @BASEBOARD_FAB2_LIB.BASEBOARD_FAB2(SCH_1):M_G_ECC(7)
  U2D1 AG66 DDR0_ECC<7> SKX_EXT_B_BGA1-IC,TBD   I172 @BASEBOARD_FAB2_LIB.BASEBOARD_FAB2(SCH_1):PAGE57
  J1G1   54  CB<6> SCONN288_H44441004_PIP-SCONN,HA   I111 @BASEBOARD_FAB2_LIB.BASEBOARD_FAB2(SCH_1):PAGE77
  J9T1  199  CB<7> SCONN288_H44441003_PIP-SCONN,HA    I13 @BASEBOARD_FAB2_LIB.BASEBOARD_FAB2(SCH_1):PAGE78

M_G_MA<0> @BASEBOARD_FAB2_LIB.BASEBOARD_FAB2(SCH_1):M_G_MA(0)
  U2D1  F53 DDR0_MA<0> SKX_EXT_B_BGA1-IC,TBD   I172 @BASEBOARD_FAB2_LIB.BASEBOARD_FAB2(SCH_1):PAGE57
  J1G1   79     A0 SCONN288_H44441004_PIP-SCONN,HA   I111 @BASEBOARD_FAB2_LIB.BASEBOARD_FAB2(SCH_1):PAGE77
  J9T1   79     A0 SCONN288_H44441003_PIP-SCONN,HA    I13 @BASEBOARD_FAB2_LIB.BASEBOARD_FAB2(SCH_1):PAGE78

M_G_MA<10> @BASEBOARD_FAB2_LIB.BASEBOARD_FAB2(SCH_1):M_G_MA(10)
  U2D1  J54 DDR0_MA<10> SKX_EXT_B_BGA1-IC,TBD   I172 @BASEBOARD_FAB2_LIB.BASEBOARD_FAB2(SCH_1):PAGE57
  J1G1  225    A10 SCONN288_H44441004_PIP-SCONN,HA   I111 @BASEBOARD_FAB2_LIB.BASEBOARD_FAB2(SCH_1):PAGE77
  J9T1  225    A10 SCONN288_H44441003_PIP-SCONN,HA    I13 @BASEBOARD_FAB2_LIB.BASEBOARD_FAB2(SCH_1):PAGE78

M_G_MA<11> @BASEBOARD_FAB2_LIB.BASEBOARD_FAB2(SCH_1):M_G_MA(11)
  U2D1  G62 DDR0_MA<11> SKX_EXT_B_BGA1-IC,TBD   I172 @BASEBOARD_FAB2_LIB.BASEBOARD_FAB2(SCH_1):PAGE57
  J1G1  210    A11 SCONN288_H44441004_PIP-SCONN,HA   I111 @BASEBOARD_FAB2_LIB.BASEBOARD_FAB2(SCH_1):PAGE77
  J9T1  210    A11 SCONN288_H44441003_PIP-SCONN,HA    I13 @BASEBOARD_FAB2_LIB.BASEBOARD_FAB2(SCH_1):PAGE78

M_G_MA<12> @BASEBOARD_FAB2_LIB.BASEBOARD_FAB2(SCH_1):M_G_MA(12)
  U2D1  J64 DDR0_MA<12> SKX_EXT_B_BGA1-IC,TBD   I172 @BASEBOARD_FAB2_LIB.BASEBOARD_FAB2(SCH_1):PAGE57
  J1G1   65    A12 SCONN288_H44441004_PIP-SCONN,HA   I111 @BASEBOARD_FAB2_LIB.BASEBOARD_FAB2(SCH_1):PAGE77
  J9T1   65    A12 SCONN288_H44441003_PIP-SCONN,HA    I13 @BASEBOARD_FAB2_LIB.BASEBOARD_FAB2(SCH_1):PAGE78

M_G_MA<13> @BASEBOARD_FAB2_LIB.BASEBOARD_FAB2(SCH_1):M_G_MA(13)
  U2D1  J48 DDR0_MA<13> SKX_EXT_B_BGA1-IC,TBD   I172 @BASEBOARD_FAB2_LIB.BASEBOARD_FAB2(SCH_1):PAGE57
  J1G1  232    A13 SCONN288_H44441004_PIP-SCONN,HA   I111 @BASEBOARD_FAB2_LIB.BASEBOARD_FAB2(SCH_1):PAGE77
  J9T1  232    A13 SCONN288_H44441003_PIP-SCONN,HA    I13 @BASEBOARD_FAB2_LIB.BASEBOARD_FAB2(SCH_1):PAGE78

M_G_MA<14> @BASEBOARD_FAB2_LIB.BASEBOARD_FAB2(SCH_1):M_G_MA(14)
  U2D1  F51 DDR0_MA<14> SKX_EXT_B_BGA1-IC,TBD   I172 @BASEBOARD_FAB2_LIB.BASEBOARD_FAB2(SCH_1):PAGE57
  J1G1  228 A14_WE_N SCONN288_H44441004_PIP-SCONN,HA   I111 @BASEBOARD_FAB2_LIB.BASEBOARD_FAB2(SCH_1):PAGE77
  J9T1  228 A14_WE_N SCONN288_H44441003_PIP-SCONN,HA    I13 @BASEBOARD_FAB2_LIB.BASEBOARD_FAB2(SCH_1):PAGE78

M_G_MA<15> @BASEBOARD_FAB2_LIB.BASEBOARD_FAB2(SCH_1):M_G_MA(15)
  U2D1  K49 DDR0_MA<15> SKX_EXT_B_BGA1-IC,TBD   I172 @BASEBOARD_FAB2_LIB.BASEBOARD_FAB2(SCH_1):PAGE57
  J1G1   86 A15_CAS_N SCONN288_H44441004_PIP-SCONN,HA   I111 @BASEBOARD_FAB2_LIB.BASEBOARD_FAB2(SCH_1):PAGE77
  J9T1   86 A15_CAS_N SCONN288_H44441003_PIP-SCONN,HA    I13 @BASEBOARD_FAB2_LIB.BASEBOARD_FAB2(SCH_1):PAGE78

M_G_MA<16> @BASEBOARD_FAB2_LIB.BASEBOARD_FAB2(SCH_1):M_G_MA(16)
  U2D1  D51 DDR0_MA<16> SKX_EXT_B_BGA1-IC,TBD   I172 @BASEBOARD_FAB2_LIB.BASEBOARD_FAB2(SCH_1):PAGE57
  J1G1   82 A16_RAS_N SCONN288_H44441004_PIP-SCONN,HA   I111 @BASEBOARD_FAB2_LIB.BASEBOARD_FAB2(SCH_1):PAGE77
  J9T1   82 A16_RAS_N SCONN288_H44441003_PIP-SCONN,HA    I13 @BASEBOARD_FAB2_LIB.BASEBOARD_FAB2(SCH_1):PAGE78

M_G_MA<17> @BASEBOARD_FAB2_LIB.BASEBOARD_FAB2(SCH_1):M_G_MA(17)
  U2D1  K47 DDR0_MA<17> SKX_EXT_B_BGA1-IC,TBD   I172 @BASEBOARD_FAB2_LIB.BASEBOARD_FAB2(SCH_1):PAGE57
  J1G1  234    A17 SCONN288_H44441004_PIP-SCONN,HA   I111 @BASEBOARD_FAB2_LIB.BASEBOARD_FAB2(SCH_1):PAGE77
  J9T1  234    A17 SCONN288_H44441003_PIP-SCONN,HA    I13 @BASEBOARD_FAB2_LIB.BASEBOARD_FAB2(SCH_1):PAGE78

M_G_MA<1> @BASEBOARD_FAB2_LIB.BASEBOARD_FAB2(SCH_1):M_G_MA(1)
  U2D1  F57 DDR0_MA<1> SKX_EXT_B_BGA1-IC,TBD   I172 @BASEBOARD_FAB2_LIB.BASEBOARD_FAB2(SCH_1):PAGE57
  J1G1   72     A1 SCONN288_H44441004_PIP-SCONN,HA   I111 @BASEBOARD_FAB2_LIB.BASEBOARD_FAB2(SCH_1):PAGE77
  J9T1   72     A1 SCONN288_H44441003_PIP-SCONN,HA    I13 @BASEBOARD_FAB2_LIB.BASEBOARD_FAB2(SCH_1):PAGE78

M_G_MA<2> @BASEBOARD_FAB2_LIB.BASEBOARD_FAB2(SCH_1):M_G_MA(2)
  U2D1  D57 DDR0_MA<2> SKX_EXT_B_BGA1-IC,TBD   I172 @BASEBOARD_FAB2_LIB.BASEBOARD_FAB2(SCH_1):PAGE57
  J1G1  216     A2 SCONN288_H44441004_PIP-SCONN,HA   I111 @BASEBOARD_FAB2_LIB.BASEBOARD_FAB2(SCH_1):PAGE77
  J9T1  216     A2 SCONN288_H44441003_PIP-SCONN,HA    I13 @BASEBOARD_FAB2_LIB.BASEBOARD_FAB2(SCH_1):PAGE78

M_G_MA<3> @BASEBOARD_FAB2_LIB.BASEBOARD_FAB2(SCH_1):M_G_MA(3)
  U2D1  C58 DDR0_MA<3> SKX_EXT_B_BGA1-IC,TBD   I172 @BASEBOARD_FAB2_LIB.BASEBOARD_FAB2(SCH_1):PAGE57
  J1G1   71     A3 SCONN288_H44441004_PIP-SCONN,HA   I111 @BASEBOARD_FAB2_LIB.BASEBOARD_FAB2(SCH_1):PAGE77
  J9T1   71     A3 SCONN288_H44441003_PIP-SCONN,HA    I13 @BASEBOARD_FAB2_LIB.BASEBOARD_FAB2(SCH_1):PAGE78

M_G_MA<4> @BASEBOARD_FAB2_LIB.BASEBOARD_FAB2(SCH_1):M_G_MA(4)
  U2D1  G58 DDR0_MA<4> SKX_EXT_B_BGA1-IC,TBD   I172 @BASEBOARD_FAB2_LIB.BASEBOARD_FAB2(SCH_1):PAGE57
  J1G1  214     A4 SCONN288_H44441004_PIP-SCONN,HA   I111 @BASEBOARD_FAB2_LIB.BASEBOARD_FAB2(SCH_1):PAGE77
  J9T1  214     A4 SCONN288_H44441003_PIP-SCONN,HA    I13 @BASEBOARD_FAB2_LIB.BASEBOARD_FAB2(SCH_1):PAGE78

M_G_MA<5> @BASEBOARD_FAB2_LIB.BASEBOARD_FAB2(SCH_1):M_G_MA(5)
  U2D1  F59 DDR0_MA<5> SKX_EXT_B_BGA1-IC,TBD   I172 @BASEBOARD_FAB2_LIB.BASEBOARD_FAB2(SCH_1):PAGE57
  J1G1  213     A5 SCONN288_H44441004_PIP-SCONN,HA   I111 @BASEBOARD_FAB2_LIB.BASEBOARD_FAB2(SCH_1):PAGE77
  J9T1  213     A5 SCONN288_H44441003_PIP-SCONN,HA    I13 @BASEBOARD_FAB2_LIB.BASEBOARD_FAB2(SCH_1):PAGE78

M_G_MA<6> @BASEBOARD_FAB2_LIB.BASEBOARD_FAB2(SCH_1):M_G_MA(6)
  U2D1  D59 DDR0_MA<6> SKX_EXT_B_BGA1-IC,TBD   I172 @BASEBOARD_FAB2_LIB.BASEBOARD_FAB2(SCH_1):PAGE57
  J1G1   69     A6 SCONN288_H44441004_PIP-SCONN,HA   I111 @BASEBOARD_FAB2_LIB.BASEBOARD_FAB2(SCH_1):PAGE77
  J9T1   69     A6 SCONN288_H44441003_PIP-SCONN,HA    I13 @BASEBOARD_FAB2_LIB.BASEBOARD_FAB2(SCH_1):PAGE78

M_G_MA<7> @BASEBOARD_FAB2_LIB.BASEBOARD_FAB2(SCH_1):M_G_MA(7)
  U2D1  G60 DDR0_MA<7> SKX_EXT_B_BGA1-IC,TBD   I172 @BASEBOARD_FAB2_LIB.BASEBOARD_FAB2(SCH_1):PAGE57
  J1G1  211     A7 SCONN288_H44441004_PIP-SCONN,HA   I111 @BASEBOARD_FAB2_LIB.BASEBOARD_FAB2(SCH_1):PAGE77
  J9T1  211     A7 SCONN288_H44441003_PIP-SCONN,HA    I13 @BASEBOARD_FAB2_LIB.BASEBOARD_FAB2(SCH_1):PAGE78

M_G_MA<8> @BASEBOARD_FAB2_LIB.BASEBOARD_FAB2(SCH_1):M_G_MA(8)
  U2D1  C60 DDR0_MA<8> SKX_EXT_B_BGA1-IC,TBD   I172 @BASEBOARD_FAB2_LIB.BASEBOARD_FAB2(SCH_1):PAGE57
  J1G1   68     A8 SCONN288_H44441004_PIP-SCONN,HA   I111 @BASEBOARD_FAB2_LIB.BASEBOARD_FAB2(SCH_1):PAGE77
  J9T1   68     A8 SCONN288_H44441003_PIP-SCONN,HA    I13 @BASEBOARD_FAB2_LIB.BASEBOARD_FAB2(SCH_1):PAGE78

M_G_MA<9> @BASEBOARD_FAB2_LIB.BASEBOARD_FAB2(SCH_1):M_G_MA(9)
  U2D1  F61 DDR0_MA<9> SKX_EXT_B_BGA1-IC,TBD   I172 @BASEBOARD_FAB2_LIB.BASEBOARD_FAB2(SCH_1):PAGE57
  J1G1   66     A9 SCONN288_H44441004_PIP-SCONN,HA   I111 @BASEBOARD_FAB2_LIB.BASEBOARD_FAB2(SCH_1):PAGE77
  J9T1   66     A9 SCONN288_H44441003_PIP-SCONN,HA    I13 @BASEBOARD_FAB2_LIB.BASEBOARD_FAB2(SCH_1):PAGE78

M_G_ODT<0> @BASEBOARD_FAB2_LIB.BASEBOARD_FAB2(SCH_1):M_G_ODT(0)
  U2D1  C50 DDR0_ODT<0> SKX_EXT_B_BGA1-IC,TBD   I172 @BASEBOARD_FAB2_LIB.BASEBOARD_FAB2(SCH_1):PAGE57
  J1G1   87 ODT<0> SCONN288_H44441004_PIP-SCONN,HA   I111 @BASEBOARD_FAB2_LIB.BASEBOARD_FAB2(SCH_1):PAGE77

M_G_ODT<1> @BASEBOARD_FAB2_LIB.BASEBOARD_FAB2(SCH_1):M_G_ODT(1)
  U2D1  C48 DDR0_ODT<1> SKX_EXT_B_BGA1-IC,TBD   I172 @BASEBOARD_FAB2_LIB.BASEBOARD_FAB2(SCH_1):PAGE57
  J1G1   91 ODT<1> SCONN288_H44441004_PIP-SCONN,HA   I111 @BASEBOARD_FAB2_LIB.BASEBOARD_FAB2(SCH_1):PAGE77

M_G_ODT<2> @BASEBOARD_FAB2_LIB.BASEBOARD_FAB2(SCH_1):M_G_ODT(2)
  U2D1  G50 DDR0_ODT<2> SKX_EXT_B_BGA1-IC,TBD   I172 @BASEBOARD_FAB2_LIB.BASEBOARD_FAB2(SCH_1):PAGE57
  J9T1   87 ODT<0> SCONN288_H44441003_PIP-SCONN,HA    I13 @BASEBOARD_FAB2_LIB.BASEBOARD_FAB2(SCH_1):PAGE78

M_G_ODT<3> @BASEBOARD_FAB2_LIB.BASEBOARD_FAB2(SCH_1):M_G_ODT(3)
  U2D1  G48 DDR0_ODT<3> SKX_EXT_B_BGA1-IC,TBD   I172 @BASEBOARD_FAB2_LIB.BASEBOARD_FAB2(SCH_1):PAGE57
  J9T1   91 ODT<1> SCONN288_H44441003_PIP-SCONN,HA    I13 @BASEBOARD_FAB2_LIB.BASEBOARD_FAB2(SCH_1):PAGE78

M_G_PAR @BASEBOARD_FAB2_LIB.BASEBOARD_FAB2(SCH_1):M_G_PAR
  U2D1  D53 DDR0_PAR SKX_EXT_B_BGA1-IC,TBD   I172 @BASEBOARD_FAB2_LIB.BASEBOARD_FAB2(SCH_1):PAGE57
  J1G1  222    PAR SCONN288_H44441004_PIP-SCONN,HA   I111 @BASEBOARD_FAB2_LIB.BASEBOARD_FAB2(SCH_1):PAGE77
  J9T1  222    PAR SCONN288_H44441003_PIP-SCONN,HA    I13 @BASEBOARD_FAB2_LIB.BASEBOARD_FAB2(SCH_1):PAGE78

M_G_VREF @BASEBOARD_FAB2_LIB.BASEBOARD_FAB2(SCH_1):M_G_VREF
  J1G1  146 VREFCA SCONN288_H44441004_PIP-SCONN,HA   I111 @BASEBOARD_FAB2_LIB.BASEBOARD_FAB2(SCH_1):PAGE77
 C1F22    1      A CAP_A_0402V-0.01UF,25V,10%,X7RA   I181 @BASEBOARD_FAB2_LIB.BASEBOARD_FAB2(SCH_1):PAGE77
  C9T7    1      A CAP_A_0402V-0.01UF,25V,10%,X7RA     I2 @BASEBOARD_FAB2_LIB.BASEBOARD_FAB2(SCH_1):PAGE78
  J9T1  146 VREFCA SCONN288_H44441003_PIP-SCONN,HA    I13 @BASEBOARD_FAB2_LIB.BASEBOARD_FAB2(SCH_1):PAGE78
  R1F6    1      A RES_0402-1.00K,1%,1/16W,CHIP,GA     I2 @BASEBOARD_FAB2_LIB.BASEBOARD_FAB2(SCH_1):PAGE100
  R1F5    2      B RES_0402-1.00K,1%,1/16W,CHIP,GA     I6 @BASEBOARD_FAB2_LIB.BASEBOARD_FAB2(SCH_1):PAGE100
  R1F4    2      B RES_0402-2,1.0%,1/16W,CHIP,G21A     I7 @BASEBOARD_FAB2_LIB.BASEBOARD_FAB2(SCH_1):PAGE100

M_H_ACT_N @BASEBOARD_FAB2_LIB.BASEBOARD_FAB2(SCH_1):M_H_ACT_N
  U2D1  T63 DDR1_ACT_N SKX_EXT_B_BGA1-IC,TBD   I172 @BASEBOARD_FAB2_LIB.BASEBOARD_FAB2(SCH_1):PAGE58
  J1G2   62  ACT_N SCONN288_H44441004_PIP-SCONN,HA   I111 @BASEBOARD_FAB2_LIB.BASEBOARD_FAB2(SCH_1):PAGE79
  J9U1   62  ACT_N SCONN288_H44441003_PIP-SCONN,HA    I24 @BASEBOARD_FAB2_LIB.BASEBOARD_FAB2(SCH_1):PAGE80

M_H_ALERT_N @BASEBOARD_FAB2_LIB.BASEBOARD_FAB2(SCH_1):M_H_ALERT_N
  U2D1  W62 DDR1_ALERT_N SKX_EXT_B_BGA1-IC,TBD   I172 @BASEBOARD_FAB2_LIB.BASEBOARD_FAB2(SCH_1):PAGE58
  J1G2  208 ALERT_N SCONN288_H44441004_PIP-SCONN,HA   I111 @BASEBOARD_FAB2_LIB.BASEBOARD_FAB2(SCH_1):PAGE79
  J9U1  208 ALERT_N SCONN288_H44441003_PIP-SCONN,HA    I24 @BASEBOARD_FAB2_LIB.BASEBOARD_FAB2(SCH_1):PAGE80

M_H_BA<0> @BASEBOARD_FAB2_LIB.BASEBOARD_FAB2(SCH_1):M_H_BA(0)
  U2D1  T53 DDR1_BA<0> SKX_EXT_B_BGA1-IC,TBD   I172 @BASEBOARD_FAB2_LIB.BASEBOARD_FAB2(SCH_1):PAGE58
  J1G2   81  BA<0> SCONN288_H44441004_PIP-SCONN,HA   I111 @BASEBOARD_FAB2_LIB.BASEBOARD_FAB2(SCH_1):PAGE79
  J9U1   81  BA<0> SCONN288_H44441003_PIP-SCONN,HA    I24 @BASEBOARD_FAB2_LIB.BASEBOARD_FAB2(SCH_1):PAGE80

M_H_BA<1> @BASEBOARD_FAB2_LIB.BASEBOARD_FAB2(SCH_1):M_H_BA(1)
  U2D1  K55 DDR1_BA<1> SKX_EXT_B_BGA1-IC,TBD   I172 @BASEBOARD_FAB2_LIB.BASEBOARD_FAB2(SCH_1):PAGE58
  J1G2  224  BA<1> SCONN288_H44441004_PIP-SCONN,HA   I111 @BASEBOARD_FAB2_LIB.BASEBOARD_FAB2(SCH_1):PAGE79
  J9U1  224  BA<1> SCONN288_H44441003_PIP-SCONN,HA    I24 @BASEBOARD_FAB2_LIB.BASEBOARD_FAB2(SCH_1):PAGE80

M_H_BG<0> @BASEBOARD_FAB2_LIB.BASEBOARD_FAB2(SCH_1):M_H_BG(0)
  U2D1  M61 DDR1_BG<0> SKX_EXT_B_BGA1-IC,TBD   I172 @BASEBOARD_FAB2_LIB.BASEBOARD_FAB2(SCH_1):PAGE58
  J1G2   63  BG<0> SCONN288_H44441004_PIP-SCONN,HA   I111 @BASEBOARD_FAB2_LIB.BASEBOARD_FAB2(SCH_1):PAGE79
  J9U1   63  BG<0> SCONN288_H44441003_PIP-SCONN,HA    I24 @BASEBOARD_FAB2_LIB.BASEBOARD_FAB2(SCH_1):PAGE80

M_H_BG<1> @BASEBOARD_FAB2_LIB.BASEBOARD_FAB2(SCH_1):M_H_BG(1)
  U2D1  N60 DDR1_BG<1> SKX_EXT_B_BGA1-IC,TBD   I172 @BASEBOARD_FAB2_LIB.BASEBOARD_FAB2(SCH_1):PAGE58
  J1G2  207  BG<1> SCONN288_H44441004_PIP-SCONN,HA   I111 @BASEBOARD_FAB2_LIB.BASEBOARD_FAB2(SCH_1):PAGE79
  J9U1  207  BG<1> SCONN288_H44441003_PIP-SCONN,HA    I24 @BASEBOARD_FAB2_LIB.BASEBOARD_FAB2(SCH_1):PAGE80

M_H_C<2> @BASEBOARD_FAB2_LIB.BASEBOARD_FAB2(SCH_1):M_H_C(2)
  U2D1  M47 DDR1_CID<2> SKX_EXT_B_BGA1-IC,TBD   I172 @BASEBOARD_FAB2_LIB.BASEBOARD_FAB2(SCH_1):PAGE58
  J1G2  235   C<2> SCONN288_H44441004_PIP-SCONN,HA   I111 @BASEBOARD_FAB2_LIB.BASEBOARD_FAB2(SCH_1):PAGE79
  J9U1  235   C<2> SCONN288_H44441003_PIP-SCONN,HA    I24 @BASEBOARD_FAB2_LIB.BASEBOARD_FAB2(SCH_1):PAGE80

M_H_CKE<0> @BASEBOARD_FAB2_LIB.BASEBOARD_FAB2(SCH_1):M_H_CKE(0)
  U2D1  N62 DDR1_CKE<0> SKX_EXT_B_BGA1-IC,TBD   I172 @BASEBOARD_FAB2_LIB.BASEBOARD_FAB2(SCH_1):PAGE58
  J1G2   60 CKE<0> SCONN288_H44441004_PIP-SCONN,HA   I111 @BASEBOARD_FAB2_LIB.BASEBOARD_FAB2(SCH_1):PAGE79

M_H_CKE<1> @BASEBOARD_FAB2_LIB.BASEBOARD_FAB2(SCH_1):M_H_CKE(1)
  U2D1  R64 DDR1_CKE<1> SKX_EXT_B_BGA1-IC,TBD   I172 @BASEBOARD_FAB2_LIB.BASEBOARD_FAB2(SCH_1):PAGE58
  J1G2  203 CKE<1> SCONN288_H44441004_PIP-SCONN,HA   I111 @BASEBOARD_FAB2_LIB.BASEBOARD_FAB2(SCH_1):PAGE79

M_H_CKE<2> @BASEBOARD_FAB2_LIB.BASEBOARD_FAB2(SCH_1):M_H_CKE(2)
  U2D1  K63 DDR1_CKE<2> SKX_EXT_B_BGA1-IC,TBD   I172 @BASEBOARD_FAB2_LIB.BASEBOARD_FAB2(SCH_1):PAGE58
  J9U1   60 CKE<0> SCONN288_H44441003_PIP-SCONN,HA    I24 @BASEBOARD_FAB2_LIB.BASEBOARD_FAB2(SCH_1):PAGE80

M_H_CKE<3> @BASEBOARD_FAB2_LIB.BASEBOARD_FAB2(SCH_1):M_H_CKE(3)
  U2D1  L64 DDR1_CKE<3> SKX_EXT_B_BGA1-IC,TBD   I172 @BASEBOARD_FAB2_LIB.BASEBOARD_FAB2(SCH_1):PAGE58
  J9U1  203 CKE<1> SCONN288_H44441003_PIP-SCONN,HA    I24 @BASEBOARD_FAB2_LIB.BASEBOARD_FAB2(SCH_1):PAGE80

M_H_CLK_DN<0> @BASEBOARD_FAB2_LIB.BASEBOARD_FAB2(SCH_1):M_H_CLK_DN(0)
  U2D1  M53 DDR1_CLK_DN<0> SKX_EXT_B_BGA1-IC,TBD   I172 @BASEBOARD_FAB2_LIB.BASEBOARD_FAB2(SCH_1):PAGE58
  J1G2   75   CK0N SCONN288_H44441004_PIP-SCONN,HA   I111 @BASEBOARD_FAB2_LIB.BASEBOARD_FAB2(SCH_1):PAGE79

M_H_CLK_DN<1> @BASEBOARD_FAB2_LIB.BASEBOARD_FAB2(SCH_1):M_H_CLK_DN(1)
  U2D1  R54 DDR1_CLK_DN<1> SKX_EXT_B_BGA1-IC,TBD   I172 @BASEBOARD_FAB2_LIB.BASEBOARD_FAB2(SCH_1):PAGE58
  J1G2  219   CK1N SCONN288_H44441004_PIP-SCONN,HA   I111 @BASEBOARD_FAB2_LIB.BASEBOARD_FAB2(SCH_1):PAGE79

M_H_CLK_DN<2> @BASEBOARD_FAB2_LIB.BASEBOARD_FAB2(SCH_1):M_H_CLK_DN(2)
  U2D1  N56 DDR1_CLK_DN<2> SKX_EXT_B_BGA1-IC,TBD   I172 @BASEBOARD_FAB2_LIB.BASEBOARD_FAB2(SCH_1):PAGE58
  J9U1   75   CK0N SCONN288_H44441003_PIP-SCONN,HA    I24 @BASEBOARD_FAB2_LIB.BASEBOARD_FAB2(SCH_1):PAGE80

M_H_CLK_DN<3> @BASEBOARD_FAB2_LIB.BASEBOARD_FAB2(SCH_1):M_H_CLK_DN(3)
  U2D1  R56 DDR1_CLK_DN<3> SKX_EXT_B_BGA1-IC,TBD   I172 @BASEBOARD_FAB2_LIB.BASEBOARD_FAB2(SCH_1):PAGE58
  J9U1  219   CK1N SCONN288_H44441003_PIP-SCONN,HA    I24 @BASEBOARD_FAB2_LIB.BASEBOARD_FAB2(SCH_1):PAGE80

M_H_CLK_DP<0> @BASEBOARD_FAB2_LIB.BASEBOARD_FAB2(SCH_1):M_H_CLK_DP(0)
  U2D1  N54 DDR1_CLK_DP<0> SKX_EXT_B_BGA1-IC,TBD   I172 @BASEBOARD_FAB2_LIB.BASEBOARD_FAB2(SCH_1):PAGE58
  J1G2   74   CK0P SCONN288_H44441004_PIP-SCONN,HA   I111 @BASEBOARD_FAB2_LIB.BASEBOARD_FAB2(SCH_1):PAGE79

M_H_CLK_DP<1> @BASEBOARD_FAB2_LIB.BASEBOARD_FAB2(SCH_1):M_H_CLK_DP(1)
  U2D1  T55 DDR1_CLK_DP<1> SKX_EXT_B_BGA1-IC,TBD   I172 @BASEBOARD_FAB2_LIB.BASEBOARD_FAB2(SCH_1):PAGE58
  J1G2  218   CK1P SCONN288_H44441004_PIP-SCONN,HA   I111 @BASEBOARD_FAB2_LIB.BASEBOARD_FAB2(SCH_1):PAGE79

M_H_CLK_DP<2> @BASEBOARD_FAB2_LIB.BASEBOARD_FAB2(SCH_1):M_H_CLK_DP(2)
  U2D1  M57 DDR1_CLK_DP<2> SKX_EXT_B_BGA1-IC,TBD   I172 @BASEBOARD_FAB2_LIB.BASEBOARD_FAB2(SCH_1):PAGE58
  J9U1   74   CK0P SCONN288_H44441003_PIP-SCONN,HA    I24 @BASEBOARD_FAB2_LIB.BASEBOARD_FAB2(SCH_1):PAGE80

M_H_CLK_DP<3> @BASEBOARD_FAB2_LIB.BASEBOARD_FAB2(SCH_1):M_H_CLK_DP(3)
  U2D1  T57 DDR1_CLK_DP<3> SKX_EXT_B_BGA1-IC,TBD   I172 @BASEBOARD_FAB2_LIB.BASEBOARD_FAB2(SCH_1):PAGE58
  J9U1  218   CK1P SCONN288_H44441003_PIP-SCONN,HA    I24 @BASEBOARD_FAB2_LIB.BASEBOARD_FAB2(SCH_1):PAGE80

M_H_CPU_VREF @BASEBOARD_FAB2_LIB.BASEBOARD_FAB2(SCH_1):M_H_CPU_VREF
  U2D1 AK63 DDR1_CAVREF SKX_EXT_B_BGA1-IC,TBD   I172 @BASEBOARD_FAB2_LIB.BASEBOARD_FAB2(SCH_1):PAGE55
  R1G1    1      A RES_0402-2,1.0%,1/16W,CHIP,G21A    I25 @BASEBOARD_FAB2_LIB.BASEBOARD_FAB2(SCH_1):PAGE100
  C1G8    1      A CAP_A_0402V-0.01UF,25V,10%,X7RA    I26 @BASEBOARD_FAB2_LIB.BASEBOARD_FAB2(SCH_1):PAGE100

M_H_CS_N<0> @BASEBOARD_FAB2_LIB.BASEBOARD_FAB2(SCH_1):M_H_CS_N(0)
  U2D1  K51 DDR1_CS_N<0> SKX_EXT_B_BGA1-IC,TBD   I172 @BASEBOARD_FAB2_LIB.BASEBOARD_FAB2(SCH_1):PAGE58
  J1G2   84   S0_N SCONN288_H44441004_PIP-SCONN,HA   I111 @BASEBOARD_FAB2_LIB.BASEBOARD_FAB2(SCH_1):PAGE79

M_H_CS_N<1> @BASEBOARD_FAB2_LIB.BASEBOARD_FAB2(SCH_1):M_H_CS_N(1)
  U2D1  R50 DDR1_CS_N<1> SKX_EXT_B_BGA1-IC,TBD   I172 @BASEBOARD_FAB2_LIB.BASEBOARD_FAB2(SCH_1):PAGE58
  J1G2   89   S1_N SCONN288_H44441004_PIP-SCONN,HA   I111 @BASEBOARD_FAB2_LIB.BASEBOARD_FAB2(SCH_1):PAGE79

M_H_CS_N<2> @BASEBOARD_FAB2_LIB.BASEBOARD_FAB2(SCH_1):M_H_CS_N(2)
  U2D1  N46 DDR1_CS_N<2> SKX_EXT_B_BGA1-IC,TBD   I172 @BASEBOARD_FAB2_LIB.BASEBOARD_FAB2(SCH_1):PAGE58
  J1G2   93 S2_N_C<0> SCONN288_H44441004_PIP-SCONN,HA   I111 @BASEBOARD_FAB2_LIB.BASEBOARD_FAB2(SCH_1):PAGE79

M_H_CS_N<3> @BASEBOARD_FAB2_LIB.BASEBOARD_FAB2(SCH_1):M_H_CS_N(3)
  U2D1  V47 DDR1_CS_N<3> SKX_EXT_B_BGA1-IC,TBD   I172 @BASEBOARD_FAB2_LIB.BASEBOARD_FAB2(SCH_1):PAGE58
  J1G2  237 S3_N_C<1> SCONN288_H44441004_PIP-SCONN,HA   I111 @BASEBOARD_FAB2_LIB.BASEBOARD_FAB2(SCH_1):PAGE79

M_H_CS_N<4> @BASEBOARD_FAB2_LIB.BASEBOARD_FAB2(SCH_1):M_H_CS_N(4)
  U2D1  J50 DDR1_CS_N<4> SKX_EXT_B_BGA1-IC,TBD   I172 @BASEBOARD_FAB2_LIB.BASEBOARD_FAB2(SCH_1):PAGE58
  J9U1   84   S0_N SCONN288_H44441003_PIP-SCONN,HA    I24 @BASEBOARD_FAB2_LIB.BASEBOARD_FAB2(SCH_1):PAGE80

M_H_CS_N<5> @BASEBOARD_FAB2_LIB.BASEBOARD_FAB2(SCH_1):M_H_CS_N(5)
  U2D1  T49 DDR1_CS_N<5> SKX_EXT_B_BGA1-IC,TBD   I172 @BASEBOARD_FAB2_LIB.BASEBOARD_FAB2(SCH_1):PAGE58
  J9U1   89   S1_N SCONN288_H44441003_PIP-SCONN,HA    I24 @BASEBOARD_FAB2_LIB.BASEBOARD_FAB2(SCH_1):PAGE80

M_H_CS_N<6> @BASEBOARD_FAB2_LIB.BASEBOARD_FAB2(SCH_1):M_H_CS_N(6)
  U2D1  M45 DDR1_CS_N<6> SKX_EXT_B_BGA1-IC,TBD   I172 @BASEBOARD_FAB2_LIB.BASEBOARD_FAB2(SCH_1):PAGE58
  J9U1   93 S2_N_C<0> SCONN288_H44441003_PIP-SCONN,HA    I24 @BASEBOARD_FAB2_LIB.BASEBOARD_FAB2(SCH_1):PAGE80

M_H_CS_N<7> @BASEBOARD_FAB2_LIB.BASEBOARD_FAB2(SCH_1):M_H_CS_N(7)
  U2D1  R46 DDR1_CS_N<7> SKX_EXT_B_BGA1-IC,TBD   I172 @BASEBOARD_FAB2_LIB.BASEBOARD_FAB2(SCH_1):PAGE58
  J9U1  237 S3_N_C<1> SCONN288_H44441003_PIP-SCONN,HA    I24 @BASEBOARD_FAB2_LIB.BASEBOARD_FAB2(SCH_1):PAGE80

M_H_DQ<0> @BASEBOARD_FAB2_LIB.BASEBOARD_FAB2(SCH_1):M_H_DQ(0)
  U2D1 AV81 DDR1_DQ<0> SKX_EXT_B_BGA1-IC,TBD   I172 @BASEBOARD_FAB2_LIB.BASEBOARD_FAB2(SCH_1):PAGE58
  J1G2  150  DQ<1> SCONN288_H44441004_PIP-SCONN,HA   I111 @BASEBOARD_FAB2_LIB.BASEBOARD_FAB2(SCH_1):PAGE79
  J9U1    5  DQ<0> SCONN288_H44441003_PIP-SCONN,HA    I24 @BASEBOARD_FAB2_LIB.BASEBOARD_FAB2(SCH_1):PAGE80

M_H_DQ<10> @BASEBOARD_FAB2_LIB.BASEBOARD_FAB2(SCH_1):M_H_DQ(10)
  U2D1 AC82 DDR1_DQ<10> SKX_EXT_B_BGA1-IC,TBD   I172 @BASEBOARD_FAB2_LIB.BASEBOARD_FAB2(SCH_1):PAGE58
  J1G2  168 DQ<11> SCONN288_H44441004_PIP-SCONN,HA   I111 @BASEBOARD_FAB2_LIB.BASEBOARD_FAB2(SCH_1):PAGE79
  J9U1   23 DQ<10> SCONN288_H44441003_PIP-SCONN,HA    I24 @BASEBOARD_FAB2_LIB.BASEBOARD_FAB2(SCH_1):PAGE80

M_H_DQ<11> @BASEBOARD_FAB2_LIB.BASEBOARD_FAB2(SCH_1):M_H_DQ(11)
  U2D1 AB81 DDR1_DQ<11> SKX_EXT_B_BGA1-IC,TBD   I172 @BASEBOARD_FAB2_LIB.BASEBOARD_FAB2(SCH_1):PAGE58
  J1G2   23 DQ<10> SCONN288_H44441004_PIP-SCONN,HA   I111 @BASEBOARD_FAB2_LIB.BASEBOARD_FAB2(SCH_1):PAGE79
  J9U1  168 DQ<11> SCONN288_H44441003_PIP-SCONN,HA    I24 @BASEBOARD_FAB2_LIB.BASEBOARD_FAB2(SCH_1):PAGE80

M_H_DQ<12> @BASEBOARD_FAB2_LIB.BASEBOARD_FAB2(SCH_1):M_H_DQ(12)
  U2D1 AJ80 DDR1_DQ<12> SKX_EXT_B_BGA1-IC,TBD   I172 @BASEBOARD_FAB2_LIB.BASEBOARD_FAB2(SCH_1):PAGE58
  J1G2  159 DQ<13> SCONN288_H44441004_PIP-SCONN,HA   I111 @BASEBOARD_FAB2_LIB.BASEBOARD_FAB2(SCH_1):PAGE79
  J9U1   14 DQ<12> SCONN288_H44441003_PIP-SCONN,HA    I24 @BASEBOARD_FAB2_LIB.BASEBOARD_FAB2(SCH_1):PAGE80

M_H_DQ<13> @BASEBOARD_FAB2_LIB.BASEBOARD_FAB2(SCH_1):M_H_DQ(13)
  U2D1 AH79 DDR1_DQ<13> SKX_EXT_B_BGA1-IC,TBD   I172 @BASEBOARD_FAB2_LIB.BASEBOARD_FAB2(SCH_1):PAGE58
  J1G2   14 DQ<12> SCONN288_H44441004_PIP-SCONN,HA   I111 @BASEBOARD_FAB2_LIB.BASEBOARD_FAB2(SCH_1):PAGE79
  J9U1  159 DQ<13> SCONN288_H44441003_PIP-SCONN,HA    I24 @BASEBOARD_FAB2_LIB.BASEBOARD_FAB2(SCH_1):PAGE80

M_H_DQ<14> @BASEBOARD_FAB2_LIB.BASEBOARD_FAB2(SCH_1):M_H_DQ(14)
  U2D1 AE82 DDR1_DQ<14> SKX_EXT_B_BGA1-IC,TBD   I172 @BASEBOARD_FAB2_LIB.BASEBOARD_FAB2(SCH_1):PAGE58
  J1G2  166 DQ<15> SCONN288_H44441004_PIP-SCONN,HA   I111 @BASEBOARD_FAB2_LIB.BASEBOARD_FAB2(SCH_1):PAGE79
  J9U1   21 DQ<14> SCONN288_H44441003_PIP-SCONN,HA    I24 @BASEBOARD_FAB2_LIB.BASEBOARD_FAB2(SCH_1):PAGE80

M_H_DQ<15> @BASEBOARD_FAB2_LIB.BASEBOARD_FAB2(SCH_1):M_H_DQ(15)
  U2D1 AC80 DDR1_DQ<15> SKX_EXT_B_BGA1-IC,TBD   I172 @BASEBOARD_FAB2_LIB.BASEBOARD_FAB2(SCH_1):PAGE58
  J1G2   21 DQ<14> SCONN288_H44441004_PIP-SCONN,HA   I111 @BASEBOARD_FAB2_LIB.BASEBOARD_FAB2(SCH_1):PAGE79
  J9U1  166 DQ<15> SCONN288_H44441003_PIP-SCONN,HA    I24 @BASEBOARD_FAB2_LIB.BASEBOARD_FAB2(SCH_1):PAGE80

M_H_DQ<16> @BASEBOARD_FAB2_LIB.BASEBOARD_FAB2(SCH_1):M_H_DQ(16)
  U2D1  E80 DDR1_DQ<16> SKX_EXT_B_BGA1-IC,TBD   I172 @BASEBOARD_FAB2_LIB.BASEBOARD_FAB2(SCH_1):PAGE58
  J1G2  172 DQ<17> SCONN288_H44441004_PIP-SCONN,HA   I111 @BASEBOARD_FAB2_LIB.BASEBOARD_FAB2(SCH_1):PAGE79
  J9U1   27 DQ<16> SCONN288_H44441003_PIP-SCONN,HA    I24 @BASEBOARD_FAB2_LIB.BASEBOARD_FAB2(SCH_1):PAGE80

M_H_DQ<17> @BASEBOARD_FAB2_LIB.BASEBOARD_FAB2(SCH_1):M_H_DQ(17)
  U2D1  J80 DDR1_DQ<17> SKX_EXT_B_BGA1-IC,TBD   I172 @BASEBOARD_FAB2_LIB.BASEBOARD_FAB2(SCH_1):PAGE58
  J1G2   27 DQ<16> SCONN288_H44441004_PIP-SCONN,HA   I111 @BASEBOARD_FAB2_LIB.BASEBOARD_FAB2(SCH_1):PAGE79
  J9U1  172 DQ<17> SCONN288_H44441003_PIP-SCONN,HA    I24 @BASEBOARD_FAB2_LIB.BASEBOARD_FAB2(SCH_1):PAGE80

M_H_DQ<18> @BASEBOARD_FAB2_LIB.BASEBOARD_FAB2(SCH_1):M_H_DQ(18)
  U2D1  F77 DDR1_DQ<18> SKX_EXT_B_BGA1-IC,TBD   I172 @BASEBOARD_FAB2_LIB.BASEBOARD_FAB2(SCH_1):PAGE58
  J1G2  179 DQ<19> SCONN288_H44441004_PIP-SCONN,HA   I111 @BASEBOARD_FAB2_LIB.BASEBOARD_FAB2(SCH_1):PAGE79
  J9U1   34 DQ<18> SCONN288_H44441003_PIP-SCONN,HA    I24 @BASEBOARD_FAB2_LIB.BASEBOARD_FAB2(SCH_1):PAGE80

M_H_DQ<19> @BASEBOARD_FAB2_LIB.BASEBOARD_FAB2(SCH_1):M_H_DQ(19)
  U2D1  H77 DDR1_DQ<19> SKX_EXT_B_BGA1-IC,TBD   I172 @BASEBOARD_FAB2_LIB.BASEBOARD_FAB2(SCH_1):PAGE58
  J1G2   34 DQ<18> SCONN288_H44441004_PIP-SCONN,HA   I111 @BASEBOARD_FAB2_LIB.BASEBOARD_FAB2(SCH_1):PAGE79
  J9U1  179 DQ<19> SCONN288_H44441003_PIP-SCONN,HA    I24 @BASEBOARD_FAB2_LIB.BASEBOARD_FAB2(SCH_1):PAGE80

M_H_DQ<1> @BASEBOARD_FAB2_LIB.BASEBOARD_FAB2(SCH_1):M_H_DQ(1)
  U2D1 AT79 DDR1_DQ<1> SKX_EXT_B_BGA1-IC,TBD   I172 @BASEBOARD_FAB2_LIB.BASEBOARD_FAB2(SCH_1):PAGE58
  J1G2    5  DQ<0> SCONN288_H44441004_PIP-SCONN,HA   I111 @BASEBOARD_FAB2_LIB.BASEBOARD_FAB2(SCH_1):PAGE79
  J9U1  150  DQ<1> SCONN288_H44441003_PIP-SCONN,HA    I24 @BASEBOARD_FAB2_LIB.BASEBOARD_FAB2(SCH_1):PAGE80

M_H_DQ<20> @BASEBOARD_FAB2_LIB.BASEBOARD_FAB2(SCH_1):M_H_DQ(20)
  U2D1  F81 DDR1_DQ<20> SKX_EXT_B_BGA1-IC,TBD   I172 @BASEBOARD_FAB2_LIB.BASEBOARD_FAB2(SCH_1):PAGE58
  J1G2  170 DQ<21> SCONN288_H44441004_PIP-SCONN,HA   I111 @BASEBOARD_FAB2_LIB.BASEBOARD_FAB2(SCH_1):PAGE79
  J9U1   25 DQ<20> SCONN288_H44441003_PIP-SCONN,HA    I24 @BASEBOARD_FAB2_LIB.BASEBOARD_FAB2(SCH_1):PAGE80

M_H_DQ<21> @BASEBOARD_FAB2_LIB.BASEBOARD_FAB2(SCH_1):M_H_DQ(21)
  U2D1  H81 DDR1_DQ<21> SKX_EXT_B_BGA1-IC,TBD   I172 @BASEBOARD_FAB2_LIB.BASEBOARD_FAB2(SCH_1):PAGE58
  J1G2   25 DQ<20> SCONN288_H44441004_PIP-SCONN,HA   I111 @BASEBOARD_FAB2_LIB.BASEBOARD_FAB2(SCH_1):PAGE79
  J9U1  170 DQ<21> SCONN288_H44441003_PIP-SCONN,HA    I24 @BASEBOARD_FAB2_LIB.BASEBOARD_FAB2(SCH_1):PAGE80

M_H_DQ<22> @BASEBOARD_FAB2_LIB.BASEBOARD_FAB2(SCH_1):M_H_DQ(22)
  U2D1  E78 DDR1_DQ<22> SKX_EXT_B_BGA1-IC,TBD   I172 @BASEBOARD_FAB2_LIB.BASEBOARD_FAB2(SCH_1):PAGE58
  J1G2  177 DQ<23> SCONN288_H44441004_PIP-SCONN,HA   I111 @BASEBOARD_FAB2_LIB.BASEBOARD_FAB2(SCH_1):PAGE79
  J9U1   32 DQ<22> SCONN288_H44441003_PIP-SCONN,HA    I24 @BASEBOARD_FAB2_LIB.BASEBOARD_FAB2(SCH_1):PAGE80

M_H_DQ<23> @BASEBOARD_FAB2_LIB.BASEBOARD_FAB2(SCH_1):M_H_DQ(23)
  U2D1  J78 DDR1_DQ<23> SKX_EXT_B_BGA1-IC,TBD   I172 @BASEBOARD_FAB2_LIB.BASEBOARD_FAB2(SCH_1):PAGE58
  J1G2   32 DQ<22> SCONN288_H44441004_PIP-SCONN,HA   I111 @BASEBOARD_FAB2_LIB.BASEBOARD_FAB2(SCH_1):PAGE79
  J9U1  177 DQ<23> SCONN288_H44441003_PIP-SCONN,HA    I24 @BASEBOARD_FAB2_LIB.BASEBOARD_FAB2(SCH_1):PAGE80

M_H_DQ<24> @BASEBOARD_FAB2_LIB.BASEBOARD_FAB2(SCH_1):M_H_DQ(24)
  U2D1  D75 DDR1_DQ<24> SKX_EXT_B_BGA1-IC,TBD   I172 @BASEBOARD_FAB2_LIB.BASEBOARD_FAB2(SCH_1):PAGE58
  J1G2  183 DQ<25> SCONN288_H44441004_PIP-SCONN,HA   I111 @BASEBOARD_FAB2_LIB.BASEBOARD_FAB2(SCH_1):PAGE79
  J9U1   38 DQ<24> SCONN288_H44441003_PIP-SCONN,HA    I24 @BASEBOARD_FAB2_LIB.BASEBOARD_FAB2(SCH_1):PAGE80

M_H_DQ<25> @BASEBOARD_FAB2_LIB.BASEBOARD_FAB2(SCH_1):M_H_DQ(25)
  U2D1  C74 DDR1_DQ<25> SKX_EXT_B_BGA1-IC,TBD   I172 @BASEBOARD_FAB2_LIB.BASEBOARD_FAB2(SCH_1):PAGE58
  J1G2   38 DQ<24> SCONN288_H44441004_PIP-SCONN,HA   I111 @BASEBOARD_FAB2_LIB.BASEBOARD_FAB2(SCH_1):PAGE79
  J9U1  183 DQ<25> SCONN288_H44441003_PIP-SCONN,HA    I24 @BASEBOARD_FAB2_LIB.BASEBOARD_FAB2(SCH_1):PAGE80

M_H_DQ<26> @BASEBOARD_FAB2_LIB.BASEBOARD_FAB2(SCH_1):M_H_DQ(26)
  U2D1  D71 DDR1_DQ<26> SKX_EXT_B_BGA1-IC,TBD   I172 @BASEBOARD_FAB2_LIB.BASEBOARD_FAB2(SCH_1):PAGE58
  J1G2  190 DQ<27> SCONN288_H44441004_PIP-SCONN,HA   I111 @BASEBOARD_FAB2_LIB.BASEBOARD_FAB2(SCH_1):PAGE79
  J9U1   45 DQ<26> SCONN288_H44441003_PIP-SCONN,HA    I24 @BASEBOARD_FAB2_LIB.BASEBOARD_FAB2(SCH_1):PAGE80

M_H_DQ<27> @BASEBOARD_FAB2_LIB.BASEBOARD_FAB2(SCH_1):M_H_DQ(27)
  U2D1  F71 DDR1_DQ<27> SKX_EXT_B_BGA1-IC,TBD   I172 @BASEBOARD_FAB2_LIB.BASEBOARD_FAB2(SCH_1):PAGE58
  J1G2   45 DQ<26> SCONN288_H44441004_PIP-SCONN,HA   I111 @BASEBOARD_FAB2_LIB.BASEBOARD_FAB2(SCH_1):PAGE79
  J9U1  190 DQ<27> SCONN288_H44441003_PIP-SCONN,HA    I24 @BASEBOARD_FAB2_LIB.BASEBOARD_FAB2(SCH_1):PAGE80

M_H_DQ<28> @BASEBOARD_FAB2_LIB.BASEBOARD_FAB2(SCH_1):M_H_DQ(28)
  U2D1  F75 DDR1_DQ<28> SKX_EXT_B_BGA1-IC,TBD   I172 @BASEBOARD_FAB2_LIB.BASEBOARD_FAB2(SCH_1):PAGE58
  J1G2  181 DQ<29> SCONN288_H44441004_PIP-SCONN,HA   I111 @BASEBOARD_FAB2_LIB.BASEBOARD_FAB2(SCH_1):PAGE79
  J9U1   36 DQ<28> SCONN288_H44441003_PIP-SCONN,HA    I24 @BASEBOARD_FAB2_LIB.BASEBOARD_FAB2(SCH_1):PAGE80

M_H_DQ<29> @BASEBOARD_FAB2_LIB.BASEBOARD_FAB2(SCH_1):M_H_DQ(29)
  U2D1  G74 DDR1_DQ<29> SKX_EXT_B_BGA1-IC,TBD   I172 @BASEBOARD_FAB2_LIB.BASEBOARD_FAB2(SCH_1):PAGE58
  J1G2   36 DQ<28> SCONN288_H44441004_PIP-SCONN,HA   I111 @BASEBOARD_FAB2_LIB.BASEBOARD_FAB2(SCH_1):PAGE79
  J9U1  181 DQ<29> SCONN288_H44441003_PIP-SCONN,HA    I24 @BASEBOARD_FAB2_LIB.BASEBOARD_FAB2(SCH_1):PAGE80

M_H_DQ<2> @BASEBOARD_FAB2_LIB.BASEBOARD_FAB2(SCH_1):M_H_DQ(2)
  U2D1 AN82 DDR1_DQ<2> SKX_EXT_B_BGA1-IC,TBD   I172 @BASEBOARD_FAB2_LIB.BASEBOARD_FAB2(SCH_1):PAGE58
  J1G2  157  DQ<3> SCONN288_H44441004_PIP-SCONN,HA   I111 @BASEBOARD_FAB2_LIB.BASEBOARD_FAB2(SCH_1):PAGE79
  J9U1   12  DQ<2> SCONN288_H44441003_PIP-SCONN,HA    I24 @BASEBOARD_FAB2_LIB.BASEBOARD_FAB2(SCH_1):PAGE80

M_H_DQ<30> @BASEBOARD_FAB2_LIB.BASEBOARD_FAB2(SCH_1):M_H_DQ(30)
  U2D1  C72 DDR1_DQ<30> SKX_EXT_B_BGA1-IC,TBD   I172 @BASEBOARD_FAB2_LIB.BASEBOARD_FAB2(SCH_1):PAGE58
  J1G2  188 DQ<31> SCONN288_H44441004_PIP-SCONN,HA   I111 @BASEBOARD_FAB2_LIB.BASEBOARD_FAB2(SCH_1):PAGE79
  J9U1   43 DQ<30> SCONN288_H44441003_PIP-SCONN,HA    I24 @BASEBOARD_FAB2_LIB.BASEBOARD_FAB2(SCH_1):PAGE80

M_H_DQ<31> @BASEBOARD_FAB2_LIB.BASEBOARD_FAB2(SCH_1):M_H_DQ(31)
  U2D1  G72 DDR1_DQ<31> SKX_EXT_B_BGA1-IC,TBD   I172 @BASEBOARD_FAB2_LIB.BASEBOARD_FAB2(SCH_1):PAGE58
  J1G2   43 DQ<30> SCONN288_H44441004_PIP-SCONN,HA   I111 @BASEBOARD_FAB2_LIB.BASEBOARD_FAB2(SCH_1):PAGE79
  J9U1  188 DQ<31> SCONN288_H44441003_PIP-SCONN,HA    I24 @BASEBOARD_FAB2_LIB.BASEBOARD_FAB2(SCH_1):PAGE80

M_H_DQ<32> @BASEBOARD_FAB2_LIB.BASEBOARD_FAB2(SCH_1):M_H_DQ(32)
  U2D1  K43 DDR1_DQ<32> SKX_EXT_B_BGA1-IC,TBD   I172 @BASEBOARD_FAB2_LIB.BASEBOARD_FAB2(SCH_1):PAGE58
  J1G2  242 DQ<33> SCONN288_H44441004_PIP-SCONN,HA   I111 @BASEBOARD_FAB2_LIB.BASEBOARD_FAB2(SCH_1):PAGE79
  J9U1   97 DQ<32> SCONN288_H44441003_PIP-SCONN,HA    I24 @BASEBOARD_FAB2_LIB.BASEBOARD_FAB2(SCH_1):PAGE80

M_H_DQ<33> @BASEBOARD_FAB2_LIB.BASEBOARD_FAB2(SCH_1):M_H_DQ(33)
  U2D1  H43 DDR1_DQ<33> SKX_EXT_B_BGA1-IC,TBD   I172 @BASEBOARD_FAB2_LIB.BASEBOARD_FAB2(SCH_1):PAGE58
  J1G2   97 DQ<32> SCONN288_H44441004_PIP-SCONN,HA   I111 @BASEBOARD_FAB2_LIB.BASEBOARD_FAB2(SCH_1):PAGE79
  J9U1  242 DQ<33> SCONN288_H44441003_PIP-SCONN,HA    I24 @BASEBOARD_FAB2_LIB.BASEBOARD_FAB2(SCH_1):PAGE80

M_H_DQ<34> @BASEBOARD_FAB2_LIB.BASEBOARD_FAB2(SCH_1):M_H_DQ(34)
  U2D1  L40 DDR1_DQ<34> SKX_EXT_B_BGA1-IC,TBD   I172 @BASEBOARD_FAB2_LIB.BASEBOARD_FAB2(SCH_1):PAGE58
  J1G2  249 DQ<35> SCONN288_H44441004_PIP-SCONN,HA   I111 @BASEBOARD_FAB2_LIB.BASEBOARD_FAB2(SCH_1):PAGE79
  J9U1  104 DQ<34> SCONN288_H44441003_PIP-SCONN,HA    I24 @BASEBOARD_FAB2_LIB.BASEBOARD_FAB2(SCH_1):PAGE80

M_H_DQ<35> @BASEBOARD_FAB2_LIB.BASEBOARD_FAB2(SCH_1):M_H_DQ(35)
  U2D1  N40 DDR1_DQ<35> SKX_EXT_B_BGA1-IC,TBD   I172 @BASEBOARD_FAB2_LIB.BASEBOARD_FAB2(SCH_1):PAGE58
  J1G2  104 DQ<34> SCONN288_H44441004_PIP-SCONN,HA   I111 @BASEBOARD_FAB2_LIB.BASEBOARD_FAB2(SCH_1):PAGE79
  J9U1  249 DQ<35> SCONN288_H44441003_PIP-SCONN,HA    I24 @BASEBOARD_FAB2_LIB.BASEBOARD_FAB2(SCH_1):PAGE80

M_H_DQ<36> @BASEBOARD_FAB2_LIB.BASEBOARD_FAB2(SCH_1):M_H_DQ(36)
  U2D1  P43 DDR1_DQ<36> SKX_EXT_B_BGA1-IC,TBD   I172 @BASEBOARD_FAB2_LIB.BASEBOARD_FAB2(SCH_1):PAGE58
  J1G2  240 DQ<37> SCONN288_H44441004_PIP-SCONN,HA   I111 @BASEBOARD_FAB2_LIB.BASEBOARD_FAB2(SCH_1):PAGE79
  J9U1   95 DQ<36> SCONN288_H44441003_PIP-SCONN,HA    I24 @BASEBOARD_FAB2_LIB.BASEBOARD_FAB2(SCH_1):PAGE80

M_H_DQ<37> @BASEBOARD_FAB2_LIB.BASEBOARD_FAB2(SCH_1):M_H_DQ(37)
  U2D1  T43 DDR1_DQ<37> SKX_EXT_B_BGA1-IC,TBD   I172 @BASEBOARD_FAB2_LIB.BASEBOARD_FAB2(SCH_1):PAGE58
  J1G2   95 DQ<36> SCONN288_H44441004_PIP-SCONN,HA   I111 @BASEBOARD_FAB2_LIB.BASEBOARD_FAB2(SCH_1):PAGE79
  J9U1  240 DQ<37> SCONN288_H44441003_PIP-SCONN,HA    I24 @BASEBOARD_FAB2_LIB.BASEBOARD_FAB2(SCH_1):PAGE80

M_H_DQ<38> @BASEBOARD_FAB2_LIB.BASEBOARD_FAB2(SCH_1):M_H_DQ(38)
  U2D1  K41 DDR1_DQ<38> SKX_EXT_B_BGA1-IC,TBD   I172 @BASEBOARD_FAB2_LIB.BASEBOARD_FAB2(SCH_1):PAGE58
  J1G2  247 DQ<39> SCONN288_H44441004_PIP-SCONN,HA   I111 @BASEBOARD_FAB2_LIB.BASEBOARD_FAB2(SCH_1):PAGE79
  J9U1  102 DQ<38> SCONN288_H44441003_PIP-SCONN,HA    I24 @BASEBOARD_FAB2_LIB.BASEBOARD_FAB2(SCH_1):PAGE80

M_H_DQ<39> @BASEBOARD_FAB2_LIB.BASEBOARD_FAB2(SCH_1):M_H_DQ(39)
  U2D1  P41 DDR1_DQ<39> SKX_EXT_B_BGA1-IC,TBD   I172 @BASEBOARD_FAB2_LIB.BASEBOARD_FAB2(SCH_1):PAGE58
  J1G2  102 DQ<38> SCONN288_H44441004_PIP-SCONN,HA   I111 @BASEBOARD_FAB2_LIB.BASEBOARD_FAB2(SCH_1):PAGE79
  J9U1  247 DQ<39> SCONN288_H44441003_PIP-SCONN,HA    I24 @BASEBOARD_FAB2_LIB.BASEBOARD_FAB2(SCH_1):PAGE80

M_H_DQ<3> @BASEBOARD_FAB2_LIB.BASEBOARD_FAB2(SCH_1):M_H_DQ(3)
  U2D1 AM81 DDR1_DQ<3> SKX_EXT_B_BGA1-IC,TBD   I172 @BASEBOARD_FAB2_LIB.BASEBOARD_FAB2(SCH_1):PAGE58
  J1G2   12  DQ<2> SCONN288_H44441004_PIP-SCONN,HA   I111 @BASEBOARD_FAB2_LIB.BASEBOARD_FAB2(SCH_1):PAGE79
  J9U1  157  DQ<3> SCONN288_H44441003_PIP-SCONN,HA    I24 @BASEBOARD_FAB2_LIB.BASEBOARD_FAB2(SCH_1):PAGE80

M_H_DQ<40> @BASEBOARD_FAB2_LIB.BASEBOARD_FAB2(SCH_1):M_H_DQ(40)
  U2D1  C36 DDR1_DQ<40> SKX_EXT_B_BGA1-IC,TBD   I172 @BASEBOARD_FAB2_LIB.BASEBOARD_FAB2(SCH_1):PAGE58
  J1G2  253 DQ<41> SCONN288_H44441004_PIP-SCONN,HA   I111 @BASEBOARD_FAB2_LIB.BASEBOARD_FAB2(SCH_1):PAGE79
  J9U1  108 DQ<40> SCONN288_H44441003_PIP-SCONN,HA    I24 @BASEBOARD_FAB2_LIB.BASEBOARD_FAB2(SCH_1):PAGE80

M_H_DQ<41> @BASEBOARD_FAB2_LIB.BASEBOARD_FAB2(SCH_1):M_H_DQ(41)
  U2D1  B35 DDR1_DQ<41> SKX_EXT_B_BGA1-IC,TBD   I172 @BASEBOARD_FAB2_LIB.BASEBOARD_FAB2(SCH_1):PAGE58
  J1G2  108 DQ<40> SCONN288_H44441004_PIP-SCONN,HA   I111 @BASEBOARD_FAB2_LIB.BASEBOARD_FAB2(SCH_1):PAGE79
  J9U1  253 DQ<41> SCONN288_H44441003_PIP-SCONN,HA    I24 @BASEBOARD_FAB2_LIB.BASEBOARD_FAB2(SCH_1):PAGE80

M_H_DQ<42> @BASEBOARD_FAB2_LIB.BASEBOARD_FAB2(SCH_1):M_H_DQ(42)
  U2D1  C32 DDR1_DQ<42> SKX_EXT_B_BGA1-IC,TBD   I172 @BASEBOARD_FAB2_LIB.BASEBOARD_FAB2(SCH_1):PAGE58
  J1G2  260 DQ<43> SCONN288_H44441004_PIP-SCONN,HA   I111 @BASEBOARD_FAB2_LIB.BASEBOARD_FAB2(SCH_1):PAGE79
  J9U1  115 DQ<42> SCONN288_H44441003_PIP-SCONN,HA    I24 @BASEBOARD_FAB2_LIB.BASEBOARD_FAB2(SCH_1):PAGE80

M_H_DQ<43> @BASEBOARD_FAB2_LIB.BASEBOARD_FAB2(SCH_1):M_H_DQ(43)
  U2D1  E32 DDR1_DQ<43> SKX_EXT_B_BGA1-IC,TBD   I172 @BASEBOARD_FAB2_LIB.BASEBOARD_FAB2(SCH_1):PAGE58
  J1G2  115 DQ<42> SCONN288_H44441004_PIP-SCONN,HA   I111 @BASEBOARD_FAB2_LIB.BASEBOARD_FAB2(SCH_1):PAGE79
  J9U1  260 DQ<43> SCONN288_H44441003_PIP-SCONN,HA    I24 @BASEBOARD_FAB2_LIB.BASEBOARD_FAB2(SCH_1):PAGE80

M_H_DQ<44> @BASEBOARD_FAB2_LIB.BASEBOARD_FAB2(SCH_1):M_H_DQ(44)
  U2D1  E36 DDR1_DQ<44> SKX_EXT_B_BGA1-IC,TBD   I172 @BASEBOARD_FAB2_LIB.BASEBOARD_FAB2(SCH_1):PAGE58
  J1G2  251 DQ<45> SCONN288_H44441004_PIP-SCONN,HA   I111 @BASEBOARD_FAB2_LIB.BASEBOARD_FAB2(SCH_1):PAGE79
  J9U1  106 DQ<44> SCONN288_H44441003_PIP-SCONN,HA    I24 @BASEBOARD_FAB2_LIB.BASEBOARD_FAB2(SCH_1):PAGE80

M_H_DQ<45> @BASEBOARD_FAB2_LIB.BASEBOARD_FAB2(SCH_1):M_H_DQ(45)
  U2D1  F35 DDR1_DQ<45> SKX_EXT_B_BGA1-IC,TBD   I172 @BASEBOARD_FAB2_LIB.BASEBOARD_FAB2(SCH_1):PAGE58
  J1G2  106 DQ<44> SCONN288_H44441004_PIP-SCONN,HA   I111 @BASEBOARD_FAB2_LIB.BASEBOARD_FAB2(SCH_1):PAGE79
  J9U1  251 DQ<45> SCONN288_H44441003_PIP-SCONN,HA    I24 @BASEBOARD_FAB2_LIB.BASEBOARD_FAB2(SCH_1):PAGE80

M_H_DQ<46> @BASEBOARD_FAB2_LIB.BASEBOARD_FAB2(SCH_1):M_H_DQ(46)
  U2D1  B33 DDR1_DQ<46> SKX_EXT_B_BGA1-IC,TBD   I172 @BASEBOARD_FAB2_LIB.BASEBOARD_FAB2(SCH_1):PAGE58
  J1G2  258 DQ<47> SCONN288_H44441004_PIP-SCONN,HA   I111 @BASEBOARD_FAB2_LIB.BASEBOARD_FAB2(SCH_1):PAGE79
  J9U1  113 DQ<46> SCONN288_H44441003_PIP-SCONN,HA    I24 @BASEBOARD_FAB2_LIB.BASEBOARD_FAB2(SCH_1):PAGE80

M_H_DQ<47> @BASEBOARD_FAB2_LIB.BASEBOARD_FAB2(SCH_1):M_H_DQ(47)
  U2D1  F33 DDR1_DQ<47> SKX_EXT_B_BGA1-IC,TBD   I172 @BASEBOARD_FAB2_LIB.BASEBOARD_FAB2(SCH_1):PAGE58
  J1G2  113 DQ<46> SCONN288_H44441004_PIP-SCONN,HA   I111 @BASEBOARD_FAB2_LIB.BASEBOARD_FAB2(SCH_1):PAGE79
  J9U1  258 DQ<47> SCONN288_H44441003_PIP-SCONN,HA    I24 @BASEBOARD_FAB2_LIB.BASEBOARD_FAB2(SCH_1):PAGE80

M_H_DQ<48> @BASEBOARD_FAB2_LIB.BASEBOARD_FAB2(SCH_1):M_H_DQ(48)
  U2D1  C30 DDR1_DQ<48> SKX_EXT_B_BGA1-IC,TBD   I172 @BASEBOARD_FAB2_LIB.BASEBOARD_FAB2(SCH_1):PAGE58
  J1G2  264 DQ<49> SCONN288_H44441004_PIP-SCONN,HA   I111 @BASEBOARD_FAB2_LIB.BASEBOARD_FAB2(SCH_1):PAGE79
  J9U1  119 DQ<48> SCONN288_H44441003_PIP-SCONN,HA    I24 @BASEBOARD_FAB2_LIB.BASEBOARD_FAB2(SCH_1):PAGE80

M_H_DQ<49> @BASEBOARD_FAB2_LIB.BASEBOARD_FAB2(SCH_1):M_H_DQ(49)
  U2D1  B29 DDR1_DQ<49> SKX_EXT_B_BGA1-IC,TBD   I172 @BASEBOARD_FAB2_LIB.BASEBOARD_FAB2(SCH_1):PAGE58
  J1G2  119 DQ<48> SCONN288_H44441004_PIP-SCONN,HA   I111 @BASEBOARD_FAB2_LIB.BASEBOARD_FAB2(SCH_1):PAGE79
  J9U1  264 DQ<49> SCONN288_H44441003_PIP-SCONN,HA    I24 @BASEBOARD_FAB2_LIB.BASEBOARD_FAB2(SCH_1):PAGE80

M_H_DQ<4> @BASEBOARD_FAB2_LIB.BASEBOARD_FAB2(SCH_1):M_H_DQ(4)
  U2D1 AW80 DDR1_DQ<4> SKX_EXT_B_BGA1-IC,TBD   I172 @BASEBOARD_FAB2_LIB.BASEBOARD_FAB2(SCH_1):PAGE58
  J1G2  148  DQ<5> SCONN288_H44441004_PIP-SCONN,HA   I111 @BASEBOARD_FAB2_LIB.BASEBOARD_FAB2(SCH_1):PAGE79
  J9U1    3  DQ<4> SCONN288_H44441003_PIP-SCONN,HA    I24 @BASEBOARD_FAB2_LIB.BASEBOARD_FAB2(SCH_1):PAGE80

M_H_DQ<50> @BASEBOARD_FAB2_LIB.BASEBOARD_FAB2(SCH_1):M_H_DQ(50)
  U2D1  C26 DDR1_DQ<50> SKX_EXT_B_BGA1-IC,TBD   I172 @BASEBOARD_FAB2_LIB.BASEBOARD_FAB2(SCH_1):PAGE58
  J1G2  271 DQ<51> SCONN288_H44441004_PIP-SCONN,HA   I111 @BASEBOARD_FAB2_LIB.BASEBOARD_FAB2(SCH_1):PAGE79
  J9U1  126 DQ<50> SCONN288_H44441003_PIP-SCONN,HA    I24 @BASEBOARD_FAB2_LIB.BASEBOARD_FAB2(SCH_1):PAGE80

M_H_DQ<51> @BASEBOARD_FAB2_LIB.BASEBOARD_FAB2(SCH_1):M_H_DQ(51)
  U2D1  E26 DDR1_DQ<51> SKX_EXT_B_BGA1-IC,TBD   I172 @BASEBOARD_FAB2_LIB.BASEBOARD_FAB2(SCH_1):PAGE58
  J1G2  126 DQ<50> SCONN288_H44441004_PIP-SCONN,HA   I111 @BASEBOARD_FAB2_LIB.BASEBOARD_FAB2(SCH_1):PAGE79
  J9U1  271 DQ<51> SCONN288_H44441003_PIP-SCONN,HA    I24 @BASEBOARD_FAB2_LIB.BASEBOARD_FAB2(SCH_1):PAGE80

M_H_DQ<52> @BASEBOARD_FAB2_LIB.BASEBOARD_FAB2(SCH_1):M_H_DQ(52)
  U2D1  E30 DDR1_DQ<52> SKX_EXT_B_BGA1-IC,TBD   I172 @BASEBOARD_FAB2_LIB.BASEBOARD_FAB2(SCH_1):PAGE58
  J1G2  262 DQ<53> SCONN288_H44441004_PIP-SCONN,HA   I111 @BASEBOARD_FAB2_LIB.BASEBOARD_FAB2(SCH_1):PAGE79
  J9U1  117 DQ<52> SCONN288_H44441003_PIP-SCONN,HA    I24 @BASEBOARD_FAB2_LIB.BASEBOARD_FAB2(SCH_1):PAGE80

M_H_DQ<53> @BASEBOARD_FAB2_LIB.BASEBOARD_FAB2(SCH_1):M_H_DQ(53)
  U2D1  F29 DDR1_DQ<53> SKX_EXT_B_BGA1-IC,TBD   I172 @BASEBOARD_FAB2_LIB.BASEBOARD_FAB2(SCH_1):PAGE58
  J1G2  117 DQ<52> SCONN288_H44441004_PIP-SCONN,HA   I111 @BASEBOARD_FAB2_LIB.BASEBOARD_FAB2(SCH_1):PAGE79
  J9U1  262 DQ<53> SCONN288_H44441003_PIP-SCONN,HA    I24 @BASEBOARD_FAB2_LIB.BASEBOARD_FAB2(SCH_1):PAGE80

M_H_DQ<54> @BASEBOARD_FAB2_LIB.BASEBOARD_FAB2(SCH_1):M_H_DQ(54)
  U2D1  B27 DDR1_DQ<54> SKX_EXT_B_BGA1-IC,TBD   I172 @BASEBOARD_FAB2_LIB.BASEBOARD_FAB2(SCH_1):PAGE58
  J1G2  269 DQ<55> SCONN288_H44441004_PIP-SCONN,HA   I111 @BASEBOARD_FAB2_LIB.BASEBOARD_FAB2(SCH_1):PAGE79
  J9U1  124 DQ<54> SCONN288_H44441003_PIP-SCONN,HA    I24 @BASEBOARD_FAB2_LIB.BASEBOARD_FAB2(SCH_1):PAGE80

M_H_DQ<55> @BASEBOARD_FAB2_LIB.BASEBOARD_FAB2(SCH_1):M_H_DQ(55)
  U2D1  F27 DDR1_DQ<55> SKX_EXT_B_BGA1-IC,TBD   I172 @BASEBOARD_FAB2_LIB.BASEBOARD_FAB2(SCH_1):PAGE58
  J1G2  124 DQ<54> SCONN288_H44441004_PIP-SCONN,HA   I111 @BASEBOARD_FAB2_LIB.BASEBOARD_FAB2(SCH_1):PAGE79
  J9U1  269 DQ<55> SCONN288_H44441003_PIP-SCONN,HA    I24 @BASEBOARD_FAB2_LIB.BASEBOARD_FAB2(SCH_1):PAGE80

M_H_DQ<56> @BASEBOARD_FAB2_LIB.BASEBOARD_FAB2(SCH_1):M_H_DQ(56)
  U2D1  U28 DDR1_DQ<56> SKX_EXT_B_BGA1-IC,TBD   I172 @BASEBOARD_FAB2_LIB.BASEBOARD_FAB2(SCH_1):PAGE58
  J1G2  275 DQ<57> SCONN288_H44441004_PIP-SCONN,HA   I111 @BASEBOARD_FAB2_LIB.BASEBOARD_FAB2(SCH_1):PAGE79
  J9U1  130 DQ<56> SCONN288_H44441003_PIP-SCONN,HA    I24 @BASEBOARD_FAB2_LIB.BASEBOARD_FAB2(SCH_1):PAGE80

M_H_DQ<57> @BASEBOARD_FAB2_LIB.BASEBOARD_FAB2(SCH_1):M_H_DQ(57)
  U2D1 AA28 DDR1_DQ<57> SKX_EXT_B_BGA1-IC,TBD   I172 @BASEBOARD_FAB2_LIB.BASEBOARD_FAB2(SCH_1):PAGE58
  J1G2  130 DQ<56> SCONN288_H44441004_PIP-SCONN,HA   I111 @BASEBOARD_FAB2_LIB.BASEBOARD_FAB2(SCH_1):PAGE79
  J9U1  275 DQ<57> SCONN288_H44441003_PIP-SCONN,HA    I24 @BASEBOARD_FAB2_LIB.BASEBOARD_FAB2(SCH_1):PAGE80

M_H_DQ<58> @BASEBOARD_FAB2_LIB.BASEBOARD_FAB2(SCH_1):M_H_DQ(58)
  U2D1  V25 DDR1_DQ<58> SKX_EXT_B_BGA1-IC,TBD   I172 @BASEBOARD_FAB2_LIB.BASEBOARD_FAB2(SCH_1):PAGE58
  J1G2  282 DQ<59> SCONN288_H44441004_PIP-SCONN,HA   I111 @BASEBOARD_FAB2_LIB.BASEBOARD_FAB2(SCH_1):PAGE79
  J9U1  137 DQ<58> SCONN288_H44441003_PIP-SCONN,HA    I24 @BASEBOARD_FAB2_LIB.BASEBOARD_FAB2(SCH_1):PAGE80

M_H_DQ<59> @BASEBOARD_FAB2_LIB.BASEBOARD_FAB2(SCH_1):M_H_DQ(59)
  U2D1  Y25 DDR1_DQ<59> SKX_EXT_B_BGA1-IC,TBD   I172 @BASEBOARD_FAB2_LIB.BASEBOARD_FAB2(SCH_1):PAGE58
  J1G2  137 DQ<58> SCONN288_H44441004_PIP-SCONN,HA   I111 @BASEBOARD_FAB2_LIB.BASEBOARD_FAB2(SCH_1):PAGE79
  J9U1  282 DQ<59> SCONN288_H44441003_PIP-SCONN,HA    I24 @BASEBOARD_FAB2_LIB.BASEBOARD_FAB2(SCH_1):PAGE80

M_H_DQ<5> @BASEBOARD_FAB2_LIB.BASEBOARD_FAB2(SCH_1):M_H_DQ(5)
  U2D1 AV79 DDR1_DQ<5> SKX_EXT_B_BGA1-IC,TBD   I172 @BASEBOARD_FAB2_LIB.BASEBOARD_FAB2(SCH_1):PAGE58
  J1G2    3  DQ<4> SCONN288_H44441004_PIP-SCONN,HA   I111 @BASEBOARD_FAB2_LIB.BASEBOARD_FAB2(SCH_1):PAGE79
  J9U1  148  DQ<5> SCONN288_H44441003_PIP-SCONN,HA    I24 @BASEBOARD_FAB2_LIB.BASEBOARD_FAB2(SCH_1):PAGE80

M_H_DQ<60> @BASEBOARD_FAB2_LIB.BASEBOARD_FAB2(SCH_1):M_H_DQ(60)
  U2D1  V29 DDR1_DQ<60> SKX_EXT_B_BGA1-IC,TBD   I172 @BASEBOARD_FAB2_LIB.BASEBOARD_FAB2(SCH_1):PAGE58
  J1G2  273 DQ<61> SCONN288_H44441004_PIP-SCONN,HA   I111 @BASEBOARD_FAB2_LIB.BASEBOARD_FAB2(SCH_1):PAGE79
  J9U1  128 DQ<60> SCONN288_H44441003_PIP-SCONN,HA    I24 @BASEBOARD_FAB2_LIB.BASEBOARD_FAB2(SCH_1):PAGE80

M_H_DQ<61> @BASEBOARD_FAB2_LIB.BASEBOARD_FAB2(SCH_1):M_H_DQ(61)
  U2D1  Y29 DDR1_DQ<61> SKX_EXT_B_BGA1-IC,TBD   I172 @BASEBOARD_FAB2_LIB.BASEBOARD_FAB2(SCH_1):PAGE58
  J1G2  128 DQ<60> SCONN288_H44441004_PIP-SCONN,HA   I111 @BASEBOARD_FAB2_LIB.BASEBOARD_FAB2(SCH_1):PAGE79
  J9U1  273 DQ<61> SCONN288_H44441003_PIP-SCONN,HA    I24 @BASEBOARD_FAB2_LIB.BASEBOARD_FAB2(SCH_1):PAGE80

M_H_DQ<62> @BASEBOARD_FAB2_LIB.BASEBOARD_FAB2(SCH_1):M_H_DQ(62)
  U2D1  U26 DDR1_DQ<62> SKX_EXT_B_BGA1-IC,TBD   I172 @BASEBOARD_FAB2_LIB.BASEBOARD_FAB2(SCH_1):PAGE58
  J1G2  280 DQ<63> SCONN288_H44441004_PIP-SCONN,HA   I111 @BASEBOARD_FAB2_LIB.BASEBOARD_FAB2(SCH_1):PAGE79
  J9U1  135 DQ<62> SCONN288_H44441003_PIP-SCONN,HA    I24 @BASEBOARD_FAB2_LIB.BASEBOARD_FAB2(SCH_1):PAGE80

M_H_DQ<63> @BASEBOARD_FAB2_LIB.BASEBOARD_FAB2(SCH_1):M_H_DQ(63)
  U2D1 AA26 DDR1_DQ<63> SKX_EXT_B_BGA1-IC,TBD   I172 @BASEBOARD_FAB2_LIB.BASEBOARD_FAB2(SCH_1):PAGE58
  J1G2  135 DQ<62> SCONN288_H44441004_PIP-SCONN,HA   I111 @BASEBOARD_FAB2_LIB.BASEBOARD_FAB2(SCH_1):PAGE79
  J9U1  280 DQ<63> SCONN288_H44441003_PIP-SCONN,HA    I24 @BASEBOARD_FAB2_LIB.BASEBOARD_FAB2(SCH_1):PAGE80

M_H_DQ<6> @BASEBOARD_FAB2_LIB.BASEBOARD_FAB2(SCH_1):M_H_DQ(6)
  U2D1 AR82 DDR1_DQ<6> SKX_EXT_B_BGA1-IC,TBD   I172 @BASEBOARD_FAB2_LIB.BASEBOARD_FAB2(SCH_1):PAGE58
  J1G2  155  DQ<7> SCONN288_H44441004_PIP-SCONN,HA   I111 @BASEBOARD_FAB2_LIB.BASEBOARD_FAB2(SCH_1):PAGE79
  J9U1   10  DQ<6> SCONN288_H44441003_PIP-SCONN,HA    I24 @BASEBOARD_FAB2_LIB.BASEBOARD_FAB2(SCH_1):PAGE80

M_H_DQ<7> @BASEBOARD_FAB2_LIB.BASEBOARD_FAB2(SCH_1):M_H_DQ(7)
  U2D1 AN80 DDR1_DQ<7> SKX_EXT_B_BGA1-IC,TBD   I172 @BASEBOARD_FAB2_LIB.BASEBOARD_FAB2(SCH_1):PAGE58
  J1G2   10  DQ<6> SCONN288_H44441004_PIP-SCONN,HA   I111 @BASEBOARD_FAB2_LIB.BASEBOARD_FAB2(SCH_1):PAGE79
  J9U1  155  DQ<7> SCONN288_H44441003_PIP-SCONN,HA    I24 @BASEBOARD_FAB2_LIB.BASEBOARD_FAB2(SCH_1):PAGE80

M_H_DQ<8> @BASEBOARD_FAB2_LIB.BASEBOARD_FAB2(SCH_1):M_H_DQ(8)
  U2D1 AH81 DDR1_DQ<8> SKX_EXT_B_BGA1-IC,TBD   I172 @BASEBOARD_FAB2_LIB.BASEBOARD_FAB2(SCH_1):PAGE58
  J1G2  161  DQ<9> SCONN288_H44441004_PIP-SCONN,HA   I111 @BASEBOARD_FAB2_LIB.BASEBOARD_FAB2(SCH_1):PAGE79
  J9U1   16  DQ<8> SCONN288_H44441003_PIP-SCONN,HA    I24 @BASEBOARD_FAB2_LIB.BASEBOARD_FAB2(SCH_1):PAGE80

M_H_DQ<9> @BASEBOARD_FAB2_LIB.BASEBOARD_FAB2(SCH_1):M_H_DQ(9)
  U2D1 AF79 DDR1_DQ<9> SKX_EXT_B_BGA1-IC,TBD   I172 @BASEBOARD_FAB2_LIB.BASEBOARD_FAB2(SCH_1):PAGE58
  J1G2   16  DQ<8> SCONN288_H44441004_PIP-SCONN,HA   I111 @BASEBOARD_FAB2_LIB.BASEBOARD_FAB2(SCH_1):PAGE79
  J9U1  161  DQ<9> SCONN288_H44441003_PIP-SCONN,HA    I24 @BASEBOARD_FAB2_LIB.BASEBOARD_FAB2(SCH_1):PAGE80

M_H_DQS_DN<0> @BASEBOARD_FAB2_LIB.BASEBOARD_FAB2(SCH_1):M_H_DQS_DN(0)
  U2D1 AP79 DDR1_DQS_DN<0> SKX_EXT_B_BGA1-IC,TBD   I172 @BASEBOARD_FAB2_LIB.BASEBOARD_FAB2(SCH_1):PAGE58
  J1G2  152  DQS0N SCONN288_H44441004_PIP-SCONN,HA    I64 @BASEBOARD_FAB2_LIB.BASEBOARD_FAB2(SCH_1):PAGE79
  J9U1  152  DQS0N SCONN288_H44441003_PIP-SCONN,HA   I101 @BASEBOARD_FAB2_LIB.BASEBOARD_FAB2(SCH_1):PAGE80

M_H_DQS_DN<10> @BASEBOARD_FAB2_LIB.BASEBOARD_FAB2(SCH_1):M_H_DQS_DN(10)
  U2D1 AG82 DDR1_DQS_DN<10> SKX_EXT_B_BGA1-IC,TBD   I172 @BASEBOARD_FAB2_LIB.BASEBOARD_FAB2(SCH_1):PAGE58
  J1G2   19 DQS10N SCONN288_H44441004_PIP-SCONN,HA    I64 @BASEBOARD_FAB2_LIB.BASEBOARD_FAB2(SCH_1):PAGE79
  J9U1   19 DQS10N SCONN288_H44441003_PIP-SCONN,HA   I101 @BASEBOARD_FAB2_LIB.BASEBOARD_FAB2(SCH_1):PAGE80

M_H_DQS_DN<11> @BASEBOARD_FAB2_LIB.BASEBOARD_FAB2(SCH_1):M_H_DQS_DN(11)
  U2D1  D79 DDR1_DQS_DN<11> SKX_EXT_B_BGA1-IC,TBD   I172 @BASEBOARD_FAB2_LIB.BASEBOARD_FAB2(SCH_1):PAGE58
  J1G2   30 DQS11N SCONN288_H44441004_PIP-SCONN,HA    I64 @BASEBOARD_FAB2_LIB.BASEBOARD_FAB2(SCH_1):PAGE79
  J9U1   30 DQS11N SCONN288_H44441003_PIP-SCONN,HA   I101 @BASEBOARD_FAB2_LIB.BASEBOARD_FAB2(SCH_1):PAGE80

M_H_DQS_DN<12> @BASEBOARD_FAB2_LIB.BASEBOARD_FAB2(SCH_1):M_H_DQS_DN(12)
  U2D1  B73 DDR1_DQS_DN<12> SKX_EXT_B_BGA1-IC,TBD   I172 @BASEBOARD_FAB2_LIB.BASEBOARD_FAB2(SCH_1):PAGE58
  J1G2   41 DQS12N SCONN288_H44441004_PIP-SCONN,HA    I64 @BASEBOARD_FAB2_LIB.BASEBOARD_FAB2(SCH_1):PAGE79
  J9U1   41 DQS12N SCONN288_H44441003_PIP-SCONN,HA   I101 @BASEBOARD_FAB2_LIB.BASEBOARD_FAB2(SCH_1):PAGE80

M_H_DQS_DN<13> @BASEBOARD_FAB2_LIB.BASEBOARD_FAB2(SCH_1):M_H_DQS_DN(13)
  U2D1  J42 DDR1_DQS_DN<13> SKX_EXT_B_BGA1-IC,TBD   I172 @BASEBOARD_FAB2_LIB.BASEBOARD_FAB2(SCH_1):PAGE58
  J1G2  100 DQS13N SCONN288_H44441004_PIP-SCONN,HA    I64 @BASEBOARD_FAB2_LIB.BASEBOARD_FAB2(SCH_1):PAGE79
  J9U1  100 DQS13N SCONN288_H44441003_PIP-SCONN,HA   I101 @BASEBOARD_FAB2_LIB.BASEBOARD_FAB2(SCH_1):PAGE80

M_H_DQS_DN<14> @BASEBOARD_FAB2_LIB.BASEBOARD_FAB2(SCH_1):M_H_DQS_DN(14)
  U2D1  A34 DDR1_DQS_DN<14> SKX_EXT_B_BGA1-IC,TBD   I172 @BASEBOARD_FAB2_LIB.BASEBOARD_FAB2(SCH_1):PAGE58
  J1G2  111 DQS14N SCONN288_H44441004_PIP-SCONN,HA    I64 @BASEBOARD_FAB2_LIB.BASEBOARD_FAB2(SCH_1):PAGE79
  J9U1  111 DQS14N SCONN288_H44441003_PIP-SCONN,HA   I101 @BASEBOARD_FAB2_LIB.BASEBOARD_FAB2(SCH_1):PAGE80

M_H_DQS_DN<15> @BASEBOARD_FAB2_LIB.BASEBOARD_FAB2(SCH_1):M_H_DQS_DN(15)
  U2D1  A28 DDR1_DQS_DN<15> SKX_EXT_B_BGA1-IC,TBD   I172 @BASEBOARD_FAB2_LIB.BASEBOARD_FAB2(SCH_1):PAGE58
  J1G2  122 DQS15N SCONN288_H44441004_PIP-SCONN,HA    I64 @BASEBOARD_FAB2_LIB.BASEBOARD_FAB2(SCH_1):PAGE79
  J9U1  122 DQS15N SCONN288_H44441003_PIP-SCONN,HA   I101 @BASEBOARD_FAB2_LIB.BASEBOARD_FAB2(SCH_1):PAGE80

M_H_DQS_DN<16> @BASEBOARD_FAB2_LIB.BASEBOARD_FAB2(SCH_1):M_H_DQS_DN(16)
  U2D1  T27 DDR1_DQS_DN<16> SKX_EXT_B_BGA1-IC,TBD   I172 @BASEBOARD_FAB2_LIB.BASEBOARD_FAB2(SCH_1):PAGE58
  J1G2  133 DQS16N SCONN288_H44441004_PIP-SCONN,HA    I64 @BASEBOARD_FAB2_LIB.BASEBOARD_FAB2(SCH_1):PAGE79
  J9U1  133 DQS16N SCONN288_H44441003_PIP-SCONN,HA   I101 @BASEBOARD_FAB2_LIB.BASEBOARD_FAB2(SCH_1):PAGE80

M_H_DQS_DN<17> @BASEBOARD_FAB2_LIB.BASEBOARD_FAB2(SCH_1):M_H_DQS_DN(17)
  U2D1  G68 DDR1_DQS_DN<17> SKX_EXT_B_BGA1-IC,TBD   I172 @BASEBOARD_FAB2_LIB.BASEBOARD_FAB2(SCH_1):PAGE58
  J1G2   52 DQS17N SCONN288_H44441004_PIP-SCONN,HA    I64 @BASEBOARD_FAB2_LIB.BASEBOARD_FAB2(SCH_1):PAGE79
  J9U1   52 DQS17N SCONN288_H44441003_PIP-SCONN,HA   I101 @BASEBOARD_FAB2_LIB.BASEBOARD_FAB2(SCH_1):PAGE80

M_H_DQS_DN<1> @BASEBOARD_FAB2_LIB.BASEBOARD_FAB2(SCH_1):M_H_DQS_DN(1)
  U2D1 AD79 DDR1_DQS_DN<1> SKX_EXT_B_BGA1-IC,TBD   I172 @BASEBOARD_FAB2_LIB.BASEBOARD_FAB2(SCH_1):PAGE58
  J1G2  163  DQS1N SCONN288_H44441004_PIP-SCONN,HA    I64 @BASEBOARD_FAB2_LIB.BASEBOARD_FAB2(SCH_1):PAGE79
  J9U1  163  DQS1N SCONN288_H44441003_PIP-SCONN,HA   I101 @BASEBOARD_FAB2_LIB.BASEBOARD_FAB2(SCH_1):PAGE80

M_H_DQS_DN<2> @BASEBOARD_FAB2_LIB.BASEBOARD_FAB2(SCH_1):M_H_DQS_DN(2)
  U2D1  K79 DDR1_DQS_DN<2> SKX_EXT_B_BGA1-IC,TBD   I172 @BASEBOARD_FAB2_LIB.BASEBOARD_FAB2(SCH_1):PAGE58
  J1G2  174  DQS2N SCONN288_H44441004_PIP-SCONN,HA    I64 @BASEBOARD_FAB2_LIB.BASEBOARD_FAB2(SCH_1):PAGE79
  J9U1  174  DQS2N SCONN288_H44441003_PIP-SCONN,HA   I101 @BASEBOARD_FAB2_LIB.BASEBOARD_FAB2(SCH_1):PAGE80

M_H_DQS_DN<3> @BASEBOARD_FAB2_LIB.BASEBOARD_FAB2(SCH_1):M_H_DQS_DN(3)
  U2D1  H73 DDR1_DQS_DN<3> SKX_EXT_B_BGA1-IC,TBD   I172 @BASEBOARD_FAB2_LIB.BASEBOARD_FAB2(SCH_1):PAGE58
  J1G2  185  DQS3N SCONN288_H44441004_PIP-SCONN,HA    I64 @BASEBOARD_FAB2_LIB.BASEBOARD_FAB2(SCH_1):PAGE79
  J9U1  185  DQS3N SCONN288_H44441003_PIP-SCONN,HA   I101 @BASEBOARD_FAB2_LIB.BASEBOARD_FAB2(SCH_1):PAGE80

M_H_DQS_DN<4> @BASEBOARD_FAB2_LIB.BASEBOARD_FAB2(SCH_1):M_H_DQS_DN(4)
  U2D1  N42 DDR1_DQS_DN<4> SKX_EXT_B_BGA1-IC,TBD   I172 @BASEBOARD_FAB2_LIB.BASEBOARD_FAB2(SCH_1):PAGE58
  J1G2  244  DQS4N SCONN288_H44441004_PIP-SCONN,HA    I64 @BASEBOARD_FAB2_LIB.BASEBOARD_FAB2(SCH_1):PAGE79
  J9U1  244  DQS4N SCONN288_H44441003_PIP-SCONN,HA   I101 @BASEBOARD_FAB2_LIB.BASEBOARD_FAB2(SCH_1):PAGE80

M_H_DQS_DN<5> @BASEBOARD_FAB2_LIB.BASEBOARD_FAB2(SCH_1):M_H_DQS_DN(5)
  U2D1  G34 DDR1_DQS_DN<5> SKX_EXT_B_BGA1-IC,TBD   I172 @BASEBOARD_FAB2_LIB.BASEBOARD_FAB2(SCH_1):PAGE58
  J1G2  255  DQS5N SCONN288_H44441004_PIP-SCONN,HA    I64 @BASEBOARD_FAB2_LIB.BASEBOARD_FAB2(SCH_1):PAGE79
  J9U1  255  DQS5N SCONN288_H44441003_PIP-SCONN,HA   I101 @BASEBOARD_FAB2_LIB.BASEBOARD_FAB2(SCH_1):PAGE80

M_H_DQS_DN<6> @BASEBOARD_FAB2_LIB.BASEBOARD_FAB2(SCH_1):M_H_DQS_DN(6)
  U2D1  G28 DDR1_DQS_DN<6> SKX_EXT_B_BGA1-IC,TBD   I172 @BASEBOARD_FAB2_LIB.BASEBOARD_FAB2(SCH_1):PAGE58
  J1G2  266  DQS6N SCONN288_H44441004_PIP-SCONN,HA    I64 @BASEBOARD_FAB2_LIB.BASEBOARD_FAB2(SCH_1):PAGE79
  J9U1  266  DQS6N SCONN288_H44441003_PIP-SCONN,HA   I101 @BASEBOARD_FAB2_LIB.BASEBOARD_FAB2(SCH_1):PAGE80

M_H_DQS_DN<7> @BASEBOARD_FAB2_LIB.BASEBOARD_FAB2(SCH_1):M_H_DQS_DN(7)
  U2D1 AB27 DDR1_DQS_DN<7> SKX_EXT_B_BGA1-IC,TBD   I172 @BASEBOARD_FAB2_LIB.BASEBOARD_FAB2(SCH_1):PAGE58
  J1G2  277  DQS7N SCONN288_H44441004_PIP-SCONN,HA    I64 @BASEBOARD_FAB2_LIB.BASEBOARD_FAB2(SCH_1):PAGE79
  J9U1  277  DQS7N SCONN288_H44441003_PIP-SCONN,HA   I101 @BASEBOARD_FAB2_LIB.BASEBOARD_FAB2(SCH_1):PAGE80

M_H_DQS_DN<8> @BASEBOARD_FAB2_LIB.BASEBOARD_FAB2(SCH_1):M_H_DQS_DN(8)
  U2D1  N68 DDR1_DQS_DN<8> SKX_EXT_B_BGA1-IC,TBD   I172 @BASEBOARD_FAB2_LIB.BASEBOARD_FAB2(SCH_1):PAGE58
  J1G2  196  DQS8N SCONN288_H44441004_PIP-SCONN,HA    I64 @BASEBOARD_FAB2_LIB.BASEBOARD_FAB2(SCH_1):PAGE79
  J9U1  196  DQS8N SCONN288_H44441003_PIP-SCONN,HA   I101 @BASEBOARD_FAB2_LIB.BASEBOARD_FAB2(SCH_1):PAGE80

M_H_DQS_DN<9> @BASEBOARD_FAB2_LIB.BASEBOARD_FAB2(SCH_1):M_H_DQS_DN(9)
  U2D1 AU82 DDR1_DQS_DN<9> SKX_EXT_B_BGA1-IC,TBD   I172 @BASEBOARD_FAB2_LIB.BASEBOARD_FAB2(SCH_1):PAGE58
  J1G2    8  DQS9N SCONN288_H44441004_PIP-SCONN,HA    I64 @BASEBOARD_FAB2_LIB.BASEBOARD_FAB2(SCH_1):PAGE79
  J9U1    8  DQS9N SCONN288_H44441003_PIP-SCONN,HA   I101 @BASEBOARD_FAB2_LIB.BASEBOARD_FAB2(SCH_1):PAGE80

M_H_DQS_DP<0> @BASEBOARD_FAB2_LIB.BASEBOARD_FAB2(SCH_1):M_H_DQS_DP(0)
  U2D1 AR80 DDR1_DQS_DP<0> SKX_EXT_B_BGA1-IC,TBD   I172 @BASEBOARD_FAB2_LIB.BASEBOARD_FAB2(SCH_1):PAGE58
  J1G2  153  DQS0P SCONN288_H44441004_PIP-SCONN,HA    I64 @BASEBOARD_FAB2_LIB.BASEBOARD_FAB2(SCH_1):PAGE79
  J9U1  153  DQS0P SCONN288_H44441003_PIP-SCONN,HA   I101 @BASEBOARD_FAB2_LIB.BASEBOARD_FAB2(SCH_1):PAGE80

M_H_DQS_DP<10> @BASEBOARD_FAB2_LIB.BASEBOARD_FAB2(SCH_1):M_H_DQS_DP(10)
  U2D1 AF81 DDR1_DQS_DP<10> SKX_EXT_B_BGA1-IC,TBD   I172 @BASEBOARD_FAB2_LIB.BASEBOARD_FAB2(SCH_1):PAGE58
  J1G2   18 DQS10P SCONN288_H44441004_PIP-SCONN,HA    I64 @BASEBOARD_FAB2_LIB.BASEBOARD_FAB2(SCH_1):PAGE79
  J9U1   18 DQS10P SCONN288_H44441003_PIP-SCONN,HA   I101 @BASEBOARD_FAB2_LIB.BASEBOARD_FAB2(SCH_1):PAGE80

M_H_DQS_DP<11> @BASEBOARD_FAB2_LIB.BASEBOARD_FAB2(SCH_1):M_H_DQS_DP(11)
  U2D1  F79 DDR1_DQS_DP<11> SKX_EXT_B_BGA1-IC,TBD   I172 @BASEBOARD_FAB2_LIB.BASEBOARD_FAB2(SCH_1):PAGE58
  J1G2   29 DQS11P SCONN288_H44441004_PIP-SCONN,HA    I64 @BASEBOARD_FAB2_LIB.BASEBOARD_FAB2(SCH_1):PAGE79
  J9U1   29 DQS11P SCONN288_H44441003_PIP-SCONN,HA   I101 @BASEBOARD_FAB2_LIB.BASEBOARD_FAB2(SCH_1):PAGE80

M_H_DQS_DP<12> @BASEBOARD_FAB2_LIB.BASEBOARD_FAB2(SCH_1):M_H_DQS_DP(12)
  U2D1  D73 DDR1_DQS_DP<12> SKX_EXT_B_BGA1-IC,TBD   I172 @BASEBOARD_FAB2_LIB.BASEBOARD_FAB2(SCH_1):PAGE58
  J1G2   40 DQS12P SCONN288_H44441004_PIP-SCONN,HA    I64 @BASEBOARD_FAB2_LIB.BASEBOARD_FAB2(SCH_1):PAGE79
  J9U1   40 DQS12P SCONN288_H44441003_PIP-SCONN,HA   I101 @BASEBOARD_FAB2_LIB.BASEBOARD_FAB2(SCH_1):PAGE80

M_H_DQS_DP<13> @BASEBOARD_FAB2_LIB.BASEBOARD_FAB2(SCH_1):M_H_DQS_DP(13)
  U2D1  L42 DDR1_DQS_DP<13> SKX_EXT_B_BGA1-IC,TBD   I172 @BASEBOARD_FAB2_LIB.BASEBOARD_FAB2(SCH_1):PAGE58
  J1G2   99 DQS13P SCONN288_H44441004_PIP-SCONN,HA    I64 @BASEBOARD_FAB2_LIB.BASEBOARD_FAB2(SCH_1):PAGE79
  J9U1   99 DQS13P SCONN288_H44441003_PIP-SCONN,HA   I101 @BASEBOARD_FAB2_LIB.BASEBOARD_FAB2(SCH_1):PAGE80

M_H_DQS_DP<14> @BASEBOARD_FAB2_LIB.BASEBOARD_FAB2(SCH_1):M_H_DQS_DP(14)
  U2D1  C34 DDR1_DQS_DP<14> SKX_EXT_B_BGA1-IC,TBD   I172 @BASEBOARD_FAB2_LIB.BASEBOARD_FAB2(SCH_1):PAGE58
  J1G2  110 DQS14P SCONN288_H44441004_PIP-SCONN,HA    I64 @BASEBOARD_FAB2_LIB.BASEBOARD_FAB2(SCH_1):PAGE79
  J9U1  110 DQS14P SCONN288_H44441003_PIP-SCONN,HA   I101 @BASEBOARD_FAB2_LIB.BASEBOARD_FAB2(SCH_1):PAGE80

M_H_DQS_DP<15> @BASEBOARD_FAB2_LIB.BASEBOARD_FAB2(SCH_1):M_H_DQS_DP(15)
  U2D1  C28 DDR1_DQS_DP<15> SKX_EXT_B_BGA1-IC,TBD   I172 @BASEBOARD_FAB2_LIB.BASEBOARD_FAB2(SCH_1):PAGE58
  J1G2  121 DQS15P SCONN288_H44441004_PIP-SCONN,HA    I64 @BASEBOARD_FAB2_LIB.BASEBOARD_FAB2(SCH_1):PAGE79
  J9U1  121 DQS15P SCONN288_H44441003_PIP-SCONN,HA   I101 @BASEBOARD_FAB2_LIB.BASEBOARD_FAB2(SCH_1):PAGE80

M_H_DQS_DP<16> @BASEBOARD_FAB2_LIB.BASEBOARD_FAB2(SCH_1):M_H_DQS_DP(16)
  U2D1  V27 DDR1_DQS_DP<16> SKX_EXT_B_BGA1-IC,TBD   I172 @BASEBOARD_FAB2_LIB.BASEBOARD_FAB2(SCH_1):PAGE58
  J1G2  132 DQS16P SCONN288_H44441004_PIP-SCONN,HA    I64 @BASEBOARD_FAB2_LIB.BASEBOARD_FAB2(SCH_1):PAGE79
  J9U1  132 DQS16P SCONN288_H44441003_PIP-SCONN,HA   I101 @BASEBOARD_FAB2_LIB.BASEBOARD_FAB2(SCH_1):PAGE80

M_H_DQS_DP<17> @BASEBOARD_FAB2_LIB.BASEBOARD_FAB2(SCH_1):M_H_DQS_DP(17)
  U2D1  J68 DDR1_DQS_DP<17> SKX_EXT_B_BGA1-IC,TBD   I172 @BASEBOARD_FAB2_LIB.BASEBOARD_FAB2(SCH_1):PAGE58
  J1G2   51 DQS17P SCONN288_H44441004_PIP-SCONN,HA    I64 @BASEBOARD_FAB2_LIB.BASEBOARD_FAB2(SCH_1):PAGE79
  J9U1   51 DQS17P SCONN288_H44441003_PIP-SCONN,HA   I101 @BASEBOARD_FAB2_LIB.BASEBOARD_FAB2(SCH_1):PAGE80

M_H_DQS_DP<1> @BASEBOARD_FAB2_LIB.BASEBOARD_FAB2(SCH_1):M_H_DQS_DP(1)
  U2D1 AE80 DDR1_DQS_DP<1> SKX_EXT_B_BGA1-IC,TBD   I172 @BASEBOARD_FAB2_LIB.BASEBOARD_FAB2(SCH_1):PAGE58
  J1G2  164  DQS1P SCONN288_H44441004_PIP-SCONN,HA    I64 @BASEBOARD_FAB2_LIB.BASEBOARD_FAB2(SCH_1):PAGE79
  J9U1  164  DQS1P SCONN288_H44441003_PIP-SCONN,HA   I101 @BASEBOARD_FAB2_LIB.BASEBOARD_FAB2(SCH_1):PAGE80

M_H_DQS_DP<2> @BASEBOARD_FAB2_LIB.BASEBOARD_FAB2(SCH_1):M_H_DQS_DP(2)
  U2D1  H79 DDR1_DQS_DP<2> SKX_EXT_B_BGA1-IC,TBD   I172 @BASEBOARD_FAB2_LIB.BASEBOARD_FAB2(SCH_1):PAGE58
  J1G2  175  DQS2P SCONN288_H44441004_PIP-SCONN,HA    I64 @BASEBOARD_FAB2_LIB.BASEBOARD_FAB2(SCH_1):PAGE79
  J9U1  175  DQS2P SCONN288_H44441003_PIP-SCONN,HA   I101 @BASEBOARD_FAB2_LIB.BASEBOARD_FAB2(SCH_1):PAGE80

M_H_DQS_DP<3> @BASEBOARD_FAB2_LIB.BASEBOARD_FAB2(SCH_1):M_H_DQS_DP(3)
  U2D1  F73 DDR1_DQS_DP<3> SKX_EXT_B_BGA1-IC,TBD   I172 @BASEBOARD_FAB2_LIB.BASEBOARD_FAB2(SCH_1):PAGE58
  J1G2  186  DQS3P SCONN288_H44441004_PIP-SCONN,HA    I64 @BASEBOARD_FAB2_LIB.BASEBOARD_FAB2(SCH_1):PAGE79
  J9U1  186  DQS3P SCONN288_H44441003_PIP-SCONN,HA   I101 @BASEBOARD_FAB2_LIB.BASEBOARD_FAB2(SCH_1):PAGE80

M_H_DQS_DP<4> @BASEBOARD_FAB2_LIB.BASEBOARD_FAB2(SCH_1):M_H_DQS_DP(4)
  U2D1  R42 DDR1_DQS_DP<4> SKX_EXT_B_BGA1-IC,TBD   I172 @BASEBOARD_FAB2_LIB.BASEBOARD_FAB2(SCH_1):PAGE58
  J1G2  245  DQS4P SCONN288_H44441004_PIP-SCONN,HA    I64 @BASEBOARD_FAB2_LIB.BASEBOARD_FAB2(SCH_1):PAGE79
  J9U1  245  DQS4P SCONN288_H44441003_PIP-SCONN,HA   I101 @BASEBOARD_FAB2_LIB.BASEBOARD_FAB2(SCH_1):PAGE80

M_H_DQS_DP<5> @BASEBOARD_FAB2_LIB.BASEBOARD_FAB2(SCH_1):M_H_DQS_DP(5)
  U2D1  E34 DDR1_DQS_DP<5> SKX_EXT_B_BGA1-IC,TBD   I172 @BASEBOARD_FAB2_LIB.BASEBOARD_FAB2(SCH_1):PAGE58
  J1G2  256  DQS5P SCONN288_H44441004_PIP-SCONN,HA    I64 @BASEBOARD_FAB2_LIB.BASEBOARD_FAB2(SCH_1):PAGE79
  J9U1  256  DQS5P SCONN288_H44441003_PIP-SCONN,HA   I101 @BASEBOARD_FAB2_LIB.BASEBOARD_FAB2(SCH_1):PAGE80

M_H_DQS_DP<6> @BASEBOARD_FAB2_LIB.BASEBOARD_FAB2(SCH_1):M_H_DQS_DP(6)
  U2D1  E28 DDR1_DQS_DP<6> SKX_EXT_B_BGA1-IC,TBD   I172 @BASEBOARD_FAB2_LIB.BASEBOARD_FAB2(SCH_1):PAGE58
  J1G2  267  DQS6P SCONN288_H44441004_PIP-SCONN,HA    I64 @BASEBOARD_FAB2_LIB.BASEBOARD_FAB2(SCH_1):PAGE79
  J9U1  267  DQS6P SCONN288_H44441003_PIP-SCONN,HA   I101 @BASEBOARD_FAB2_LIB.BASEBOARD_FAB2(SCH_1):PAGE80

M_H_DQS_DP<7> @BASEBOARD_FAB2_LIB.BASEBOARD_FAB2(SCH_1):M_H_DQS_DP(7)
  U2D1  Y27 DDR1_DQS_DP<7> SKX_EXT_B_BGA1-IC,TBD   I172 @BASEBOARD_FAB2_LIB.BASEBOARD_FAB2(SCH_1):PAGE58
  J1G2  278  DQS7P SCONN288_H44441004_PIP-SCONN,HA    I64 @BASEBOARD_FAB2_LIB.BASEBOARD_FAB2(SCH_1):PAGE79
  J9U1  278  DQS7P SCONN288_H44441003_PIP-SCONN,HA   I101 @BASEBOARD_FAB2_LIB.BASEBOARD_FAB2(SCH_1):PAGE80

M_H_DQS_DP<8> @BASEBOARD_FAB2_LIB.BASEBOARD_FAB2(SCH_1):M_H_DQS_DP(8)
  U2D1  L68 DDR1_DQS_DP<8> SKX_EXT_B_BGA1-IC,TBD   I172 @BASEBOARD_FAB2_LIB.BASEBOARD_FAB2(SCH_1):PAGE58
  J1G2  197  DQS8P SCONN288_H44441004_PIP-SCONN,HA    I64 @BASEBOARD_FAB2_LIB.BASEBOARD_FAB2(SCH_1):PAGE79
  J9U1  197  DQS8P SCONN288_H44441003_PIP-SCONN,HA   I101 @BASEBOARD_FAB2_LIB.BASEBOARD_FAB2(SCH_1):PAGE80

M_H_DQS_DP<9> @BASEBOARD_FAB2_LIB.BASEBOARD_FAB2(SCH_1):M_H_DQS_DP(9)
  U2D1 AT81 DDR1_DQS_DP<9> SKX_EXT_B_BGA1-IC,TBD   I172 @BASEBOARD_FAB2_LIB.BASEBOARD_FAB2(SCH_1):PAGE58
  J1G2    7  DQS9P SCONN288_H44441004_PIP-SCONN,HA    I64 @BASEBOARD_FAB2_LIB.BASEBOARD_FAB2(SCH_1):PAGE79
  J9U1    7  DQS9P SCONN288_H44441003_PIP-SCONN,HA   I101 @BASEBOARD_FAB2_LIB.BASEBOARD_FAB2(SCH_1):PAGE80

M_H_ECC<0> @BASEBOARD_FAB2_LIB.BASEBOARD_FAB2(SCH_1):M_H_ECC(0)
  U2D1  J70 DDR1_ECC<0> SKX_EXT_B_BGA1-IC,TBD   I172 @BASEBOARD_FAB2_LIB.BASEBOARD_FAB2(SCH_1):PAGE58
  J1G2  194  CB<1> SCONN288_H44441004_PIP-SCONN,HA   I111 @BASEBOARD_FAB2_LIB.BASEBOARD_FAB2(SCH_1):PAGE79
  J9U1   49  CB<0> SCONN288_H44441003_PIP-SCONN,HA    I24 @BASEBOARD_FAB2_LIB.BASEBOARD_FAB2(SCH_1):PAGE80

M_H_ECC<1> @BASEBOARD_FAB2_LIB.BASEBOARD_FAB2(SCH_1):M_H_ECC(1)
  U2D1  H69 DDR1_ECC<1> SKX_EXT_B_BGA1-IC,TBD   I172 @BASEBOARD_FAB2_LIB.BASEBOARD_FAB2(SCH_1):PAGE58
  J1G2   49  CB<0> SCONN288_H44441004_PIP-SCONN,HA   I111 @BASEBOARD_FAB2_LIB.BASEBOARD_FAB2(SCH_1):PAGE79
  J9U1  194  CB<1> SCONN288_H44441003_PIP-SCONN,HA    I24 @BASEBOARD_FAB2_LIB.BASEBOARD_FAB2(SCH_1):PAGE80

M_H_ECC<2> @BASEBOARD_FAB2_LIB.BASEBOARD_FAB2(SCH_1):M_H_ECC(2)
  U2D1  J66 DDR1_ECC<2> SKX_EXT_B_BGA1-IC,TBD   I172 @BASEBOARD_FAB2_LIB.BASEBOARD_FAB2(SCH_1):PAGE58
  J1G2  201  CB<3> SCONN288_H44441004_PIP-SCONN,HA   I111 @BASEBOARD_FAB2_LIB.BASEBOARD_FAB2(SCH_1):PAGE79
  J9U1   56  CB<2> SCONN288_H44441003_PIP-SCONN,HA    I24 @BASEBOARD_FAB2_LIB.BASEBOARD_FAB2(SCH_1):PAGE80

M_H_ECC<3> @BASEBOARD_FAB2_LIB.BASEBOARD_FAB2(SCH_1):M_H_ECC(3)
  U2D1  L66 DDR1_ECC<3> SKX_EXT_B_BGA1-IC,TBD   I172 @BASEBOARD_FAB2_LIB.BASEBOARD_FAB2(SCH_1):PAGE58
  J1G2   56  CB<2> SCONN288_H44441004_PIP-SCONN,HA   I111 @BASEBOARD_FAB2_LIB.BASEBOARD_FAB2(SCH_1):PAGE79
  J9U1  201  CB<3> SCONN288_H44441003_PIP-SCONN,HA    I24 @BASEBOARD_FAB2_LIB.BASEBOARD_FAB2(SCH_1):PAGE80

M_H_ECC<4> @BASEBOARD_FAB2_LIB.BASEBOARD_FAB2(SCH_1):M_H_ECC(4)
  U2D1  L70 DDR1_ECC<4> SKX_EXT_B_BGA1-IC,TBD   I172 @BASEBOARD_FAB2_LIB.BASEBOARD_FAB2(SCH_1):PAGE58
  J1G2  192  CB<5> SCONN288_H44441004_PIP-SCONN,HA   I111 @BASEBOARD_FAB2_LIB.BASEBOARD_FAB2(SCH_1):PAGE79
  J9U1   47  CB<4> SCONN288_H44441003_PIP-SCONN,HA    I24 @BASEBOARD_FAB2_LIB.BASEBOARD_FAB2(SCH_1):PAGE80

M_H_ECC<5> @BASEBOARD_FAB2_LIB.BASEBOARD_FAB2(SCH_1):M_H_ECC(5)
  U2D1  M69 DDR1_ECC<5> SKX_EXT_B_BGA1-IC,TBD   I172 @BASEBOARD_FAB2_LIB.BASEBOARD_FAB2(SCH_1):PAGE58
  J1G2   47  CB<4> SCONN288_H44441004_PIP-SCONN,HA   I111 @BASEBOARD_FAB2_LIB.BASEBOARD_FAB2(SCH_1):PAGE79
  J9U1  192  CB<5> SCONN288_H44441003_PIP-SCONN,HA    I24 @BASEBOARD_FAB2_LIB.BASEBOARD_FAB2(SCH_1):PAGE80

M_H_ECC<6> @BASEBOARD_FAB2_LIB.BASEBOARD_FAB2(SCH_1):M_H_ECC(6)
  U2D1  H67 DDR1_ECC<6> SKX_EXT_B_BGA1-IC,TBD   I172 @BASEBOARD_FAB2_LIB.BASEBOARD_FAB2(SCH_1):PAGE58
  J1G2  199  CB<7> SCONN288_H44441004_PIP-SCONN,HA   I111 @BASEBOARD_FAB2_LIB.BASEBOARD_FAB2(SCH_1):PAGE79
  J9U1   54  CB<6> SCONN288_H44441003_PIP-SCONN,HA    I24 @BASEBOARD_FAB2_LIB.BASEBOARD_FAB2(SCH_1):PAGE80

M_H_ECC<7> @BASEBOARD_FAB2_LIB.BASEBOARD_FAB2(SCH_1):M_H_ECC(7)
  U2D1  M67 DDR1_ECC<7> SKX_EXT_B_BGA1-IC,TBD   I172 @BASEBOARD_FAB2_LIB.BASEBOARD_FAB2(SCH_1):PAGE58
  J1G2   54  CB<6> SCONN288_H44441004_PIP-SCONN,HA   I111 @BASEBOARD_FAB2_LIB.BASEBOARD_FAB2(SCH_1):PAGE79
  J9U1  199  CB<7> SCONN288_H44441003_PIP-SCONN,HA    I24 @BASEBOARD_FAB2_LIB.BASEBOARD_FAB2(SCH_1):PAGE80

M_H_MA<0> @BASEBOARD_FAB2_LIB.BASEBOARD_FAB2(SCH_1):M_H_MA(0)
  U2D1  J52 DDR1_MA<0> SKX_EXT_B_BGA1-IC,TBD   I172 @BASEBOARD_FAB2_LIB.BASEBOARD_FAB2(SCH_1):PAGE58
  J1G2   79     A0 SCONN288_H44441004_PIP-SCONN,HA   I111 @BASEBOARD_FAB2_LIB.BASEBOARD_FAB2(SCH_1):PAGE79
  J9U1   79     A0 SCONN288_H44441003_PIP-SCONN,HA    I24 @BASEBOARD_FAB2_LIB.BASEBOARD_FAB2(SCH_1):PAGE80

M_H_MA<10> @BASEBOARD_FAB2_LIB.BASEBOARD_FAB2(SCH_1):M_H_MA(10)
  U2D1  M55 DDR1_MA<10> SKX_EXT_B_BGA1-IC,TBD   I172 @BASEBOARD_FAB2_LIB.BASEBOARD_FAB2(SCH_1):PAGE58
  J1G2  225    A10 SCONN288_H44441004_PIP-SCONN,HA   I111 @BASEBOARD_FAB2_LIB.BASEBOARD_FAB2(SCH_1):PAGE79
  J9U1  225    A10 SCONN288_H44441003_PIP-SCONN,HA    I24 @BASEBOARD_FAB2_LIB.BASEBOARD_FAB2(SCH_1):PAGE80

M_H_MA<11> @BASEBOARD_FAB2_LIB.BASEBOARD_FAB2(SCH_1):M_H_MA(11)
  U2D1  R60 DDR1_MA<11> SKX_EXT_B_BGA1-IC,TBD   I172 @BASEBOARD_FAB2_LIB.BASEBOARD_FAB2(SCH_1):PAGE58
  J1G2  210    A11 SCONN288_H44441004_PIP-SCONN,HA   I111 @BASEBOARD_FAB2_LIB.BASEBOARD_FAB2(SCH_1):PAGE79
  J9U1  210    A11 SCONN288_H44441003_PIP-SCONN,HA    I24 @BASEBOARD_FAB2_LIB.BASEBOARD_FAB2(SCH_1):PAGE80

M_H_MA<12> @BASEBOARD_FAB2_LIB.BASEBOARD_FAB2(SCH_1):M_H_MA(12)
  U2D1  T61 DDR1_MA<12> SKX_EXT_B_BGA1-IC,TBD   I172 @BASEBOARD_FAB2_LIB.BASEBOARD_FAB2(SCH_1):PAGE58
  J1G2   65    A12 SCONN288_H44441004_PIP-SCONN,HA   I111 @BASEBOARD_FAB2_LIB.BASEBOARD_FAB2(SCH_1):PAGE79
  J9U1   65    A12 SCONN288_H44441003_PIP-SCONN,HA    I24 @BASEBOARD_FAB2_LIB.BASEBOARD_FAB2(SCH_1):PAGE80

M_H_MA<13> @BASEBOARD_FAB2_LIB.BASEBOARD_FAB2(SCH_1):M_H_MA(13)
  U2D1  M51 DDR1_MA<13> SKX_EXT_B_BGA1-IC,TBD   I172 @BASEBOARD_FAB2_LIB.BASEBOARD_FAB2(SCH_1):PAGE58
  J1G2  232    A13 SCONN288_H44441004_PIP-SCONN,HA   I111 @BASEBOARD_FAB2_LIB.BASEBOARD_FAB2(SCH_1):PAGE79
  J9U1  232    A13 SCONN288_H44441003_PIP-SCONN,HA    I24 @BASEBOARD_FAB2_LIB.BASEBOARD_FAB2(SCH_1):PAGE80

M_H_MA<14> @BASEBOARD_FAB2_LIB.BASEBOARD_FAB2(SCH_1):M_H_MA(14)
  U2D1  T51 DDR1_MA<14> SKX_EXT_B_BGA1-IC,TBD   I172 @BASEBOARD_FAB2_LIB.BASEBOARD_FAB2(SCH_1):PAGE58
  J1G2  228 A14_WE_N SCONN288_H44441004_PIP-SCONN,HA   I111 @BASEBOARD_FAB2_LIB.BASEBOARD_FAB2(SCH_1):PAGE79
  J9U1  228 A14_WE_N SCONN288_H44441003_PIP-SCONN,HA    I24 @BASEBOARD_FAB2_LIB.BASEBOARD_FAB2(SCH_1):PAGE80

M_H_MA<15> @BASEBOARD_FAB2_LIB.BASEBOARD_FAB2(SCH_1):M_H_MA(15)
  U2D1  N52 DDR1_MA<15> SKX_EXT_B_BGA1-IC,TBD   I172 @BASEBOARD_FAB2_LIB.BASEBOARD_FAB2(SCH_1):PAGE58
  J1G2   86 A15_CAS_N SCONN288_H44441004_PIP-SCONN,HA   I111 @BASEBOARD_FAB2_LIB.BASEBOARD_FAB2(SCH_1):PAGE79
  J9U1   86 A15_CAS_N SCONN288_H44441003_PIP-SCONN,HA    I24 @BASEBOARD_FAB2_LIB.BASEBOARD_FAB2(SCH_1):PAGE80

M_H_MA<16> @BASEBOARD_FAB2_LIB.BASEBOARD_FAB2(SCH_1):M_H_MA(16)
  U2D1  R52 DDR1_MA<16> SKX_EXT_B_BGA1-IC,TBD   I172 @BASEBOARD_FAB2_LIB.BASEBOARD_FAB2(SCH_1):PAGE58
  J1G2   82 A16_RAS_N SCONN288_H44441004_PIP-SCONN,HA   I111 @BASEBOARD_FAB2_LIB.BASEBOARD_FAB2(SCH_1):PAGE79
  J9U1   82 A16_RAS_N SCONN288_H44441003_PIP-SCONN,HA    I24 @BASEBOARD_FAB2_LIB.BASEBOARD_FAB2(SCH_1):PAGE80

M_H_MA<17> @BASEBOARD_FAB2_LIB.BASEBOARD_FAB2(SCH_1):M_H_MA(17)
  U2D1  N48 DDR1_MA<17> SKX_EXT_B_BGA1-IC,TBD   I172 @BASEBOARD_FAB2_LIB.BASEBOARD_FAB2(SCH_1):PAGE58
  J1G2  234    A17 SCONN288_H44441004_PIP-SCONN,HA   I111 @BASEBOARD_FAB2_LIB.BASEBOARD_FAB2(SCH_1):PAGE79
  J9U1  234    A17 SCONN288_H44441003_PIP-SCONN,HA    I24 @BASEBOARD_FAB2_LIB.BASEBOARD_FAB2(SCH_1):PAGE80

M_H_MA<1> @BASEBOARD_FAB2_LIB.BASEBOARD_FAB2(SCH_1):M_H_MA(1)
  U2D1  J58 DDR1_MA<1> SKX_EXT_B_BGA1-IC,TBD   I172 @BASEBOARD_FAB2_LIB.BASEBOARD_FAB2(SCH_1):PAGE58
  J1G2   72     A1 SCONN288_H44441004_PIP-SCONN,HA   I111 @BASEBOARD_FAB2_LIB.BASEBOARD_FAB2(SCH_1):PAGE79
  J9U1   72     A1 SCONN288_H44441003_PIP-SCONN,HA    I24 @BASEBOARD_FAB2_LIB.BASEBOARD_FAB2(SCH_1):PAGE80

M_H_MA<2> @BASEBOARD_FAB2_LIB.BASEBOARD_FAB2(SCH_1):M_H_MA(2)
  U2D1  K57 DDR1_MA<2> SKX_EXT_B_BGA1-IC,TBD   I172 @BASEBOARD_FAB2_LIB.BASEBOARD_FAB2(SCH_1):PAGE58
  J1G2  216     A2 SCONN288_H44441004_PIP-SCONN,HA   I111 @BASEBOARD_FAB2_LIB.BASEBOARD_FAB2(SCH_1):PAGE79
  J9U1  216     A2 SCONN288_H44441003_PIP-SCONN,HA    I24 @BASEBOARD_FAB2_LIB.BASEBOARD_FAB2(SCH_1):PAGE80

M_H_MA<3> @BASEBOARD_FAB2_LIB.BASEBOARD_FAB2(SCH_1):M_H_MA(3)
  U2D1  N58 DDR1_MA<3> SKX_EXT_B_BGA1-IC,TBD   I172 @BASEBOARD_FAB2_LIB.BASEBOARD_FAB2(SCH_1):PAGE58
  J1G2   71     A3 SCONN288_H44441004_PIP-SCONN,HA   I111 @BASEBOARD_FAB2_LIB.BASEBOARD_FAB2(SCH_1):PAGE79
  J9U1   71     A3 SCONN288_H44441003_PIP-SCONN,HA    I24 @BASEBOARD_FAB2_LIB.BASEBOARD_FAB2(SCH_1):PAGE80

M_H_MA<4> @BASEBOARD_FAB2_LIB.BASEBOARD_FAB2(SCH_1):M_H_MA(4)
  U2D1  M59 DDR1_MA<4> SKX_EXT_B_BGA1-IC,TBD   I172 @BASEBOARD_FAB2_LIB.BASEBOARD_FAB2(SCH_1):PAGE58
  J1G2  214     A4 SCONN288_H44441004_PIP-SCONN,HA   I111 @BASEBOARD_FAB2_LIB.BASEBOARD_FAB2(SCH_1):PAGE79
  J9U1  214     A4 SCONN288_H44441003_PIP-SCONN,HA    I24 @BASEBOARD_FAB2_LIB.BASEBOARD_FAB2(SCH_1):PAGE80

M_H_MA<5> @BASEBOARD_FAB2_LIB.BASEBOARD_FAB2(SCH_1):M_H_MA(5)
  U2D1  R58 DDR1_MA<5> SKX_EXT_B_BGA1-IC,TBD   I172 @BASEBOARD_FAB2_LIB.BASEBOARD_FAB2(SCH_1):PAGE58
  J1G2  213     A5 SCONN288_H44441004_PIP-SCONN,HA   I111 @BASEBOARD_FAB2_LIB.BASEBOARD_FAB2(SCH_1):PAGE79
  J9U1  213     A5 SCONN288_H44441003_PIP-SCONN,HA    I24 @BASEBOARD_FAB2_LIB.BASEBOARD_FAB2(SCH_1):PAGE80

M_H_MA<6> @BASEBOARD_FAB2_LIB.BASEBOARD_FAB2(SCH_1):M_H_MA(6)
  U2D1  T59 DDR1_MA<6> SKX_EXT_B_BGA1-IC,TBD   I172 @BASEBOARD_FAB2_LIB.BASEBOARD_FAB2(SCH_1):PAGE58
  J1G2   69     A6 SCONN288_H44441004_PIP-SCONN,HA   I111 @BASEBOARD_FAB2_LIB.BASEBOARD_FAB2(SCH_1):PAGE79
  J9U1   69     A6 SCONN288_H44441003_PIP-SCONN,HA    I24 @BASEBOARD_FAB2_LIB.BASEBOARD_FAB2(SCH_1):PAGE80

M_H_MA<7> @BASEBOARD_FAB2_LIB.BASEBOARD_FAB2(SCH_1):M_H_MA(7)
  U2D1  V61 DDR1_MA<7> SKX_EXT_B_BGA1-IC,TBD   I172 @BASEBOARD_FAB2_LIB.BASEBOARD_FAB2(SCH_1):PAGE58
  J1G2  211     A7 SCONN288_H44441004_PIP-SCONN,HA   I111 @BASEBOARD_FAB2_LIB.BASEBOARD_FAB2(SCH_1):PAGE79
  J9U1  211     A7 SCONN288_H44441003_PIP-SCONN,HA    I24 @BASEBOARD_FAB2_LIB.BASEBOARD_FAB2(SCH_1):PAGE80

M_H_MA<8> @BASEBOARD_FAB2_LIB.BASEBOARD_FAB2(SCH_1):M_H_MA(8)
  U2D1  W60 DDR1_MA<8> SKX_EXT_B_BGA1-IC,TBD   I172 @BASEBOARD_FAB2_LIB.BASEBOARD_FAB2(SCH_1):PAGE58
  J1G2   68     A8 SCONN288_H44441004_PIP-SCONN,HA   I111 @BASEBOARD_FAB2_LIB.BASEBOARD_FAB2(SCH_1):PAGE79
  J9U1   68     A8 SCONN288_H44441003_PIP-SCONN,HA    I24 @BASEBOARD_FAB2_LIB.BASEBOARD_FAB2(SCH_1):PAGE80

M_H_MA<9> @BASEBOARD_FAB2_LIB.BASEBOARD_FAB2(SCH_1):M_H_MA(9)
  U2D1  K59 DDR1_MA<9> SKX_EXT_B_BGA1-IC,TBD   I172 @BASEBOARD_FAB2_LIB.BASEBOARD_FAB2(SCH_1):PAGE58
  J1G2   66     A9 SCONN288_H44441004_PIP-SCONN,HA   I111 @BASEBOARD_FAB2_LIB.BASEBOARD_FAB2(SCH_1):PAGE79
  J9U1   66     A9 SCONN288_H44441003_PIP-SCONN,HA    I24 @BASEBOARD_FAB2_LIB.BASEBOARD_FAB2(SCH_1):PAGE80

M_H_ODT<0> @BASEBOARD_FAB2_LIB.BASEBOARD_FAB2(SCH_1):M_H_ODT(0)
  U2D1  N50 DDR1_ODT<0> SKX_EXT_B_BGA1-IC,TBD   I172 @BASEBOARD_FAB2_LIB.BASEBOARD_FAB2(SCH_1):PAGE58
  J1G2   87 ODT<0> SCONN288_H44441004_PIP-SCONN,HA   I111 @BASEBOARD_FAB2_LIB.BASEBOARD_FAB2(SCH_1):PAGE79

M_H_ODT<1> @BASEBOARD_FAB2_LIB.BASEBOARD_FAB2(SCH_1):M_H_ODT(1)
  U2D1  R48 DDR1_ODT<1> SKX_EXT_B_BGA1-IC,TBD   I172 @BASEBOARD_FAB2_LIB.BASEBOARD_FAB2(SCH_1):PAGE58
  J1G2   91 ODT<1> SCONN288_H44441004_PIP-SCONN,HA   I111 @BASEBOARD_FAB2_LIB.BASEBOARD_FAB2(SCH_1):PAGE79

M_H_ODT<2> @BASEBOARD_FAB2_LIB.BASEBOARD_FAB2(SCH_1):M_H_ODT(2)
  U2D1  M49 DDR1_ODT<2> SKX_EXT_B_BGA1-IC,TBD   I172 @BASEBOARD_FAB2_LIB.BASEBOARD_FAB2(SCH_1):PAGE58
  J9U1   87 ODT<0> SCONN288_H44441003_PIP-SCONN,HA    I24 @BASEBOARD_FAB2_LIB.BASEBOARD_FAB2(SCH_1):PAGE80

M_H_ODT<3> @BASEBOARD_FAB2_LIB.BASEBOARD_FAB2(SCH_1):M_H_ODT(3)
  U2D1  T47 DDR1_ODT<3> SKX_EXT_B_BGA1-IC,TBD   I172 @BASEBOARD_FAB2_LIB.BASEBOARD_FAB2(SCH_1):PAGE58
  J9U1   91 ODT<1> SCONN288_H44441003_PIP-SCONN,HA    I24 @BASEBOARD_FAB2_LIB.BASEBOARD_FAB2(SCH_1):PAGE80

M_H_PAR @BASEBOARD_FAB2_LIB.BASEBOARD_FAB2(SCH_1):M_H_PAR
  U2D1  K53 DDR1_PAR SKX_EXT_B_BGA1-IC,TBD   I172 @BASEBOARD_FAB2_LIB.BASEBOARD_FAB2(SCH_1):PAGE58
  J1G2  222    PAR SCONN288_H44441004_PIP-SCONN,HA   I111 @BASEBOARD_FAB2_LIB.BASEBOARD_FAB2(SCH_1):PAGE79
  J9U1  222    PAR SCONN288_H44441003_PIP-SCONN,HA    I24 @BASEBOARD_FAB2_LIB.BASEBOARD_FAB2(SCH_1):PAGE80

M_H_VREF @BASEBOARD_FAB2_LIB.BASEBOARD_FAB2(SCH_1):M_H_VREF
  J1G2  146 VREFCA SCONN288_H44441004_PIP-SCONN,HA   I111 @BASEBOARD_FAB2_LIB.BASEBOARD_FAB2(SCH_1):PAGE79
  C9U7    1      A CAP_A_0402V-0.01UF,25V,10%,X7RA   I178 @BASEBOARD_FAB2_LIB.BASEBOARD_FAB2(SCH_1):PAGE79
 C1G10    1      A CAP_A_0402V-0.01UF,25V,10%,X7RA     I3 @BASEBOARD_FAB2_LIB.BASEBOARD_FAB2(SCH_1):PAGE80
  J9U1  146 VREFCA SCONN288_H44441003_PIP-SCONN,HA    I24 @BASEBOARD_FAB2_LIB.BASEBOARD_FAB2(SCH_1):PAGE80
  R1G2    2      B RES_0402-1.00K,1%,1/16W,CHIP,GA    I19 @BASEBOARD_FAB2_LIB.BASEBOARD_FAB2(SCH_1):PAGE100
  R1G3    1      A RES_0402-1.00K,1%,1/16W,CHIP,GA    I20 @BASEBOARD_FAB2_LIB.BASEBOARD_FAB2(SCH_1):PAGE100
  R1G1    2      B RES_0402-2,1.0%,1/16W,CHIP,G21A    I25 @BASEBOARD_FAB2_LIB.BASEBOARD_FAB2(SCH_1):PAGE100

M_J_ACT_N @BASEBOARD_FAB2_LIB.BASEBOARD_FAB2(SCH_1):M_J_ACT_N
  U2D1 AB61 DDR2_ACT_N SKX_EXT_B_BGA1-IC,TBD   I172 @BASEBOARD_FAB2_LIB.BASEBOARD_FAB2(SCH_1):PAGE59
  J1G3   62  ACT_N SCONN288_H44441004_PIP-SCONN,HA   I186 @BASEBOARD_FAB2_LIB.BASEBOARD_FAB2(SCH_1):PAGE81
  J9U2   62  ACT_N SCONN288_H44441003_PIP-SCONN,HA   I187 @BASEBOARD_FAB2_LIB.BASEBOARD_FAB2(SCH_1):PAGE82

M_J_ALERT_N @BASEBOARD_FAB2_LIB.BASEBOARD_FAB2(SCH_1):M_J_ALERT_N
  U2D1 AD61 DDR2_ALERT_N SKX_EXT_B_BGA1-IC,TBD   I172 @BASEBOARD_FAB2_LIB.BASEBOARD_FAB2(SCH_1):PAGE59
  J1G3  208 ALERT_N SCONN288_H44441004_PIP-SCONN,HA   I186 @BASEBOARD_FAB2_LIB.BASEBOARD_FAB2(SCH_1):PAGE81
  J9U2  208 ALERT_N SCONN288_H44441003_PIP-SCONN,HA   I187 @BASEBOARD_FAB2_LIB.BASEBOARD_FAB2(SCH_1):PAGE82

M_J_BA<0> @BASEBOARD_FAB2_LIB.BASEBOARD_FAB2(SCH_1):M_J_BA(0)
  U2D1  W52 DDR2_BA<0> SKX_EXT_B_BGA1-IC,TBD   I172 @BASEBOARD_FAB2_LIB.BASEBOARD_FAB2(SCH_1):PAGE59
  J1G3   81  BA<0> SCONN288_H44441004_PIP-SCONN,HA   I186 @BASEBOARD_FAB2_LIB.BASEBOARD_FAB2(SCH_1):PAGE81
  J9U2   81  BA<0> SCONN288_H44441003_PIP-SCONN,HA   I187 @BASEBOARD_FAB2_LIB.BASEBOARD_FAB2(SCH_1):PAGE82

M_J_BA<1> @BASEBOARD_FAB2_LIB.BASEBOARD_FAB2(SCH_1):M_J_BA(1)
  U2D1 AE56 DDR2_BA<1> SKX_EXT_B_BGA1-IC,TBD   I172 @BASEBOARD_FAB2_LIB.BASEBOARD_FAB2(SCH_1):PAGE59
  J1G3  224  BA<1> SCONN288_H44441004_PIP-SCONN,HA   I186 @BASEBOARD_FAB2_LIB.BASEBOARD_FAB2(SCH_1):PAGE81
  J9U2  224  BA<1> SCONN288_H44441003_PIP-SCONN,HA   I187 @BASEBOARD_FAB2_LIB.BASEBOARD_FAB2(SCH_1):PAGE82

M_J_BG<0> @BASEBOARD_FAB2_LIB.BASEBOARD_FAB2(SCH_1):M_J_BG(0)
  U2D1 AA60 DDR2_BG<0> SKX_EXT_B_BGA1-IC,TBD   I172 @BASEBOARD_FAB2_LIB.BASEBOARD_FAB2(SCH_1):PAGE59
  J1G3   63  BG<0> SCONN288_H44441004_PIP-SCONN,HA   I186 @BASEBOARD_FAB2_LIB.BASEBOARD_FAB2(SCH_1):PAGE81
  J9U2   63  BG<0> SCONN288_H44441003_PIP-SCONN,HA   I187 @BASEBOARD_FAB2_LIB.BASEBOARD_FAB2(SCH_1):PAGE82

M_J_BG<1> @BASEBOARD_FAB2_LIB.BASEBOARD_FAB2(SCH_1):M_J_BG(1)
  U2D1 AE62 DDR2_BG<1> SKX_EXT_B_BGA1-IC,TBD   I172 @BASEBOARD_FAB2_LIB.BASEBOARD_FAB2(SCH_1):PAGE59
  J1G3  207  BG<1> SCONN288_H44441004_PIP-SCONN,HA   I186 @BASEBOARD_FAB2_LIB.BASEBOARD_FAB2(SCH_1):PAGE81
  J9U2  207  BG<1> SCONN288_H44441003_PIP-SCONN,HA   I187 @BASEBOARD_FAB2_LIB.BASEBOARD_FAB2(SCH_1):PAGE82

M_J_C<2> @BASEBOARD_FAB2_LIB.BASEBOARD_FAB2(SCH_1):M_J_C(2)
  U2D1 AB45 DDR2_CID<2> SKX_EXT_B_BGA1-IC,TBD   I172 @BASEBOARD_FAB2_LIB.BASEBOARD_FAB2(SCH_1):PAGE59
  J1G3  235   C<2> SCONN288_H44441004_PIP-SCONN,HA   I186 @BASEBOARD_FAB2_LIB.BASEBOARD_FAB2(SCH_1):PAGE81
  J9U2  235   C<2> SCONN288_H44441003_PIP-SCONN,HA   I187 @BASEBOARD_FAB2_LIB.BASEBOARD_FAB2(SCH_1):PAGE82

M_J_CKE<0> @BASEBOARD_FAB2_LIB.BASEBOARD_FAB2(SCH_1):M_J_CKE(0)
  U2D1 AA62 DDR2_CKE<0> SKX_EXT_B_BGA1-IC,TBD   I172 @BASEBOARD_FAB2_LIB.BASEBOARD_FAB2(SCH_1):PAGE59
  J1G3   60 CKE<0> SCONN288_H44441004_PIP-SCONN,HA   I186 @BASEBOARD_FAB2_LIB.BASEBOARD_FAB2(SCH_1):PAGE81

M_J_CKE<1> @BASEBOARD_FAB2_LIB.BASEBOARD_FAB2(SCH_1):M_J_CKE(1)
  U2D1 AD63 DDR2_CKE<1> SKX_EXT_B_BGA1-IC,TBD   I172 @BASEBOARD_FAB2_LIB.BASEBOARD_FAB2(SCH_1):PAGE59
  J1G3  203 CKE<1> SCONN288_H44441004_PIP-SCONN,HA   I186 @BASEBOARD_FAB2_LIB.BASEBOARD_FAB2(SCH_1):PAGE81

M_J_CKE<2> @BASEBOARD_FAB2_LIB.BASEBOARD_FAB2(SCH_1):M_J_CKE(2)
  U2D1  V63 DDR2_CKE<2> SKX_EXT_B_BGA1-IC,TBD   I172 @BASEBOARD_FAB2_LIB.BASEBOARD_FAB2(SCH_1):PAGE59
  J9U2   60 CKE<0> SCONN288_H44441003_PIP-SCONN,HA   I187 @BASEBOARD_FAB2_LIB.BASEBOARD_FAB2(SCH_1):PAGE82

M_J_CKE<3> @BASEBOARD_FAB2_LIB.BASEBOARD_FAB2(SCH_1):M_J_CKE(3)
  U2D1 AB63 DDR2_CKE<3> SKX_EXT_B_BGA1-IC,TBD   I172 @BASEBOARD_FAB2_LIB.BASEBOARD_FAB2(SCH_1):PAGE59
  J9U2  203 CKE<1> SCONN288_H44441003_PIP-SCONN,HA   I187 @BASEBOARD_FAB2_LIB.BASEBOARD_FAB2(SCH_1):PAGE82

M_J_CLK_DN<0> @BASEBOARD_FAB2_LIB.BASEBOARD_FAB2(SCH_1):M_J_CLK_DN(0)
  U2D1 AA54 DDR2_CLK_DN<0> SKX_EXT_B_BGA1-IC,TBD   I172 @BASEBOARD_FAB2_LIB.BASEBOARD_FAB2(SCH_1):PAGE59
  J1G3   75   CK0N SCONN288_H44441004_PIP-SCONN,HA   I186 @BASEBOARD_FAB2_LIB.BASEBOARD_FAB2(SCH_1):PAGE81

M_J_CLK_DN<1> @BASEBOARD_FAB2_LIB.BASEBOARD_FAB2(SCH_1):M_J_CLK_DN(1)
  U2D1  W54 DDR2_CLK_DN<1> SKX_EXT_B_BGA1-IC,TBD   I172 @BASEBOARD_FAB2_LIB.BASEBOARD_FAB2(SCH_1):PAGE59
  J1G3  219   CK1N SCONN288_H44441004_PIP-SCONN,HA   I186 @BASEBOARD_FAB2_LIB.BASEBOARD_FAB2(SCH_1):PAGE81

M_J_CLK_DN<2> @BASEBOARD_FAB2_LIB.BASEBOARD_FAB2(SCH_1):M_J_CLK_DN(2)
  U2D1 AA56 DDR2_CLK_DN<2> SKX_EXT_B_BGA1-IC,TBD   I172 @BASEBOARD_FAB2_LIB.BASEBOARD_FAB2(SCH_1):PAGE59
  J9U2   75   CK0N SCONN288_H44441003_PIP-SCONN,HA   I187 @BASEBOARD_FAB2_LIB.BASEBOARD_FAB2(SCH_1):PAGE82

M_J_CLK_DN<3> @BASEBOARD_FAB2_LIB.BASEBOARD_FAB2(SCH_1):M_J_CLK_DN(3)
  U2D1  W56 DDR2_CLK_DN<3> SKX_EXT_B_BGA1-IC,TBD   I172 @BASEBOARD_FAB2_LIB.BASEBOARD_FAB2(SCH_1):PAGE59
  J9U2  219   CK1N SCONN288_H44441003_PIP-SCONN,HA   I187 @BASEBOARD_FAB2_LIB.BASEBOARD_FAB2(SCH_1):PAGE82

M_J_CLK_DP<0> @BASEBOARD_FAB2_LIB.BASEBOARD_FAB2(SCH_1):M_J_CLK_DP(0)
  U2D1 AB55 DDR2_CLK_DP<0> SKX_EXT_B_BGA1-IC,TBD   I172 @BASEBOARD_FAB2_LIB.BASEBOARD_FAB2(SCH_1):PAGE59
  J1G3   74   CK0P SCONN288_H44441004_PIP-SCONN,HA   I186 @BASEBOARD_FAB2_LIB.BASEBOARD_FAB2(SCH_1):PAGE81

M_J_CLK_DP<1> @BASEBOARD_FAB2_LIB.BASEBOARD_FAB2(SCH_1):M_J_CLK_DP(1)
  U2D1  V55 DDR2_CLK_DP<1> SKX_EXT_B_BGA1-IC,TBD   I172 @BASEBOARD_FAB2_LIB.BASEBOARD_FAB2(SCH_1):PAGE59
  J1G3  218   CK1P SCONN288_H44441004_PIP-SCONN,HA   I186 @BASEBOARD_FAB2_LIB.BASEBOARD_FAB2(SCH_1):PAGE81

M_J_CLK_DP<2> @BASEBOARD_FAB2_LIB.BASEBOARD_FAB2(SCH_1):M_J_CLK_DP(2)
  U2D1 AB57 DDR2_CLK_DP<2> SKX_EXT_B_BGA1-IC,TBD   I172 @BASEBOARD_FAB2_LIB.BASEBOARD_FAB2(SCH_1):PAGE59
  J9U2   74   CK0P SCONN288_H44441003_PIP-SCONN,HA   I187 @BASEBOARD_FAB2_LIB.BASEBOARD_FAB2(SCH_1):PAGE82

M_J_CLK_DP<3> @BASEBOARD_FAB2_LIB.BASEBOARD_FAB2(SCH_1):M_J_CLK_DP(3)
  U2D1  V57 DDR2_CLK_DP<3> SKX_EXT_B_BGA1-IC,TBD   I172 @BASEBOARD_FAB2_LIB.BASEBOARD_FAB2(SCH_1):PAGE59
  J9U2  218   CK1P SCONN288_H44441003_PIP-SCONN,HA   I187 @BASEBOARD_FAB2_LIB.BASEBOARD_FAB2(SCH_1):PAGE82

M_J_CPU_VREF @BASEBOARD_FAB2_LIB.BASEBOARD_FAB2(SCH_1):M_J_CPU_VREF
  U2D1 AH63 DDR2_CAVREF SKX_EXT_B_BGA1-IC,TBD   I172 @BASEBOARD_FAB2_LIB.BASEBOARD_FAB2(SCH_1):PAGE55
 R1G14    1      A RES_0402-2,1.0%,1/16W,CHIP,G21A    I41 @BASEBOARD_FAB2_LIB.BASEBOARD_FAB2(SCH_1):PAGE100
 C1G18    1      A CAP_A_0402V-0.01UF,25V,10%,X7RA    I42 @BASEBOARD_FAB2_LIB.BASEBOARD_FAB2(SCH_1):PAGE100

M_J_CS_N<0> @BASEBOARD_FAB2_LIB.BASEBOARD_FAB2(SCH_1):M_J_CS_N(0)
  U2D1  V51 DDR2_CS_N<0> SKX_EXT_B_BGA1-IC,TBD   I172 @BASEBOARD_FAB2_LIB.BASEBOARD_FAB2(SCH_1):PAGE59
  J1G3   84   S0_N SCONN288_H44441004_PIP-SCONN,HA   I186 @BASEBOARD_FAB2_LIB.BASEBOARD_FAB2(SCH_1):PAGE81

M_J_CS_N<1> @BASEBOARD_FAB2_LIB.BASEBOARD_FAB2(SCH_1):M_J_CS_N(1)
  U2D1 AB49 DDR2_CS_N<1> SKX_EXT_B_BGA1-IC,TBD   I172 @BASEBOARD_FAB2_LIB.BASEBOARD_FAB2(SCH_1):PAGE59
  J1G3   89   S1_N SCONN288_H44441004_PIP-SCONN,HA   I186 @BASEBOARD_FAB2_LIB.BASEBOARD_FAB2(SCH_1):PAGE81

M_J_CS_N<2> @BASEBOARD_FAB2_LIB.BASEBOARD_FAB2(SCH_1):M_J_CS_N(2)
  U2D1  W46 DDR2_CS_N<2> SKX_EXT_B_BGA1-IC,TBD   I172 @BASEBOARD_FAB2_LIB.BASEBOARD_FAB2(SCH_1):PAGE59
  J1G3   93 S2_N_C<0> SCONN288_H44441004_PIP-SCONN,HA   I186 @BASEBOARD_FAB2_LIB.BASEBOARD_FAB2(SCH_1):PAGE81

M_J_CS_N<3> @BASEBOARD_FAB2_LIB.BASEBOARD_FAB2(SCH_1):M_J_CS_N(3)
  U2D1 AA46 DDR2_CS_N<3> SKX_EXT_B_BGA1-IC,TBD   I172 @BASEBOARD_FAB2_LIB.BASEBOARD_FAB2(SCH_1):PAGE59
  J1G3  237 S3_N_C<1> SCONN288_H44441004_PIP-SCONN,HA   I186 @BASEBOARD_FAB2_LIB.BASEBOARD_FAB2(SCH_1):PAGE81

M_J_CS_N<4> @BASEBOARD_FAB2_LIB.BASEBOARD_FAB2(SCH_1):M_J_CS_N(4)
  U2D1 AB51 DDR2_CS_N<4> SKX_EXT_B_BGA1-IC,TBD   I172 @BASEBOARD_FAB2_LIB.BASEBOARD_FAB2(SCH_1):PAGE59
  J9U2   84   S0_N SCONN288_H44441003_PIP-SCONN,HA   I187 @BASEBOARD_FAB2_LIB.BASEBOARD_FAB2(SCH_1):PAGE82

M_J_CS_N<5> @BASEBOARD_FAB2_LIB.BASEBOARD_FAB2(SCH_1):M_J_CS_N(5)
  U2D1  W48 DDR2_CS_N<5> SKX_EXT_B_BGA1-IC,TBD   I172 @BASEBOARD_FAB2_LIB.BASEBOARD_FAB2(SCH_1):PAGE59
  J9U2   89   S1_N SCONN288_H44441003_PIP-SCONN,HA   I187 @BASEBOARD_FAB2_LIB.BASEBOARD_FAB2(SCH_1):PAGE82

M_J_CS_N<6> @BASEBOARD_FAB2_LIB.BASEBOARD_FAB2(SCH_1):M_J_CS_N(6)
  U2D1  T45 DDR2_CS_N<6> SKX_EXT_B_BGA1-IC,TBD   I172 @BASEBOARD_FAB2_LIB.BASEBOARD_FAB2(SCH_1):PAGE59
  J9U2   93 S2_N_C<0> SCONN288_H44441003_PIP-SCONN,HA   I187 @BASEBOARD_FAB2_LIB.BASEBOARD_FAB2(SCH_1):PAGE82

M_J_CS_N<7> @BASEBOARD_FAB2_LIB.BASEBOARD_FAB2(SCH_1):M_J_CS_N(7)
  U2D1  V45 DDR2_CS_N<7> SKX_EXT_B_BGA1-IC,TBD   I172 @BASEBOARD_FAB2_LIB.BASEBOARD_FAB2(SCH_1):PAGE59
  J9U2  237 S3_N_C<1> SCONN288_H44441003_PIP-SCONN,HA   I187 @BASEBOARD_FAB2_LIB.BASEBOARD_FAB2(SCH_1):PAGE82

M_J_DQ<0> @BASEBOARD_FAB2_LIB.BASEBOARD_FAB2(SCH_1):M_J_DQ(0)
  U2D1 AR76 DDR2_DQ<0> SKX_EXT_B_BGA1-IC,TBD   I172 @BASEBOARD_FAB2_LIB.BASEBOARD_FAB2(SCH_1):PAGE59
  J1G3  150  DQ<1> SCONN288_H44441004_PIP-SCONN,HA   I186 @BASEBOARD_FAB2_LIB.BASEBOARD_FAB2(SCH_1):PAGE81
  J9U2    5  DQ<0> SCONN288_H44441003_PIP-SCONN,HA   I187 @BASEBOARD_FAB2_LIB.BASEBOARD_FAB2(SCH_1):PAGE82

M_J_DQ<10> @BASEBOARD_FAB2_LIB.BASEBOARD_FAB2(SCH_1):M_J_DQ(10)
  U2D1  Y77 DDR2_DQ<10> SKX_EXT_B_BGA1-IC,TBD   I172 @BASEBOARD_FAB2_LIB.BASEBOARD_FAB2(SCH_1):PAGE59
  J1G3  168 DQ<11> SCONN288_H44441004_PIP-SCONN,HA   I186 @BASEBOARD_FAB2_LIB.BASEBOARD_FAB2(SCH_1):PAGE81
  J9U2   23 DQ<10> SCONN288_H44441003_PIP-SCONN,HA   I187 @BASEBOARD_FAB2_LIB.BASEBOARD_FAB2(SCH_1):PAGE82

M_J_DQ<11> @BASEBOARD_FAB2_LIB.BASEBOARD_FAB2(SCH_1):M_J_DQ(11)
  U2D1  W76 DDR2_DQ<11> SKX_EXT_B_BGA1-IC,TBD   I172 @BASEBOARD_FAB2_LIB.BASEBOARD_FAB2(SCH_1):PAGE59
  J1G3   23 DQ<10> SCONN288_H44441004_PIP-SCONN,HA   I186 @BASEBOARD_FAB2_LIB.BASEBOARD_FAB2(SCH_1):PAGE81
  J9U2  168 DQ<11> SCONN288_H44441003_PIP-SCONN,HA   I187 @BASEBOARD_FAB2_LIB.BASEBOARD_FAB2(SCH_1):PAGE82

M_J_DQ<12> @BASEBOARD_FAB2_LIB.BASEBOARD_FAB2(SCH_1):M_J_DQ(12)
  U2D1 AF75 DDR2_DQ<12> SKX_EXT_B_BGA1-IC,TBD   I172 @BASEBOARD_FAB2_LIB.BASEBOARD_FAB2(SCH_1):PAGE59
  J1G3  159 DQ<13> SCONN288_H44441004_PIP-SCONN,HA   I186 @BASEBOARD_FAB2_LIB.BASEBOARD_FAB2(SCH_1):PAGE81
  J9U2   14 DQ<12> SCONN288_H44441003_PIP-SCONN,HA   I187 @BASEBOARD_FAB2_LIB.BASEBOARD_FAB2(SCH_1):PAGE82

M_J_DQ<13> @BASEBOARD_FAB2_LIB.BASEBOARD_FAB2(SCH_1):M_J_DQ(13)
  U2D1 AE74 DDR2_DQ<13> SKX_EXT_B_BGA1-IC,TBD   I172 @BASEBOARD_FAB2_LIB.BASEBOARD_FAB2(SCH_1):PAGE59
  J1G3   14 DQ<12> SCONN288_H44441004_PIP-SCONN,HA   I186 @BASEBOARD_FAB2_LIB.BASEBOARD_FAB2(SCH_1):PAGE81
  J9U2  159 DQ<13> SCONN288_H44441003_PIP-SCONN,HA   I187 @BASEBOARD_FAB2_LIB.BASEBOARD_FAB2(SCH_1):PAGE82

M_J_DQ<14> @BASEBOARD_FAB2_LIB.BASEBOARD_FAB2(SCH_1):M_J_DQ(14)
  U2D1 AB77 DDR2_DQ<14> SKX_EXT_B_BGA1-IC,TBD   I172 @BASEBOARD_FAB2_LIB.BASEBOARD_FAB2(SCH_1):PAGE59
  J1G3  166 DQ<15> SCONN288_H44441004_PIP-SCONN,HA   I186 @BASEBOARD_FAB2_LIB.BASEBOARD_FAB2(SCH_1):PAGE81
  J9U2   21 DQ<14> SCONN288_H44441003_PIP-SCONN,HA   I187 @BASEBOARD_FAB2_LIB.BASEBOARD_FAB2(SCH_1):PAGE82

M_J_DQ<15> @BASEBOARD_FAB2_LIB.BASEBOARD_FAB2(SCH_1):M_J_DQ(15)
  U2D1  Y75 DDR2_DQ<15> SKX_EXT_B_BGA1-IC,TBD   I172 @BASEBOARD_FAB2_LIB.BASEBOARD_FAB2(SCH_1):PAGE59
  J1G3   21 DQ<14> SCONN288_H44441004_PIP-SCONN,HA   I186 @BASEBOARD_FAB2_LIB.BASEBOARD_FAB2(SCH_1):PAGE81
  J9U2  166 DQ<15> SCONN288_H44441003_PIP-SCONN,HA   I187 @BASEBOARD_FAB2_LIB.BASEBOARD_FAB2(SCH_1):PAGE82

M_J_DQ<16> @BASEBOARD_FAB2_LIB.BASEBOARD_FAB2(SCH_1):M_J_DQ(16)
  U2D1  W72 DDR2_DQ<16> SKX_EXT_B_BGA1-IC,TBD   I172 @BASEBOARD_FAB2_LIB.BASEBOARD_FAB2(SCH_1):PAGE59
  J1G3  172 DQ<17> SCONN288_H44441004_PIP-SCONN,HA   I186 @BASEBOARD_FAB2_LIB.BASEBOARD_FAB2(SCH_1):PAGE81
  J9U2   27 DQ<16> SCONN288_H44441003_PIP-SCONN,HA   I187 @BASEBOARD_FAB2_LIB.BASEBOARD_FAB2(SCH_1):PAGE82

M_J_DQ<17> @BASEBOARD_FAB2_LIB.BASEBOARD_FAB2(SCH_1):M_J_DQ(17)
  U2D1 AA70 DDR2_DQ<17> SKX_EXT_B_BGA1-IC,TBD   I172 @BASEBOARD_FAB2_LIB.BASEBOARD_FAB2(SCH_1):PAGE59
  J1G3   27 DQ<16> SCONN288_H44441004_PIP-SCONN,HA   I186 @BASEBOARD_FAB2_LIB.BASEBOARD_FAB2(SCH_1):PAGE81
  J9U2  172 DQ<17> SCONN288_H44441003_PIP-SCONN,HA   I187 @BASEBOARD_FAB2_LIB.BASEBOARD_FAB2(SCH_1):PAGE82

M_J_DQ<18> @BASEBOARD_FAB2_LIB.BASEBOARD_FAB2(SCH_1):M_J_DQ(18)
  U2D1  R70 DDR2_DQ<18> SKX_EXT_B_BGA1-IC,TBD   I172 @BASEBOARD_FAB2_LIB.BASEBOARD_FAB2(SCH_1):PAGE59
  J1G3  179 DQ<19> SCONN288_H44441004_PIP-SCONN,HA   I186 @BASEBOARD_FAB2_LIB.BASEBOARD_FAB2(SCH_1):PAGE81
  J9U2   34 DQ<18> SCONN288_H44441003_PIP-SCONN,HA   I187 @BASEBOARD_FAB2_LIB.BASEBOARD_FAB2(SCH_1):PAGE82

M_J_DQ<19> @BASEBOARD_FAB2_LIB.BASEBOARD_FAB2(SCH_1):M_J_DQ(19)
  U2D1  T69 DDR2_DQ<19> SKX_EXT_B_BGA1-IC,TBD   I172 @BASEBOARD_FAB2_LIB.BASEBOARD_FAB2(SCH_1):PAGE59
  J1G3   34 DQ<18> SCONN288_H44441004_PIP-SCONN,HA   I186 @BASEBOARD_FAB2_LIB.BASEBOARD_FAB2(SCH_1):PAGE81
  J9U2  179 DQ<19> SCONN288_H44441003_PIP-SCONN,HA   I187 @BASEBOARD_FAB2_LIB.BASEBOARD_FAB2(SCH_1):PAGE82

M_J_DQ<1> @BASEBOARD_FAB2_LIB.BASEBOARD_FAB2(SCH_1):M_J_DQ(1)
  U2D1 AN74 DDR2_DQ<1> SKX_EXT_B_BGA1-IC,TBD   I172 @BASEBOARD_FAB2_LIB.BASEBOARD_FAB2(SCH_1):PAGE59
  J1G3    5  DQ<0> SCONN288_H44441004_PIP-SCONN,HA   I186 @BASEBOARD_FAB2_LIB.BASEBOARD_FAB2(SCH_1):PAGE81
  J9U2  150  DQ<1> SCONN288_H44441003_PIP-SCONN,HA   I187 @BASEBOARD_FAB2_LIB.BASEBOARD_FAB2(SCH_1):PAGE82

M_J_DQ<20> @BASEBOARD_FAB2_LIB.BASEBOARD_FAB2(SCH_1):M_J_DQ(20)
  U2D1 AA72 DDR2_DQ<20> SKX_EXT_B_BGA1-IC,TBD   I172 @BASEBOARD_FAB2_LIB.BASEBOARD_FAB2(SCH_1):PAGE59
  J1G3  170 DQ<21> SCONN288_H44441004_PIP-SCONN,HA   I186 @BASEBOARD_FAB2_LIB.BASEBOARD_FAB2(SCH_1):PAGE81
  J9U2   25 DQ<20> SCONN288_H44441003_PIP-SCONN,HA   I187 @BASEBOARD_FAB2_LIB.BASEBOARD_FAB2(SCH_1):PAGE82

M_J_DQ<21> @BASEBOARD_FAB2_LIB.BASEBOARD_FAB2(SCH_1):M_J_DQ(21)
  U2D1 AB71 DDR2_DQ<21> SKX_EXT_B_BGA1-IC,TBD   I172 @BASEBOARD_FAB2_LIB.BASEBOARD_FAB2(SCH_1):PAGE59
  J1G3   25 DQ<20> SCONN288_H44441004_PIP-SCONN,HA   I186 @BASEBOARD_FAB2_LIB.BASEBOARD_FAB2(SCH_1):PAGE81
  J9U2  170 DQ<21> SCONN288_H44441003_PIP-SCONN,HA   I187 @BASEBOARD_FAB2_LIB.BASEBOARD_FAB2(SCH_1):PAGE82

M_J_DQ<22> @BASEBOARD_FAB2_LIB.BASEBOARD_FAB2(SCH_1):M_J_DQ(22)
  U2D1  T71 DDR2_DQ<22> SKX_EXT_B_BGA1-IC,TBD   I172 @BASEBOARD_FAB2_LIB.BASEBOARD_FAB2(SCH_1):PAGE59
  J1G3  177 DQ<23> SCONN288_H44441004_PIP-SCONN,HA   I186 @BASEBOARD_FAB2_LIB.BASEBOARD_FAB2(SCH_1):PAGE81
  J9U2   32 DQ<22> SCONN288_H44441003_PIP-SCONN,HA   I187 @BASEBOARD_FAB2_LIB.BASEBOARD_FAB2(SCH_1):PAGE82

M_J_DQ<23> @BASEBOARD_FAB2_LIB.BASEBOARD_FAB2(SCH_1):M_J_DQ(23)
  U2D1  V69 DDR2_DQ<23> SKX_EXT_B_BGA1-IC,TBD   I172 @BASEBOARD_FAB2_LIB.BASEBOARD_FAB2(SCH_1):PAGE59
  J1G3   32 DQ<22> SCONN288_H44441004_PIP-SCONN,HA   I186 @BASEBOARD_FAB2_LIB.BASEBOARD_FAB2(SCH_1):PAGE81
  J9U2  177 DQ<23> SCONN288_H44441003_PIP-SCONN,HA   I187 @BASEBOARD_FAB2_LIB.BASEBOARD_FAB2(SCH_1):PAGE82

M_J_DQ<24> @BASEBOARD_FAB2_LIB.BASEBOARD_FAB2(SCH_1):M_J_DQ(24)
  U2D1 AM67 DDR2_DQ<24> SKX_EXT_B_BGA1-IC,TBD   I172 @BASEBOARD_FAB2_LIB.BASEBOARD_FAB2(SCH_1):PAGE59
  J1G3  183 DQ<25> SCONN288_H44441004_PIP-SCONN,HA   I186 @BASEBOARD_FAB2_LIB.BASEBOARD_FAB2(SCH_1):PAGE81
  J9U2   38 DQ<24> SCONN288_H44441003_PIP-SCONN,HA   I187 @BASEBOARD_FAB2_LIB.BASEBOARD_FAB2(SCH_1):PAGE82

M_J_DQ<25> @BASEBOARD_FAB2_LIB.BASEBOARD_FAB2(SCH_1):M_J_DQ(25)
  U2D1 AT67 DDR2_DQ<25> SKX_EXT_B_BGA1-IC,TBD   I172 @BASEBOARD_FAB2_LIB.BASEBOARD_FAB2(SCH_1):PAGE59
  J1G3   38 DQ<24> SCONN288_H44441004_PIP-SCONN,HA   I186 @BASEBOARD_FAB2_LIB.BASEBOARD_FAB2(SCH_1):PAGE81
  J9U2  183 DQ<25> SCONN288_H44441003_PIP-SCONN,HA   I187 @BASEBOARD_FAB2_LIB.BASEBOARD_FAB2(SCH_1):PAGE82

M_J_DQ<26> @BASEBOARD_FAB2_LIB.BASEBOARD_FAB2(SCH_1):M_J_DQ(26)
  U2D1 AN64 DDR2_DQ<26> SKX_EXT_B_BGA1-IC,TBD   I172 @BASEBOARD_FAB2_LIB.BASEBOARD_FAB2(SCH_1):PAGE59
  J1G3  190 DQ<27> SCONN288_H44441004_PIP-SCONN,HA   I186 @BASEBOARD_FAB2_LIB.BASEBOARD_FAB2(SCH_1):PAGE81
  J9U2   45 DQ<26> SCONN288_H44441003_PIP-SCONN,HA   I187 @BASEBOARD_FAB2_LIB.BASEBOARD_FAB2(SCH_1):PAGE82

M_J_DQ<27> @BASEBOARD_FAB2_LIB.BASEBOARD_FAB2(SCH_1):M_J_DQ(27)
  U2D1 AR64 DDR2_DQ<27> SKX_EXT_B_BGA1-IC,TBD   I172 @BASEBOARD_FAB2_LIB.BASEBOARD_FAB2(SCH_1):PAGE59
  J1G3   45 DQ<26> SCONN288_H44441004_PIP-SCONN,HA   I186 @BASEBOARD_FAB2_LIB.BASEBOARD_FAB2(SCH_1):PAGE81
  J9U2  190 DQ<27> SCONN288_H44441003_PIP-SCONN,HA   I187 @BASEBOARD_FAB2_LIB.BASEBOARD_FAB2(SCH_1):PAGE82

M_J_DQ<28> @BASEBOARD_FAB2_LIB.BASEBOARD_FAB2(SCH_1):M_J_DQ(28)
  U2D1 AN68 DDR2_DQ<28> SKX_EXT_B_BGA1-IC,TBD   I172 @BASEBOARD_FAB2_LIB.BASEBOARD_FAB2(SCH_1):PAGE59
  J1G3  181 DQ<29> SCONN288_H44441004_PIP-SCONN,HA   I186 @BASEBOARD_FAB2_LIB.BASEBOARD_FAB2(SCH_1):PAGE81
  J9U2   36 DQ<28> SCONN288_H44441003_PIP-SCONN,HA   I187 @BASEBOARD_FAB2_LIB.BASEBOARD_FAB2(SCH_1):PAGE82

M_J_DQ<29> @BASEBOARD_FAB2_LIB.BASEBOARD_FAB2(SCH_1):M_J_DQ(29)
  U2D1 AR68 DDR2_DQ<29> SKX_EXT_B_BGA1-IC,TBD   I172 @BASEBOARD_FAB2_LIB.BASEBOARD_FAB2(SCH_1):PAGE59
  J1G3   36 DQ<28> SCONN288_H44441004_PIP-SCONN,HA   I186 @BASEBOARD_FAB2_LIB.BASEBOARD_FAB2(SCH_1):PAGE81
  J9U2  181 DQ<29> SCONN288_H44441003_PIP-SCONN,HA   I187 @BASEBOARD_FAB2_LIB.BASEBOARD_FAB2(SCH_1):PAGE82

M_J_DQ<2> @BASEBOARD_FAB2_LIB.BASEBOARD_FAB2(SCH_1):M_J_DQ(2)
  U2D1 AK77 DDR2_DQ<2> SKX_EXT_B_BGA1-IC,TBD   I172 @BASEBOARD_FAB2_LIB.BASEBOARD_FAB2(SCH_1):PAGE59
  J1G3  157  DQ<3> SCONN288_H44441004_PIP-SCONN,HA   I186 @BASEBOARD_FAB2_LIB.BASEBOARD_FAB2(SCH_1):PAGE81
  J9U2   12  DQ<2> SCONN288_H44441003_PIP-SCONN,HA   I187 @BASEBOARD_FAB2_LIB.BASEBOARD_FAB2(SCH_1):PAGE82

M_J_DQ<30> @BASEBOARD_FAB2_LIB.BASEBOARD_FAB2(SCH_1):M_J_DQ(30)
  U2D1 AM65 DDR2_DQ<30> SKX_EXT_B_BGA1-IC,TBD   I172 @BASEBOARD_FAB2_LIB.BASEBOARD_FAB2(SCH_1):PAGE59
  J1G3  188 DQ<31> SCONN288_H44441004_PIP-SCONN,HA   I186 @BASEBOARD_FAB2_LIB.BASEBOARD_FAB2(SCH_1):PAGE81
  J9U2   43 DQ<30> SCONN288_H44441003_PIP-SCONN,HA   I187 @BASEBOARD_FAB2_LIB.BASEBOARD_FAB2(SCH_1):PAGE82

M_J_DQ<31> @BASEBOARD_FAB2_LIB.BASEBOARD_FAB2(SCH_1):M_J_DQ(31)
  U2D1 AT65 DDR2_DQ<31> SKX_EXT_B_BGA1-IC,TBD   I172 @BASEBOARD_FAB2_LIB.BASEBOARD_FAB2(SCH_1):PAGE59
  J1G3   43 DQ<30> SCONN288_H44441004_PIP-SCONN,HA   I186 @BASEBOARD_FAB2_LIB.BASEBOARD_FAB2(SCH_1):PAGE81
  J9U2  188 DQ<31> SCONN288_H44441003_PIP-SCONN,HA   I187 @BASEBOARD_FAB2_LIB.BASEBOARD_FAB2(SCH_1):PAGE82

M_J_DQ<32> @BASEBOARD_FAB2_LIB.BASEBOARD_FAB2(SCH_1):M_J_DQ(32)
  U2D1  U40 DDR2_DQ<32> SKX_EXT_B_BGA1-IC,TBD   I172 @BASEBOARD_FAB2_LIB.BASEBOARD_FAB2(SCH_1):PAGE59
  J1G3  242 DQ<33> SCONN288_H44441004_PIP-SCONN,HA   I186 @BASEBOARD_FAB2_LIB.BASEBOARD_FAB2(SCH_1):PAGE81
  J9U2   97 DQ<32> SCONN288_H44441003_PIP-SCONN,HA   I187 @BASEBOARD_FAB2_LIB.BASEBOARD_FAB2(SCH_1):PAGE82

M_J_DQ<33> @BASEBOARD_FAB2_LIB.BASEBOARD_FAB2(SCH_1):M_J_DQ(33)
  U2D1 AA40 DDR2_DQ<33> SKX_EXT_B_BGA1-IC,TBD   I172 @BASEBOARD_FAB2_LIB.BASEBOARD_FAB2(SCH_1):PAGE59
  J1G3   97 DQ<32> SCONN288_H44441004_PIP-SCONN,HA   I186 @BASEBOARD_FAB2_LIB.BASEBOARD_FAB2(SCH_1):PAGE81
  J9U2  242 DQ<33> SCONN288_H44441003_PIP-SCONN,HA   I187 @BASEBOARD_FAB2_LIB.BASEBOARD_FAB2(SCH_1):PAGE82

M_J_DQ<34> @BASEBOARD_FAB2_LIB.BASEBOARD_FAB2(SCH_1):M_J_DQ(34)
  U2D1  V37 DDR2_DQ<34> SKX_EXT_B_BGA1-IC,TBD   I172 @BASEBOARD_FAB2_LIB.BASEBOARD_FAB2(SCH_1):PAGE59
  J1G3  249 DQ<35> SCONN288_H44441004_PIP-SCONN,HA   I186 @BASEBOARD_FAB2_LIB.BASEBOARD_FAB2(SCH_1):PAGE81
  J9U2  104 DQ<34> SCONN288_H44441003_PIP-SCONN,HA   I187 @BASEBOARD_FAB2_LIB.BASEBOARD_FAB2(SCH_1):PAGE82

M_J_DQ<35> @BASEBOARD_FAB2_LIB.BASEBOARD_FAB2(SCH_1):M_J_DQ(35)
  U2D1  Y37 DDR2_DQ<35> SKX_EXT_B_BGA1-IC,TBD   I172 @BASEBOARD_FAB2_LIB.BASEBOARD_FAB2(SCH_1):PAGE59
  J1G3  104 DQ<34> SCONN288_H44441004_PIP-SCONN,HA   I186 @BASEBOARD_FAB2_LIB.BASEBOARD_FAB2(SCH_1):PAGE81
  J9U2  249 DQ<35> SCONN288_H44441003_PIP-SCONN,HA   I187 @BASEBOARD_FAB2_LIB.BASEBOARD_FAB2(SCH_1):PAGE82

M_J_DQ<36> @BASEBOARD_FAB2_LIB.BASEBOARD_FAB2(SCH_1):M_J_DQ(36)
  U2D1  V41 DDR2_DQ<36> SKX_EXT_B_BGA1-IC,TBD   I172 @BASEBOARD_FAB2_LIB.BASEBOARD_FAB2(SCH_1):PAGE59
  J1G3  240 DQ<37> SCONN288_H44441004_PIP-SCONN,HA   I186 @BASEBOARD_FAB2_LIB.BASEBOARD_FAB2(SCH_1):PAGE81
  J9U2   95 DQ<36> SCONN288_H44441003_PIP-SCONN,HA   I187 @BASEBOARD_FAB2_LIB.BASEBOARD_FAB2(SCH_1):PAGE82

M_J_DQ<37> @BASEBOARD_FAB2_LIB.BASEBOARD_FAB2(SCH_1):M_J_DQ(37)
  U2D1  Y41 DDR2_DQ<37> SKX_EXT_B_BGA1-IC,TBD   I172 @BASEBOARD_FAB2_LIB.BASEBOARD_FAB2(SCH_1):PAGE59
  J1G3   95 DQ<36> SCONN288_H44441004_PIP-SCONN,HA   I186 @BASEBOARD_FAB2_LIB.BASEBOARD_FAB2(SCH_1):PAGE81
  J9U2  240 DQ<37> SCONN288_H44441003_PIP-SCONN,HA   I187 @BASEBOARD_FAB2_LIB.BASEBOARD_FAB2(SCH_1):PAGE82

M_J_DQ<38> @BASEBOARD_FAB2_LIB.BASEBOARD_FAB2(SCH_1):M_J_DQ(38)
  U2D1  U38 DDR2_DQ<38> SKX_EXT_B_BGA1-IC,TBD   I172 @BASEBOARD_FAB2_LIB.BASEBOARD_FAB2(SCH_1):PAGE59
  J1G3  247 DQ<39> SCONN288_H44441004_PIP-SCONN,HA   I186 @BASEBOARD_FAB2_LIB.BASEBOARD_FAB2(SCH_1):PAGE81
  J9U2  102 DQ<38> SCONN288_H44441003_PIP-SCONN,HA   I187 @BASEBOARD_FAB2_LIB.BASEBOARD_FAB2(SCH_1):PAGE82

M_J_DQ<39> @BASEBOARD_FAB2_LIB.BASEBOARD_FAB2(SCH_1):M_J_DQ(39)
  U2D1 AA38 DDR2_DQ<39> SKX_EXT_B_BGA1-IC,TBD   I172 @BASEBOARD_FAB2_LIB.BASEBOARD_FAB2(SCH_1):PAGE59
  J1G3  102 DQ<38> SCONN288_H44441004_PIP-SCONN,HA   I186 @BASEBOARD_FAB2_LIB.BASEBOARD_FAB2(SCH_1):PAGE81
  J9U2  247 DQ<39> SCONN288_H44441003_PIP-SCONN,HA   I187 @BASEBOARD_FAB2_LIB.BASEBOARD_FAB2(SCH_1):PAGE82

M_J_DQ<3> @BASEBOARD_FAB2_LIB.BASEBOARD_FAB2(SCH_1):M_J_DQ(3)
  U2D1 AJ76 DDR2_DQ<3> SKX_EXT_B_BGA1-IC,TBD   I172 @BASEBOARD_FAB2_LIB.BASEBOARD_FAB2(SCH_1):PAGE59
  J1G3   12  DQ<2> SCONN288_H44441004_PIP-SCONN,HA   I186 @BASEBOARD_FAB2_LIB.BASEBOARD_FAB2(SCH_1):PAGE81
  J9U2  157  DQ<3> SCONN288_H44441003_PIP-SCONN,HA   I187 @BASEBOARD_FAB2_LIB.BASEBOARD_FAB2(SCH_1):PAGE82

M_J_DQ<40> @BASEBOARD_FAB2_LIB.BASEBOARD_FAB2(SCH_1):M_J_DQ(40)
  U2D1  U34 DDR2_DQ<40> SKX_EXT_B_BGA1-IC,TBD   I172 @BASEBOARD_FAB2_LIB.BASEBOARD_FAB2(SCH_1):PAGE59
  J1G3  253 DQ<41> SCONN288_H44441004_PIP-SCONN,HA   I186 @BASEBOARD_FAB2_LIB.BASEBOARD_FAB2(SCH_1):PAGE81
  J9U2  108 DQ<40> SCONN288_H44441003_PIP-SCONN,HA   I187 @BASEBOARD_FAB2_LIB.BASEBOARD_FAB2(SCH_1):PAGE82

M_J_DQ<41> @BASEBOARD_FAB2_LIB.BASEBOARD_FAB2(SCH_1):M_J_DQ(41)
  U2D1 AA34 DDR2_DQ<41> SKX_EXT_B_BGA1-IC,TBD   I172 @BASEBOARD_FAB2_LIB.BASEBOARD_FAB2(SCH_1):PAGE59
  J1G3  108 DQ<40> SCONN288_H44441004_PIP-SCONN,HA   I186 @BASEBOARD_FAB2_LIB.BASEBOARD_FAB2(SCH_1):PAGE81
  J9U2  253 DQ<41> SCONN288_H44441003_PIP-SCONN,HA   I187 @BASEBOARD_FAB2_LIB.BASEBOARD_FAB2(SCH_1):PAGE82

M_J_DQ<42> @BASEBOARD_FAB2_LIB.BASEBOARD_FAB2(SCH_1):M_J_DQ(42)
  U2D1  V31 DDR2_DQ<42> SKX_EXT_B_BGA1-IC,TBD   I172 @BASEBOARD_FAB2_LIB.BASEBOARD_FAB2(SCH_1):PAGE59
  J1G3  260 DQ<43> SCONN288_H44441004_PIP-SCONN,HA   I186 @BASEBOARD_FAB2_LIB.BASEBOARD_FAB2(SCH_1):PAGE81
  J9U2  115 DQ<42> SCONN288_H44441003_PIP-SCONN,HA   I187 @BASEBOARD_FAB2_LIB.BASEBOARD_FAB2(SCH_1):PAGE82

M_J_DQ<43> @BASEBOARD_FAB2_LIB.BASEBOARD_FAB2(SCH_1):M_J_DQ(43)
  U2D1  Y31 DDR2_DQ<43> SKX_EXT_B_BGA1-IC,TBD   I172 @BASEBOARD_FAB2_LIB.BASEBOARD_FAB2(SCH_1):PAGE59
  J1G3  115 DQ<42> SCONN288_H44441004_PIP-SCONN,HA   I186 @BASEBOARD_FAB2_LIB.BASEBOARD_FAB2(SCH_1):PAGE81
  J9U2  260 DQ<43> SCONN288_H44441003_PIP-SCONN,HA   I187 @BASEBOARD_FAB2_LIB.BASEBOARD_FAB2(SCH_1):PAGE82

M_J_DQ<44> @BASEBOARD_FAB2_LIB.BASEBOARD_FAB2(SCH_1):M_J_DQ(44)
  U2D1  V35 DDR2_DQ<44> SKX_EXT_B_BGA1-IC,TBD   I172 @BASEBOARD_FAB2_LIB.BASEBOARD_FAB2(SCH_1):PAGE59
  J1G3  251 DQ<45> SCONN288_H44441004_PIP-SCONN,HA   I186 @BASEBOARD_FAB2_LIB.BASEBOARD_FAB2(SCH_1):PAGE81
  J9U2  106 DQ<44> SCONN288_H44441003_PIP-SCONN,HA   I187 @BASEBOARD_FAB2_LIB.BASEBOARD_FAB2(SCH_1):PAGE82

M_J_DQ<45> @BASEBOARD_FAB2_LIB.BASEBOARD_FAB2(SCH_1):M_J_DQ(45)
  U2D1  Y35 DDR2_DQ<45> SKX_EXT_B_BGA1-IC,TBD   I172 @BASEBOARD_FAB2_LIB.BASEBOARD_FAB2(SCH_1):PAGE59
  J1G3  106 DQ<44> SCONN288_H44441004_PIP-SCONN,HA   I186 @BASEBOARD_FAB2_LIB.BASEBOARD_FAB2(SCH_1):PAGE81
  J9U2  251 DQ<45> SCONN288_H44441003_PIP-SCONN,HA   I187 @BASEBOARD_FAB2_LIB.BASEBOARD_FAB2(SCH_1):PAGE82

M_J_DQ<46> @BASEBOARD_FAB2_LIB.BASEBOARD_FAB2(SCH_1):M_J_DQ(46)
  U2D1  U32 DDR2_DQ<46> SKX_EXT_B_BGA1-IC,TBD   I172 @BASEBOARD_FAB2_LIB.BASEBOARD_FAB2(SCH_1):PAGE59
  J1G3  258 DQ<47> SCONN288_H44441004_PIP-SCONN,HA   I186 @BASEBOARD_FAB2_LIB.BASEBOARD_FAB2(SCH_1):PAGE81
  J9U2  113 DQ<46> SCONN288_H44441003_PIP-SCONN,HA   I187 @BASEBOARD_FAB2_LIB.BASEBOARD_FAB2(SCH_1):PAGE82

M_J_DQ<47> @BASEBOARD_FAB2_LIB.BASEBOARD_FAB2(SCH_1):M_J_DQ(47)
  U2D1 AA32 DDR2_DQ<47> SKX_EXT_B_BGA1-IC,TBD   I172 @BASEBOARD_FAB2_LIB.BASEBOARD_FAB2(SCH_1):PAGE59
  J1G3  113 DQ<46> SCONN288_H44441004_PIP-SCONN,HA   I186 @BASEBOARD_FAB2_LIB.BASEBOARD_FAB2(SCH_1):PAGE81
  J9U2  258 DQ<47> SCONN288_H44441003_PIP-SCONN,HA   I187 @BASEBOARD_FAB2_LIB.BASEBOARD_FAB2(SCH_1):PAGE82

M_J_DQ<48> @BASEBOARD_FAB2_LIB.BASEBOARD_FAB2(SCH_1):M_J_DQ(48)
  U2D1 AD31 DDR2_DQ<48> SKX_EXT_B_BGA1-IC,TBD   I172 @BASEBOARD_FAB2_LIB.BASEBOARD_FAB2(SCH_1):PAGE59
  J1G3  264 DQ<49> SCONN288_H44441004_PIP-SCONN,HA   I186 @BASEBOARD_FAB2_LIB.BASEBOARD_FAB2(SCH_1):PAGE81
  J9U2  119 DQ<48> SCONN288_H44441003_PIP-SCONN,HA   I187 @BASEBOARD_FAB2_LIB.BASEBOARD_FAB2(SCH_1):PAGE82

M_J_DQ<49> @BASEBOARD_FAB2_LIB.BASEBOARD_FAB2(SCH_1):M_J_DQ(49)
  U2D1 AH31 DDR2_DQ<49> SKX_EXT_B_BGA1-IC,TBD   I172 @BASEBOARD_FAB2_LIB.BASEBOARD_FAB2(SCH_1):PAGE59
  J1G3  119 DQ<48> SCONN288_H44441004_PIP-SCONN,HA   I186 @BASEBOARD_FAB2_LIB.BASEBOARD_FAB2(SCH_1):PAGE81
  J9U2  264 DQ<49> SCONN288_H44441003_PIP-SCONN,HA   I187 @BASEBOARD_FAB2_LIB.BASEBOARD_FAB2(SCH_1):PAGE82

M_J_DQ<4> @BASEBOARD_FAB2_LIB.BASEBOARD_FAB2(SCH_1):M_J_DQ(4)
  U2D1 AT75 DDR2_DQ<4> SKX_EXT_B_BGA1-IC,TBD   I172 @BASEBOARD_FAB2_LIB.BASEBOARD_FAB2(SCH_1):PAGE59
  J1G3  148  DQ<5> SCONN288_H44441004_PIP-SCONN,HA   I186 @BASEBOARD_FAB2_LIB.BASEBOARD_FAB2(SCH_1):PAGE81
  J9U2    3  DQ<4> SCONN288_H44441003_PIP-SCONN,HA   I187 @BASEBOARD_FAB2_LIB.BASEBOARD_FAB2(SCH_1):PAGE82

M_J_DQ<50> @BASEBOARD_FAB2_LIB.BASEBOARD_FAB2(SCH_1):M_J_DQ(50)
  U2D1 AE28 DDR2_DQ<50> SKX_EXT_B_BGA1-IC,TBD   I172 @BASEBOARD_FAB2_LIB.BASEBOARD_FAB2(SCH_1):PAGE59
  J1G3  271 DQ<51> SCONN288_H44441004_PIP-SCONN,HA   I186 @BASEBOARD_FAB2_LIB.BASEBOARD_FAB2(SCH_1):PAGE81
  J9U2  126 DQ<50> SCONN288_H44441003_PIP-SCONN,HA   I187 @BASEBOARD_FAB2_LIB.BASEBOARD_FAB2(SCH_1):PAGE82

M_J_DQ<51> @BASEBOARD_FAB2_LIB.BASEBOARD_FAB2(SCH_1):M_J_DQ(51)
  U2D1 AG28 DDR2_DQ<51> SKX_EXT_B_BGA1-IC,TBD   I172 @BASEBOARD_FAB2_LIB.BASEBOARD_FAB2(SCH_1):PAGE59
  J1G3  126 DQ<50> SCONN288_H44441004_PIP-SCONN,HA   I186 @BASEBOARD_FAB2_LIB.BASEBOARD_FAB2(SCH_1):PAGE81
  J9U2  271 DQ<51> SCONN288_H44441003_PIP-SCONN,HA   I187 @BASEBOARD_FAB2_LIB.BASEBOARD_FAB2(SCH_1):PAGE82

M_J_DQ<52> @BASEBOARD_FAB2_LIB.BASEBOARD_FAB2(SCH_1):M_J_DQ(52)
  U2D1 AE32 DDR2_DQ<52> SKX_EXT_B_BGA1-IC,TBD   I172 @BASEBOARD_FAB2_LIB.BASEBOARD_FAB2(SCH_1):PAGE59
  J1G3  262 DQ<53> SCONN288_H44441004_PIP-SCONN,HA   I186 @BASEBOARD_FAB2_LIB.BASEBOARD_FAB2(SCH_1):PAGE81
  J9U2  117 DQ<52> SCONN288_H44441003_PIP-SCONN,HA   I187 @BASEBOARD_FAB2_LIB.BASEBOARD_FAB2(SCH_1):PAGE82

M_J_DQ<53> @BASEBOARD_FAB2_LIB.BASEBOARD_FAB2(SCH_1):M_J_DQ(53)
  U2D1 AG32 DDR2_DQ<53> SKX_EXT_B_BGA1-IC,TBD   I172 @BASEBOARD_FAB2_LIB.BASEBOARD_FAB2(SCH_1):PAGE59
  J1G3  117 DQ<52> SCONN288_H44441004_PIP-SCONN,HA   I186 @BASEBOARD_FAB2_LIB.BASEBOARD_FAB2(SCH_1):PAGE81
  J9U2  262 DQ<53> SCONN288_H44441003_PIP-SCONN,HA   I187 @BASEBOARD_FAB2_LIB.BASEBOARD_FAB2(SCH_1):PAGE82

M_J_DQ<54> @BASEBOARD_FAB2_LIB.BASEBOARD_FAB2(SCH_1):M_J_DQ(54)
  U2D1 AD29 DDR2_DQ<54> SKX_EXT_B_BGA1-IC,TBD   I172 @BASEBOARD_FAB2_LIB.BASEBOARD_FAB2(SCH_1):PAGE59
  J1G3  269 DQ<55> SCONN288_H44441004_PIP-SCONN,HA   I186 @BASEBOARD_FAB2_LIB.BASEBOARD_FAB2(SCH_1):PAGE81
  J9U2  124 DQ<54> SCONN288_H44441003_PIP-SCONN,HA   I187 @BASEBOARD_FAB2_LIB.BASEBOARD_FAB2(SCH_1):PAGE82

M_J_DQ<55> @BASEBOARD_FAB2_LIB.BASEBOARD_FAB2(SCH_1):M_J_DQ(55)
  U2D1 AH29 DDR2_DQ<55> SKX_EXT_B_BGA1-IC,TBD   I172 @BASEBOARD_FAB2_LIB.BASEBOARD_FAB2(SCH_1):PAGE59
  J1G3  124 DQ<54> SCONN288_H44441004_PIP-SCONN,HA   I186 @BASEBOARD_FAB2_LIB.BASEBOARD_FAB2(SCH_1):PAGE81
  J9U2  269 DQ<55> SCONN288_H44441003_PIP-SCONN,HA   I187 @BASEBOARD_FAB2_LIB.BASEBOARD_FAB2(SCH_1):PAGE82

M_J_DQ<56> @BASEBOARD_FAB2_LIB.BASEBOARD_FAB2(SCH_1):M_J_DQ(56)
  U2D1 AD25 DDR2_DQ<56> SKX_EXT_B_BGA1-IC,TBD   I172 @BASEBOARD_FAB2_LIB.BASEBOARD_FAB2(SCH_1):PAGE59
  J1G3  275 DQ<57> SCONN288_H44441004_PIP-SCONN,HA   I186 @BASEBOARD_FAB2_LIB.BASEBOARD_FAB2(SCH_1):PAGE81
  J9U2  130 DQ<56> SCONN288_H44441003_PIP-SCONN,HA   I187 @BASEBOARD_FAB2_LIB.BASEBOARD_FAB2(SCH_1):PAGE82

M_J_DQ<57> @BASEBOARD_FAB2_LIB.BASEBOARD_FAB2(SCH_1):M_J_DQ(57)
  U2D1 AH25 DDR2_DQ<57> SKX_EXT_B_BGA1-IC,TBD   I172 @BASEBOARD_FAB2_LIB.BASEBOARD_FAB2(SCH_1):PAGE59
  J1G3  130 DQ<56> SCONN288_H44441004_PIP-SCONN,HA   I186 @BASEBOARD_FAB2_LIB.BASEBOARD_FAB2(SCH_1):PAGE81
  J9U2  275 DQ<57> SCONN288_H44441003_PIP-SCONN,HA   I187 @BASEBOARD_FAB2_LIB.BASEBOARD_FAB2(SCH_1):PAGE82

M_J_DQ<58> @BASEBOARD_FAB2_LIB.BASEBOARD_FAB2(SCH_1):M_J_DQ(58)
  U2D1 AE22 DDR2_DQ<58> SKX_EXT_B_BGA1-IC,TBD   I172 @BASEBOARD_FAB2_LIB.BASEBOARD_FAB2(SCH_1):PAGE59
  J1G3  282 DQ<59> SCONN288_H44441004_PIP-SCONN,HA   I186 @BASEBOARD_FAB2_LIB.BASEBOARD_FAB2(SCH_1):PAGE81
  J9U2  137 DQ<58> SCONN288_H44441003_PIP-SCONN,HA   I187 @BASEBOARD_FAB2_LIB.BASEBOARD_FAB2(SCH_1):PAGE82

M_J_DQ<59> @BASEBOARD_FAB2_LIB.BASEBOARD_FAB2(SCH_1):M_J_DQ(59)
  U2D1 AG22 DDR2_DQ<59> SKX_EXT_B_BGA1-IC,TBD   I172 @BASEBOARD_FAB2_LIB.BASEBOARD_FAB2(SCH_1):PAGE59
  J1G3  137 DQ<58> SCONN288_H44441004_PIP-SCONN,HA   I186 @BASEBOARD_FAB2_LIB.BASEBOARD_FAB2(SCH_1):PAGE81
  J9U2  282 DQ<59> SCONN288_H44441003_PIP-SCONN,HA   I187 @BASEBOARD_FAB2_LIB.BASEBOARD_FAB2(SCH_1):PAGE82

M_J_DQ<5> @BASEBOARD_FAB2_LIB.BASEBOARD_FAB2(SCH_1):M_J_DQ(5)
  U2D1 AR74 DDR2_DQ<5> SKX_EXT_B_BGA1-IC,TBD   I172 @BASEBOARD_FAB2_LIB.BASEBOARD_FAB2(SCH_1):PAGE59
  J1G3    3  DQ<4> SCONN288_H44441004_PIP-SCONN,HA   I186 @BASEBOARD_FAB2_LIB.BASEBOARD_FAB2(SCH_1):PAGE81
  J9U2  148  DQ<5> SCONN288_H44441003_PIP-SCONN,HA   I187 @BASEBOARD_FAB2_LIB.BASEBOARD_FAB2(SCH_1):PAGE82

M_J_DQ<60> @BASEBOARD_FAB2_LIB.BASEBOARD_FAB2(SCH_1):M_J_DQ(60)
  U2D1 AE26 DDR2_DQ<60> SKX_EXT_B_BGA1-IC,TBD   I172 @BASEBOARD_FAB2_LIB.BASEBOARD_FAB2(SCH_1):PAGE59
  J1G3  273 DQ<61> SCONN288_H44441004_PIP-SCONN,HA   I186 @BASEBOARD_FAB2_LIB.BASEBOARD_FAB2(SCH_1):PAGE81
  J9U2  128 DQ<60> SCONN288_H44441003_PIP-SCONN,HA   I187 @BASEBOARD_FAB2_LIB.BASEBOARD_FAB2(SCH_1):PAGE82

M_J_DQ<61> @BASEBOARD_FAB2_LIB.BASEBOARD_FAB2(SCH_1):M_J_DQ(61)
  U2D1 AG26 DDR2_DQ<61> SKX_EXT_B_BGA1-IC,TBD   I172 @BASEBOARD_FAB2_LIB.BASEBOARD_FAB2(SCH_1):PAGE59
  J1G3  128 DQ<60> SCONN288_H44441004_PIP-SCONN,HA   I186 @BASEBOARD_FAB2_LIB.BASEBOARD_FAB2(SCH_1):PAGE81
  J9U2  273 DQ<61> SCONN288_H44441003_PIP-SCONN,HA   I187 @BASEBOARD_FAB2_LIB.BASEBOARD_FAB2(SCH_1):PAGE82

M_J_DQ<62> @BASEBOARD_FAB2_LIB.BASEBOARD_FAB2(SCH_1):M_J_DQ(62)
  U2D1 AD23 DDR2_DQ<62> SKX_EXT_B_BGA1-IC,TBD   I172 @BASEBOARD_FAB2_LIB.BASEBOARD_FAB2(SCH_1):PAGE59
  J1G3  280 DQ<63> SCONN288_H44441004_PIP-SCONN,HA   I186 @BASEBOARD_FAB2_LIB.BASEBOARD_FAB2(SCH_1):PAGE81
  J9U2  135 DQ<62> SCONN288_H44441003_PIP-SCONN,HA   I187 @BASEBOARD_FAB2_LIB.BASEBOARD_FAB2(SCH_1):PAGE82

M_J_DQ<63> @BASEBOARD_FAB2_LIB.BASEBOARD_FAB2(SCH_1):M_J_DQ(63)
  U2D1 AH23 DDR2_DQ<63> SKX_EXT_B_BGA1-IC,TBD   I172 @BASEBOARD_FAB2_LIB.BASEBOARD_FAB2(SCH_1):PAGE59
  J1G3  135 DQ<62> SCONN288_H44441004_PIP-SCONN,HA   I186 @BASEBOARD_FAB2_LIB.BASEBOARD_FAB2(SCH_1):PAGE81
  J9U2  280 DQ<63> SCONN288_H44441003_PIP-SCONN,HA   I187 @BASEBOARD_FAB2_LIB.BASEBOARD_FAB2(SCH_1):PAGE82

M_J_DQ<6> @BASEBOARD_FAB2_LIB.BASEBOARD_FAB2(SCH_1):M_J_DQ(6)
  U2D1 AM77 DDR2_DQ<6> SKX_EXT_B_BGA1-IC,TBD   I172 @BASEBOARD_FAB2_LIB.BASEBOARD_FAB2(SCH_1):PAGE59
  J1G3  155  DQ<7> SCONN288_H44441004_PIP-SCONN,HA   I186 @BASEBOARD_FAB2_LIB.BASEBOARD_FAB2(SCH_1):PAGE81
  J9U2   10  DQ<6> SCONN288_H44441003_PIP-SCONN,HA   I187 @BASEBOARD_FAB2_LIB.BASEBOARD_FAB2(SCH_1):PAGE82

M_J_DQ<7> @BASEBOARD_FAB2_LIB.BASEBOARD_FAB2(SCH_1):M_J_DQ(7)
  U2D1 AK75 DDR2_DQ<7> SKX_EXT_B_BGA1-IC,TBD   I172 @BASEBOARD_FAB2_LIB.BASEBOARD_FAB2(SCH_1):PAGE59
  J1G3   10  DQ<6> SCONN288_H44441004_PIP-SCONN,HA   I186 @BASEBOARD_FAB2_LIB.BASEBOARD_FAB2(SCH_1):PAGE81
  J9U2  155  DQ<7> SCONN288_H44441003_PIP-SCONN,HA   I187 @BASEBOARD_FAB2_LIB.BASEBOARD_FAB2(SCH_1):PAGE82

M_J_DQ<8> @BASEBOARD_FAB2_LIB.BASEBOARD_FAB2(SCH_1):M_J_DQ(8)
  U2D1 AE76 DDR2_DQ<8> SKX_EXT_B_BGA1-IC,TBD   I172 @BASEBOARD_FAB2_LIB.BASEBOARD_FAB2(SCH_1):PAGE59
  J1G3  161  DQ<9> SCONN288_H44441004_PIP-SCONN,HA   I186 @BASEBOARD_FAB2_LIB.BASEBOARD_FAB2(SCH_1):PAGE81
  J9U2   16  DQ<8> SCONN288_H44441003_PIP-SCONN,HA   I187 @BASEBOARD_FAB2_LIB.BASEBOARD_FAB2(SCH_1):PAGE82

M_J_DQ<9> @BASEBOARD_FAB2_LIB.BASEBOARD_FAB2(SCH_1):M_J_DQ(9)
  U2D1 AC74 DDR2_DQ<9> SKX_EXT_B_BGA1-IC,TBD   I172 @BASEBOARD_FAB2_LIB.BASEBOARD_FAB2(SCH_1):PAGE59
  J1G3   16  DQ<8> SCONN288_H44441004_PIP-SCONN,HA   I186 @BASEBOARD_FAB2_LIB.BASEBOARD_FAB2(SCH_1):PAGE81
  J9U2  161  DQ<9> SCONN288_H44441003_PIP-SCONN,HA   I187 @BASEBOARD_FAB2_LIB.BASEBOARD_FAB2(SCH_1):PAGE82

M_J_DQS_DN<0> @BASEBOARD_FAB2_LIB.BASEBOARD_FAB2(SCH_1):M_J_DQS_DN(0)
  U2D1 AL74 DDR2_DQS_DN<0> SKX_EXT_B_BGA1-IC,TBD   I172 @BASEBOARD_FAB2_LIB.BASEBOARD_FAB2(SCH_1):PAGE59
  J1G3  152  DQS0N SCONN288_H44441004_PIP-SCONN,HA    I67 @BASEBOARD_FAB2_LIB.BASEBOARD_FAB2(SCH_1):PAGE81
  J9U2  152  DQS0N SCONN288_H44441003_PIP-SCONN,HA    I64 @BASEBOARD_FAB2_LIB.BASEBOARD_FAB2(SCH_1):PAGE82

M_J_DQS_DN<10> @BASEBOARD_FAB2_LIB.BASEBOARD_FAB2(SCH_1):M_J_DQS_DN(10)
  U2D1 AD77 DDR2_DQS_DN<10> SKX_EXT_B_BGA1-IC,TBD   I172 @BASEBOARD_FAB2_LIB.BASEBOARD_FAB2(SCH_1):PAGE59
  J1G3   19 DQS10N SCONN288_H44441004_PIP-SCONN,HA    I67 @BASEBOARD_FAB2_LIB.BASEBOARD_FAB2(SCH_1):PAGE81
  J9U2   19 DQS10N SCONN288_H44441003_PIP-SCONN,HA    I64 @BASEBOARD_FAB2_LIB.BASEBOARD_FAB2(SCH_1):PAGE82

M_J_DQS_DN<11> @BASEBOARD_FAB2_LIB.BASEBOARD_FAB2(SCH_1):M_J_DQS_DN(11)
  U2D1  U72 DDR2_DQS_DN<11> SKX_EXT_B_BGA1-IC,TBD   I172 @BASEBOARD_FAB2_LIB.BASEBOARD_FAB2(SCH_1):PAGE59
  J1G3   30 DQS11N SCONN288_H44441004_PIP-SCONN,HA    I67 @BASEBOARD_FAB2_LIB.BASEBOARD_FAB2(SCH_1):PAGE81
  J9U2   30 DQS11N SCONN288_H44441003_PIP-SCONN,HA    I64 @BASEBOARD_FAB2_LIB.BASEBOARD_FAB2(SCH_1):PAGE82

M_J_DQS_DN<12> @BASEBOARD_FAB2_LIB.BASEBOARD_FAB2(SCH_1):M_J_DQS_DN(12)
  U2D1 AL66 DDR2_DQS_DN<12> SKX_EXT_B_BGA1-IC,TBD   I172 @BASEBOARD_FAB2_LIB.BASEBOARD_FAB2(SCH_1):PAGE59
  J1G3   41 DQS12N SCONN288_H44441004_PIP-SCONN,HA    I67 @BASEBOARD_FAB2_LIB.BASEBOARD_FAB2(SCH_1):PAGE81
  J9U2   41 DQS12N SCONN288_H44441003_PIP-SCONN,HA    I64 @BASEBOARD_FAB2_LIB.BASEBOARD_FAB2(SCH_1):PAGE82

M_J_DQS_DN<13> @BASEBOARD_FAB2_LIB.BASEBOARD_FAB2(SCH_1):M_J_DQS_DN(13)
  U2D1  T39 DDR2_DQS_DN<13> SKX_EXT_B_BGA1-IC,TBD   I172 @BASEBOARD_FAB2_LIB.BASEBOARD_FAB2(SCH_1):PAGE59
  J1G3  100 DQS13N SCONN288_H44441004_PIP-SCONN,HA    I67 @BASEBOARD_FAB2_LIB.BASEBOARD_FAB2(SCH_1):PAGE81
  J9U2  100 DQS13N SCONN288_H44441003_PIP-SCONN,HA    I64 @BASEBOARD_FAB2_LIB.BASEBOARD_FAB2(SCH_1):PAGE82

M_J_DQS_DN<14> @BASEBOARD_FAB2_LIB.BASEBOARD_FAB2(SCH_1):M_J_DQS_DN(14)
  U2D1  T33 DDR2_DQS_DN<14> SKX_EXT_B_BGA1-IC,TBD   I172 @BASEBOARD_FAB2_LIB.BASEBOARD_FAB2(SCH_1):PAGE59
  J1G3  111 DQS14N SCONN288_H44441004_PIP-SCONN,HA    I67 @BASEBOARD_FAB2_LIB.BASEBOARD_FAB2(SCH_1):PAGE81
  J9U2  111 DQS14N SCONN288_H44441003_PIP-SCONN,HA    I64 @BASEBOARD_FAB2_LIB.BASEBOARD_FAB2(SCH_1):PAGE82

M_J_DQS_DN<15> @BASEBOARD_FAB2_LIB.BASEBOARD_FAB2(SCH_1):M_J_DQS_DN(15)
  U2D1 AC30 DDR2_DQS_DN<15> SKX_EXT_B_BGA1-IC,TBD   I172 @BASEBOARD_FAB2_LIB.BASEBOARD_FAB2(SCH_1):PAGE59
  J1G3  122 DQS15N SCONN288_H44441004_PIP-SCONN,HA    I67 @BASEBOARD_FAB2_LIB.BASEBOARD_FAB2(SCH_1):PAGE81
  J9U2  122 DQS15N SCONN288_H44441003_PIP-SCONN,HA    I64 @BASEBOARD_FAB2_LIB.BASEBOARD_FAB2(SCH_1):PAGE82

M_J_DQS_DN<16> @BASEBOARD_FAB2_LIB.BASEBOARD_FAB2(SCH_1):M_J_DQS_DN(16)
  U2D1 AC24 DDR2_DQS_DN<16> SKX_EXT_B_BGA1-IC,TBD   I172 @BASEBOARD_FAB2_LIB.BASEBOARD_FAB2(SCH_1):PAGE59
  J1G3  133 DQS16N SCONN288_H44441004_PIP-SCONN,HA    I67 @BASEBOARD_FAB2_LIB.BASEBOARD_FAB2(SCH_1):PAGE81
  J9U2  133 DQS16N SCONN288_H44441003_PIP-SCONN,HA    I64 @BASEBOARD_FAB2_LIB.BASEBOARD_FAB2(SCH_1):PAGE82

M_J_DQS_DN<17> @BASEBOARD_FAB2_LIB.BASEBOARD_FAB2(SCH_1):M_J_DQS_DN(17)
  U2D1 AT71 DDR2_DQS_DN<17> SKX_EXT_B_BGA1-IC,TBD   I172 @BASEBOARD_FAB2_LIB.BASEBOARD_FAB2(SCH_1):PAGE59
  J1G3   52 DQS17N SCONN288_H44441004_PIP-SCONN,HA    I67 @BASEBOARD_FAB2_LIB.BASEBOARD_FAB2(SCH_1):PAGE81
  J9U2   52 DQS17N SCONN288_H44441003_PIP-SCONN,HA    I64 @BASEBOARD_FAB2_LIB.BASEBOARD_FAB2(SCH_1):PAGE82

M_J_DQS_DN<1> @BASEBOARD_FAB2_LIB.BASEBOARD_FAB2(SCH_1):M_J_DQS_DN(1)
  U2D1 AA74 DDR2_DQS_DN<1> SKX_EXT_B_BGA1-IC,TBD   I172 @BASEBOARD_FAB2_LIB.BASEBOARD_FAB2(SCH_1):PAGE59
  J1G3  163  DQS1N SCONN288_H44441004_PIP-SCONN,HA    I67 @BASEBOARD_FAB2_LIB.BASEBOARD_FAB2(SCH_1):PAGE81
  J9U2  163  DQS1N SCONN288_H44441003_PIP-SCONN,HA    I64 @BASEBOARD_FAB2_LIB.BASEBOARD_FAB2(SCH_1):PAGE82

M_J_DQS_DN<2> @BASEBOARD_FAB2_LIB.BASEBOARD_FAB2(SCH_1):M_J_DQS_DN(2)
  U2D1  Y69 DDR2_DQS_DN<2> SKX_EXT_B_BGA1-IC,TBD   I172 @BASEBOARD_FAB2_LIB.BASEBOARD_FAB2(SCH_1):PAGE59
  J1G3  174  DQS2N SCONN288_H44441004_PIP-SCONN,HA    I67 @BASEBOARD_FAB2_LIB.BASEBOARD_FAB2(SCH_1):PAGE81
  J9U2  174  DQS2N SCONN288_H44441003_PIP-SCONN,HA    I64 @BASEBOARD_FAB2_LIB.BASEBOARD_FAB2(SCH_1):PAGE82

M_J_DQS_DN<3> @BASEBOARD_FAB2_LIB.BASEBOARD_FAB2(SCH_1):M_J_DQS_DN(3)
  U2D1 AU66 DDR2_DQS_DN<3> SKX_EXT_B_BGA1-IC,TBD   I172 @BASEBOARD_FAB2_LIB.BASEBOARD_FAB2(SCH_1):PAGE59
  J1G3  185  DQS3N SCONN288_H44441004_PIP-SCONN,HA    I67 @BASEBOARD_FAB2_LIB.BASEBOARD_FAB2(SCH_1):PAGE81
  J9U2  185  DQS3N SCONN288_H44441003_PIP-SCONN,HA    I64 @BASEBOARD_FAB2_LIB.BASEBOARD_FAB2(SCH_1):PAGE82

M_J_DQS_DN<4> @BASEBOARD_FAB2_LIB.BASEBOARD_FAB2(SCH_1):M_J_DQS_DN(4)
  U2D1 AB39 DDR2_DQS_DN<4> SKX_EXT_B_BGA1-IC,TBD   I172 @BASEBOARD_FAB2_LIB.BASEBOARD_FAB2(SCH_1):PAGE59
  J1G3  244  DQS4N SCONN288_H44441004_PIP-SCONN,HA    I67 @BASEBOARD_FAB2_LIB.BASEBOARD_FAB2(SCH_1):PAGE81
  J9U2  244  DQS4N SCONN288_H44441003_PIP-SCONN,HA    I64 @BASEBOARD_FAB2_LIB.BASEBOARD_FAB2(SCH_1):PAGE82

M_J_DQS_DN<5> @BASEBOARD_FAB2_LIB.BASEBOARD_FAB2(SCH_1):M_J_DQS_DN(5)
  U2D1 AB33 DDR2_DQS_DN<5> SKX_EXT_B_BGA1-IC,TBD   I172 @BASEBOARD_FAB2_LIB.BASEBOARD_FAB2(SCH_1):PAGE59
  J1G3  255  DQS5N SCONN288_H44441004_PIP-SCONN,HA    I67 @BASEBOARD_FAB2_LIB.BASEBOARD_FAB2(SCH_1):PAGE81
  J9U2  255  DQS5N SCONN288_H44441003_PIP-SCONN,HA    I64 @BASEBOARD_FAB2_LIB.BASEBOARD_FAB2(SCH_1):PAGE82

M_J_DQS_DN<6> @BASEBOARD_FAB2_LIB.BASEBOARD_FAB2(SCH_1):M_J_DQS_DN(6)
  U2D1 AJ30 DDR2_DQS_DN<6> SKX_EXT_B_BGA1-IC,TBD   I172 @BASEBOARD_FAB2_LIB.BASEBOARD_FAB2(SCH_1):PAGE59
  J1G3  266  DQS6N SCONN288_H44441004_PIP-SCONN,HA    I67 @BASEBOARD_FAB2_LIB.BASEBOARD_FAB2(SCH_1):PAGE81
  J9U2  266  DQS6N SCONN288_H44441003_PIP-SCONN,HA    I64 @BASEBOARD_FAB2_LIB.BASEBOARD_FAB2(SCH_1):PAGE82

M_J_DQS_DN<7> @BASEBOARD_FAB2_LIB.BASEBOARD_FAB2(SCH_1):M_J_DQS_DN(7)
  U2D1 AJ24 DDR2_DQS_DN<7> SKX_EXT_B_BGA1-IC,TBD   I172 @BASEBOARD_FAB2_LIB.BASEBOARD_FAB2(SCH_1):PAGE59
  J1G3  277  DQS7N SCONN288_H44441004_PIP-SCONN,HA    I67 @BASEBOARD_FAB2_LIB.BASEBOARD_FAB2(SCH_1):PAGE81
  J9U2  277  DQS7N SCONN288_H44441003_PIP-SCONN,HA    I64 @BASEBOARD_FAB2_LIB.BASEBOARD_FAB2(SCH_1):PAGE82

M_J_DQS_DN<8> @BASEBOARD_FAB2_LIB.BASEBOARD_FAB2(SCH_1):M_J_DQS_DN(8)
  U2D1 BB71 DDR2_DQS_DN<8> SKX_EXT_B_BGA1-IC,TBD   I172 @BASEBOARD_FAB2_LIB.BASEBOARD_FAB2(SCH_1):PAGE59
  J1G3  196  DQS8N SCONN288_H44441004_PIP-SCONN,HA    I67 @BASEBOARD_FAB2_LIB.BASEBOARD_FAB2(SCH_1):PAGE81
  J9U2  196  DQS8N SCONN288_H44441003_PIP-SCONN,HA    I64 @BASEBOARD_FAB2_LIB.BASEBOARD_FAB2(SCH_1):PAGE82

M_J_DQS_DN<9> @BASEBOARD_FAB2_LIB.BASEBOARD_FAB2(SCH_1):M_J_DQS_DN(9)
  U2D1 AP77 DDR2_DQS_DN<9> SKX_EXT_B_BGA1-IC,TBD   I172 @BASEBOARD_FAB2_LIB.BASEBOARD_FAB2(SCH_1):PAGE59
  J1G3    8  DQS9N SCONN288_H44441004_PIP-SCONN,HA    I67 @BASEBOARD_FAB2_LIB.BASEBOARD_FAB2(SCH_1):PAGE81
  J9U2    8  DQS9N SCONN288_H44441003_PIP-SCONN,HA    I64 @BASEBOARD_FAB2_LIB.BASEBOARD_FAB2(SCH_1):PAGE82

M_J_DQS_DP<0> @BASEBOARD_FAB2_LIB.BASEBOARD_FAB2(SCH_1):M_J_DQS_DP(0)
  U2D1 AM75 DDR2_DQS_DP<0> SKX_EXT_B_BGA1-IC,TBD   I172 @BASEBOARD_FAB2_LIB.BASEBOARD_FAB2(SCH_1):PAGE59
  J1G3  153  DQS0P SCONN288_H44441004_PIP-SCONN,HA    I67 @BASEBOARD_FAB2_LIB.BASEBOARD_FAB2(SCH_1):PAGE81
  J9U2  153  DQS0P SCONN288_H44441003_PIP-SCONN,HA    I64 @BASEBOARD_FAB2_LIB.BASEBOARD_FAB2(SCH_1):PAGE82

M_J_DQS_DP<10> @BASEBOARD_FAB2_LIB.BASEBOARD_FAB2(SCH_1):M_J_DQS_DP(10)
  U2D1 AC76 DDR2_DQS_DP<10> SKX_EXT_B_BGA1-IC,TBD   I172 @BASEBOARD_FAB2_LIB.BASEBOARD_FAB2(SCH_1):PAGE59
  J1G3   18 DQS10P SCONN288_H44441004_PIP-SCONN,HA    I67 @BASEBOARD_FAB2_LIB.BASEBOARD_FAB2(SCH_1):PAGE81
  J9U2   18 DQS10P SCONN288_H44441003_PIP-SCONN,HA    I64 @BASEBOARD_FAB2_LIB.BASEBOARD_FAB2(SCH_1):PAGE82

M_J_DQS_DP<11> @BASEBOARD_FAB2_LIB.BASEBOARD_FAB2(SCH_1):M_J_DQS_DP(11)
  U2D1  V71 DDR2_DQS_DP<11> SKX_EXT_B_BGA1-IC,TBD   I172 @BASEBOARD_FAB2_LIB.BASEBOARD_FAB2(SCH_1):PAGE59
  J1G3   29 DQS11P SCONN288_H44441004_PIP-SCONN,HA    I67 @BASEBOARD_FAB2_LIB.BASEBOARD_FAB2(SCH_1):PAGE81
  J9U2   29 DQS11P SCONN288_H44441003_PIP-SCONN,HA    I64 @BASEBOARD_FAB2_LIB.BASEBOARD_FAB2(SCH_1):PAGE82

M_J_DQS_DP<12> @BASEBOARD_FAB2_LIB.BASEBOARD_FAB2(SCH_1):M_J_DQS_DP(12)
  U2D1 AN66 DDR2_DQS_DP<12> SKX_EXT_B_BGA1-IC,TBD   I172 @BASEBOARD_FAB2_LIB.BASEBOARD_FAB2(SCH_1):PAGE59
  J1G3   40 DQS12P SCONN288_H44441004_PIP-SCONN,HA    I67 @BASEBOARD_FAB2_LIB.BASEBOARD_FAB2(SCH_1):PAGE81
  J9U2   40 DQS12P SCONN288_H44441003_PIP-SCONN,HA    I64 @BASEBOARD_FAB2_LIB.BASEBOARD_FAB2(SCH_1):PAGE82

M_J_DQS_DP<13> @BASEBOARD_FAB2_LIB.BASEBOARD_FAB2(SCH_1):M_J_DQS_DP(13)
  U2D1  V39 DDR2_DQS_DP<13> SKX_EXT_B_BGA1-IC,TBD   I172 @BASEBOARD_FAB2_LIB.BASEBOARD_FAB2(SCH_1):PAGE59
  J1G3   99 DQS13P SCONN288_H44441004_PIP-SCONN,HA    I67 @BASEBOARD_FAB2_LIB.BASEBOARD_FAB2(SCH_1):PAGE81
  J9U2   99 DQS13P SCONN288_H44441003_PIP-SCONN,HA    I64 @BASEBOARD_FAB2_LIB.BASEBOARD_FAB2(SCH_1):PAGE82

M_J_DQS_DP<14> @BASEBOARD_FAB2_LIB.BASEBOARD_FAB2(SCH_1):M_J_DQS_DP(14)
  U2D1  V33 DDR2_DQS_DP<14> SKX_EXT_B_BGA1-IC,TBD   I172 @BASEBOARD_FAB2_LIB.BASEBOARD_FAB2(SCH_1):PAGE59
  J1G3  110 DQS14P SCONN288_H44441004_PIP-SCONN,HA    I67 @BASEBOARD_FAB2_LIB.BASEBOARD_FAB2(SCH_1):PAGE81
  J9U2  110 DQS14P SCONN288_H44441003_PIP-SCONN,HA    I64 @BASEBOARD_FAB2_LIB.BASEBOARD_FAB2(SCH_1):PAGE82

M_J_DQS_DP<15> @BASEBOARD_FAB2_LIB.BASEBOARD_FAB2(SCH_1):M_J_DQS_DP(15)
  U2D1 AE30 DDR2_DQS_DP<15> SKX_EXT_B_BGA1-IC,TBD   I172 @BASEBOARD_FAB2_LIB.BASEBOARD_FAB2(SCH_1):PAGE59
  J1G3  121 DQS15P SCONN288_H44441004_PIP-SCONN,HA    I67 @BASEBOARD_FAB2_LIB.BASEBOARD_FAB2(SCH_1):PAGE81
  J9U2  121 DQS15P SCONN288_H44441003_PIP-SCONN,HA    I64 @BASEBOARD_FAB2_LIB.BASEBOARD_FAB2(SCH_1):PAGE82

M_J_DQS_DP<16> @BASEBOARD_FAB2_LIB.BASEBOARD_FAB2(SCH_1):M_J_DQS_DP(16)
  U2D1 AE24 DDR2_DQS_DP<16> SKX_EXT_B_BGA1-IC,TBD   I172 @BASEBOARD_FAB2_LIB.BASEBOARD_FAB2(SCH_1):PAGE59
  J1G3  132 DQS16P SCONN288_H44441004_PIP-SCONN,HA    I67 @BASEBOARD_FAB2_LIB.BASEBOARD_FAB2(SCH_1):PAGE81
  J9U2  132 DQS16P SCONN288_H44441003_PIP-SCONN,HA    I64 @BASEBOARD_FAB2_LIB.BASEBOARD_FAB2(SCH_1):PAGE82

M_J_DQS_DP<17> @BASEBOARD_FAB2_LIB.BASEBOARD_FAB2(SCH_1):M_J_DQS_DP(17)
  U2D1 AV71 DDR2_DQS_DP<17> SKX_EXT_B_BGA1-IC,TBD   I172 @BASEBOARD_FAB2_LIB.BASEBOARD_FAB2(SCH_1):PAGE59
  J1G3   51 DQS17P SCONN288_H44441004_PIP-SCONN,HA    I67 @BASEBOARD_FAB2_LIB.BASEBOARD_FAB2(SCH_1):PAGE81
  J9U2   51 DQS17P SCONN288_H44441003_PIP-SCONN,HA    I64 @BASEBOARD_FAB2_LIB.BASEBOARD_FAB2(SCH_1):PAGE82

M_J_DQS_DP<1> @BASEBOARD_FAB2_LIB.BASEBOARD_FAB2(SCH_1):M_J_DQS_DP(1)
  U2D1 AB75 DDR2_DQS_DP<1> SKX_EXT_B_BGA1-IC,TBD   I172 @BASEBOARD_FAB2_LIB.BASEBOARD_FAB2(SCH_1):PAGE59
  J1G3  164  DQS1P SCONN288_H44441004_PIP-SCONN,HA    I67 @BASEBOARD_FAB2_LIB.BASEBOARD_FAB2(SCH_1):PAGE81
  J9U2  164  DQS1P SCONN288_H44441003_PIP-SCONN,HA    I64 @BASEBOARD_FAB2_LIB.BASEBOARD_FAB2(SCH_1):PAGE82

M_J_DQS_DP<2> @BASEBOARD_FAB2_LIB.BASEBOARD_FAB2(SCH_1):M_J_DQS_DP(2)
  U2D1  W70 DDR2_DQS_DP<2> SKX_EXT_B_BGA1-IC,TBD   I172 @BASEBOARD_FAB2_LIB.BASEBOARD_FAB2(SCH_1):PAGE59
  J1G3  175  DQS2P SCONN288_H44441004_PIP-SCONN,HA    I67 @BASEBOARD_FAB2_LIB.BASEBOARD_FAB2(SCH_1):PAGE81
  J9U2  175  DQS2P SCONN288_H44441003_PIP-SCONN,HA    I64 @BASEBOARD_FAB2_LIB.BASEBOARD_FAB2(SCH_1):PAGE82

M_J_DQS_DP<3> @BASEBOARD_FAB2_LIB.BASEBOARD_FAB2(SCH_1):M_J_DQS_DP(3)
  U2D1 AR66 DDR2_DQS_DP<3> SKX_EXT_B_BGA1-IC,TBD   I172 @BASEBOARD_FAB2_LIB.BASEBOARD_FAB2(SCH_1):PAGE59
  J1G3  186  DQS3P SCONN288_H44441004_PIP-SCONN,HA    I67 @BASEBOARD_FAB2_LIB.BASEBOARD_FAB2(SCH_1):PAGE81
  J9U2  186  DQS3P SCONN288_H44441003_PIP-SCONN,HA    I64 @BASEBOARD_FAB2_LIB.BASEBOARD_FAB2(SCH_1):PAGE82

M_J_DQS_DP<4> @BASEBOARD_FAB2_LIB.BASEBOARD_FAB2(SCH_1):M_J_DQS_DP(4)
  U2D1  Y39 DDR2_DQS_DP<4> SKX_EXT_B_BGA1-IC,TBD   I172 @BASEBOARD_FAB2_LIB.BASEBOARD_FAB2(SCH_1):PAGE59
  J1G3  245  DQS4P SCONN288_H44441004_PIP-SCONN,HA    I67 @BASEBOARD_FAB2_LIB.BASEBOARD_FAB2(SCH_1):PAGE81
  J9U2  245  DQS4P SCONN288_H44441003_PIP-SCONN,HA    I64 @BASEBOARD_FAB2_LIB.BASEBOARD_FAB2(SCH_1):PAGE82

M_J_DQS_DP<5> @BASEBOARD_FAB2_LIB.BASEBOARD_FAB2(SCH_1):M_J_DQS_DP(5)
  U2D1  Y33 DDR2_DQS_DP<5> SKX_EXT_B_BGA1-IC,TBD   I172 @BASEBOARD_FAB2_LIB.BASEBOARD_FAB2(SCH_1):PAGE59
  J1G3  256  DQS5P SCONN288_H44441004_PIP-SCONN,HA    I67 @BASEBOARD_FAB2_LIB.BASEBOARD_FAB2(SCH_1):PAGE81
  J9U2  256  DQS5P SCONN288_H44441003_PIP-SCONN,HA    I64 @BASEBOARD_FAB2_LIB.BASEBOARD_FAB2(SCH_1):PAGE82

M_J_DQS_DP<6> @BASEBOARD_FAB2_LIB.BASEBOARD_FAB2(SCH_1):M_J_DQS_DP(6)
  U2D1 AG30 DDR2_DQS_DP<6> SKX_EXT_B_BGA1-IC,TBD   I172 @BASEBOARD_FAB2_LIB.BASEBOARD_FAB2(SCH_1):PAGE59
  J1G3  267  DQS6P SCONN288_H44441004_PIP-SCONN,HA    I67 @BASEBOARD_FAB2_LIB.BASEBOARD_FAB2(SCH_1):PAGE81
  J9U2  267  DQS6P SCONN288_H44441003_PIP-SCONN,HA    I64 @BASEBOARD_FAB2_LIB.BASEBOARD_FAB2(SCH_1):PAGE82

M_J_DQS_DP<7> @BASEBOARD_FAB2_LIB.BASEBOARD_FAB2(SCH_1):M_J_DQS_DP(7)
  U2D1 AG24 DDR2_DQS_DP<7> SKX_EXT_B_BGA1-IC,TBD   I172 @BASEBOARD_FAB2_LIB.BASEBOARD_FAB2(SCH_1):PAGE59
  J1G3  278  DQS7P SCONN288_H44441004_PIP-SCONN,HA    I67 @BASEBOARD_FAB2_LIB.BASEBOARD_FAB2(SCH_1):PAGE81
  J9U2  278  DQS7P SCONN288_H44441003_PIP-SCONN,HA    I64 @BASEBOARD_FAB2_LIB.BASEBOARD_FAB2(SCH_1):PAGE82

M_J_DQS_DP<8> @BASEBOARD_FAB2_LIB.BASEBOARD_FAB2(SCH_1):M_J_DQS_DP(8)
  U2D1 AY71 DDR2_DQS_DP<8> SKX_EXT_B_BGA1-IC,TBD   I172 @BASEBOARD_FAB2_LIB.BASEBOARD_FAB2(SCH_1):PAGE59
  J1G3  197  DQS8P SCONN288_H44441004_PIP-SCONN,HA    I67 @BASEBOARD_FAB2_LIB.BASEBOARD_FAB2(SCH_1):PAGE81
  J9U2  197  DQS8P SCONN288_H44441003_PIP-SCONN,HA    I64 @BASEBOARD_FAB2_LIB.BASEBOARD_FAB2(SCH_1):PAGE82

M_J_DQS_DP<9> @BASEBOARD_FAB2_LIB.BASEBOARD_FAB2(SCH_1):M_J_DQS_DP(9)
  U2D1 AN76 DDR2_DQS_DP<9> SKX_EXT_B_BGA1-IC,TBD   I172 @BASEBOARD_FAB2_LIB.BASEBOARD_FAB2(SCH_1):PAGE59
  J1G3    7  DQS9P SCONN288_H44441004_PIP-SCONN,HA    I67 @BASEBOARD_FAB2_LIB.BASEBOARD_FAB2(SCH_1):PAGE81
  J9U2    7  DQS9P SCONN288_H44441003_PIP-SCONN,HA    I64 @BASEBOARD_FAB2_LIB.BASEBOARD_FAB2(SCH_1):PAGE82

M_J_ECC<0> @BASEBOARD_FAB2_LIB.BASEBOARD_FAB2(SCH_1):M_J_ECC(0)
  U2D1 AU72 DDR2_ECC<0> SKX_EXT_B_BGA1-IC,TBD   I172 @BASEBOARD_FAB2_LIB.BASEBOARD_FAB2(SCH_1):PAGE59
  J1G3  194  CB<1> SCONN288_H44441004_PIP-SCONN,HA   I186 @BASEBOARD_FAB2_LIB.BASEBOARD_FAB2(SCH_1):PAGE81
  J9U2   49  CB<0> SCONN288_H44441003_PIP-SCONN,HA   I187 @BASEBOARD_FAB2_LIB.BASEBOARD_FAB2(SCH_1):PAGE82

M_J_ECC<1> @BASEBOARD_FAB2_LIB.BASEBOARD_FAB2(SCH_1):M_J_ECC(1)
  U2D1 BA72 DDR2_ECC<1> SKX_EXT_B_BGA1-IC,TBD   I172 @BASEBOARD_FAB2_LIB.BASEBOARD_FAB2(SCH_1):PAGE59
  J1G3   49  CB<0> SCONN288_H44441004_PIP-SCONN,HA   I186 @BASEBOARD_FAB2_LIB.BASEBOARD_FAB2(SCH_1):PAGE81
  J9U2  194  CB<1> SCONN288_H44441003_PIP-SCONN,HA   I187 @BASEBOARD_FAB2_LIB.BASEBOARD_FAB2(SCH_1):PAGE82

M_J_ECC<2> @BASEBOARD_FAB2_LIB.BASEBOARD_FAB2(SCH_1):M_J_ECC(2)
  U2D1 AV69 DDR2_ECC<2> SKX_EXT_B_BGA1-IC,TBD   I172 @BASEBOARD_FAB2_LIB.BASEBOARD_FAB2(SCH_1):PAGE59
  J1G3  201  CB<3> SCONN288_H44441004_PIP-SCONN,HA   I186 @BASEBOARD_FAB2_LIB.BASEBOARD_FAB2(SCH_1):PAGE81
  J9U2   56  CB<2> SCONN288_H44441003_PIP-SCONN,HA   I187 @BASEBOARD_FAB2_LIB.BASEBOARD_FAB2(SCH_1):PAGE82

M_J_ECC<3> @BASEBOARD_FAB2_LIB.BASEBOARD_FAB2(SCH_1):M_J_ECC(3)
  U2D1 AY69 DDR2_ECC<3> SKX_EXT_B_BGA1-IC,TBD   I172 @BASEBOARD_FAB2_LIB.BASEBOARD_FAB2(SCH_1):PAGE59
  J1G3   56  CB<2> SCONN288_H44441004_PIP-SCONN,HA   I186 @BASEBOARD_FAB2_LIB.BASEBOARD_FAB2(SCH_1):PAGE81
  J9U2  201  CB<3> SCONN288_H44441003_PIP-SCONN,HA   I187 @BASEBOARD_FAB2_LIB.BASEBOARD_FAB2(SCH_1):PAGE82

M_J_ECC<4> @BASEBOARD_FAB2_LIB.BASEBOARD_FAB2(SCH_1):M_J_ECC(4)
  U2D1 AV73 DDR2_ECC<4> SKX_EXT_B_BGA1-IC,TBD   I172 @BASEBOARD_FAB2_LIB.BASEBOARD_FAB2(SCH_1):PAGE59
  J1G3  192  CB<5> SCONN288_H44441004_PIP-SCONN,HA   I186 @BASEBOARD_FAB2_LIB.BASEBOARD_FAB2(SCH_1):PAGE81
  J9U2   47  CB<4> SCONN288_H44441003_PIP-SCONN,HA   I187 @BASEBOARD_FAB2_LIB.BASEBOARD_FAB2(SCH_1):PAGE82

M_J_ECC<5> @BASEBOARD_FAB2_LIB.BASEBOARD_FAB2(SCH_1):M_J_ECC(5)
  U2D1 AY73 DDR2_ECC<5> SKX_EXT_B_BGA1-IC,TBD   I172 @BASEBOARD_FAB2_LIB.BASEBOARD_FAB2(SCH_1):PAGE59
  J1G3   47  CB<4> SCONN288_H44441004_PIP-SCONN,HA   I186 @BASEBOARD_FAB2_LIB.BASEBOARD_FAB2(SCH_1):PAGE81
  J9U2  192  CB<5> SCONN288_H44441003_PIP-SCONN,HA   I187 @BASEBOARD_FAB2_LIB.BASEBOARD_FAB2(SCH_1):PAGE82

M_J_ECC<6> @BASEBOARD_FAB2_LIB.BASEBOARD_FAB2(SCH_1):M_J_ECC(6)
  U2D1 AU70 DDR2_ECC<6> SKX_EXT_B_BGA1-IC,TBD   I172 @BASEBOARD_FAB2_LIB.BASEBOARD_FAB2(SCH_1):PAGE59
  J1G3  199  CB<7> SCONN288_H44441004_PIP-SCONN,HA   I186 @BASEBOARD_FAB2_LIB.BASEBOARD_FAB2(SCH_1):PAGE81
  J9U2   54  CB<6> SCONN288_H44441003_PIP-SCONN,HA   I187 @BASEBOARD_FAB2_LIB.BASEBOARD_FAB2(SCH_1):PAGE82

M_J_ECC<7> @BASEBOARD_FAB2_LIB.BASEBOARD_FAB2(SCH_1):M_J_ECC(7)
  U2D1 BA70 DDR2_ECC<7> SKX_EXT_B_BGA1-IC,TBD   I172 @BASEBOARD_FAB2_LIB.BASEBOARD_FAB2(SCH_1):PAGE59
  J1G3   54  CB<6> SCONN288_H44441004_PIP-SCONN,HA   I186 @BASEBOARD_FAB2_LIB.BASEBOARD_FAB2(SCH_1):PAGE81
  J9U2  199  CB<7> SCONN288_H44441003_PIP-SCONN,HA   I187 @BASEBOARD_FAB2_LIB.BASEBOARD_FAB2(SCH_1):PAGE82

M_J_MA<0> @BASEBOARD_FAB2_LIB.BASEBOARD_FAB2(SCH_1):M_J_MA(0)
  U2D1 AB53 DDR2_MA<0> SKX_EXT_B_BGA1-IC,TBD   I172 @BASEBOARD_FAB2_LIB.BASEBOARD_FAB2(SCH_1):PAGE59
  J1G3   79     A0 SCONN288_H44441004_PIP-SCONN,HA   I186 @BASEBOARD_FAB2_LIB.BASEBOARD_FAB2(SCH_1):PAGE81
  J9U2   79     A0 SCONN288_H44441003_PIP-SCONN,HA   I187 @BASEBOARD_FAB2_LIB.BASEBOARD_FAB2(SCH_1):PAGE82

M_J_MA<10> @BASEBOARD_FAB2_LIB.BASEBOARD_FAB2(SCH_1):M_J_MA(10)
  U2D1 AD55 DDR2_MA<10> SKX_EXT_B_BGA1-IC,TBD   I172 @BASEBOARD_FAB2_LIB.BASEBOARD_FAB2(SCH_1):PAGE59
  J1G3  225    A10 SCONN288_H44441004_PIP-SCONN,HA   I186 @BASEBOARD_FAB2_LIB.BASEBOARD_FAB2(SCH_1):PAGE81
  J9U2  225    A10 SCONN288_H44441003_PIP-SCONN,HA   I187 @BASEBOARD_FAB2_LIB.BASEBOARD_FAB2(SCH_1):PAGE82

M_J_MA<11> @BASEBOARD_FAB2_LIB.BASEBOARD_FAB2(SCH_1):M_J_MA(11)
  U2D1 AG60 DDR2_MA<11> SKX_EXT_B_BGA1-IC,TBD   I172 @BASEBOARD_FAB2_LIB.BASEBOARD_FAB2(SCH_1):PAGE59
  J1G3  210    A11 SCONN288_H44441004_PIP-SCONN,HA   I186 @BASEBOARD_FAB2_LIB.BASEBOARD_FAB2(SCH_1):PAGE81
  J9U2  210    A11 SCONN288_H44441003_PIP-SCONN,HA   I187 @BASEBOARD_FAB2_LIB.BASEBOARD_FAB2(SCH_1):PAGE82

M_J_MA<12> @BASEBOARD_FAB2_LIB.BASEBOARD_FAB2(SCH_1):M_J_MA(12)
  U2D1 AG62 DDR2_MA<12> SKX_EXT_B_BGA1-IC,TBD   I172 @BASEBOARD_FAB2_LIB.BASEBOARD_FAB2(SCH_1):PAGE59
  J1G3   65    A12 SCONN288_H44441004_PIP-SCONN,HA   I186 @BASEBOARD_FAB2_LIB.BASEBOARD_FAB2(SCH_1):PAGE81
  J9U2   65    A12 SCONN288_H44441003_PIP-SCONN,HA   I187 @BASEBOARD_FAB2_LIB.BASEBOARD_FAB2(SCH_1):PAGE82

M_J_MA<13> @BASEBOARD_FAB2_LIB.BASEBOARD_FAB2(SCH_1):M_J_MA(13)
  U2D1 AD53 DDR2_MA<13> SKX_EXT_B_BGA1-IC,TBD   I172 @BASEBOARD_FAB2_LIB.BASEBOARD_FAB2(SCH_1):PAGE59
  J1G3  232    A13 SCONN288_H44441004_PIP-SCONN,HA   I186 @BASEBOARD_FAB2_LIB.BASEBOARD_FAB2(SCH_1):PAGE81
  J9U2  232    A13 SCONN288_H44441003_PIP-SCONN,HA   I187 @BASEBOARD_FAB2_LIB.BASEBOARD_FAB2(SCH_1):PAGE82

M_J_MA<14> @BASEBOARD_FAB2_LIB.BASEBOARD_FAB2(SCH_1):M_J_MA(14)
  U2D1  W50 DDR2_MA<14> SKX_EXT_B_BGA1-IC,TBD   I172 @BASEBOARD_FAB2_LIB.BASEBOARD_FAB2(SCH_1):PAGE59
  J1G3  228 A14_WE_N SCONN288_H44441004_PIP-SCONN,HA   I186 @BASEBOARD_FAB2_LIB.BASEBOARD_FAB2(SCH_1):PAGE81
  J9U2  228 A14_WE_N SCONN288_H44441003_PIP-SCONN,HA   I187 @BASEBOARD_FAB2_LIB.BASEBOARD_FAB2(SCH_1):PAGE82

M_J_MA<15> @BASEBOARD_FAB2_LIB.BASEBOARD_FAB2(SCH_1):M_J_MA(15)
  U2D1 AE54 DDR2_MA<15> SKX_EXT_B_BGA1-IC,TBD   I172 @BASEBOARD_FAB2_LIB.BASEBOARD_FAB2(SCH_1):PAGE59
  J1G3   86 A15_CAS_N SCONN288_H44441004_PIP-SCONN,HA   I186 @BASEBOARD_FAB2_LIB.BASEBOARD_FAB2(SCH_1):PAGE81
  J9U2   86 A15_CAS_N SCONN288_H44441003_PIP-SCONN,HA   I187 @BASEBOARD_FAB2_LIB.BASEBOARD_FAB2(SCH_1):PAGE82

M_J_MA<16> @BASEBOARD_FAB2_LIB.BASEBOARD_FAB2(SCH_1):M_J_MA(16)
  U2D1 AA52 DDR2_MA<16> SKX_EXT_B_BGA1-IC,TBD   I172 @BASEBOARD_FAB2_LIB.BASEBOARD_FAB2(SCH_1):PAGE59
  J1G3   82 A16_RAS_N SCONN288_H44441004_PIP-SCONN,HA   I186 @BASEBOARD_FAB2_LIB.BASEBOARD_FAB2(SCH_1):PAGE81
  J9U2   82 A16_RAS_N SCONN288_H44441003_PIP-SCONN,HA   I187 @BASEBOARD_FAB2_LIB.BASEBOARD_FAB2(SCH_1):PAGE82

M_J_MA<17> @BASEBOARD_FAB2_LIB.BASEBOARD_FAB2(SCH_1):M_J_MA(17)
  U2D1 AC46 DDR2_MA<17> SKX_EXT_B_BGA1-IC,TBD   I172 @BASEBOARD_FAB2_LIB.BASEBOARD_FAB2(SCH_1):PAGE59
  J1G3  234    A17 SCONN288_H44441004_PIP-SCONN,HA   I186 @BASEBOARD_FAB2_LIB.BASEBOARD_FAB2(SCH_1):PAGE81
  J9U2  234    A17 SCONN288_H44441003_PIP-SCONN,HA   I187 @BASEBOARD_FAB2_LIB.BASEBOARD_FAB2(SCH_1):PAGE82

M_J_MA<1> @BASEBOARD_FAB2_LIB.BASEBOARD_FAB2(SCH_1):M_J_MA(1)
  U2D1 AE58 DDR2_MA<1> SKX_EXT_B_BGA1-IC,TBD   I172 @BASEBOARD_FAB2_LIB.BASEBOARD_FAB2(SCH_1):PAGE59
  J1G3   72     A1 SCONN288_H44441004_PIP-SCONN,HA   I186 @BASEBOARD_FAB2_LIB.BASEBOARD_FAB2(SCH_1):PAGE81
  J9U2   72     A1 SCONN288_H44441003_PIP-SCONN,HA   I187 @BASEBOARD_FAB2_LIB.BASEBOARD_FAB2(SCH_1):PAGE82

M_J_MA<2> @BASEBOARD_FAB2_LIB.BASEBOARD_FAB2(SCH_1):M_J_MA(2)
  U2D1 AD57 DDR2_MA<2> SKX_EXT_B_BGA1-IC,TBD   I172 @BASEBOARD_FAB2_LIB.BASEBOARD_FAB2(SCH_1):PAGE59
  J1G3  216     A2 SCONN288_H44441004_PIP-SCONN,HA   I186 @BASEBOARD_FAB2_LIB.BASEBOARD_FAB2(SCH_1):PAGE81
  J9U2  216     A2 SCONN288_H44441003_PIP-SCONN,HA   I187 @BASEBOARD_FAB2_LIB.BASEBOARD_FAB2(SCH_1):PAGE82

M_J_MA<3> @BASEBOARD_FAB2_LIB.BASEBOARD_FAB2(SCH_1):M_J_MA(3)
  U2D1  W58 DDR2_MA<3> SKX_EXT_B_BGA1-IC,TBD   I172 @BASEBOARD_FAB2_LIB.BASEBOARD_FAB2(SCH_1):PAGE59
  J1G3   71     A3 SCONN288_H44441004_PIP-SCONN,HA   I186 @BASEBOARD_FAB2_LIB.BASEBOARD_FAB2(SCH_1):PAGE81
  J9U2   71     A3 SCONN288_H44441003_PIP-SCONN,HA   I187 @BASEBOARD_FAB2_LIB.BASEBOARD_FAB2(SCH_1):PAGE82

M_J_MA<4> @BASEBOARD_FAB2_LIB.BASEBOARD_FAB2(SCH_1):M_J_MA(4)
  U2D1 AA58 DDR2_MA<4> SKX_EXT_B_BGA1-IC,TBD   I172 @BASEBOARD_FAB2_LIB.BASEBOARD_FAB2(SCH_1):PAGE59
  J1G3  214     A4 SCONN288_H44441004_PIP-SCONN,HA   I186 @BASEBOARD_FAB2_LIB.BASEBOARD_FAB2(SCH_1):PAGE81
  J9U2  214     A4 SCONN288_H44441003_PIP-SCONN,HA   I187 @BASEBOARD_FAB2_LIB.BASEBOARD_FAB2(SCH_1):PAGE82

M_J_MA<5> @BASEBOARD_FAB2_LIB.BASEBOARD_FAB2(SCH_1):M_J_MA(5)
  U2D1  V59 DDR2_MA<5> SKX_EXT_B_BGA1-IC,TBD   I172 @BASEBOARD_FAB2_LIB.BASEBOARD_FAB2(SCH_1):PAGE59
  J1G3  213     A5 SCONN288_H44441004_PIP-SCONN,HA   I186 @BASEBOARD_FAB2_LIB.BASEBOARD_FAB2(SCH_1):PAGE81
  J9U2  213     A5 SCONN288_H44441003_PIP-SCONN,HA   I187 @BASEBOARD_FAB2_LIB.BASEBOARD_FAB2(SCH_1):PAGE82

M_J_MA<6> @BASEBOARD_FAB2_LIB.BASEBOARD_FAB2(SCH_1):M_J_MA(6)
  U2D1 AB59 DDR2_MA<6> SKX_EXT_B_BGA1-IC,TBD   I172 @BASEBOARD_FAB2_LIB.BASEBOARD_FAB2(SCH_1):PAGE59
  J1G3   69     A6 SCONN288_H44441004_PIP-SCONN,HA   I186 @BASEBOARD_FAB2_LIB.BASEBOARD_FAB2(SCH_1):PAGE81
  J9U2   69     A6 SCONN288_H44441003_PIP-SCONN,HA   I187 @BASEBOARD_FAB2_LIB.BASEBOARD_FAB2(SCH_1):PAGE82

M_J_MA<7> @BASEBOARD_FAB2_LIB.BASEBOARD_FAB2(SCH_1):M_J_MA(7)
  U2D1 AE60 DDR2_MA<7> SKX_EXT_B_BGA1-IC,TBD   I172 @BASEBOARD_FAB2_LIB.BASEBOARD_FAB2(SCH_1):PAGE59
  J1G3  211     A7 SCONN288_H44441004_PIP-SCONN,HA   I186 @BASEBOARD_FAB2_LIB.BASEBOARD_FAB2(SCH_1):PAGE81
  J9U2  211     A7 SCONN288_H44441003_PIP-SCONN,HA   I187 @BASEBOARD_FAB2_LIB.BASEBOARD_FAB2(SCH_1):PAGE82

M_J_MA<8> @BASEBOARD_FAB2_LIB.BASEBOARD_FAB2(SCH_1):M_J_MA(8)
  U2D1 AD59 DDR2_MA<8> SKX_EXT_B_BGA1-IC,TBD   I172 @BASEBOARD_FAB2_LIB.BASEBOARD_FAB2(SCH_1):PAGE59
  J1G3   68     A8 SCONN288_H44441004_PIP-SCONN,HA   I186 @BASEBOARD_FAB2_LIB.BASEBOARD_FAB2(SCH_1):PAGE81
  J9U2   68     A8 SCONN288_H44441003_PIP-SCONN,HA   I187 @BASEBOARD_FAB2_LIB.BASEBOARD_FAB2(SCH_1):PAGE82

M_J_MA<9> @BASEBOARD_FAB2_LIB.BASEBOARD_FAB2(SCH_1):M_J_MA(9)
  U2D1 AG58 DDR2_MA<9> SKX_EXT_B_BGA1-IC,TBD   I172 @BASEBOARD_FAB2_LIB.BASEBOARD_FAB2(SCH_1):PAGE59
  J1G3   66     A9 SCONN288_H44441004_PIP-SCONN,HA   I186 @BASEBOARD_FAB2_LIB.BASEBOARD_FAB2(SCH_1):PAGE81
  J9U2   66     A9 SCONN288_H44441003_PIP-SCONN,HA   I187 @BASEBOARD_FAB2_LIB.BASEBOARD_FAB2(SCH_1):PAGE82

M_J_ODT<0> @BASEBOARD_FAB2_LIB.BASEBOARD_FAB2(SCH_1):M_J_ODT(0)
  U2D1 AA50 DDR2_ODT<0> SKX_EXT_B_BGA1-IC,TBD   I172 @BASEBOARD_FAB2_LIB.BASEBOARD_FAB2(SCH_1):PAGE59
  J1G3   87 ODT<0> SCONN288_H44441004_PIP-SCONN,HA   I186 @BASEBOARD_FAB2_LIB.BASEBOARD_FAB2(SCH_1):PAGE81

M_J_ODT<1> @BASEBOARD_FAB2_LIB.BASEBOARD_FAB2(SCH_1):M_J_ODT(1)
  U2D1 AA48 DDR2_ODT<1> SKX_EXT_B_BGA1-IC,TBD   I172 @BASEBOARD_FAB2_LIB.BASEBOARD_FAB2(SCH_1):PAGE59
  J1G3   91 ODT<1> SCONN288_H44441004_PIP-SCONN,HA   I186 @BASEBOARD_FAB2_LIB.BASEBOARD_FAB2(SCH_1):PAGE81

M_J_ODT<2> @BASEBOARD_FAB2_LIB.BASEBOARD_FAB2(SCH_1):M_J_ODT(2)
  U2D1  V49 DDR2_ODT<2> SKX_EXT_B_BGA1-IC,TBD   I172 @BASEBOARD_FAB2_LIB.BASEBOARD_FAB2(SCH_1):PAGE59
  J9U2   87 ODT<0> SCONN288_H44441003_PIP-SCONN,HA   I187 @BASEBOARD_FAB2_LIB.BASEBOARD_FAB2(SCH_1):PAGE82

M_J_ODT<3> @BASEBOARD_FAB2_LIB.BASEBOARD_FAB2(SCH_1):M_J_ODT(3)
  U2D1 AB47 DDR2_ODT<3> SKX_EXT_B_BGA1-IC,TBD   I172 @BASEBOARD_FAB2_LIB.BASEBOARD_FAB2(SCH_1):PAGE59
  J9U2   91 ODT<1> SCONN288_H44441003_PIP-SCONN,HA   I187 @BASEBOARD_FAB2_LIB.BASEBOARD_FAB2(SCH_1):PAGE82

M_J_PAR @BASEBOARD_FAB2_LIB.BASEBOARD_FAB2(SCH_1):M_J_PAR
  U2D1  V53 DDR2_PAR SKX_EXT_B_BGA1-IC,TBD   I172 @BASEBOARD_FAB2_LIB.BASEBOARD_FAB2(SCH_1):PAGE59
  J1G3  222    PAR SCONN288_H44441004_PIP-SCONN,HA   I186 @BASEBOARD_FAB2_LIB.BASEBOARD_FAB2(SCH_1):PAGE81
  J9U2  222    PAR SCONN288_H44441003_PIP-SCONN,HA   I187 @BASEBOARD_FAB2_LIB.BASEBOARD_FAB2(SCH_1):PAGE82

M_J_VREF @BASEBOARD_FAB2_LIB.BASEBOARD_FAB2(SCH_1):M_J_VREF
 C9U10    1      A CAP_A_0402V-0.01UF,25V,10%,X7RA   I178 @BASEBOARD_FAB2_LIB.BASEBOARD_FAB2(SCH_1):PAGE81
  J1G3  146 VREFCA SCONN288_H44441004_PIP-SCONN,HA   I186 @BASEBOARD_FAB2_LIB.BASEBOARD_FAB2(SCH_1):PAGE81
 C1G19    1      A CAP_A_0402V-0.01UF,25V,10%,X7RA   I180 @BASEBOARD_FAB2_LIB.BASEBOARD_FAB2(SCH_1):PAGE82
  J9U2  146 VREFCA SCONN288_H44441003_PIP-SCONN,HA   I187 @BASEBOARD_FAB2_LIB.BASEBOARD_FAB2(SCH_1):PAGE82
 R1G15    2      B RES_0402-1.00K,1%,1/16W,CHIP,GA    I35 @BASEBOARD_FAB2_LIB.BASEBOARD_FAB2(SCH_1):PAGE100
 R1G17    1      A RES_0402-1.00K,1%,1/16W,CHIP,GA    I36 @BASEBOARD_FAB2_LIB.BASEBOARD_FAB2(SCH_1):PAGE100
 R1G14    2      B RES_0402-2,1.0%,1/16W,CHIP,G21A    I41 @BASEBOARD_FAB2_LIB.BASEBOARD_FAB2(SCH_1):PAGE100

M_KLM_RST_N @BASEBOARD_FAB2_LIB.BASEBOARD_FAB2(SCH_1):M_KLM_RST_N
  U2D1 DV63 DDR345_RESET_N SKX_EXT_B_BGA1-IC,TBD   I172 @BASEBOARD_FAB2_LIB.BASEBOARD_FAB2(SCH_1):PAGE55
  J1B1   58 RESET_N SCONN288_H44441004_PIP-SCONN,HA   I111 @BASEBOARD_FAB2_LIB.BASEBOARD_FAB2(SCH_1):PAGE83
  J9M1   58 RESET_N SCONN288_H44441003_PIP-SCONN,HA    I14 @BASEBOARD_FAB2_LIB.BASEBOARD_FAB2(SCH_1):PAGE84
  J1A2   58 RESET_N SCONN288_H44441004_PIP-SCONN,HA   I111 @BASEBOARD_FAB2_LIB.BASEBOARD_FAB2(SCH_1):PAGE85
  J9L2   58 RESET_N SCONN288_H44441003_PIP-SCONN,HA    I12 @BASEBOARD_FAB2_LIB.BASEBOARD_FAB2(SCH_1):PAGE86
  J1A1   58 RESET_N SCONN288_H44441004_PIP-SCONN,HA   I186 @BASEBOARD_FAB2_LIB.BASEBOARD_FAB2(SCH_1):PAGE87
  J9L1   58 RESET_N SCONN288_H44441003_PIP-SCONN,HA   I111 @BASEBOARD_FAB2_LIB.BASEBOARD_FAB2(SCH_1):PAGE88

M_K_ACT_N @BASEBOARD_FAB2_LIB.BASEBOARD_FAB2(SCH_1):M_K_ACT_N
  U2D1 DW60 DDR3_ACT_N SKX_EXT_B_BGA1-IC,TBD   I172 @BASEBOARD_FAB2_LIB.BASEBOARD_FAB2(SCH_1):PAGE60
  J1B1   62  ACT_N SCONN288_H44441004_PIP-SCONN,HA   I111 @BASEBOARD_FAB2_LIB.BASEBOARD_FAB2(SCH_1):PAGE83
  J9M1   62  ACT_N SCONN288_H44441003_PIP-SCONN,HA    I14 @BASEBOARD_FAB2_LIB.BASEBOARD_FAB2(SCH_1):PAGE84

M_K_ALERT_N @BASEBOARD_FAB2_LIB.BASEBOARD_FAB2(SCH_1):M_K_ALERT_N
  U2D1 ED63 DDR3_ALERT_N SKX_EXT_B_BGA1-IC,TBD   I172 @BASEBOARD_FAB2_LIB.BASEBOARD_FAB2(SCH_1):PAGE60
  J1B1  208 ALERT_N SCONN288_H44441004_PIP-SCONN,HA   I111 @BASEBOARD_FAB2_LIB.BASEBOARD_FAB2(SCH_1):PAGE83
  J9M1  208 ALERT_N SCONN288_H44441003_PIP-SCONN,HA    I14 @BASEBOARD_FAB2_LIB.BASEBOARD_FAB2(SCH_1):PAGE84

M_K_BA<0> @BASEBOARD_FAB2_LIB.BASEBOARD_FAB2(SCH_1):M_K_BA(0)
  U2D1 EE52 DDR3_BA<0> SKX_EXT_B_BGA1-IC,TBD   I172 @BASEBOARD_FAB2_LIB.BASEBOARD_FAB2(SCH_1):PAGE60
  J1B1   81  BA<0> SCONN288_H44441004_PIP-SCONN,HA   I111 @BASEBOARD_FAB2_LIB.BASEBOARD_FAB2(SCH_1):PAGE83
  J9M1   81  BA<0> SCONN288_H44441003_PIP-SCONN,HA    I14 @BASEBOARD_FAB2_LIB.BASEBOARD_FAB2(SCH_1):PAGE84

M_K_BA<1> @BASEBOARD_FAB2_LIB.BASEBOARD_FAB2(SCH_1):M_K_BA(1)
  U2D1 EA54 DDR3_BA<1> SKX_EXT_B_BGA1-IC,TBD   I172 @BASEBOARD_FAB2_LIB.BASEBOARD_FAB2(SCH_1):PAGE60
  J1B1  224  BA<1> SCONN288_H44441004_PIP-SCONN,HA   I111 @BASEBOARD_FAB2_LIB.BASEBOARD_FAB2(SCH_1):PAGE83
  J9M1  224  BA<1> SCONN288_H44441003_PIP-SCONN,HA    I14 @BASEBOARD_FAB2_LIB.BASEBOARD_FAB2(SCH_1):PAGE84

M_K_BG<0> @BASEBOARD_FAB2_LIB.BASEBOARD_FAB2(SCH_1):M_K_BG(0)
  U2D1 ED61 DDR3_BG<0> SKX_EXT_B_BGA1-IC,TBD   I172 @BASEBOARD_FAB2_LIB.BASEBOARD_FAB2(SCH_1):PAGE60
  J1B1   63  BG<0> SCONN288_H44441004_PIP-SCONN,HA   I111 @BASEBOARD_FAB2_LIB.BASEBOARD_FAB2(SCH_1):PAGE83
  J9M1   63  BG<0> SCONN288_H44441003_PIP-SCONN,HA    I14 @BASEBOARD_FAB2_LIB.BASEBOARD_FAB2(SCH_1):PAGE84

M_K_BG<1> @BASEBOARD_FAB2_LIB.BASEBOARD_FAB2(SCH_1):M_K_BG(1)
  U2D1 DW62 DDR3_BG<1> SKX_EXT_B_BGA1-IC,TBD   I172 @BASEBOARD_FAB2_LIB.BASEBOARD_FAB2(SCH_1):PAGE60
  J1B1  207  BG<1> SCONN288_H44441004_PIP-SCONN,HA   I111 @BASEBOARD_FAB2_LIB.BASEBOARD_FAB2(SCH_1):PAGE83
  J9M1  207  BG<1> SCONN288_H44441003_PIP-SCONN,HA    I14 @BASEBOARD_FAB2_LIB.BASEBOARD_FAB2(SCH_1):PAGE84

M_K_C<2> @BASEBOARD_FAB2_LIB.BASEBOARD_FAB2(SCH_1):M_K_C(2)
  U2D1 DV47 DDR3_CID<2> SKX_EXT_B_BGA1-IC,TBD   I172 @BASEBOARD_FAB2_LIB.BASEBOARD_FAB2(SCH_1):PAGE60
  J1B1  235   C<2> SCONN288_H44441004_PIP-SCONN,HA   I111 @BASEBOARD_FAB2_LIB.BASEBOARD_FAB2(SCH_1):PAGE83
  J9M1  235   C<2> SCONN288_H44441003_PIP-SCONN,HA    I14 @BASEBOARD_FAB2_LIB.BASEBOARD_FAB2(SCH_1):PAGE84

M_K_CKE<0> @BASEBOARD_FAB2_LIB.BASEBOARD_FAB2(SCH_1):M_K_CKE(0)
  U2D1 EE62 DDR3_CKE<0> SKX_EXT_B_BGA1-IC,TBD   I172 @BASEBOARD_FAB2_LIB.BASEBOARD_FAB2(SCH_1):PAGE60
  J1B1   60 CKE<0> SCONN288_H44441004_PIP-SCONN,HA   I111 @BASEBOARD_FAB2_LIB.BASEBOARD_FAB2(SCH_1):PAGE83

M_K_CKE<1> @BASEBOARD_FAB2_LIB.BASEBOARD_FAB2(SCH_1):M_K_CKE(1)
  U2D1 EF63 DDR3_CKE<1> SKX_EXT_B_BGA1-IC,TBD   I172 @BASEBOARD_FAB2_LIB.BASEBOARD_FAB2(SCH_1):PAGE60
  J1B1  203 CKE<1> SCONN288_H44441004_PIP-SCONN,HA   I111 @BASEBOARD_FAB2_LIB.BASEBOARD_FAB2(SCH_1):PAGE83

M_K_CKE<2> @BASEBOARD_FAB2_LIB.BASEBOARD_FAB2(SCH_1):M_K_CKE(2)
  U2D1 EA62 DDR3_CKE<2> SKX_EXT_B_BGA1-IC,TBD   I172 @BASEBOARD_FAB2_LIB.BASEBOARD_FAB2(SCH_1):PAGE60
  J9M1   60 CKE<0> SCONN288_H44441003_PIP-SCONN,HA    I14 @BASEBOARD_FAB2_LIB.BASEBOARD_FAB2(SCH_1):PAGE84

M_K_CKE<3> @BASEBOARD_FAB2_LIB.BASEBOARD_FAB2(SCH_1):M_K_CKE(3)
  U2D1 EB63 DDR3_CKE<3> SKX_EXT_B_BGA1-IC,TBD   I172 @BASEBOARD_FAB2_LIB.BASEBOARD_FAB2(SCH_1):PAGE60
  J9M1  203 CKE<1> SCONN288_H44441003_PIP-SCONN,HA    I14 @BASEBOARD_FAB2_LIB.BASEBOARD_FAB2(SCH_1):PAGE84

M_K_CLK_DN<0> @BASEBOARD_FAB2_LIB.BASEBOARD_FAB2(SCH_1):M_K_CLK_DN(0)
  U2D1 ED55 DDR3_CLK_DN<0> SKX_EXT_B_BGA1-IC,TBD   I172 @BASEBOARD_FAB2_LIB.BASEBOARD_FAB2(SCH_1):PAGE60
  J1B1   75   CK0N SCONN288_H44441004_PIP-SCONN,HA   I111 @BASEBOARD_FAB2_LIB.BASEBOARD_FAB2(SCH_1):PAGE83

M_K_CLK_DN<1> @BASEBOARD_FAB2_LIB.BASEBOARD_FAB2(SCH_1):M_K_CLK_DN(1)
  U2D1 EF55 DDR3_CLK_DN<1> SKX_EXT_B_BGA1-IC,TBD   I172 @BASEBOARD_FAB2_LIB.BASEBOARD_FAB2(SCH_1):PAGE60
  J1B1  219   CK1N SCONN288_H44441004_PIP-SCONN,HA   I111 @BASEBOARD_FAB2_LIB.BASEBOARD_FAB2(SCH_1):PAGE83

M_K_CLK_DN<2> @BASEBOARD_FAB2_LIB.BASEBOARD_FAB2(SCH_1):M_K_CLK_DN(2)
  U2D1 DW56 DDR3_CLK_DN<2> SKX_EXT_B_BGA1-IC,TBD   I172 @BASEBOARD_FAB2_LIB.BASEBOARD_FAB2(SCH_1):PAGE60
  J9M1   75   CK0N SCONN288_H44441003_PIP-SCONN,HA    I14 @BASEBOARD_FAB2_LIB.BASEBOARD_FAB2(SCH_1):PAGE84

M_K_CLK_DN<3> @BASEBOARD_FAB2_LIB.BASEBOARD_FAB2(SCH_1):M_K_CLK_DN(3)
  U2D1 EF57 DDR3_CLK_DN<3> SKX_EXT_B_BGA1-IC,TBD   I172 @BASEBOARD_FAB2_LIB.BASEBOARD_FAB2(SCH_1):PAGE60
  J9M1  219   CK1N SCONN288_H44441003_PIP-SCONN,HA    I14 @BASEBOARD_FAB2_LIB.BASEBOARD_FAB2(SCH_1):PAGE84

M_K_CLK_DP<0> @BASEBOARD_FAB2_LIB.BASEBOARD_FAB2(SCH_1):M_K_CLK_DP(0)
  U2D1 EB55 DDR3_CLK_DP<0> SKX_EXT_B_BGA1-IC,TBD   I172 @BASEBOARD_FAB2_LIB.BASEBOARD_FAB2(SCH_1):PAGE60
  J1B1   74   CK0P SCONN288_H44441004_PIP-SCONN,HA   I111 @BASEBOARD_FAB2_LIB.BASEBOARD_FAB2(SCH_1):PAGE83

M_K_CLK_DP<1> @BASEBOARD_FAB2_LIB.BASEBOARD_FAB2(SCH_1):M_K_CLK_DP(1)
  U2D1 EE54 DDR3_CLK_DP<1> SKX_EXT_B_BGA1-IC,TBD   I172 @BASEBOARD_FAB2_LIB.BASEBOARD_FAB2(SCH_1):PAGE60
  J1B1  218   CK1P SCONN288_H44441004_PIP-SCONN,HA   I111 @BASEBOARD_FAB2_LIB.BASEBOARD_FAB2(SCH_1):PAGE83

M_K_CLK_DP<2> @BASEBOARD_FAB2_LIB.BASEBOARD_FAB2(SCH_1):M_K_CLK_DP(2)
  U2D1 EA56 DDR3_CLK_DP<2> SKX_EXT_B_BGA1-IC,TBD   I172 @BASEBOARD_FAB2_LIB.BASEBOARD_FAB2(SCH_1):PAGE60
  J9M1   74   CK0P SCONN288_H44441003_PIP-SCONN,HA    I14 @BASEBOARD_FAB2_LIB.BASEBOARD_FAB2(SCH_1):PAGE84

M_K_CLK_DP<3> @BASEBOARD_FAB2_LIB.BASEBOARD_FAB2(SCH_1):M_K_CLK_DP(3)
  U2D1 EE56 DDR3_CLK_DP<3> SKX_EXT_B_BGA1-IC,TBD   I172 @BASEBOARD_FAB2_LIB.BASEBOARD_FAB2(SCH_1):PAGE60
  J9M1  218   CK1P SCONN288_H44441003_PIP-SCONN,HA    I14 @BASEBOARD_FAB2_LIB.BASEBOARD_FAB2(SCH_1):PAGE84

M_K_CPU_VREF @BASEBOARD_FAB2_LIB.BASEBOARD_FAB2(SCH_1):M_K_CPU_VREF
  U2D1 CP61 DDR3_CAVREF SKX_EXT_B_BGA1-IC,TBD   I172 @BASEBOARD_FAB2_LIB.BASEBOARD_FAB2(SCH_1):PAGE55
  R9M2    1      A RES_0402-2,1.0%,1/16W,CHIP,G21A    I13 @BASEBOARD_FAB2_LIB.BASEBOARD_FAB2(SCH_1):PAGE100
  C9M2    1      A CAP_A_0402V-0.01UF,25V,10%,X7RA    I15 @BASEBOARD_FAB2_LIB.BASEBOARD_FAB2(SCH_1):PAGE100

M_K_CS_N<0> @BASEBOARD_FAB2_LIB.BASEBOARD_FAB2(SCH_1):M_K_CS_N(0)
  U2D1 EF51 DDR3_CS_N<0> SKX_EXT_B_BGA1-IC,TBD   I172 @BASEBOARD_FAB2_LIB.BASEBOARD_FAB2(SCH_1):PAGE60
  J1B1   84   S0_N SCONN288_H44441004_PIP-SCONN,HA   I111 @BASEBOARD_FAB2_LIB.BASEBOARD_FAB2(SCH_1):PAGE83

M_K_CS_N<1> @BASEBOARD_FAB2_LIB.BASEBOARD_FAB2(SCH_1):M_K_CS_N(1)
  U2D1 ED49 DDR3_CS_N<1> SKX_EXT_B_BGA1-IC,TBD   I172 @BASEBOARD_FAB2_LIB.BASEBOARD_FAB2(SCH_1):PAGE60
  J1B1   89   S1_N SCONN288_H44441004_PIP-SCONN,HA   I111 @BASEBOARD_FAB2_LIB.BASEBOARD_FAB2(SCH_1):PAGE83

M_K_CS_N<2> @BASEBOARD_FAB2_LIB.BASEBOARD_FAB2(SCH_1):M_K_CS_N(2)
  U2D1 ED47 DDR3_CS_N<2> SKX_EXT_B_BGA1-IC,TBD   I172 @BASEBOARD_FAB2_LIB.BASEBOARD_FAB2(SCH_1):PAGE60
  J1B1   93 S2_N_C<0> SCONN288_H44441004_PIP-SCONN,HA   I111 @BASEBOARD_FAB2_LIB.BASEBOARD_FAB2(SCH_1):PAGE83

M_K_CS_N<3> @BASEBOARD_FAB2_LIB.BASEBOARD_FAB2(SCH_1):M_K_CS_N(3)
  U2D1 EB47 DDR3_CS_N<3> SKX_EXT_B_BGA1-IC,TBD   I172 @BASEBOARD_FAB2_LIB.BASEBOARD_FAB2(SCH_1):PAGE60
  J1B1  237 S3_N_C<1> SCONN288_H44441004_PIP-SCONN,HA   I111 @BASEBOARD_FAB2_LIB.BASEBOARD_FAB2(SCH_1):PAGE83

M_K_CS_N<4> @BASEBOARD_FAB2_LIB.BASEBOARD_FAB2(SCH_1):M_K_CS_N(4)
  U2D1 EB51 DDR3_CS_N<4> SKX_EXT_B_BGA1-IC,TBD   I172 @BASEBOARD_FAB2_LIB.BASEBOARD_FAB2(SCH_1):PAGE60
  J9M1   84   S0_N SCONN288_H44441003_PIP-SCONN,HA    I14 @BASEBOARD_FAB2_LIB.BASEBOARD_FAB2(SCH_1):PAGE84

M_K_CS_N<5> @BASEBOARD_FAB2_LIB.BASEBOARD_FAB2(SCH_1):M_K_CS_N(5)
  U2D1 EB49 DDR3_CS_N<5> SKX_EXT_B_BGA1-IC,TBD   I172 @BASEBOARD_FAB2_LIB.BASEBOARD_FAB2(SCH_1):PAGE60
  J9M1   89   S1_N SCONN288_H44441003_PIP-SCONN,HA    I14 @BASEBOARD_FAB2_LIB.BASEBOARD_FAB2(SCH_1):PAGE84

M_K_CS_N<6> @BASEBOARD_FAB2_LIB.BASEBOARD_FAB2(SCH_1):M_K_CS_N(6)
  U2D1 DV45 DDR3_CS_N<6> SKX_EXT_B_BGA1-IC,TBD   I172 @BASEBOARD_FAB2_LIB.BASEBOARD_FAB2(SCH_1):PAGE60
  J9M1   93 S2_N_C<0> SCONN288_H44441003_PIP-SCONN,HA    I14 @BASEBOARD_FAB2_LIB.BASEBOARD_FAB2(SCH_1):PAGE84

M_K_CS_N<7> @BASEBOARD_FAB2_LIB.BASEBOARD_FAB2(SCH_1):M_K_CS_N(7)
  U2D1 EB45 DDR3_CS_N<7> SKX_EXT_B_BGA1-IC,TBD   I172 @BASEBOARD_FAB2_LIB.BASEBOARD_FAB2(SCH_1):PAGE60
  J9M1  237 S3_N_C<1> SCONN288_H44441003_PIP-SCONN,HA    I14 @BASEBOARD_FAB2_LIB.BASEBOARD_FAB2(SCH_1):PAGE84

M_K_DQ<0> @BASEBOARD_FAB2_LIB.BASEBOARD_FAB2(SCH_1):M_K_DQ(0)
  U2D1 CN84 DDR3_DQ<0> SKX_EXT_B_BGA1-IC,TBD   I172 @BASEBOARD_FAB2_LIB.BASEBOARD_FAB2(SCH_1):PAGE60
  J1B1  150  DQ<1> SCONN288_H44441004_PIP-SCONN,HA   I111 @BASEBOARD_FAB2_LIB.BASEBOARD_FAB2(SCH_1):PAGE83
  J9M1    5  DQ<0> SCONN288_H44441003_PIP-SCONN,HA    I14 @BASEBOARD_FAB2_LIB.BASEBOARD_FAB2(SCH_1):PAGE84

M_K_DQ<10> @BASEBOARD_FAB2_LIB.BASEBOARD_FAB2(SCH_1):M_K_DQ(10)
  U2D1 DV83 DDR3_DQ<10> SKX_EXT_B_BGA1-IC,TBD   I172 @BASEBOARD_FAB2_LIB.BASEBOARD_FAB2(SCH_1):PAGE60
  J1B1  168 DQ<11> SCONN288_H44441004_PIP-SCONN,HA   I111 @BASEBOARD_FAB2_LIB.BASEBOARD_FAB2(SCH_1):PAGE83
  J9M1   23 DQ<10> SCONN288_H44441003_PIP-SCONN,HA    I14 @BASEBOARD_FAB2_LIB.BASEBOARD_FAB2(SCH_1):PAGE84

M_K_DQ<11> @BASEBOARD_FAB2_LIB.BASEBOARD_FAB2(SCH_1):M_K_DQ(11)
  U2D1 DY83 DDR3_DQ<11> SKX_EXT_B_BGA1-IC,TBD   I172 @BASEBOARD_FAB2_LIB.BASEBOARD_FAB2(SCH_1):PAGE60
  J1B1   23 DQ<10> SCONN288_H44441004_PIP-SCONN,HA   I111 @BASEBOARD_FAB2_LIB.BASEBOARD_FAB2(SCH_1):PAGE83
  J9M1  168 DQ<11> SCONN288_H44441003_PIP-SCONN,HA    I14 @BASEBOARD_FAB2_LIB.BASEBOARD_FAB2(SCH_1):PAGE84

M_K_DQ<12> @BASEBOARD_FAB2_LIB.BASEBOARD_FAB2(SCH_1):M_K_DQ(12)
  U2D1 DD85 DDR3_DQ<12> SKX_EXT_B_BGA1-IC,TBD   I172 @BASEBOARD_FAB2_LIB.BASEBOARD_FAB2(SCH_1):PAGE60
  J1B1  159 DQ<13> SCONN288_H44441004_PIP-SCONN,HA   I111 @BASEBOARD_FAB2_LIB.BASEBOARD_FAB2(SCH_1):PAGE83
  J9M1   14 DQ<12> SCONN288_H44441003_PIP-SCONN,HA    I14 @BASEBOARD_FAB2_LIB.BASEBOARD_FAB2(SCH_1):PAGE84

M_K_DQ<13> @BASEBOARD_FAB2_LIB.BASEBOARD_FAB2(SCH_1):M_K_DQ(13)
  U2D1 DE84 DDR3_DQ<13> SKX_EXT_B_BGA1-IC,TBD   I172 @BASEBOARD_FAB2_LIB.BASEBOARD_FAB2(SCH_1):PAGE60
  J1B1   14 DQ<12> SCONN288_H44441004_PIP-SCONN,HA   I111 @BASEBOARD_FAB2_LIB.BASEBOARD_FAB2(SCH_1):PAGE83
  J9M1  159 DQ<13> SCONN288_H44441003_PIP-SCONN,HA    I14 @BASEBOARD_FAB2_LIB.BASEBOARD_FAB2(SCH_1):PAGE84

M_K_DQ<14> @BASEBOARD_FAB2_LIB.BASEBOARD_FAB2(SCH_1):M_K_DQ(14)
  U2D1 DR84 DDR3_DQ<14> SKX_EXT_B_BGA1-IC,TBD   I172 @BASEBOARD_FAB2_LIB.BASEBOARD_FAB2(SCH_1):PAGE60
  J1B1  166 DQ<15> SCONN288_H44441004_PIP-SCONN,HA   I111 @BASEBOARD_FAB2_LIB.BASEBOARD_FAB2(SCH_1):PAGE83
  J9M1   21 DQ<14> SCONN288_H44441003_PIP-SCONN,HA    I14 @BASEBOARD_FAB2_LIB.BASEBOARD_FAB2(SCH_1):PAGE84

M_K_DQ<15> @BASEBOARD_FAB2_LIB.BASEBOARD_FAB2(SCH_1):M_K_DQ(15)
  U2D1 DV85 DDR3_DQ<15> SKX_EXT_B_BGA1-IC,TBD   I172 @BASEBOARD_FAB2_LIB.BASEBOARD_FAB2(SCH_1):PAGE60
  J1B1   21 DQ<14> SCONN288_H44441004_PIP-SCONN,HA   I111 @BASEBOARD_FAB2_LIB.BASEBOARD_FAB2(SCH_1):PAGE83
  J9M1  166 DQ<15> SCONN288_H44441003_PIP-SCONN,HA    I14 @BASEBOARD_FAB2_LIB.BASEBOARD_FAB2(SCH_1):PAGE84

M_K_DQ<16> @BASEBOARD_FAB2_LIB.BASEBOARD_FAB2(SCH_1):M_K_DQ(16)
  U2D1 DM79 DDR3_DQ<16> SKX_EXT_B_BGA1-IC,TBD   I172 @BASEBOARD_FAB2_LIB.BASEBOARD_FAB2(SCH_1):PAGE60
  J1B1  172 DQ<17> SCONN288_H44441004_PIP-SCONN,HA   I111 @BASEBOARD_FAB2_LIB.BASEBOARD_FAB2(SCH_1):PAGE83
  J9M1   27 DQ<16> SCONN288_H44441003_PIP-SCONN,HA    I14 @BASEBOARD_FAB2_LIB.BASEBOARD_FAB2(SCH_1):PAGE84

M_K_DQ<17> @BASEBOARD_FAB2_LIB.BASEBOARD_FAB2(SCH_1):M_K_DQ(17)
  U2D1 DK81 DDR3_DQ<17> SKX_EXT_B_BGA1-IC,TBD   I172 @BASEBOARD_FAB2_LIB.BASEBOARD_FAB2(SCH_1):PAGE60
  J1B1   27 DQ<16> SCONN288_H44441004_PIP-SCONN,HA   I111 @BASEBOARD_FAB2_LIB.BASEBOARD_FAB2(SCH_1):PAGE83
  J9M1  172 DQ<17> SCONN288_H44441003_PIP-SCONN,HA    I14 @BASEBOARD_FAB2_LIB.BASEBOARD_FAB2(SCH_1):PAGE84

M_K_DQ<18> @BASEBOARD_FAB2_LIB.BASEBOARD_FAB2(SCH_1):M_K_DQ(18)
  U2D1 DT81 DDR3_DQ<18> SKX_EXT_B_BGA1-IC,TBD   I172 @BASEBOARD_FAB2_LIB.BASEBOARD_FAB2(SCH_1):PAGE60
  J1B1  179 DQ<19> SCONN288_H44441004_PIP-SCONN,HA   I111 @BASEBOARD_FAB2_LIB.BASEBOARD_FAB2(SCH_1):PAGE83
  J9M1   34 DQ<18> SCONN288_H44441003_PIP-SCONN,HA    I14 @BASEBOARD_FAB2_LIB.BASEBOARD_FAB2(SCH_1):PAGE84

M_K_DQ<19> @BASEBOARD_FAB2_LIB.BASEBOARD_FAB2(SCH_1):M_K_DQ(19)
  U2D1 DR82 DDR3_DQ<19> SKX_EXT_B_BGA1-IC,TBD   I172 @BASEBOARD_FAB2_LIB.BASEBOARD_FAB2(SCH_1):PAGE60
  J1B1   34 DQ<18> SCONN288_H44441004_PIP-SCONN,HA   I111 @BASEBOARD_FAB2_LIB.BASEBOARD_FAB2(SCH_1):PAGE83
  J9M1  179 DQ<19> SCONN288_H44441003_PIP-SCONN,HA    I14 @BASEBOARD_FAB2_LIB.BASEBOARD_FAB2(SCH_1):PAGE84

M_K_DQ<1> @BASEBOARD_FAB2_LIB.BASEBOARD_FAB2(SCH_1):M_K_DQ(1)
  U2D1 CN86 DDR3_DQ<1> SKX_EXT_B_BGA1-IC,TBD   I172 @BASEBOARD_FAB2_LIB.BASEBOARD_FAB2(SCH_1):PAGE60
  J1B1    5  DQ<0> SCONN288_H44441004_PIP-SCONN,HA   I111 @BASEBOARD_FAB2_LIB.BASEBOARD_FAB2(SCH_1):PAGE83
  J9M1  150  DQ<1> SCONN288_H44441003_PIP-SCONN,HA    I14 @BASEBOARD_FAB2_LIB.BASEBOARD_FAB2(SCH_1):PAGE84

M_K_DQ<20> @BASEBOARD_FAB2_LIB.BASEBOARD_FAB2(SCH_1):M_K_DQ(20)
  U2D1 DK79 DDR3_DQ<20> SKX_EXT_B_BGA1-IC,TBD   I172 @BASEBOARD_FAB2_LIB.BASEBOARD_FAB2(SCH_1):PAGE60
  J1B1  170 DQ<21> SCONN288_H44441004_PIP-SCONN,HA   I111 @BASEBOARD_FAB2_LIB.BASEBOARD_FAB2(SCH_1):PAGE83
  J9M1   25 DQ<20> SCONN288_H44441003_PIP-SCONN,HA    I14 @BASEBOARD_FAB2_LIB.BASEBOARD_FAB2(SCH_1):PAGE84

M_K_DQ<21> @BASEBOARD_FAB2_LIB.BASEBOARD_FAB2(SCH_1):M_K_DQ(21)
  U2D1 DJ80 DDR3_DQ<21> SKX_EXT_B_BGA1-IC,TBD   I172 @BASEBOARD_FAB2_LIB.BASEBOARD_FAB2(SCH_1):PAGE60
  J1B1   25 DQ<20> SCONN288_H44441004_PIP-SCONN,HA   I111 @BASEBOARD_FAB2_LIB.BASEBOARD_FAB2(SCH_1):PAGE83
  J9M1  170 DQ<21> SCONN288_H44441003_PIP-SCONN,HA    I14 @BASEBOARD_FAB2_LIB.BASEBOARD_FAB2(SCH_1):PAGE84

M_K_DQ<22> @BASEBOARD_FAB2_LIB.BASEBOARD_FAB2(SCH_1):M_K_DQ(22)
  U2D1 DR80 DDR3_DQ<22> SKX_EXT_B_BGA1-IC,TBD   I172 @BASEBOARD_FAB2_LIB.BASEBOARD_FAB2(SCH_1):PAGE60
  J1B1  177 DQ<23> SCONN288_H44441004_PIP-SCONN,HA   I111 @BASEBOARD_FAB2_LIB.BASEBOARD_FAB2(SCH_1):PAGE83
  J9M1   32 DQ<22> SCONN288_H44441003_PIP-SCONN,HA    I14 @BASEBOARD_FAB2_LIB.BASEBOARD_FAB2(SCH_1):PAGE84

M_K_DQ<23> @BASEBOARD_FAB2_LIB.BASEBOARD_FAB2(SCH_1):M_K_DQ(23)
  U2D1 DN82 DDR3_DQ<23> SKX_EXT_B_BGA1-IC,TBD   I172 @BASEBOARD_FAB2_LIB.BASEBOARD_FAB2(SCH_1):PAGE60
  J1B1   32 DQ<22> SCONN288_H44441004_PIP-SCONN,HA   I111 @BASEBOARD_FAB2_LIB.BASEBOARD_FAB2(SCH_1):PAGE83
  J9M1  177 DQ<23> SCONN288_H44441003_PIP-SCONN,HA    I14 @BASEBOARD_FAB2_LIB.BASEBOARD_FAB2(SCH_1):PAGE84

M_K_DQ<24> @BASEBOARD_FAB2_LIB.BASEBOARD_FAB2(SCH_1):M_K_DQ(24)
  U2D1 DN76 DDR3_DQ<24> SKX_EXT_B_BGA1-IC,TBD   I172 @BASEBOARD_FAB2_LIB.BASEBOARD_FAB2(SCH_1):PAGE60
  J1B1  183 DQ<25> SCONN288_H44441004_PIP-SCONN,HA   I111 @BASEBOARD_FAB2_LIB.BASEBOARD_FAB2(SCH_1):PAGE83
  J9M1   38 DQ<24> SCONN288_H44441003_PIP-SCONN,HA    I14 @BASEBOARD_FAB2_LIB.BASEBOARD_FAB2(SCH_1):PAGE84

M_K_DQ<25> @BASEBOARD_FAB2_LIB.BASEBOARD_FAB2(SCH_1):M_K_DQ(25)
  U2D1 DU76 DDR3_DQ<25> SKX_EXT_B_BGA1-IC,TBD   I172 @BASEBOARD_FAB2_LIB.BASEBOARD_FAB2(SCH_1):PAGE60
  J1B1   38 DQ<24> SCONN288_H44441004_PIP-SCONN,HA   I111 @BASEBOARD_FAB2_LIB.BASEBOARD_FAB2(SCH_1):PAGE83
  J9M1  183 DQ<25> SCONN288_H44441003_PIP-SCONN,HA    I14 @BASEBOARD_FAB2_LIB.BASEBOARD_FAB2(SCH_1):PAGE84

M_K_DQ<26> @BASEBOARD_FAB2_LIB.BASEBOARD_FAB2(SCH_1):M_K_DQ(26)
  U2D1 DP73 DDR3_DQ<26> SKX_EXT_B_BGA1-IC,TBD   I172 @BASEBOARD_FAB2_LIB.BASEBOARD_FAB2(SCH_1):PAGE60
  J1B1  190 DQ<27> SCONN288_H44441004_PIP-SCONN,HA   I111 @BASEBOARD_FAB2_LIB.BASEBOARD_FAB2(SCH_1):PAGE83
  J9M1   45 DQ<26> SCONN288_H44441003_PIP-SCONN,HA    I14 @BASEBOARD_FAB2_LIB.BASEBOARD_FAB2(SCH_1):PAGE84

M_K_DQ<27> @BASEBOARD_FAB2_LIB.BASEBOARD_FAB2(SCH_1):M_K_DQ(27)
  U2D1 DT73 DDR3_DQ<27> SKX_EXT_B_BGA1-IC,TBD   I172 @BASEBOARD_FAB2_LIB.BASEBOARD_FAB2(SCH_1):PAGE60
  J1B1   45 DQ<26> SCONN288_H44441004_PIP-SCONN,HA   I111 @BASEBOARD_FAB2_LIB.BASEBOARD_FAB2(SCH_1):PAGE83
  J9M1  190 DQ<27> SCONN288_H44441003_PIP-SCONN,HA    I14 @BASEBOARD_FAB2_LIB.BASEBOARD_FAB2(SCH_1):PAGE84

M_K_DQ<28> @BASEBOARD_FAB2_LIB.BASEBOARD_FAB2(SCH_1):M_K_DQ(28)
  U2D1 DP77 DDR3_DQ<28> SKX_EXT_B_BGA1-IC,TBD   I172 @BASEBOARD_FAB2_LIB.BASEBOARD_FAB2(SCH_1):PAGE60
  J1B1  181 DQ<29> SCONN288_H44441004_PIP-SCONN,HA   I111 @BASEBOARD_FAB2_LIB.BASEBOARD_FAB2(SCH_1):PAGE83
  J9M1   36 DQ<28> SCONN288_H44441003_PIP-SCONN,HA    I14 @BASEBOARD_FAB2_LIB.BASEBOARD_FAB2(SCH_1):PAGE84

M_K_DQ<29> @BASEBOARD_FAB2_LIB.BASEBOARD_FAB2(SCH_1):M_K_DQ(29)
  U2D1 DT77 DDR3_DQ<29> SKX_EXT_B_BGA1-IC,TBD   I172 @BASEBOARD_FAB2_LIB.BASEBOARD_FAB2(SCH_1):PAGE60
  J1B1   36 DQ<28> SCONN288_H44441004_PIP-SCONN,HA   I111 @BASEBOARD_FAB2_LIB.BASEBOARD_FAB2(SCH_1):PAGE83
  J9M1  181 DQ<29> SCONN288_H44441003_PIP-SCONN,HA    I14 @BASEBOARD_FAB2_LIB.BASEBOARD_FAB2(SCH_1):PAGE84

M_K_DQ<2> @BASEBOARD_FAB2_LIB.BASEBOARD_FAB2(SCH_1):M_K_DQ(2)
  U2D1 DA86 DDR3_DQ<2> SKX_EXT_B_BGA1-IC,TBD   I172 @BASEBOARD_FAB2_LIB.BASEBOARD_FAB2(SCH_1):PAGE60
  J1B1  157  DQ<3> SCONN288_H44441004_PIP-SCONN,HA   I111 @BASEBOARD_FAB2_LIB.BASEBOARD_FAB2(SCH_1):PAGE83
  J9M1   12  DQ<2> SCONN288_H44441003_PIP-SCONN,HA    I14 @BASEBOARD_FAB2_LIB.BASEBOARD_FAB2(SCH_1):PAGE84

M_K_DQ<30> @BASEBOARD_FAB2_LIB.BASEBOARD_FAB2(SCH_1):M_K_DQ(30)
  U2D1 DN74 DDR3_DQ<30> SKX_EXT_B_BGA1-IC,TBD   I172 @BASEBOARD_FAB2_LIB.BASEBOARD_FAB2(SCH_1):PAGE60
  J1B1  188 DQ<31> SCONN288_H44441004_PIP-SCONN,HA   I111 @BASEBOARD_FAB2_LIB.BASEBOARD_FAB2(SCH_1):PAGE83
  J9M1   43 DQ<30> SCONN288_H44441003_PIP-SCONN,HA    I14 @BASEBOARD_FAB2_LIB.BASEBOARD_FAB2(SCH_1):PAGE84

M_K_DQ<31> @BASEBOARD_FAB2_LIB.BASEBOARD_FAB2(SCH_1):M_K_DQ(31)
  U2D1 DU74 DDR3_DQ<31> SKX_EXT_B_BGA1-IC,TBD   I172 @BASEBOARD_FAB2_LIB.BASEBOARD_FAB2(SCH_1):PAGE60
  J1B1   43 DQ<30> SCONN288_H44441004_PIP-SCONN,HA   I111 @BASEBOARD_FAB2_LIB.BASEBOARD_FAB2(SCH_1):PAGE83
  J9M1  188 DQ<31> SCONN288_H44441003_PIP-SCONN,HA    I14 @BASEBOARD_FAB2_LIB.BASEBOARD_FAB2(SCH_1):PAGE84

M_K_DQ<32> @BASEBOARD_FAB2_LIB.BASEBOARD_FAB2(SCH_1):M_K_DQ(32)
  U2D1 EC40 DDR3_DQ<32> SKX_EXT_B_BGA1-IC,TBD   I172 @BASEBOARD_FAB2_LIB.BASEBOARD_FAB2(SCH_1):PAGE60
  J1B1  242 DQ<33> SCONN288_H44441004_PIP-SCONN,HA   I111 @BASEBOARD_FAB2_LIB.BASEBOARD_FAB2(SCH_1):PAGE83
  J9M1   97 DQ<32> SCONN288_H44441003_PIP-SCONN,HA    I14 @BASEBOARD_FAB2_LIB.BASEBOARD_FAB2(SCH_1):PAGE84

M_K_DQ<33> @BASEBOARD_FAB2_LIB.BASEBOARD_FAB2(SCH_1):M_K_DQ(33)
  U2D1 ED39 DDR3_DQ<33> SKX_EXT_B_BGA1-IC,TBD   I172 @BASEBOARD_FAB2_LIB.BASEBOARD_FAB2(SCH_1):PAGE60
  J1B1   97 DQ<32> SCONN288_H44441004_PIP-SCONN,HA   I111 @BASEBOARD_FAB2_LIB.BASEBOARD_FAB2(SCH_1):PAGE83
  J9M1  242 DQ<33> SCONN288_H44441003_PIP-SCONN,HA    I14 @BASEBOARD_FAB2_LIB.BASEBOARD_FAB2(SCH_1):PAGE84

M_K_DQ<34> @BASEBOARD_FAB2_LIB.BASEBOARD_FAB2(SCH_1):M_K_DQ(34)
  U2D1 EA36 DDR3_DQ<34> SKX_EXT_B_BGA1-IC,TBD   I172 @BASEBOARD_FAB2_LIB.BASEBOARD_FAB2(SCH_1):PAGE60
  J1B1  249 DQ<35> SCONN288_H44441004_PIP-SCONN,HA   I111 @BASEBOARD_FAB2_LIB.BASEBOARD_FAB2(SCH_1):PAGE83
  J9M1  104 DQ<34> SCONN288_H44441003_PIP-SCONN,HA    I14 @BASEBOARD_FAB2_LIB.BASEBOARD_FAB2(SCH_1):PAGE84

M_K_DQ<35> @BASEBOARD_FAB2_LIB.BASEBOARD_FAB2(SCH_1):M_K_DQ(35)
  U2D1 EC36 DDR3_DQ<35> SKX_EXT_B_BGA1-IC,TBD   I172 @BASEBOARD_FAB2_LIB.BASEBOARD_FAB2(SCH_1):PAGE60
  J1B1  104 DQ<34> SCONN288_H44441004_PIP-SCONN,HA   I111 @BASEBOARD_FAB2_LIB.BASEBOARD_FAB2(SCH_1):PAGE83
  J9M1  249 DQ<35> SCONN288_H44441003_PIP-SCONN,HA    I14 @BASEBOARD_FAB2_LIB.BASEBOARD_FAB2(SCH_1):PAGE84

M_K_DQ<36> @BASEBOARD_FAB2_LIB.BASEBOARD_FAB2(SCH_1):M_K_DQ(36)
  U2D1 DY39 DDR3_DQ<36> SKX_EXT_B_BGA1-IC,TBD   I172 @BASEBOARD_FAB2_LIB.BASEBOARD_FAB2(SCH_1):PAGE60
  J1B1  240 DQ<37> SCONN288_H44441004_PIP-SCONN,HA   I111 @BASEBOARD_FAB2_LIB.BASEBOARD_FAB2(SCH_1):PAGE83
  J9M1   95 DQ<36> SCONN288_H44441003_PIP-SCONN,HA    I14 @BASEBOARD_FAB2_LIB.BASEBOARD_FAB2(SCH_1):PAGE84

M_K_DQ<37> @BASEBOARD_FAB2_LIB.BASEBOARD_FAB2(SCH_1):M_K_DQ(37)
  U2D1 EA40 DDR3_DQ<37> SKX_EXT_B_BGA1-IC,TBD   I172 @BASEBOARD_FAB2_LIB.BASEBOARD_FAB2(SCH_1):PAGE60
  J1B1   95 DQ<36> SCONN288_H44441004_PIP-SCONN,HA   I111 @BASEBOARD_FAB2_LIB.BASEBOARD_FAB2(SCH_1):PAGE83
  J9M1  240 DQ<37> SCONN288_H44441003_PIP-SCONN,HA    I14 @BASEBOARD_FAB2_LIB.BASEBOARD_FAB2(SCH_1):PAGE84

M_K_DQ<38> @BASEBOARD_FAB2_LIB.BASEBOARD_FAB2(SCH_1):M_K_DQ(38)
  U2D1 DY37 DDR3_DQ<38> SKX_EXT_B_BGA1-IC,TBD   I172 @BASEBOARD_FAB2_LIB.BASEBOARD_FAB2(SCH_1):PAGE60
  J1B1  247 DQ<39> SCONN288_H44441004_PIP-SCONN,HA   I111 @BASEBOARD_FAB2_LIB.BASEBOARD_FAB2(SCH_1):PAGE83
  J9M1  102 DQ<38> SCONN288_H44441003_PIP-SCONN,HA    I14 @BASEBOARD_FAB2_LIB.BASEBOARD_FAB2(SCH_1):PAGE84

M_K_DQ<39> @BASEBOARD_FAB2_LIB.BASEBOARD_FAB2(SCH_1):M_K_DQ(39)
  U2D1 ED37 DDR3_DQ<39> SKX_EXT_B_BGA1-IC,TBD   I172 @BASEBOARD_FAB2_LIB.BASEBOARD_FAB2(SCH_1):PAGE60
  J1B1  102 DQ<38> SCONN288_H44441004_PIP-SCONN,HA   I111 @BASEBOARD_FAB2_LIB.BASEBOARD_FAB2(SCH_1):PAGE83
  J9M1  247 DQ<39> SCONN288_H44441003_PIP-SCONN,HA    I14 @BASEBOARD_FAB2_LIB.BASEBOARD_FAB2(SCH_1):PAGE84

M_K_DQ<3> @BASEBOARD_FAB2_LIB.BASEBOARD_FAB2(SCH_1):M_K_DQ(3)
  U2D1 DA84 DDR3_DQ<3> SKX_EXT_B_BGA1-IC,TBD   I172 @BASEBOARD_FAB2_LIB.BASEBOARD_FAB2(SCH_1):PAGE60
  J1B1   12  DQ<2> SCONN288_H44441004_PIP-SCONN,HA   I111 @BASEBOARD_FAB2_LIB.BASEBOARD_FAB2(SCH_1):PAGE83
  J9M1  157  DQ<3> SCONN288_H44441003_PIP-SCONN,HA    I14 @BASEBOARD_FAB2_LIB.BASEBOARD_FAB2(SCH_1):PAGE84

M_K_DQ<40> @BASEBOARD_FAB2_LIB.BASEBOARD_FAB2(SCH_1):M_K_DQ(40)
  U2D1 DN36 DDR3_DQ<40> SKX_EXT_B_BGA1-IC,TBD   I172 @BASEBOARD_FAB2_LIB.BASEBOARD_FAB2(SCH_1):PAGE60
  J1B1  253 DQ<41> SCONN288_H44441004_PIP-SCONN,HA   I111 @BASEBOARD_FAB2_LIB.BASEBOARD_FAB2(SCH_1):PAGE83
  J9M1  108 DQ<40> SCONN288_H44441003_PIP-SCONN,HA    I14 @BASEBOARD_FAB2_LIB.BASEBOARD_FAB2(SCH_1):PAGE84

M_K_DQ<41> @BASEBOARD_FAB2_LIB.BASEBOARD_FAB2(SCH_1):M_K_DQ(41)
  U2D1 DU36 DDR3_DQ<41> SKX_EXT_B_BGA1-IC,TBD   I172 @BASEBOARD_FAB2_LIB.BASEBOARD_FAB2(SCH_1):PAGE60
  J1B1  108 DQ<40> SCONN288_H44441004_PIP-SCONN,HA   I111 @BASEBOARD_FAB2_LIB.BASEBOARD_FAB2(SCH_1):PAGE83
  J9M1  253 DQ<41> SCONN288_H44441003_PIP-SCONN,HA    I14 @BASEBOARD_FAB2_LIB.BASEBOARD_FAB2(SCH_1):PAGE84

M_K_DQ<42> @BASEBOARD_FAB2_LIB.BASEBOARD_FAB2(SCH_1):M_K_DQ(42)
  U2D1 DP33 DDR3_DQ<42> SKX_EXT_B_BGA1-IC,TBD   I172 @BASEBOARD_FAB2_LIB.BASEBOARD_FAB2(SCH_1):PAGE60
  J1B1  260 DQ<43> SCONN288_H44441004_PIP-SCONN,HA   I111 @BASEBOARD_FAB2_LIB.BASEBOARD_FAB2(SCH_1):PAGE83
  J9M1  115 DQ<42> SCONN288_H44441003_PIP-SCONN,HA    I14 @BASEBOARD_FAB2_LIB.BASEBOARD_FAB2(SCH_1):PAGE84

M_K_DQ<43> @BASEBOARD_FAB2_LIB.BASEBOARD_FAB2(SCH_1):M_K_DQ(43)
  U2D1 DT33 DDR3_DQ<43> SKX_EXT_B_BGA1-IC,TBD   I172 @BASEBOARD_FAB2_LIB.BASEBOARD_FAB2(SCH_1):PAGE60
  J1B1  115 DQ<42> SCONN288_H44441004_PIP-SCONN,HA   I111 @BASEBOARD_FAB2_LIB.BASEBOARD_FAB2(SCH_1):PAGE83
  J9M1  260 DQ<43> SCONN288_H44441003_PIP-SCONN,HA    I14 @BASEBOARD_FAB2_LIB.BASEBOARD_FAB2(SCH_1):PAGE84

M_K_DQ<44> @BASEBOARD_FAB2_LIB.BASEBOARD_FAB2(SCH_1):M_K_DQ(44)
  U2D1 DP37 DDR3_DQ<44> SKX_EXT_B_BGA1-IC,TBD   I172 @BASEBOARD_FAB2_LIB.BASEBOARD_FAB2(SCH_1):PAGE60
  J1B1  251 DQ<45> SCONN288_H44441004_PIP-SCONN,HA   I111 @BASEBOARD_FAB2_LIB.BASEBOARD_FAB2(SCH_1):PAGE83
  J9M1  106 DQ<44> SCONN288_H44441003_PIP-SCONN,HA    I14 @BASEBOARD_FAB2_LIB.BASEBOARD_FAB2(SCH_1):PAGE84

M_K_DQ<45> @BASEBOARD_FAB2_LIB.BASEBOARD_FAB2(SCH_1):M_K_DQ(45)
  U2D1 DT37 DDR3_DQ<45> SKX_EXT_B_BGA1-IC,TBD   I172 @BASEBOARD_FAB2_LIB.BASEBOARD_FAB2(SCH_1):PAGE60
  J1B1  106 DQ<44> SCONN288_H44441004_PIP-SCONN,HA   I111 @BASEBOARD_FAB2_LIB.BASEBOARD_FAB2(SCH_1):PAGE83
  J9M1  251 DQ<45> SCONN288_H44441003_PIP-SCONN,HA    I14 @BASEBOARD_FAB2_LIB.BASEBOARD_FAB2(SCH_1):PAGE84

M_K_DQ<46> @BASEBOARD_FAB2_LIB.BASEBOARD_FAB2(SCH_1):M_K_DQ(46)
  U2D1 DN34 DDR3_DQ<46> SKX_EXT_B_BGA1-IC,TBD   I172 @BASEBOARD_FAB2_LIB.BASEBOARD_FAB2(SCH_1):PAGE60
  J1B1  258 DQ<47> SCONN288_H44441004_PIP-SCONN,HA   I111 @BASEBOARD_FAB2_LIB.BASEBOARD_FAB2(SCH_1):PAGE83
  J9M1  113 DQ<46> SCONN288_H44441003_PIP-SCONN,HA    I14 @BASEBOARD_FAB2_LIB.BASEBOARD_FAB2(SCH_1):PAGE84

M_K_DQ<47> @BASEBOARD_FAB2_LIB.BASEBOARD_FAB2(SCH_1):M_K_DQ(47)
  U2D1 DU34 DDR3_DQ<47> SKX_EXT_B_BGA1-IC,TBD   I172 @BASEBOARD_FAB2_LIB.BASEBOARD_FAB2(SCH_1):PAGE60
  J1B1  113 DQ<46> SCONN288_H44441004_PIP-SCONN,HA   I111 @BASEBOARD_FAB2_LIB.BASEBOARD_FAB2(SCH_1):PAGE83
  J9M1  258 DQ<47> SCONN288_H44441003_PIP-SCONN,HA    I14 @BASEBOARD_FAB2_LIB.BASEBOARD_FAB2(SCH_1):PAGE84

M_K_DQ<48> @BASEBOARD_FAB2_LIB.BASEBOARD_FAB2(SCH_1):M_K_DQ(48)
  U2D1 DN30 DDR3_DQ<48> SKX_EXT_B_BGA1-IC,TBD   I172 @BASEBOARD_FAB2_LIB.BASEBOARD_FAB2(SCH_1):PAGE60
  J1B1  264 DQ<49> SCONN288_H44441004_PIP-SCONN,HA   I111 @BASEBOARD_FAB2_LIB.BASEBOARD_FAB2(SCH_1):PAGE83
  J9M1  119 DQ<48> SCONN288_H44441003_PIP-SCONN,HA    I14 @BASEBOARD_FAB2_LIB.BASEBOARD_FAB2(SCH_1):PAGE84

M_K_DQ<49> @BASEBOARD_FAB2_LIB.BASEBOARD_FAB2(SCH_1):M_K_DQ(49)
  U2D1 DU30 DDR3_DQ<49> SKX_EXT_B_BGA1-IC,TBD   I172 @BASEBOARD_FAB2_LIB.BASEBOARD_FAB2(SCH_1):PAGE60
  J1B1  119 DQ<48> SCONN288_H44441004_PIP-SCONN,HA   I111 @BASEBOARD_FAB2_LIB.BASEBOARD_FAB2(SCH_1):PAGE83
  J9M1  264 DQ<49> SCONN288_H44441003_PIP-SCONN,HA    I14 @BASEBOARD_FAB2_LIB.BASEBOARD_FAB2(SCH_1):PAGE84

M_K_DQ<4> @BASEBOARD_FAB2_LIB.BASEBOARD_FAB2(SCH_1):M_K_DQ(4)
  U2D1 CL84 DDR3_DQ<4> SKX_EXT_B_BGA1-IC,TBD   I172 @BASEBOARD_FAB2_LIB.BASEBOARD_FAB2(SCH_1):PAGE60
  J1B1  148  DQ<5> SCONN288_H44441004_PIP-SCONN,HA   I111 @BASEBOARD_FAB2_LIB.BASEBOARD_FAB2(SCH_1):PAGE83
  J9M1    3  DQ<4> SCONN288_H44441003_PIP-SCONN,HA    I14 @BASEBOARD_FAB2_LIB.BASEBOARD_FAB2(SCH_1):PAGE84

M_K_DQ<50> @BASEBOARD_FAB2_LIB.BASEBOARD_FAB2(SCH_1):M_K_DQ(50)
  U2D1 DP27 DDR3_DQ<50> SKX_EXT_B_BGA1-IC,TBD   I172 @BASEBOARD_FAB2_LIB.BASEBOARD_FAB2(SCH_1):PAGE60
  J1B1  271 DQ<51> SCONN288_H44441004_PIP-SCONN,HA   I111 @BASEBOARD_FAB2_LIB.BASEBOARD_FAB2(SCH_1):PAGE83
  J9M1  126 DQ<50> SCONN288_H44441003_PIP-SCONN,HA    I14 @BASEBOARD_FAB2_LIB.BASEBOARD_FAB2(SCH_1):PAGE84

M_K_DQ<51> @BASEBOARD_FAB2_LIB.BASEBOARD_FAB2(SCH_1):M_K_DQ(51)
  U2D1 DT27 DDR3_DQ<51> SKX_EXT_B_BGA1-IC,TBD   I172 @BASEBOARD_FAB2_LIB.BASEBOARD_FAB2(SCH_1):PAGE60
  J1B1  126 DQ<50> SCONN288_H44441004_PIP-SCONN,HA   I111 @BASEBOARD_FAB2_LIB.BASEBOARD_FAB2(SCH_1):PAGE83
  J9M1  271 DQ<51> SCONN288_H44441003_PIP-SCONN,HA    I14 @BASEBOARD_FAB2_LIB.BASEBOARD_FAB2(SCH_1):PAGE84

M_K_DQ<52> @BASEBOARD_FAB2_LIB.BASEBOARD_FAB2(SCH_1):M_K_DQ(52)
  U2D1 DP31 DDR3_DQ<52> SKX_EXT_B_BGA1-IC,TBD   I172 @BASEBOARD_FAB2_LIB.BASEBOARD_FAB2(SCH_1):PAGE60
  J1B1  262 DQ<53> SCONN288_H44441004_PIP-SCONN,HA   I111 @BASEBOARD_FAB2_LIB.BASEBOARD_FAB2(SCH_1):PAGE83
  J9M1  117 DQ<52> SCONN288_H44441003_PIP-SCONN,HA    I14 @BASEBOARD_FAB2_LIB.BASEBOARD_FAB2(SCH_1):PAGE84

M_K_DQ<53> @BASEBOARD_FAB2_LIB.BASEBOARD_FAB2(SCH_1):M_K_DQ(53)
  U2D1 DT31 DDR3_DQ<53> SKX_EXT_B_BGA1-IC,TBD   I172 @BASEBOARD_FAB2_LIB.BASEBOARD_FAB2(SCH_1):PAGE60
  J1B1  117 DQ<52> SCONN288_H44441004_PIP-SCONN,HA   I111 @BASEBOARD_FAB2_LIB.BASEBOARD_FAB2(SCH_1):PAGE83
  J9M1  262 DQ<53> SCONN288_H44441003_PIP-SCONN,HA    I14 @BASEBOARD_FAB2_LIB.BASEBOARD_FAB2(SCH_1):PAGE84

M_K_DQ<54> @BASEBOARD_FAB2_LIB.BASEBOARD_FAB2(SCH_1):M_K_DQ(54)
  U2D1 DN28 DDR3_DQ<54> SKX_EXT_B_BGA1-IC,TBD   I172 @BASEBOARD_FAB2_LIB.BASEBOARD_FAB2(SCH_1):PAGE60
  J1B1  269 DQ<55> SCONN288_H44441004_PIP-SCONN,HA   I111 @BASEBOARD_FAB2_LIB.BASEBOARD_FAB2(SCH_1):PAGE83
  J9M1  124 DQ<54> SCONN288_H44441003_PIP-SCONN,HA    I14 @BASEBOARD_FAB2_LIB.BASEBOARD_FAB2(SCH_1):PAGE84

M_K_DQ<55> @BASEBOARD_FAB2_LIB.BASEBOARD_FAB2(SCH_1):M_K_DQ(55)
  U2D1 DU28 DDR3_DQ<55> SKX_EXT_B_BGA1-IC,TBD   I172 @BASEBOARD_FAB2_LIB.BASEBOARD_FAB2(SCH_1):PAGE60
  J1B1  124 DQ<54> SCONN288_H44441004_PIP-SCONN,HA   I111 @BASEBOARD_FAB2_LIB.BASEBOARD_FAB2(SCH_1):PAGE83
  J9M1  269 DQ<55> SCONN288_H44441003_PIP-SCONN,HA    I14 @BASEBOARD_FAB2_LIB.BASEBOARD_FAB2(SCH_1):PAGE84

M_K_DQ<56> @BASEBOARD_FAB2_LIB.BASEBOARD_FAB2(SCH_1):M_K_DQ(56)
  U2D1 DN24 DDR3_DQ<56> SKX_EXT_B_BGA1-IC,TBD   I172 @BASEBOARD_FAB2_LIB.BASEBOARD_FAB2(SCH_1):PAGE60
  J1B1  275 DQ<57> SCONN288_H44441004_PIP-SCONN,HA   I111 @BASEBOARD_FAB2_LIB.BASEBOARD_FAB2(SCH_1):PAGE83
  J9M1  130 DQ<56> SCONN288_H44441003_PIP-SCONN,HA    I14 @BASEBOARD_FAB2_LIB.BASEBOARD_FAB2(SCH_1):PAGE84

M_K_DQ<57> @BASEBOARD_FAB2_LIB.BASEBOARD_FAB2(SCH_1):M_K_DQ(57)
  U2D1 DU24 DDR3_DQ<57> SKX_EXT_B_BGA1-IC,TBD   I172 @BASEBOARD_FAB2_LIB.BASEBOARD_FAB2(SCH_1):PAGE60
  J1B1  130 DQ<56> SCONN288_H44441004_PIP-SCONN,HA   I111 @BASEBOARD_FAB2_LIB.BASEBOARD_FAB2(SCH_1):PAGE83
  J9M1  275 DQ<57> SCONN288_H44441003_PIP-SCONN,HA    I14 @BASEBOARD_FAB2_LIB.BASEBOARD_FAB2(SCH_1):PAGE84

M_K_DQ<58> @BASEBOARD_FAB2_LIB.BASEBOARD_FAB2(SCH_1):M_K_DQ(58)
  U2D1 DY21 DDR3_DQ<58> SKX_EXT_B_BGA1-IC,TBD   I172 @BASEBOARD_FAB2_LIB.BASEBOARD_FAB2(SCH_1):PAGE60
  J1B1  282 DQ<59> SCONN288_H44441004_PIP-SCONN,HA   I111 @BASEBOARD_FAB2_LIB.BASEBOARD_FAB2(SCH_1):PAGE83
  J9M1  137 DQ<58> SCONN288_H44441003_PIP-SCONN,HA    I14 @BASEBOARD_FAB2_LIB.BASEBOARD_FAB2(SCH_1):PAGE84

M_K_DQ<59> @BASEBOARD_FAB2_LIB.BASEBOARD_FAB2(SCH_1):M_K_DQ(59)
  U2D1 EB21 DDR3_DQ<59> SKX_EXT_B_BGA1-IC,TBD   I172 @BASEBOARD_FAB2_LIB.BASEBOARD_FAB2(SCH_1):PAGE60
  J1B1  137 DQ<58> SCONN288_H44441004_PIP-SCONN,HA   I111 @BASEBOARD_FAB2_LIB.BASEBOARD_FAB2(SCH_1):PAGE83
  J9M1  282 DQ<59> SCONN288_H44441003_PIP-SCONN,HA    I14 @BASEBOARD_FAB2_LIB.BASEBOARD_FAB2(SCH_1):PAGE84

M_K_DQ<5> @BASEBOARD_FAB2_LIB.BASEBOARD_FAB2(SCH_1):M_K_DQ(5)
  U2D1 CL86 DDR3_DQ<5> SKX_EXT_B_BGA1-IC,TBD   I172 @BASEBOARD_FAB2_LIB.BASEBOARD_FAB2(SCH_1):PAGE60
  J1B1    3  DQ<4> SCONN288_H44441004_PIP-SCONN,HA   I111 @BASEBOARD_FAB2_LIB.BASEBOARD_FAB2(SCH_1):PAGE83
  J9M1  148  DQ<5> SCONN288_H44441003_PIP-SCONN,HA    I14 @BASEBOARD_FAB2_LIB.BASEBOARD_FAB2(SCH_1):PAGE84

M_K_DQ<60> @BASEBOARD_FAB2_LIB.BASEBOARD_FAB2(SCH_1):M_K_DQ(60)
  U2D1 DP25 DDR3_DQ<60> SKX_EXT_B_BGA1-IC,TBD   I172 @BASEBOARD_FAB2_LIB.BASEBOARD_FAB2(SCH_1):PAGE60
  J1B1  273 DQ<61> SCONN288_H44441004_PIP-SCONN,HA   I111 @BASEBOARD_FAB2_LIB.BASEBOARD_FAB2(SCH_1):PAGE83
  J9M1  128 DQ<60> SCONN288_H44441003_PIP-SCONN,HA    I14 @BASEBOARD_FAB2_LIB.BASEBOARD_FAB2(SCH_1):PAGE84

M_K_DQ<61> @BASEBOARD_FAB2_LIB.BASEBOARD_FAB2(SCH_1):M_K_DQ(61)
  U2D1 DT25 DDR3_DQ<61> SKX_EXT_B_BGA1-IC,TBD   I172 @BASEBOARD_FAB2_LIB.BASEBOARD_FAB2(SCH_1):PAGE60
  J1B1  128 DQ<60> SCONN288_H44441004_PIP-SCONN,HA   I111 @BASEBOARD_FAB2_LIB.BASEBOARD_FAB2(SCH_1):PAGE83
  J9M1  273 DQ<61> SCONN288_H44441003_PIP-SCONN,HA    I14 @BASEBOARD_FAB2_LIB.BASEBOARD_FAB2(SCH_1):PAGE84

M_K_DQ<62> @BASEBOARD_FAB2_LIB.BASEBOARD_FAB2(SCH_1):M_K_DQ(62)
  U2D1 EC22 DDR3_DQ<62> SKX_EXT_B_BGA1-IC,TBD   I172 @BASEBOARD_FAB2_LIB.BASEBOARD_FAB2(SCH_1):PAGE60
  J1B1  280 DQ<63> SCONN288_H44441004_PIP-SCONN,HA   I111 @BASEBOARD_FAB2_LIB.BASEBOARD_FAB2(SCH_1):PAGE83
  J9M1  135 DQ<62> SCONN288_H44441003_PIP-SCONN,HA    I14 @BASEBOARD_FAB2_LIB.BASEBOARD_FAB2(SCH_1):PAGE84

M_K_DQ<63> @BASEBOARD_FAB2_LIB.BASEBOARD_FAB2(SCH_1):M_K_DQ(63)
  U2D1 DW22 DDR3_DQ<63> SKX_EXT_B_BGA1-IC,TBD   I172 @BASEBOARD_FAB2_LIB.BASEBOARD_FAB2(SCH_1):PAGE60
  J1B1  135 DQ<62> SCONN288_H44441004_PIP-SCONN,HA   I111 @BASEBOARD_FAB2_LIB.BASEBOARD_FAB2(SCH_1):PAGE83
  J9M1  280 DQ<63> SCONN288_H44441003_PIP-SCONN,HA    I14 @BASEBOARD_FAB2_LIB.BASEBOARD_FAB2(SCH_1):PAGE84

M_K_DQ<6> @BASEBOARD_FAB2_LIB.BASEBOARD_FAB2(SCH_1):M_K_DQ(6)
  U2D1 CW86 DDR3_DQ<6> SKX_EXT_B_BGA1-IC,TBD   I172 @BASEBOARD_FAB2_LIB.BASEBOARD_FAB2(SCH_1):PAGE60
  J1B1  155  DQ<7> SCONN288_H44441004_PIP-SCONN,HA   I111 @BASEBOARD_FAB2_LIB.BASEBOARD_FAB2(SCH_1):PAGE83
  J9M1   10  DQ<6> SCONN288_H44441003_PIP-SCONN,HA    I14 @BASEBOARD_FAB2_LIB.BASEBOARD_FAB2(SCH_1):PAGE84

M_K_DQ<7> @BASEBOARD_FAB2_LIB.BASEBOARD_FAB2(SCH_1):M_K_DQ(7)
  U2D1 CW84 DDR3_DQ<7> SKX_EXT_B_BGA1-IC,TBD   I172 @BASEBOARD_FAB2_LIB.BASEBOARD_FAB2(SCH_1):PAGE60
  J1B1   10  DQ<6> SCONN288_H44441004_PIP-SCONN,HA   I111 @BASEBOARD_FAB2_LIB.BASEBOARD_FAB2(SCH_1):PAGE83
  J9M1  155  DQ<7> SCONN288_H44441003_PIP-SCONN,HA    I14 @BASEBOARD_FAB2_LIB.BASEBOARD_FAB2(SCH_1):PAGE84

M_K_DQ<8> @BASEBOARD_FAB2_LIB.BASEBOARD_FAB2(SCH_1):M_K_DQ(8)
  U2D1 DG84 DDR3_DQ<8> SKX_EXT_B_BGA1-IC,TBD   I172 @BASEBOARD_FAB2_LIB.BASEBOARD_FAB2(SCH_1):PAGE60
  J1B1  161  DQ<9> SCONN288_H44441004_PIP-SCONN,HA   I111 @BASEBOARD_FAB2_LIB.BASEBOARD_FAB2(SCH_1):PAGE83
  J9M1   16  DQ<8> SCONN288_H44441003_PIP-SCONN,HA    I14 @BASEBOARD_FAB2_LIB.BASEBOARD_FAB2(SCH_1):PAGE84

M_K_DQ<9> @BASEBOARD_FAB2_LIB.BASEBOARD_FAB2(SCH_1):M_K_DQ(9)
  U2D1 DH85 DDR3_DQ<9> SKX_EXT_B_BGA1-IC,TBD   I172 @BASEBOARD_FAB2_LIB.BASEBOARD_FAB2(SCH_1):PAGE60
  J1B1   16  DQ<8> SCONN288_H44441004_PIP-SCONN,HA   I111 @BASEBOARD_FAB2_LIB.BASEBOARD_FAB2(SCH_1):PAGE83
  J9M1  161  DQ<9> SCONN288_H44441003_PIP-SCONN,HA    I14 @BASEBOARD_FAB2_LIB.BASEBOARD_FAB2(SCH_1):PAGE84

M_K_DQS_DN<0> @BASEBOARD_FAB2_LIB.BASEBOARD_FAB2(SCH_1):M_K_DQS_DN(0)
  U2D1 CU84 DDR3_DQS_DN<0> SKX_EXT_B_BGA1-IC,TBD   I172 @BASEBOARD_FAB2_LIB.BASEBOARD_FAB2(SCH_1):PAGE60
  J1B1  152  DQS0N SCONN288_H44441004_PIP-SCONN,HA    I66 @BASEBOARD_FAB2_LIB.BASEBOARD_FAB2(SCH_1):PAGE83
  J9M1  152  DQS0N SCONN288_H44441003_PIP-SCONN,HA   I102 @BASEBOARD_FAB2_LIB.BASEBOARD_FAB2(SCH_1):PAGE84

M_K_DQS_DN<10> @BASEBOARD_FAB2_LIB.BASEBOARD_FAB2(SCH_1):M_K_DQS_DN(10)
  U2D1 DM85 DDR3_DQS_DN<10> SKX_EXT_B_BGA1-IC,TBD   I172 @BASEBOARD_FAB2_LIB.BASEBOARD_FAB2(SCH_1):PAGE60
  J1B1   19 DQS10N SCONN288_H44441004_PIP-SCONN,HA    I66 @BASEBOARD_FAB2_LIB.BASEBOARD_FAB2(SCH_1):PAGE83
  J9M1   19 DQS10N SCONN288_H44441003_PIP-SCONN,HA   I102 @BASEBOARD_FAB2_LIB.BASEBOARD_FAB2(SCH_1):PAGE84

M_K_DQS_DN<11> @BASEBOARD_FAB2_LIB.BASEBOARD_FAB2(SCH_1):M_K_DQS_DN(11)
  U2D1 DN80 DDR3_DQS_DN<11> SKX_EXT_B_BGA1-IC,TBD   I172 @BASEBOARD_FAB2_LIB.BASEBOARD_FAB2(SCH_1):PAGE60
  J1B1   30 DQS11N SCONN288_H44441004_PIP-SCONN,HA    I66 @BASEBOARD_FAB2_LIB.BASEBOARD_FAB2(SCH_1):PAGE83
  J9M1   30 DQS11N SCONN288_H44441003_PIP-SCONN,HA   I102 @BASEBOARD_FAB2_LIB.BASEBOARD_FAB2(SCH_1):PAGE84

M_K_DQS_DN<12> @BASEBOARD_FAB2_LIB.BASEBOARD_FAB2(SCH_1):M_K_DQS_DN(12)
  U2D1 DP75 DDR3_DQS_DN<12> SKX_EXT_B_BGA1-IC,TBD   I172 @BASEBOARD_FAB2_LIB.BASEBOARD_FAB2(SCH_1):PAGE60
  J1B1   41 DQS12N SCONN288_H44441004_PIP-SCONN,HA    I66 @BASEBOARD_FAB2_LIB.BASEBOARD_FAB2(SCH_1):PAGE83
  J9M1   41 DQS12N SCONN288_H44441003_PIP-SCONN,HA   I102 @BASEBOARD_FAB2_LIB.BASEBOARD_FAB2(SCH_1):PAGE84

M_K_DQS_DN<13> @BASEBOARD_FAB2_LIB.BASEBOARD_FAB2(SCH_1):M_K_DQS_DN(13)
  U2D1 EA38 DDR3_DQS_DN<13> SKX_EXT_B_BGA1-IC,TBD   I172 @BASEBOARD_FAB2_LIB.BASEBOARD_FAB2(SCH_1):PAGE60
  J1B1  100 DQS13N SCONN288_H44441004_PIP-SCONN,HA    I66 @BASEBOARD_FAB2_LIB.BASEBOARD_FAB2(SCH_1):PAGE83
  J9M1  100 DQS13N SCONN288_H44441003_PIP-SCONN,HA   I102 @BASEBOARD_FAB2_LIB.BASEBOARD_FAB2(SCH_1):PAGE84

M_K_DQS_DN<14> @BASEBOARD_FAB2_LIB.BASEBOARD_FAB2(SCH_1):M_K_DQS_DN(14)
  U2D1 DP35 DDR3_DQS_DN<14> SKX_EXT_B_BGA1-IC,TBD   I172 @BASEBOARD_FAB2_LIB.BASEBOARD_FAB2(SCH_1):PAGE60
  J1B1  111 DQS14N SCONN288_H44441004_PIP-SCONN,HA    I66 @BASEBOARD_FAB2_LIB.BASEBOARD_FAB2(SCH_1):PAGE83
  J9M1  111 DQS14N SCONN288_H44441003_PIP-SCONN,HA   I102 @BASEBOARD_FAB2_LIB.BASEBOARD_FAB2(SCH_1):PAGE84

M_K_DQS_DN<15> @BASEBOARD_FAB2_LIB.BASEBOARD_FAB2(SCH_1):M_K_DQS_DN(15)
  U2D1 DM29 DDR3_DQS_DN<15> SKX_EXT_B_BGA1-IC,TBD   I172 @BASEBOARD_FAB2_LIB.BASEBOARD_FAB2(SCH_1):PAGE60
  J1B1  122 DQS15N SCONN288_H44441004_PIP-SCONN,HA    I66 @BASEBOARD_FAB2_LIB.BASEBOARD_FAB2(SCH_1):PAGE83
  J9M1  122 DQS15N SCONN288_H44441003_PIP-SCONN,HA   I102 @BASEBOARD_FAB2_LIB.BASEBOARD_FAB2(SCH_1):PAGE84

M_K_DQS_DN<16> @BASEBOARD_FAB2_LIB.BASEBOARD_FAB2(SCH_1):M_K_DQS_DN(16)
  U2D1 DM23 DDR3_DQS_DN<16> SKX_EXT_B_BGA1-IC,TBD   I172 @BASEBOARD_FAB2_LIB.BASEBOARD_FAB2(SCH_1):PAGE60
  J1B1  133 DQS16N SCONN288_H44441004_PIP-SCONN,HA    I66 @BASEBOARD_FAB2_LIB.BASEBOARD_FAB2(SCH_1):PAGE83
  J9M1  133 DQS16N SCONN288_H44441003_PIP-SCONN,HA   I102 @BASEBOARD_FAB2_LIB.BASEBOARD_FAB2(SCH_1):PAGE84

M_K_DQS_DN<17> @BASEBOARD_FAB2_LIB.BASEBOARD_FAB2(SCH_1):M_K_DQS_DN(17)
  U2D1 DB67 DDR3_DQS_DN<17> SKX_EXT_B_BGA1-IC,TBD   I172 @BASEBOARD_FAB2_LIB.BASEBOARD_FAB2(SCH_1):PAGE60
  J1B1   52 DQS17N SCONN288_H44441004_PIP-SCONN,HA    I66 @BASEBOARD_FAB2_LIB.BASEBOARD_FAB2(SCH_1):PAGE83
  J9M1   52 DQS17N SCONN288_H44441003_PIP-SCONN,HA   I102 @BASEBOARD_FAB2_LIB.BASEBOARD_FAB2(SCH_1):PAGE84

M_K_DQS_DN<1> @BASEBOARD_FAB2_LIB.BASEBOARD_FAB2(SCH_1):M_K_DQS_DN(1)
  U2D1 DN84 DDR3_DQS_DN<1> SKX_EXT_B_BGA1-IC,TBD   I172 @BASEBOARD_FAB2_LIB.BASEBOARD_FAB2(SCH_1):PAGE60
  J1B1  163  DQS1N SCONN288_H44441004_PIP-SCONN,HA    I66 @BASEBOARD_FAB2_LIB.BASEBOARD_FAB2(SCH_1):PAGE83
  J9M1  163  DQS1N SCONN288_H44441003_PIP-SCONN,HA   I102 @BASEBOARD_FAB2_LIB.BASEBOARD_FAB2(SCH_1):PAGE84

M_K_DQS_DN<2> @BASEBOARD_FAB2_LIB.BASEBOARD_FAB2(SCH_1):M_K_DQS_DN(2)
  U2D1 DL82 DDR3_DQS_DN<2> SKX_EXT_B_BGA1-IC,TBD   I172 @BASEBOARD_FAB2_LIB.BASEBOARD_FAB2(SCH_1):PAGE60
  J1B1  174  DQS2N SCONN288_H44441004_PIP-SCONN,HA    I66 @BASEBOARD_FAB2_LIB.BASEBOARD_FAB2(SCH_1):PAGE83
  J9M1  174  DQS2N SCONN288_H44441003_PIP-SCONN,HA   I102 @BASEBOARD_FAB2_LIB.BASEBOARD_FAB2(SCH_1):PAGE84

M_K_DQS_DN<3> @BASEBOARD_FAB2_LIB.BASEBOARD_FAB2(SCH_1):M_K_DQS_DN(3)
  U2D1 DV75 DDR3_DQS_DN<3> SKX_EXT_B_BGA1-IC,TBD   I172 @BASEBOARD_FAB2_LIB.BASEBOARD_FAB2(SCH_1):PAGE60
  J1B1  185  DQS3N SCONN288_H44441004_PIP-SCONN,HA    I66 @BASEBOARD_FAB2_LIB.BASEBOARD_FAB2(SCH_1):PAGE83
  J9M1  185  DQS3N SCONN288_H44441003_PIP-SCONN,HA   I102 @BASEBOARD_FAB2_LIB.BASEBOARD_FAB2(SCH_1):PAGE84

M_K_DQS_DN<4> @BASEBOARD_FAB2_LIB.BASEBOARD_FAB2(SCH_1):M_K_DQS_DN(4)
  U2D1 EE38 DDR3_DQS_DN<4> SKX_EXT_B_BGA1-IC,TBD   I172 @BASEBOARD_FAB2_LIB.BASEBOARD_FAB2(SCH_1):PAGE60
  J1B1  244  DQS4N SCONN288_H44441004_PIP-SCONN,HA    I66 @BASEBOARD_FAB2_LIB.BASEBOARD_FAB2(SCH_1):PAGE83
  J9M1  244  DQS4N SCONN288_H44441003_PIP-SCONN,HA   I102 @BASEBOARD_FAB2_LIB.BASEBOARD_FAB2(SCH_1):PAGE84

M_K_DQS_DN<5> @BASEBOARD_FAB2_LIB.BASEBOARD_FAB2(SCH_1):M_K_DQS_DN(5)
  U2D1 DV35 DDR3_DQS_DN<5> SKX_EXT_B_BGA1-IC,TBD   I172 @BASEBOARD_FAB2_LIB.BASEBOARD_FAB2(SCH_1):PAGE60
  J1B1  255  DQS5N SCONN288_H44441004_PIP-SCONN,HA    I66 @BASEBOARD_FAB2_LIB.BASEBOARD_FAB2(SCH_1):PAGE83
  J9M1  255  DQS5N SCONN288_H44441003_PIP-SCONN,HA   I102 @BASEBOARD_FAB2_LIB.BASEBOARD_FAB2(SCH_1):PAGE84

M_K_DQS_DN<6> @BASEBOARD_FAB2_LIB.BASEBOARD_FAB2(SCH_1):M_K_DQS_DN(6)
  U2D1 DV29 DDR3_DQS_DN<6> SKX_EXT_B_BGA1-IC,TBD   I172 @BASEBOARD_FAB2_LIB.BASEBOARD_FAB2(SCH_1):PAGE60
  J1B1  266  DQS6N SCONN288_H44441004_PIP-SCONN,HA    I66 @BASEBOARD_FAB2_LIB.BASEBOARD_FAB2(SCH_1):PAGE83
  J9M1  266  DQS6N SCONN288_H44441003_PIP-SCONN,HA   I102 @BASEBOARD_FAB2_LIB.BASEBOARD_FAB2(SCH_1):PAGE84

M_K_DQS_DN<7> @BASEBOARD_FAB2_LIB.BASEBOARD_FAB2(SCH_1):M_K_DQS_DN(7)
  U2D1 DV23 DDR3_DQS_DN<7> SKX_EXT_B_BGA1-IC,TBD   I172 @BASEBOARD_FAB2_LIB.BASEBOARD_FAB2(SCH_1):PAGE60
  J1B1  277  DQS7N SCONN288_H44441004_PIP-SCONN,HA    I66 @BASEBOARD_FAB2_LIB.BASEBOARD_FAB2(SCH_1):PAGE83
  J9M1  277  DQS7N SCONN288_H44441003_PIP-SCONN,HA   I102 @BASEBOARD_FAB2_LIB.BASEBOARD_FAB2(SCH_1):PAGE84

M_K_DQS_DN<8> @BASEBOARD_FAB2_LIB.BASEBOARD_FAB2(SCH_1):M_K_DQS_DN(8)
  U2D1 DF67 DDR3_DQS_DN<8> SKX_EXT_B_BGA1-IC,TBD   I172 @BASEBOARD_FAB2_LIB.BASEBOARD_FAB2(SCH_1):PAGE60
  J1B1  196  DQS8N SCONN288_H44441004_PIP-SCONN,HA    I66 @BASEBOARD_FAB2_LIB.BASEBOARD_FAB2(SCH_1):PAGE83
  J9M1  196  DQS8N SCONN288_H44441003_PIP-SCONN,HA   I102 @BASEBOARD_FAB2_LIB.BASEBOARD_FAB2(SCH_1):PAGE84

M_K_DQS_DN<9> @BASEBOARD_FAB2_LIB.BASEBOARD_FAB2(SCH_1):M_K_DQS_DN(9)
  U2D1 CR84 DDR3_DQS_DN<9> SKX_EXT_B_BGA1-IC,TBD   I172 @BASEBOARD_FAB2_LIB.BASEBOARD_FAB2(SCH_1):PAGE60
  J1B1    8  DQS9N SCONN288_H44441004_PIP-SCONN,HA    I66 @BASEBOARD_FAB2_LIB.BASEBOARD_FAB2(SCH_1):PAGE83
  J9M1    8  DQS9N SCONN288_H44441003_PIP-SCONN,HA   I102 @BASEBOARD_FAB2_LIB.BASEBOARD_FAB2(SCH_1):PAGE84

M_K_DQS_DP<0> @BASEBOARD_FAB2_LIB.BASEBOARD_FAB2(SCH_1):M_K_DQS_DP(0)
  U2D1 CV85 DDR3_DQS_DP<0> SKX_EXT_B_BGA1-IC,TBD   I172 @BASEBOARD_FAB2_LIB.BASEBOARD_FAB2(SCH_1):PAGE60
  J1B1  153  DQS0P SCONN288_H44441004_PIP-SCONN,HA    I66 @BASEBOARD_FAB2_LIB.BASEBOARD_FAB2(SCH_1):PAGE83
  J9M1  153  DQS0P SCONN288_H44441003_PIP-SCONN,HA   I102 @BASEBOARD_FAB2_LIB.BASEBOARD_FAB2(SCH_1):PAGE84

M_K_DQS_DP<10> @BASEBOARD_FAB2_LIB.BASEBOARD_FAB2(SCH_1):M_K_DQS_DP(10)
  U2D1 DL84 DDR3_DQS_DP<10> SKX_EXT_B_BGA1-IC,TBD   I172 @BASEBOARD_FAB2_LIB.BASEBOARD_FAB2(SCH_1):PAGE60
  J1B1   18 DQS10P SCONN288_H44441004_PIP-SCONN,HA    I66 @BASEBOARD_FAB2_LIB.BASEBOARD_FAB2(SCH_1):PAGE83
  J9M1   18 DQS10P SCONN288_H44441003_PIP-SCONN,HA   I102 @BASEBOARD_FAB2_LIB.BASEBOARD_FAB2(SCH_1):PAGE84

M_K_DQS_DP<11> @BASEBOARD_FAB2_LIB.BASEBOARD_FAB2(SCH_1):M_K_DQS_DP(11)
  U2D1 DP79 DDR3_DQS_DP<11> SKX_EXT_B_BGA1-IC,TBD   I172 @BASEBOARD_FAB2_LIB.BASEBOARD_FAB2(SCH_1):PAGE60
  J1B1   29 DQS11P SCONN288_H44441004_PIP-SCONN,HA    I66 @BASEBOARD_FAB2_LIB.BASEBOARD_FAB2(SCH_1):PAGE83
  J9M1   29 DQS11P SCONN288_H44441003_PIP-SCONN,HA   I102 @BASEBOARD_FAB2_LIB.BASEBOARD_FAB2(SCH_1):PAGE84

M_K_DQS_DP<12> @BASEBOARD_FAB2_LIB.BASEBOARD_FAB2(SCH_1):M_K_DQS_DP(12)
  U2D1 DM75 DDR3_DQS_DP<12> SKX_EXT_B_BGA1-IC,TBD   I172 @BASEBOARD_FAB2_LIB.BASEBOARD_FAB2(SCH_1):PAGE60
  J1B1   40 DQS12P SCONN288_H44441004_PIP-SCONN,HA    I66 @BASEBOARD_FAB2_LIB.BASEBOARD_FAB2(SCH_1):PAGE83
  J9M1   40 DQS12P SCONN288_H44441003_PIP-SCONN,HA   I102 @BASEBOARD_FAB2_LIB.BASEBOARD_FAB2(SCH_1):PAGE84

M_K_DQS_DP<13> @BASEBOARD_FAB2_LIB.BASEBOARD_FAB2(SCH_1):M_K_DQS_DP(13)
  U2D1 DW38 DDR3_DQS_DP<13> SKX_EXT_B_BGA1-IC,TBD   I172 @BASEBOARD_FAB2_LIB.BASEBOARD_FAB2(SCH_1):PAGE60
  J1B1   99 DQS13P SCONN288_H44441004_PIP-SCONN,HA    I66 @BASEBOARD_FAB2_LIB.BASEBOARD_FAB2(SCH_1):PAGE83
  J9M1   99 DQS13P SCONN288_H44441003_PIP-SCONN,HA   I102 @BASEBOARD_FAB2_LIB.BASEBOARD_FAB2(SCH_1):PAGE84

M_K_DQS_DP<14> @BASEBOARD_FAB2_LIB.BASEBOARD_FAB2(SCH_1):M_K_DQS_DP(14)
  U2D1 DM35 DDR3_DQS_DP<14> SKX_EXT_B_BGA1-IC,TBD   I172 @BASEBOARD_FAB2_LIB.BASEBOARD_FAB2(SCH_1):PAGE60
  J1B1  110 DQS14P SCONN288_H44441004_PIP-SCONN,HA    I66 @BASEBOARD_FAB2_LIB.BASEBOARD_FAB2(SCH_1):PAGE83
  J9M1  110 DQS14P SCONN288_H44441003_PIP-SCONN,HA   I102 @BASEBOARD_FAB2_LIB.BASEBOARD_FAB2(SCH_1):PAGE84

M_K_DQS_DP<15> @BASEBOARD_FAB2_LIB.BASEBOARD_FAB2(SCH_1):M_K_DQS_DP(15)
  U2D1 DP29 DDR3_DQS_DP<15> SKX_EXT_B_BGA1-IC,TBD   I172 @BASEBOARD_FAB2_LIB.BASEBOARD_FAB2(SCH_1):PAGE60
  J1B1  121 DQS15P SCONN288_H44441004_PIP-SCONN,HA    I66 @BASEBOARD_FAB2_LIB.BASEBOARD_FAB2(SCH_1):PAGE83
  J9M1  121 DQS15P SCONN288_H44441003_PIP-SCONN,HA   I102 @BASEBOARD_FAB2_LIB.BASEBOARD_FAB2(SCH_1):PAGE84

M_K_DQS_DP<16> @BASEBOARD_FAB2_LIB.BASEBOARD_FAB2(SCH_1):M_K_DQS_DP(16)
  U2D1 DP23 DDR3_DQS_DP<16> SKX_EXT_B_BGA1-IC,TBD   I172 @BASEBOARD_FAB2_LIB.BASEBOARD_FAB2(SCH_1):PAGE60
  J1B1  132 DQS16P SCONN288_H44441004_PIP-SCONN,HA    I66 @BASEBOARD_FAB2_LIB.BASEBOARD_FAB2(SCH_1):PAGE83
  J9M1  132 DQS16P SCONN288_H44441003_PIP-SCONN,HA   I102 @BASEBOARD_FAB2_LIB.BASEBOARD_FAB2(SCH_1):PAGE84

M_K_DQS_DP<17> @BASEBOARD_FAB2_LIB.BASEBOARD_FAB2(SCH_1):M_K_DQS_DP(17)
  U2D1 CY67 DDR3_DQS_DP<17> SKX_EXT_B_BGA1-IC,TBD   I172 @BASEBOARD_FAB2_LIB.BASEBOARD_FAB2(SCH_1):PAGE60
  J1B1   51 DQS17P SCONN288_H44441004_PIP-SCONN,HA    I66 @BASEBOARD_FAB2_LIB.BASEBOARD_FAB2(SCH_1):PAGE83
  J9M1   51 DQS17P SCONN288_H44441003_PIP-SCONN,HA   I102 @BASEBOARD_FAB2_LIB.BASEBOARD_FAB2(SCH_1):PAGE84

M_K_DQS_DP<1> @BASEBOARD_FAB2_LIB.BASEBOARD_FAB2(SCH_1):M_K_DQS_DP(1)
  U2D1 DP85 DDR3_DQS_DP<1> SKX_EXT_B_BGA1-IC,TBD   I172 @BASEBOARD_FAB2_LIB.BASEBOARD_FAB2(SCH_1):PAGE60
  J1B1  164  DQS1P SCONN288_H44441004_PIP-SCONN,HA    I66 @BASEBOARD_FAB2_LIB.BASEBOARD_FAB2(SCH_1):PAGE83
  J9M1  164  DQS1P SCONN288_H44441003_PIP-SCONN,HA   I102 @BASEBOARD_FAB2_LIB.BASEBOARD_FAB2(SCH_1):PAGE84

M_K_DQS_DP<2> @BASEBOARD_FAB2_LIB.BASEBOARD_FAB2(SCH_1):M_K_DQS_DP(2)
  U2D1 DM81 DDR3_DQS_DP<2> SKX_EXT_B_BGA1-IC,TBD   I172 @BASEBOARD_FAB2_LIB.BASEBOARD_FAB2(SCH_1):PAGE60
  J1B1  175  DQS2P SCONN288_H44441004_PIP-SCONN,HA    I66 @BASEBOARD_FAB2_LIB.BASEBOARD_FAB2(SCH_1):PAGE83
  J9M1  175  DQS2P SCONN288_H44441003_PIP-SCONN,HA   I102 @BASEBOARD_FAB2_LIB.BASEBOARD_FAB2(SCH_1):PAGE84

M_K_DQS_DP<3> @BASEBOARD_FAB2_LIB.BASEBOARD_FAB2(SCH_1):M_K_DQS_DP(3)
  U2D1 DT75 DDR3_DQS_DP<3> SKX_EXT_B_BGA1-IC,TBD   I172 @BASEBOARD_FAB2_LIB.BASEBOARD_FAB2(SCH_1):PAGE60
  J1B1  186  DQS3P SCONN288_H44441004_PIP-SCONN,HA    I66 @BASEBOARD_FAB2_LIB.BASEBOARD_FAB2(SCH_1):PAGE83
  J9M1  186  DQS3P SCONN288_H44441003_PIP-SCONN,HA   I102 @BASEBOARD_FAB2_LIB.BASEBOARD_FAB2(SCH_1):PAGE84

M_K_DQS_DP<4> @BASEBOARD_FAB2_LIB.BASEBOARD_FAB2(SCH_1):M_K_DQS_DP(4)
  U2D1 EC38 DDR3_DQS_DP<4> SKX_EXT_B_BGA1-IC,TBD   I172 @BASEBOARD_FAB2_LIB.BASEBOARD_FAB2(SCH_1):PAGE60
  J1B1  245  DQS4P SCONN288_H44441004_PIP-SCONN,HA    I66 @BASEBOARD_FAB2_LIB.BASEBOARD_FAB2(SCH_1):PAGE83
  J9M1  245  DQS4P SCONN288_H44441003_PIP-SCONN,HA   I102 @BASEBOARD_FAB2_LIB.BASEBOARD_FAB2(SCH_1):PAGE84

M_K_DQS_DP<5> @BASEBOARD_FAB2_LIB.BASEBOARD_FAB2(SCH_1):M_K_DQS_DP(5)
  U2D1 DT35 DDR3_DQS_DP<5> SKX_EXT_B_BGA1-IC,TBD   I172 @BASEBOARD_FAB2_LIB.BASEBOARD_FAB2(SCH_1):PAGE60
  J1B1  256  DQS5P SCONN288_H44441004_PIP-SCONN,HA    I66 @BASEBOARD_FAB2_LIB.BASEBOARD_FAB2(SCH_1):PAGE83
  J9M1  256  DQS5P SCONN288_H44441003_PIP-SCONN,HA   I102 @BASEBOARD_FAB2_LIB.BASEBOARD_FAB2(SCH_1):PAGE84

M_K_DQS_DP<6> @BASEBOARD_FAB2_LIB.BASEBOARD_FAB2(SCH_1):M_K_DQS_DP(6)
  U2D1 DT29 DDR3_DQS_DP<6> SKX_EXT_B_BGA1-IC,TBD   I172 @BASEBOARD_FAB2_LIB.BASEBOARD_FAB2(SCH_1):PAGE60
  J1B1  267  DQS6P SCONN288_H44441004_PIP-SCONN,HA    I66 @BASEBOARD_FAB2_LIB.BASEBOARD_FAB2(SCH_1):PAGE83
  J9M1  267  DQS6P SCONN288_H44441003_PIP-SCONN,HA   I102 @BASEBOARD_FAB2_LIB.BASEBOARD_FAB2(SCH_1):PAGE84

M_K_DQS_DP<7> @BASEBOARD_FAB2_LIB.BASEBOARD_FAB2(SCH_1):M_K_DQS_DP(7)
  U2D1 DT23 DDR3_DQS_DP<7> SKX_EXT_B_BGA1-IC,TBD   I172 @BASEBOARD_FAB2_LIB.BASEBOARD_FAB2(SCH_1):PAGE60
  J1B1  278  DQS7P SCONN288_H44441004_PIP-SCONN,HA    I66 @BASEBOARD_FAB2_LIB.BASEBOARD_FAB2(SCH_1):PAGE83
  J9M1  278  DQS7P SCONN288_H44441003_PIP-SCONN,HA   I102 @BASEBOARD_FAB2_LIB.BASEBOARD_FAB2(SCH_1):PAGE84

M_K_DQS_DP<8> @BASEBOARD_FAB2_LIB.BASEBOARD_FAB2(SCH_1):M_K_DQS_DP(8)
  U2D1 DD67 DDR3_DQS_DP<8> SKX_EXT_B_BGA1-IC,TBD   I172 @BASEBOARD_FAB2_LIB.BASEBOARD_FAB2(SCH_1):PAGE60
  J1B1  197  DQS8P SCONN288_H44441004_PIP-SCONN,HA    I66 @BASEBOARD_FAB2_LIB.BASEBOARD_FAB2(SCH_1):PAGE83
  J9M1  197  DQS8P SCONN288_H44441003_PIP-SCONN,HA   I102 @BASEBOARD_FAB2_LIB.BASEBOARD_FAB2(SCH_1):PAGE84

M_K_DQS_DP<9> @BASEBOARD_FAB2_LIB.BASEBOARD_FAB2(SCH_1):M_K_DQS_DP(9)
  U2D1 CP85 DDR3_DQS_DP<9> SKX_EXT_B_BGA1-IC,TBD   I172 @BASEBOARD_FAB2_LIB.BASEBOARD_FAB2(SCH_1):PAGE60
  J1B1    7  DQS9P SCONN288_H44441004_PIP-SCONN,HA    I66 @BASEBOARD_FAB2_LIB.BASEBOARD_FAB2(SCH_1):PAGE83
  J9M1    7  DQS9P SCONN288_H44441003_PIP-SCONN,HA   I102 @BASEBOARD_FAB2_LIB.BASEBOARD_FAB2(SCH_1):PAGE84

M_K_ECC<0> @BASEBOARD_FAB2_LIB.BASEBOARD_FAB2(SCH_1):M_K_ECC(0)
  U2D1 DA68 DDR3_ECC<0> SKX_EXT_B_BGA1-IC,TBD   I172 @BASEBOARD_FAB2_LIB.BASEBOARD_FAB2(SCH_1):PAGE60
  J1B1  194  CB<1> SCONN288_H44441004_PIP-SCONN,HA   I111 @BASEBOARD_FAB2_LIB.BASEBOARD_FAB2(SCH_1):PAGE83
  J9M1   49  CB<0> SCONN288_H44441003_PIP-SCONN,HA    I14 @BASEBOARD_FAB2_LIB.BASEBOARD_FAB2(SCH_1):PAGE84

M_K_ECC<1> @BASEBOARD_FAB2_LIB.BASEBOARD_FAB2(SCH_1):M_K_ECC(1)
  U2D1 DE68 DDR3_ECC<1> SKX_EXT_B_BGA1-IC,TBD   I172 @BASEBOARD_FAB2_LIB.BASEBOARD_FAB2(SCH_1):PAGE60
  J1B1   49  CB<0> SCONN288_H44441004_PIP-SCONN,HA   I111 @BASEBOARD_FAB2_LIB.BASEBOARD_FAB2(SCH_1):PAGE83
  J9M1  194  CB<1> SCONN288_H44441003_PIP-SCONN,HA    I14 @BASEBOARD_FAB2_LIB.BASEBOARD_FAB2(SCH_1):PAGE84

M_K_ECC<2> @BASEBOARD_FAB2_LIB.BASEBOARD_FAB2(SCH_1):M_K_ECC(2)
  U2D1 DB65 DDR3_ECC<2> SKX_EXT_B_BGA1-IC,TBD   I172 @BASEBOARD_FAB2_LIB.BASEBOARD_FAB2(SCH_1):PAGE60
  J1B1  201  CB<3> SCONN288_H44441004_PIP-SCONN,HA   I111 @BASEBOARD_FAB2_LIB.BASEBOARD_FAB2(SCH_1):PAGE83
  J9M1   56  CB<2> SCONN288_H44441003_PIP-SCONN,HA    I14 @BASEBOARD_FAB2_LIB.BASEBOARD_FAB2(SCH_1):PAGE84

M_K_ECC<3> @BASEBOARD_FAB2_LIB.BASEBOARD_FAB2(SCH_1):M_K_ECC(3)
  U2D1 DD65 DDR3_ECC<3> SKX_EXT_B_BGA1-IC,TBD   I172 @BASEBOARD_FAB2_LIB.BASEBOARD_FAB2(SCH_1):PAGE60
  J1B1   56  CB<2> SCONN288_H44441004_PIP-SCONN,HA   I111 @BASEBOARD_FAB2_LIB.BASEBOARD_FAB2(SCH_1):PAGE83
  J9M1  201  CB<3> SCONN288_H44441003_PIP-SCONN,HA    I14 @BASEBOARD_FAB2_LIB.BASEBOARD_FAB2(SCH_1):PAGE84

M_K_ECC<4> @BASEBOARD_FAB2_LIB.BASEBOARD_FAB2(SCH_1):M_K_ECC(4)
  U2D1 DB69 DDR3_ECC<4> SKX_EXT_B_BGA1-IC,TBD   I172 @BASEBOARD_FAB2_LIB.BASEBOARD_FAB2(SCH_1):PAGE60
  J1B1  192  CB<5> SCONN288_H44441004_PIP-SCONN,HA   I111 @BASEBOARD_FAB2_LIB.BASEBOARD_FAB2(SCH_1):PAGE83
  J9M1   47  CB<4> SCONN288_H44441003_PIP-SCONN,HA    I14 @BASEBOARD_FAB2_LIB.BASEBOARD_FAB2(SCH_1):PAGE84

M_K_ECC<5> @BASEBOARD_FAB2_LIB.BASEBOARD_FAB2(SCH_1):M_K_ECC(5)
  U2D1 DD69 DDR3_ECC<5> SKX_EXT_B_BGA1-IC,TBD   I172 @BASEBOARD_FAB2_LIB.BASEBOARD_FAB2(SCH_1):PAGE60
  J1B1   47  CB<4> SCONN288_H44441004_PIP-SCONN,HA   I111 @BASEBOARD_FAB2_LIB.BASEBOARD_FAB2(SCH_1):PAGE83
  J9M1  192  CB<5> SCONN288_H44441003_PIP-SCONN,HA    I14 @BASEBOARD_FAB2_LIB.BASEBOARD_FAB2(SCH_1):PAGE84

M_K_ECC<6> @BASEBOARD_FAB2_LIB.BASEBOARD_FAB2(SCH_1):M_K_ECC(6)
  U2D1 DA66 DDR3_ECC<6> SKX_EXT_B_BGA1-IC,TBD   I172 @BASEBOARD_FAB2_LIB.BASEBOARD_FAB2(SCH_1):PAGE60
  J1B1  199  CB<7> SCONN288_H44441004_PIP-SCONN,HA   I111 @BASEBOARD_FAB2_LIB.BASEBOARD_FAB2(SCH_1):PAGE83
  J9M1   54  CB<6> SCONN288_H44441003_PIP-SCONN,HA    I14 @BASEBOARD_FAB2_LIB.BASEBOARD_FAB2(SCH_1):PAGE84

M_K_ECC<7> @BASEBOARD_FAB2_LIB.BASEBOARD_FAB2(SCH_1):M_K_ECC(7)
  U2D1 DE66 DDR3_ECC<7> SKX_EXT_B_BGA1-IC,TBD   I172 @BASEBOARD_FAB2_LIB.BASEBOARD_FAB2(SCH_1):PAGE60
  J1B1   54  CB<6> SCONN288_H44441004_PIP-SCONN,HA   I111 @BASEBOARD_FAB2_LIB.BASEBOARD_FAB2(SCH_1):PAGE83
  J9M1  199  CB<7> SCONN288_H44441003_PIP-SCONN,HA    I14 @BASEBOARD_FAB2_LIB.BASEBOARD_FAB2(SCH_1):PAGE84

M_K_MA<0> @BASEBOARD_FAB2_LIB.BASEBOARD_FAB2(SCH_1):M_K_MA(0)
  U2D1 EB53 DDR3_MA<0> SKX_EXT_B_BGA1-IC,TBD   I172 @BASEBOARD_FAB2_LIB.BASEBOARD_FAB2(SCH_1):PAGE60
  J1B1   79     A0 SCONN288_H44441004_PIP-SCONN,HA   I111 @BASEBOARD_FAB2_LIB.BASEBOARD_FAB2(SCH_1):PAGE83
  J9M1   79     A0 SCONN288_H44441003_PIP-SCONN,HA    I14 @BASEBOARD_FAB2_LIB.BASEBOARD_FAB2(SCH_1):PAGE84

M_K_MA<10> @BASEBOARD_FAB2_LIB.BASEBOARD_FAB2(SCH_1):M_K_MA(10)
  U2D1 DW54 DDR3_MA<10> SKX_EXT_B_BGA1-IC,TBD   I172 @BASEBOARD_FAB2_LIB.BASEBOARD_FAB2(SCH_1):PAGE60
  J1B1  225    A10 SCONN288_H44441004_PIP-SCONN,HA   I111 @BASEBOARD_FAB2_LIB.BASEBOARD_FAB2(SCH_1):PAGE83
  J9M1  225    A10 SCONN288_H44441003_PIP-SCONN,HA    I14 @BASEBOARD_FAB2_LIB.BASEBOARD_FAB2(SCH_1):PAGE84

M_K_MA<11> @BASEBOARD_FAB2_LIB.BASEBOARD_FAB2(SCH_1):M_K_MA(11)
  U2D1 EB61 DDR3_MA<11> SKX_EXT_B_BGA1-IC,TBD   I172 @BASEBOARD_FAB2_LIB.BASEBOARD_FAB2(SCH_1):PAGE60
  J1B1  210    A11 SCONN288_H44441004_PIP-SCONN,HA   I111 @BASEBOARD_FAB2_LIB.BASEBOARD_FAB2(SCH_1):PAGE83
  J9M1  210    A11 SCONN288_H44441003_PIP-SCONN,HA    I14 @BASEBOARD_FAB2_LIB.BASEBOARD_FAB2(SCH_1):PAGE84

M_K_MA<12> @BASEBOARD_FAB2_LIB.BASEBOARD_FAB2(SCH_1):M_K_MA(12)
  U2D1 DT63 DDR3_MA<12> SKX_EXT_B_BGA1-IC,TBD   I172 @BASEBOARD_FAB2_LIB.BASEBOARD_FAB2(SCH_1):PAGE60
  J1B1   65    A12 SCONN288_H44441004_PIP-SCONN,HA   I111 @BASEBOARD_FAB2_LIB.BASEBOARD_FAB2(SCH_1):PAGE83
  J9M1   65    A12 SCONN288_H44441003_PIP-SCONN,HA    I14 @BASEBOARD_FAB2_LIB.BASEBOARD_FAB2(SCH_1):PAGE84

M_K_MA<13> @BASEBOARD_FAB2_LIB.BASEBOARD_FAB2(SCH_1):M_K_MA(13)
  U2D1 DW48 DDR3_MA<13> SKX_EXT_B_BGA1-IC,TBD   I172 @BASEBOARD_FAB2_LIB.BASEBOARD_FAB2(SCH_1):PAGE60
  J1B1  232    A13 SCONN288_H44441004_PIP-SCONN,HA   I111 @BASEBOARD_FAB2_LIB.BASEBOARD_FAB2(SCH_1):PAGE83
  J9M1  232    A13 SCONN288_H44441003_PIP-SCONN,HA    I14 @BASEBOARD_FAB2_LIB.BASEBOARD_FAB2(SCH_1):PAGE84

M_K_MA<14> @BASEBOARD_FAB2_LIB.BASEBOARD_FAB2(SCH_1):M_K_MA(14)
  U2D1 ED51 DDR3_MA<14> SKX_EXT_B_BGA1-IC,TBD   I172 @BASEBOARD_FAB2_LIB.BASEBOARD_FAB2(SCH_1):PAGE60
  J1B1  228 A14_WE_N SCONN288_H44441004_PIP-SCONN,HA   I111 @BASEBOARD_FAB2_LIB.BASEBOARD_FAB2(SCH_1):PAGE83
  J9M1  228 A14_WE_N SCONN288_H44441003_PIP-SCONN,HA    I14 @BASEBOARD_FAB2_LIB.BASEBOARD_FAB2(SCH_1):PAGE84

M_K_MA<15> @BASEBOARD_FAB2_LIB.BASEBOARD_FAB2(SCH_1):M_K_MA(15)
  U2D1 DV49 DDR3_MA<15> SKX_EXT_B_BGA1-IC,TBD   I172 @BASEBOARD_FAB2_LIB.BASEBOARD_FAB2(SCH_1):PAGE60
  J1B1   86 A15_CAS_N SCONN288_H44441004_PIP-SCONN,HA   I111 @BASEBOARD_FAB2_LIB.BASEBOARD_FAB2(SCH_1):PAGE83
  J9M1   86 A15_CAS_N SCONN288_H44441003_PIP-SCONN,HA    I14 @BASEBOARD_FAB2_LIB.BASEBOARD_FAB2(SCH_1):PAGE84

M_K_MA<16> @BASEBOARD_FAB2_LIB.BASEBOARD_FAB2(SCH_1):M_K_MA(16)
  U2D1 EA52 DDR3_MA<16> SKX_EXT_B_BGA1-IC,TBD   I172 @BASEBOARD_FAB2_LIB.BASEBOARD_FAB2(SCH_1):PAGE60
  J1B1   82 A16_RAS_N SCONN288_H44441004_PIP-SCONN,HA   I111 @BASEBOARD_FAB2_LIB.BASEBOARD_FAB2(SCH_1):PAGE83
  J9M1   82 A16_RAS_N SCONN288_H44441003_PIP-SCONN,HA    I14 @BASEBOARD_FAB2_LIB.BASEBOARD_FAB2(SCH_1):PAGE84

M_K_MA<17> @BASEBOARD_FAB2_LIB.BASEBOARD_FAB2(SCH_1):M_K_MA(17)
  U2D1 EA46 DDR3_MA<17> SKX_EXT_B_BGA1-IC,TBD   I172 @BASEBOARD_FAB2_LIB.BASEBOARD_FAB2(SCH_1):PAGE60
  J1B1  234    A17 SCONN288_H44441004_PIP-SCONN,HA   I111 @BASEBOARD_FAB2_LIB.BASEBOARD_FAB2(SCH_1):PAGE83
  J9M1  234    A17 SCONN288_H44441003_PIP-SCONN,HA    I14 @BASEBOARD_FAB2_LIB.BASEBOARD_FAB2(SCH_1):PAGE84

M_K_MA<1> @BASEBOARD_FAB2_LIB.BASEBOARD_FAB2(SCH_1):M_K_MA(1)
  U2D1 ED57 DDR3_MA<1> SKX_EXT_B_BGA1-IC,TBD   I172 @BASEBOARD_FAB2_LIB.BASEBOARD_FAB2(SCH_1):PAGE60
  J1B1   72     A1 SCONN288_H44441004_PIP-SCONN,HA   I111 @BASEBOARD_FAB2_LIB.BASEBOARD_FAB2(SCH_1):PAGE83
  J9M1   72     A1 SCONN288_H44441003_PIP-SCONN,HA    I14 @BASEBOARD_FAB2_LIB.BASEBOARD_FAB2(SCH_1):PAGE84

M_K_MA<2> @BASEBOARD_FAB2_LIB.BASEBOARD_FAB2(SCH_1):M_K_MA(2)
  U2D1 EE58 DDR3_MA<2> SKX_EXT_B_BGA1-IC,TBD   I172 @BASEBOARD_FAB2_LIB.BASEBOARD_FAB2(SCH_1):PAGE60
  J1B1  216     A2 SCONN288_H44441004_PIP-SCONN,HA   I111 @BASEBOARD_FAB2_LIB.BASEBOARD_FAB2(SCH_1):PAGE83
  J9M1  216     A2 SCONN288_H44441003_PIP-SCONN,HA    I14 @BASEBOARD_FAB2_LIB.BASEBOARD_FAB2(SCH_1):PAGE84

M_K_MA<3> @BASEBOARD_FAB2_LIB.BASEBOARD_FAB2(SCH_1):M_K_MA(3)
  U2D1 EB57 DDR3_MA<3> SKX_EXT_B_BGA1-IC,TBD   I172 @BASEBOARD_FAB2_LIB.BASEBOARD_FAB2(SCH_1):PAGE60
  J1B1   71     A3 SCONN288_H44441004_PIP-SCONN,HA   I111 @BASEBOARD_FAB2_LIB.BASEBOARD_FAB2(SCH_1):PAGE83
  J9M1   71     A3 SCONN288_H44441003_PIP-SCONN,HA    I14 @BASEBOARD_FAB2_LIB.BASEBOARD_FAB2(SCH_1):PAGE84

M_K_MA<4> @BASEBOARD_FAB2_LIB.BASEBOARD_FAB2(SCH_1):M_K_MA(4)
  U2D1 ED59 DDR3_MA<4> SKX_EXT_B_BGA1-IC,TBD   I172 @BASEBOARD_FAB2_LIB.BASEBOARD_FAB2(SCH_1):PAGE60
  J1B1  214     A4 SCONN288_H44441004_PIP-SCONN,HA   I111 @BASEBOARD_FAB2_LIB.BASEBOARD_FAB2(SCH_1):PAGE83
  J9M1  214     A4 SCONN288_H44441003_PIP-SCONN,HA    I14 @BASEBOARD_FAB2_LIB.BASEBOARD_FAB2(SCH_1):PAGE84

M_K_MA<5> @BASEBOARD_FAB2_LIB.BASEBOARD_FAB2(SCH_1):M_K_MA(5)
  U2D1 EA58 DDR3_MA<5> SKX_EXT_B_BGA1-IC,TBD   I172 @BASEBOARD_FAB2_LIB.BASEBOARD_FAB2(SCH_1):PAGE60
  J1B1  213     A5 SCONN288_H44441004_PIP-SCONN,HA   I111 @BASEBOARD_FAB2_LIB.BASEBOARD_FAB2(SCH_1):PAGE83
  J9M1  213     A5 SCONN288_H44441003_PIP-SCONN,HA    I14 @BASEBOARD_FAB2_LIB.BASEBOARD_FAB2(SCH_1):PAGE84

M_K_MA<6> @BASEBOARD_FAB2_LIB.BASEBOARD_FAB2(SCH_1):M_K_MA(6)
  U2D1 EE60 DDR3_MA<6> SKX_EXT_B_BGA1-IC,TBD   I172 @BASEBOARD_FAB2_LIB.BASEBOARD_FAB2(SCH_1):PAGE60
  J1B1   69     A6 SCONN288_H44441004_PIP-SCONN,HA   I111 @BASEBOARD_FAB2_LIB.BASEBOARD_FAB2(SCH_1):PAGE83
  J9M1   69     A6 SCONN288_H44441003_PIP-SCONN,HA    I14 @BASEBOARD_FAB2_LIB.BASEBOARD_FAB2(SCH_1):PAGE84

M_K_MA<7> @BASEBOARD_FAB2_LIB.BASEBOARD_FAB2(SCH_1):M_K_MA(7)
  U2D1 EA60 DDR3_MA<7> SKX_EXT_B_BGA1-IC,TBD   I172 @BASEBOARD_FAB2_LIB.BASEBOARD_FAB2(SCH_1):PAGE60
  J1B1  211     A7 SCONN288_H44441004_PIP-SCONN,HA   I111 @BASEBOARD_FAB2_LIB.BASEBOARD_FAB2(SCH_1):PAGE83
  J9M1  211     A7 SCONN288_H44441003_PIP-SCONN,HA    I14 @BASEBOARD_FAB2_LIB.BASEBOARD_FAB2(SCH_1):PAGE84

M_K_MA<8> @BASEBOARD_FAB2_LIB.BASEBOARD_FAB2(SCH_1):M_K_MA(8)
  U2D1 EB59 DDR3_MA<8> SKX_EXT_B_BGA1-IC,TBD   I172 @BASEBOARD_FAB2_LIB.BASEBOARD_FAB2(SCH_1):PAGE60
  J1B1   68     A8 SCONN288_H44441004_PIP-SCONN,HA   I111 @BASEBOARD_FAB2_LIB.BASEBOARD_FAB2(SCH_1):PAGE83
  J9M1   68     A8 SCONN288_H44441003_PIP-SCONN,HA    I14 @BASEBOARD_FAB2_LIB.BASEBOARD_FAB2(SCH_1):PAGE84

M_K_MA<9> @BASEBOARD_FAB2_LIB.BASEBOARD_FAB2(SCH_1):M_K_MA(9)
  U2D1 EF61 DDR3_MA<9> SKX_EXT_B_BGA1-IC,TBD   I172 @BASEBOARD_FAB2_LIB.BASEBOARD_FAB2(SCH_1):PAGE60
  J1B1   66     A9 SCONN288_H44441004_PIP-SCONN,HA   I111 @BASEBOARD_FAB2_LIB.BASEBOARD_FAB2(SCH_1):PAGE83
  J9M1   66     A9 SCONN288_H44441003_PIP-SCONN,HA    I14 @BASEBOARD_FAB2_LIB.BASEBOARD_FAB2(SCH_1):PAGE84

M_K_ODT<0> @BASEBOARD_FAB2_LIB.BASEBOARD_FAB2(SCH_1):M_K_ODT(0)
  U2D1 EE50 DDR3_ODT<0> SKX_EXT_B_BGA1-IC,TBD   I172 @BASEBOARD_FAB2_LIB.BASEBOARD_FAB2(SCH_1):PAGE60
  J1B1   87 ODT<0> SCONN288_H44441004_PIP-SCONN,HA   I111 @BASEBOARD_FAB2_LIB.BASEBOARD_FAB2(SCH_1):PAGE83

M_K_ODT<1> @BASEBOARD_FAB2_LIB.BASEBOARD_FAB2(SCH_1):M_K_ODT(1)
  U2D1 EE48 DDR3_ODT<1> SKX_EXT_B_BGA1-IC,TBD   I172 @BASEBOARD_FAB2_LIB.BASEBOARD_FAB2(SCH_1):PAGE60
  J1B1   91 ODT<1> SCONN288_H44441004_PIP-SCONN,HA   I111 @BASEBOARD_FAB2_LIB.BASEBOARD_FAB2(SCH_1):PAGE83

M_K_ODT<2> @BASEBOARD_FAB2_LIB.BASEBOARD_FAB2(SCH_1):M_K_ODT(2)
  U2D1 EA50 DDR3_ODT<2> SKX_EXT_B_BGA1-IC,TBD   I172 @BASEBOARD_FAB2_LIB.BASEBOARD_FAB2(SCH_1):PAGE60
  J9M1   87 ODT<0> SCONN288_H44441003_PIP-SCONN,HA    I14 @BASEBOARD_FAB2_LIB.BASEBOARD_FAB2(SCH_1):PAGE84

M_K_ODT<3> @BASEBOARD_FAB2_LIB.BASEBOARD_FAB2(SCH_1):M_K_ODT(3)
  U2D1 EA48 DDR3_ODT<3> SKX_EXT_B_BGA1-IC,TBD   I172 @BASEBOARD_FAB2_LIB.BASEBOARD_FAB2(SCH_1):PAGE60
  J9M1   91 ODT<1> SCONN288_H44441003_PIP-SCONN,HA    I14 @BASEBOARD_FAB2_LIB.BASEBOARD_FAB2(SCH_1):PAGE84

M_K_PAR @BASEBOARD_FAB2_LIB.BASEBOARD_FAB2(SCH_1):M_K_PAR
  U2D1 ED53 DDR3_PAR SKX_EXT_B_BGA1-IC,TBD   I172 @BASEBOARD_FAB2_LIB.BASEBOARD_FAB2(SCH_1):PAGE60
  J1B1  222    PAR SCONN288_H44441004_PIP-SCONN,HA   I111 @BASEBOARD_FAB2_LIB.BASEBOARD_FAB2(SCH_1):PAGE83
  J9M1  222    PAR SCONN288_H44441003_PIP-SCONN,HA    I14 @BASEBOARD_FAB2_LIB.BASEBOARD_FAB2(SCH_1):PAGE84

M_K_VREF @BASEBOARD_FAB2_LIB.BASEBOARD_FAB2(SCH_1):M_K_VREF
  J1B1  146 VREFCA SCONN288_H44441004_PIP-SCONN,HA   I111 @BASEBOARD_FAB2_LIB.BASEBOARD_FAB2(SCH_1):PAGE83
  C1B9    1      A CAP_A_0402V-0.01UF,25V,10%,X7RA   I176 @BASEBOARD_FAB2_LIB.BASEBOARD_FAB2(SCH_1):PAGE83
  C9M1    1      A CAP_A_0402V-0.01UF,25V,10%,X7RA     I4 @BASEBOARD_FAB2_LIB.BASEBOARD_FAB2(SCH_1):PAGE84
  J9M1  146 VREFCA SCONN288_H44441003_PIP-SCONN,HA    I14 @BASEBOARD_FAB2_LIB.BASEBOARD_FAB2(SCH_1):PAGE84
 R9L11    1      A RES_0402-1.00K,1%,1/16W,CHIP,GA     I4 @BASEBOARD_FAB2_LIB.BASEBOARD_FAB2(SCH_1):PAGE100
  R9M1    2      B RES_0402-1.00K,1%,1/16W,CHIP,GA    I11 @BASEBOARD_FAB2_LIB.BASEBOARD_FAB2(SCH_1):PAGE100
  R9M2    2      B RES_0402-2,1.0%,1/16W,CHIP,G21A    I13 @BASEBOARD_FAB2_LIB.BASEBOARD_FAB2(SCH_1):PAGE100

M_L_ACT_N @BASEBOARD_FAB2_LIB.BASEBOARD_FAB2(SCH_1):M_L_ACT_N
  U2D1 DR62 DDR4_ACT_N SKX_EXT_B_BGA1-IC,TBD   I172 @BASEBOARD_FAB2_LIB.BASEBOARD_FAB2(SCH_1):PAGE61
  J1A2   62  ACT_N SCONN288_H44441004_PIP-SCONN,HA   I111 @BASEBOARD_FAB2_LIB.BASEBOARD_FAB2(SCH_1):PAGE85
  J9L2   62  ACT_N SCONN288_H44441003_PIP-SCONN,HA    I12 @BASEBOARD_FAB2_LIB.BASEBOARD_FAB2(SCH_1):PAGE86

M_L_ALERT_N @BASEBOARD_FAB2_LIB.BASEBOARD_FAB2(SCH_1):M_L_ALERT_N
  U2D1 DT61 DDR4_ALERT_N SKX_EXT_B_BGA1-IC,TBD   I172 @BASEBOARD_FAB2_LIB.BASEBOARD_FAB2(SCH_1):PAGE61
  J1A2  208 ALERT_N SCONN288_H44441004_PIP-SCONN,HA   I111 @BASEBOARD_FAB2_LIB.BASEBOARD_FAB2(SCH_1):PAGE85
  J9L2  208 ALERT_N SCONN288_H44441003_PIP-SCONN,HA    I12 @BASEBOARD_FAB2_LIB.BASEBOARD_FAB2(SCH_1):PAGE86

M_L_BA<0> @BASEBOARD_FAB2_LIB.BASEBOARD_FAB2(SCH_1):M_L_BA(0)
  U2D1 DM53 DDR4_BA<0> SKX_EXT_B_BGA1-IC,TBD   I172 @BASEBOARD_FAB2_LIB.BASEBOARD_FAB2(SCH_1):PAGE61
  J1A2   81  BA<0> SCONN288_H44441004_PIP-SCONN,HA   I111 @BASEBOARD_FAB2_LIB.BASEBOARD_FAB2(SCH_1):PAGE85
  J9L2   81  BA<0> SCONN288_H44441003_PIP-SCONN,HA    I12 @BASEBOARD_FAB2_LIB.BASEBOARD_FAB2(SCH_1):PAGE86

M_L_BA<1> @BASEBOARD_FAB2_LIB.BASEBOARD_FAB2(SCH_1):M_L_BA(1)
  U2D1 DV55 DDR4_BA<1> SKX_EXT_B_BGA1-IC,TBD   I172 @BASEBOARD_FAB2_LIB.BASEBOARD_FAB2(SCH_1):PAGE61
  J1A2  224  BA<1> SCONN288_H44441004_PIP-SCONN,HA   I111 @BASEBOARD_FAB2_LIB.BASEBOARD_FAB2(SCH_1):PAGE85
  J9L2  224  BA<1> SCONN288_H44441003_PIP-SCONN,HA    I12 @BASEBOARD_FAB2_LIB.BASEBOARD_FAB2(SCH_1):PAGE86

M_L_BG<0> @BASEBOARD_FAB2_LIB.BASEBOARD_FAB2(SCH_1):M_L_BG(0)
  U2D1 DJ62 DDR4_BG<0> SKX_EXT_B_BGA1-IC,TBD   I172 @BASEBOARD_FAB2_LIB.BASEBOARD_FAB2(SCH_1):PAGE61
  J1A2   63  BG<0> SCONN288_H44441004_PIP-SCONN,HA   I111 @BASEBOARD_FAB2_LIB.BASEBOARD_FAB2(SCH_1):PAGE85
  J9L2   63  BG<0> SCONN288_H44441003_PIP-SCONN,HA    I12 @BASEBOARD_FAB2_LIB.BASEBOARD_FAB2(SCH_1):PAGE86

M_L_BG<1> @BASEBOARD_FAB2_LIB.BASEBOARD_FAB2(SCH_1):M_L_BG(1)
  U2D1 DM61 DDR4_BG<1> SKX_EXT_B_BGA1-IC,TBD   I172 @BASEBOARD_FAB2_LIB.BASEBOARD_FAB2(SCH_1):PAGE61
  J1A2  207  BG<1> SCONN288_H44441004_PIP-SCONN,HA   I111 @BASEBOARD_FAB2_LIB.BASEBOARD_FAB2(SCH_1):PAGE85
  J9L2  207  BG<1> SCONN288_H44441003_PIP-SCONN,HA    I12 @BASEBOARD_FAB2_LIB.BASEBOARD_FAB2(SCH_1):PAGE86

M_L_C<2> @BASEBOARD_FAB2_LIB.BASEBOARD_FAB2(SCH_1):M_L_C(2)
  U2D1 DT47 DDR4_CID<2> SKX_EXT_B_BGA1-IC,TBD   I172 @BASEBOARD_FAB2_LIB.BASEBOARD_FAB2(SCH_1):PAGE61
  J1A2  235   C<2> SCONN288_H44441004_PIP-SCONN,HA   I111 @BASEBOARD_FAB2_LIB.BASEBOARD_FAB2(SCH_1):PAGE85
  J9L2  235   C<2> SCONN288_H44441003_PIP-SCONN,HA    I12 @BASEBOARD_FAB2_LIB.BASEBOARD_FAB2(SCH_1):PAGE86

M_L_CKE<0> @BASEBOARD_FAB2_LIB.BASEBOARD_FAB2(SCH_1):M_L_CKE(0)
  U2D1 DM63 DDR4_CKE<0> SKX_EXT_B_BGA1-IC,TBD   I172 @BASEBOARD_FAB2_LIB.BASEBOARD_FAB2(SCH_1):PAGE61
  J1A2   60 CKE<0> SCONN288_H44441004_PIP-SCONN,HA   I111 @BASEBOARD_FAB2_LIB.BASEBOARD_FAB2(SCH_1):PAGE85

M_L_CKE<1> @BASEBOARD_FAB2_LIB.BASEBOARD_FAB2(SCH_1):M_L_CKE(1)
  U2D1 DN64 DDR4_CKE<1> SKX_EXT_B_BGA1-IC,TBD   I172 @BASEBOARD_FAB2_LIB.BASEBOARD_FAB2(SCH_1):PAGE61
  J1A2  203 CKE<1> SCONN288_H44441004_PIP-SCONN,HA   I111 @BASEBOARD_FAB2_LIB.BASEBOARD_FAB2(SCH_1):PAGE85

M_L_CKE<2> @BASEBOARD_FAB2_LIB.BASEBOARD_FAB2(SCH_1):M_L_CKE(2)
  U2D1 DL64 DDR4_CKE<2> SKX_EXT_B_BGA1-IC,TBD   I172 @BASEBOARD_FAB2_LIB.BASEBOARD_FAB2(SCH_1):PAGE61
  J9L2   60 CKE<0> SCONN288_H44441003_PIP-SCONN,HA    I12 @BASEBOARD_FAB2_LIB.BASEBOARD_FAB2(SCH_1):PAGE86

M_L_CKE<3> @BASEBOARD_FAB2_LIB.BASEBOARD_FAB2(SCH_1):M_L_CKE(3)
  U2D1 DR64 DDR4_CKE<3> SKX_EXT_B_BGA1-IC,TBD   I172 @BASEBOARD_FAB2_LIB.BASEBOARD_FAB2(SCH_1):PAGE61
  J9L2  203 CKE<1> SCONN288_H44441003_PIP-SCONN,HA    I12 @BASEBOARD_FAB2_LIB.BASEBOARD_FAB2(SCH_1):PAGE86

M_L_CLK_DN<0> @BASEBOARD_FAB2_LIB.BASEBOARD_FAB2(SCH_1):M_L_CLK_DN(0)
  U2D1 DM55 DDR4_CLK_DN<0> SKX_EXT_B_BGA1-IC,TBD   I172 @BASEBOARD_FAB2_LIB.BASEBOARD_FAB2(SCH_1):PAGE61
  J1A2   75   CK0N SCONN288_H44441004_PIP-SCONN,HA   I111 @BASEBOARD_FAB2_LIB.BASEBOARD_FAB2(SCH_1):PAGE85

M_L_CLK_DN<1> @BASEBOARD_FAB2_LIB.BASEBOARD_FAB2(SCH_1):M_L_CLK_DN(1)
  U2D1 DR54 DDR4_CLK_DN<1> SKX_EXT_B_BGA1-IC,TBD   I172 @BASEBOARD_FAB2_LIB.BASEBOARD_FAB2(SCH_1):PAGE61
  J1A2  219   CK1N SCONN288_H44441004_PIP-SCONN,HA   I111 @BASEBOARD_FAB2_LIB.BASEBOARD_FAB2(SCH_1):PAGE85

M_L_CLK_DN<2> @BASEBOARD_FAB2_LIB.BASEBOARD_FAB2(SCH_1):M_L_CLK_DN(2)
  U2D1 DM57 DDR4_CLK_DN<2> SKX_EXT_B_BGA1-IC,TBD   I172 @BASEBOARD_FAB2_LIB.BASEBOARD_FAB2(SCH_1):PAGE61
  J9L2   75   CK0N SCONN288_H44441003_PIP-SCONN,HA    I12 @BASEBOARD_FAB2_LIB.BASEBOARD_FAB2(SCH_1):PAGE86

M_L_CLK_DN<3> @BASEBOARD_FAB2_LIB.BASEBOARD_FAB2(SCH_1):M_L_CLK_DN(3)
  U2D1 DT57 DDR4_CLK_DN<3> SKX_EXT_B_BGA1-IC,TBD   I172 @BASEBOARD_FAB2_LIB.BASEBOARD_FAB2(SCH_1):PAGE61
  J9L2  219   CK1N SCONN288_H44441003_PIP-SCONN,HA    I12 @BASEBOARD_FAB2_LIB.BASEBOARD_FAB2(SCH_1):PAGE86

M_L_CLK_DP<0> @BASEBOARD_FAB2_LIB.BASEBOARD_FAB2(SCH_1):M_L_CLK_DP(0)
  U2D1 DN54 DDR4_CLK_DP<0> SKX_EXT_B_BGA1-IC,TBD   I172 @BASEBOARD_FAB2_LIB.BASEBOARD_FAB2(SCH_1):PAGE61
  J1A2   74   CK0P SCONN288_H44441004_PIP-SCONN,HA   I111 @BASEBOARD_FAB2_LIB.BASEBOARD_FAB2(SCH_1):PAGE85

M_L_CLK_DP<1> @BASEBOARD_FAB2_LIB.BASEBOARD_FAB2(SCH_1):M_L_CLK_DP(1)
  U2D1 DT53 DDR4_CLK_DP<1> SKX_EXT_B_BGA1-IC,TBD   I172 @BASEBOARD_FAB2_LIB.BASEBOARD_FAB2(SCH_1):PAGE61
  J1A2  218   CK1P SCONN288_H44441004_PIP-SCONN,HA   I111 @BASEBOARD_FAB2_LIB.BASEBOARD_FAB2(SCH_1):PAGE85

M_L_CLK_DP<2> @BASEBOARD_FAB2_LIB.BASEBOARD_FAB2(SCH_1):M_L_CLK_DP(2)
  U2D1 DN56 DDR4_CLK_DP<2> SKX_EXT_B_BGA1-IC,TBD   I172 @BASEBOARD_FAB2_LIB.BASEBOARD_FAB2(SCH_1):PAGE61
  J9L2   74   CK0P SCONN288_H44441003_PIP-SCONN,HA    I12 @BASEBOARD_FAB2_LIB.BASEBOARD_FAB2(SCH_1):PAGE86

M_L_CLK_DP<3> @BASEBOARD_FAB2_LIB.BASEBOARD_FAB2(SCH_1):M_L_CLK_DP(3)
  U2D1 DR56 DDR4_CLK_DP<3> SKX_EXT_B_BGA1-IC,TBD   I172 @BASEBOARD_FAB2_LIB.BASEBOARD_FAB2(SCH_1):PAGE61
  J9L2  218   CK1P SCONN288_H44441003_PIP-SCONN,HA    I12 @BASEBOARD_FAB2_LIB.BASEBOARD_FAB2(SCH_1):PAGE86

M_L_CPU_VREF @BASEBOARD_FAB2_LIB.BASEBOARD_FAB2(SCH_1):M_L_CPU_VREF
  U2D1 CT61 DDR4_CAVREF SKX_EXT_B_BGA1-IC,TBD   I172 @BASEBOARD_FAB2_LIB.BASEBOARD_FAB2(SCH_1):PAGE55
  R9L8    1      A RES_0402-2,1.0%,1/16W,CHIP,G21A    I29 @BASEBOARD_FAB2_LIB.BASEBOARD_FAB2(SCH_1):PAGE100
  C9L8    1      A CAP_A_0402V-0.01UF,25V,10%,X7RA    I30 @BASEBOARD_FAB2_LIB.BASEBOARD_FAB2(SCH_1):PAGE100

M_L_CS_N<0> @BASEBOARD_FAB2_LIB.BASEBOARD_FAB2(SCH_1):M_L_CS_N(0)
  U2D1 DV51 DDR4_CS_N<0> SKX_EXT_B_BGA1-IC,TBD   I172 @BASEBOARD_FAB2_LIB.BASEBOARD_FAB2(SCH_1):PAGE61
  J1A2   84   S0_N SCONN288_H44441004_PIP-SCONN,HA   I111 @BASEBOARD_FAB2_LIB.BASEBOARD_FAB2(SCH_1):PAGE85

M_L_CS_N<1> @BASEBOARD_FAB2_LIB.BASEBOARD_FAB2(SCH_1):M_L_CS_N(1)
  U2D1 DN50 DDR4_CS_N<1> SKX_EXT_B_BGA1-IC,TBD   I172 @BASEBOARD_FAB2_LIB.BASEBOARD_FAB2(SCH_1):PAGE61
  J1A2   89   S1_N SCONN288_H44441004_PIP-SCONN,HA   I111 @BASEBOARD_FAB2_LIB.BASEBOARD_FAB2(SCH_1):PAGE85

M_L_CS_N<2> @BASEBOARD_FAB2_LIB.BASEBOARD_FAB2(SCH_1):M_L_CS_N(2)
  U2D1 DR46 DDR4_CS_N<2> SKX_EXT_B_BGA1-IC,TBD   I172 @BASEBOARD_FAB2_LIB.BASEBOARD_FAB2(SCH_1):PAGE61
  J1A2   93 S2_N_C<0> SCONN288_H44441004_PIP-SCONN,HA   I111 @BASEBOARD_FAB2_LIB.BASEBOARD_FAB2(SCH_1):PAGE85

M_L_CS_N<3> @BASEBOARD_FAB2_LIB.BASEBOARD_FAB2(SCH_1):M_L_CS_N(3)
  U2D1 DK47 DDR4_CS_N<3> SKX_EXT_B_BGA1-IC,TBD   I172 @BASEBOARD_FAB2_LIB.BASEBOARD_FAB2(SCH_1):PAGE61
  J1A2  237 S3_N_C<1> SCONN288_H44441004_PIP-SCONN,HA   I111 @BASEBOARD_FAB2_LIB.BASEBOARD_FAB2(SCH_1):PAGE85

M_L_CS_N<4> @BASEBOARD_FAB2_LIB.BASEBOARD_FAB2(SCH_1):M_L_CS_N(4)
  U2D1 DW50 DDR4_CS_N<4> SKX_EXT_B_BGA1-IC,TBD   I172 @BASEBOARD_FAB2_LIB.BASEBOARD_FAB2(SCH_1):PAGE61
  J9L2   84   S0_N SCONN288_H44441003_PIP-SCONN,HA    I12 @BASEBOARD_FAB2_LIB.BASEBOARD_FAB2(SCH_1):PAGE86

M_L_CS_N<5> @BASEBOARD_FAB2_LIB.BASEBOARD_FAB2(SCH_1):M_L_CS_N(5)
  U2D1 DM49 DDR4_CS_N<5> SKX_EXT_B_BGA1-IC,TBD   I172 @BASEBOARD_FAB2_LIB.BASEBOARD_FAB2(SCH_1):PAGE61
  J9L2   89   S1_N SCONN288_H44441003_PIP-SCONN,HA    I12 @BASEBOARD_FAB2_LIB.BASEBOARD_FAB2(SCH_1):PAGE86

M_L_CS_N<6> @BASEBOARD_FAB2_LIB.BASEBOARD_FAB2(SCH_1):M_L_CS_N(6)
  U2D1 DT45 DDR4_CS_N<6> SKX_EXT_B_BGA1-IC,TBD   I172 @BASEBOARD_FAB2_LIB.BASEBOARD_FAB2(SCH_1):PAGE61
  J9L2   93 S2_N_C<0> SCONN288_H44441003_PIP-SCONN,HA    I12 @BASEBOARD_FAB2_LIB.BASEBOARD_FAB2(SCH_1):PAGE86

M_L_CS_N<7> @BASEBOARD_FAB2_LIB.BASEBOARD_FAB2(SCH_1):M_L_CS_N(7)
  U2D1 DN46 DDR4_CS_N<7> SKX_EXT_B_BGA1-IC,TBD   I172 @BASEBOARD_FAB2_LIB.BASEBOARD_FAB2(SCH_1):PAGE61
  J9L2  237 S3_N_C<1> SCONN288_H44441003_PIP-SCONN,HA    I12 @BASEBOARD_FAB2_LIB.BASEBOARD_FAB2(SCH_1):PAGE86

M_L_DQ<0> @BASEBOARD_FAB2_LIB.BASEBOARD_FAB2(SCH_1):M_L_DQ(0)
  U2D1 CM79 DDR4_DQ<0> SKX_EXT_B_BGA1-IC,TBD   I172 @BASEBOARD_FAB2_LIB.BASEBOARD_FAB2(SCH_1):PAGE61
  J1A2  150  DQ<1> SCONN288_H44441004_PIP-SCONN,HA   I111 @BASEBOARD_FAB2_LIB.BASEBOARD_FAB2(SCH_1):PAGE85
  J9L2    5  DQ<0> SCONN288_H44441003_PIP-SCONN,HA    I12 @BASEBOARD_FAB2_LIB.BASEBOARD_FAB2(SCH_1):PAGE86

M_L_DQ<10> @BASEBOARD_FAB2_LIB.BASEBOARD_FAB2(SCH_1):M_L_DQ(10)
  U2D1 DE80 DDR4_DQ<10> SKX_EXT_B_BGA1-IC,TBD   I172 @BASEBOARD_FAB2_LIB.BASEBOARD_FAB2(SCH_1):PAGE61
  J1A2  168 DQ<11> SCONN288_H44441004_PIP-SCONN,HA   I111 @BASEBOARD_FAB2_LIB.BASEBOARD_FAB2(SCH_1):PAGE85
  J9L2   23 DQ<10> SCONN288_H44441003_PIP-SCONN,HA    I12 @BASEBOARD_FAB2_LIB.BASEBOARD_FAB2(SCH_1):PAGE86

M_L_DQ<11> @BASEBOARD_FAB2_LIB.BASEBOARD_FAB2(SCH_1):M_L_DQ(11)
  U2D1 DF81 DDR4_DQ<11> SKX_EXT_B_BGA1-IC,TBD   I172 @BASEBOARD_FAB2_LIB.BASEBOARD_FAB2(SCH_1):PAGE61
  J1A2   23 DQ<10> SCONN288_H44441004_PIP-SCONN,HA   I111 @BASEBOARD_FAB2_LIB.BASEBOARD_FAB2(SCH_1):PAGE85
  J9L2  168 DQ<11> SCONN288_H44441003_PIP-SCONN,HA    I12 @BASEBOARD_FAB2_LIB.BASEBOARD_FAB2(SCH_1):PAGE86

M_L_DQ<12> @BASEBOARD_FAB2_LIB.BASEBOARD_FAB2(SCH_1):M_L_DQ(12)
  U2D1 CY79 DDR4_DQ<12> SKX_EXT_B_BGA1-IC,TBD   I172 @BASEBOARD_FAB2_LIB.BASEBOARD_FAB2(SCH_1):PAGE61
  J1A2  159 DQ<13> SCONN288_H44441004_PIP-SCONN,HA   I111 @BASEBOARD_FAB2_LIB.BASEBOARD_FAB2(SCH_1):PAGE85
  J9L2   14 DQ<12> SCONN288_H44441003_PIP-SCONN,HA    I12 @BASEBOARD_FAB2_LIB.BASEBOARD_FAB2(SCH_1):PAGE86

M_L_DQ<13> @BASEBOARD_FAB2_LIB.BASEBOARD_FAB2(SCH_1):M_L_DQ(13)
  U2D1 CW80 DDR4_DQ<13> SKX_EXT_B_BGA1-IC,TBD   I172 @BASEBOARD_FAB2_LIB.BASEBOARD_FAB2(SCH_1):PAGE61
  J1A2   14 DQ<12> SCONN288_H44441004_PIP-SCONN,HA   I111 @BASEBOARD_FAB2_LIB.BASEBOARD_FAB2(SCH_1):PAGE85
  J9L2  159 DQ<13> SCONN288_H44441003_PIP-SCONN,HA    I12 @BASEBOARD_FAB2_LIB.BASEBOARD_FAB2(SCH_1):PAGE86

M_L_DQ<14> @BASEBOARD_FAB2_LIB.BASEBOARD_FAB2(SCH_1):M_L_DQ(14)
  U2D1 DC82 DDR4_DQ<14> SKX_EXT_B_BGA1-IC,TBD   I172 @BASEBOARD_FAB2_LIB.BASEBOARD_FAB2(SCH_1):PAGE61
  J1A2  166 DQ<15> SCONN288_H44441004_PIP-SCONN,HA   I111 @BASEBOARD_FAB2_LIB.BASEBOARD_FAB2(SCH_1):PAGE85
  J9L2   21 DQ<14> SCONN288_H44441003_PIP-SCONN,HA    I12 @BASEBOARD_FAB2_LIB.BASEBOARD_FAB2(SCH_1):PAGE86

M_L_DQ<15> @BASEBOARD_FAB2_LIB.BASEBOARD_FAB2(SCH_1):M_L_DQ(15)
  U2D1 DE82 DDR4_DQ<15> SKX_EXT_B_BGA1-IC,TBD   I172 @BASEBOARD_FAB2_LIB.BASEBOARD_FAB2(SCH_1):PAGE61
  J1A2   21 DQ<14> SCONN288_H44441004_PIP-SCONN,HA   I111 @BASEBOARD_FAB2_LIB.BASEBOARD_FAB2(SCH_1):PAGE85
  J9L2  166 DQ<15> SCONN288_H44441003_PIP-SCONN,HA    I12 @BASEBOARD_FAB2_LIB.BASEBOARD_FAB2(SCH_1):PAGE86

M_L_DQ<16> @BASEBOARD_FAB2_LIB.BASEBOARD_FAB2(SCH_1):M_L_DQ(16)
  U2D1 DW80 DDR4_DQ<16> SKX_EXT_B_BGA1-IC,TBD   I172 @BASEBOARD_FAB2_LIB.BASEBOARD_FAB2(SCH_1):PAGE61
  J1A2  172 DQ<17> SCONN288_H44441004_PIP-SCONN,HA   I111 @BASEBOARD_FAB2_LIB.BASEBOARD_FAB2(SCH_1):PAGE85
  J9L2   27 DQ<16> SCONN288_H44441003_PIP-SCONN,HA    I12 @BASEBOARD_FAB2_LIB.BASEBOARD_FAB2(SCH_1):PAGE86

M_L_DQ<17> @BASEBOARD_FAB2_LIB.BASEBOARD_FAB2(SCH_1):M_L_DQ(17)
  U2D1 EC80 DDR4_DQ<17> SKX_EXT_B_BGA1-IC,TBD   I172 @BASEBOARD_FAB2_LIB.BASEBOARD_FAB2(SCH_1):PAGE61
  J1A2   27 DQ<16> SCONN288_H44441004_PIP-SCONN,HA   I111 @BASEBOARD_FAB2_LIB.BASEBOARD_FAB2(SCH_1):PAGE85
  J9L2  172 DQ<17> SCONN288_H44441003_PIP-SCONN,HA    I12 @BASEBOARD_FAB2_LIB.BASEBOARD_FAB2(SCH_1):PAGE86

M_L_DQ<18> @BASEBOARD_FAB2_LIB.BASEBOARD_FAB2(SCH_1):M_L_DQ(18)
  U2D1 DY77 DDR4_DQ<18> SKX_EXT_B_BGA1-IC,TBD   I172 @BASEBOARD_FAB2_LIB.BASEBOARD_FAB2(SCH_1):PAGE61
  J1A2  179 DQ<19> SCONN288_H44441004_PIP-SCONN,HA   I111 @BASEBOARD_FAB2_LIB.BASEBOARD_FAB2(SCH_1):PAGE85
  J9L2   34 DQ<18> SCONN288_H44441003_PIP-SCONN,HA    I12 @BASEBOARD_FAB2_LIB.BASEBOARD_FAB2(SCH_1):PAGE86

M_L_DQ<19> @BASEBOARD_FAB2_LIB.BASEBOARD_FAB2(SCH_1):M_L_DQ(19)
  U2D1 EB77 DDR4_DQ<19> SKX_EXT_B_BGA1-IC,TBD   I172 @BASEBOARD_FAB2_LIB.BASEBOARD_FAB2(SCH_1):PAGE61
  J1A2   34 DQ<18> SCONN288_H44441004_PIP-SCONN,HA   I111 @BASEBOARD_FAB2_LIB.BASEBOARD_FAB2(SCH_1):PAGE85
  J9L2  179 DQ<19> SCONN288_H44441003_PIP-SCONN,HA    I12 @BASEBOARD_FAB2_LIB.BASEBOARD_FAB2(SCH_1):PAGE86

M_L_DQ<1> @BASEBOARD_FAB2_LIB.BASEBOARD_FAB2(SCH_1):M_L_DQ(1)
  U2D1 CK81 DDR4_DQ<1> SKX_EXT_B_BGA1-IC,TBD   I172 @BASEBOARD_FAB2_LIB.BASEBOARD_FAB2(SCH_1):PAGE61
  J1A2    5  DQ<0> SCONN288_H44441004_PIP-SCONN,HA   I111 @BASEBOARD_FAB2_LIB.BASEBOARD_FAB2(SCH_1):PAGE85
  J9L2  150  DQ<1> SCONN288_H44441003_PIP-SCONN,HA    I12 @BASEBOARD_FAB2_LIB.BASEBOARD_FAB2(SCH_1):PAGE86

M_L_DQ<20> @BASEBOARD_FAB2_LIB.BASEBOARD_FAB2(SCH_1):M_L_DQ(20)
  U2D1 DY81 DDR4_DQ<20> SKX_EXT_B_BGA1-IC,TBD   I172 @BASEBOARD_FAB2_LIB.BASEBOARD_FAB2(SCH_1):PAGE61
  J1A2  170 DQ<21> SCONN288_H44441004_PIP-SCONN,HA   I111 @BASEBOARD_FAB2_LIB.BASEBOARD_FAB2(SCH_1):PAGE85
  J9L2   25 DQ<20> SCONN288_H44441003_PIP-SCONN,HA    I12 @BASEBOARD_FAB2_LIB.BASEBOARD_FAB2(SCH_1):PAGE86

M_L_DQ<21> @BASEBOARD_FAB2_LIB.BASEBOARD_FAB2(SCH_1):M_L_DQ(21)
  U2D1 EB81 DDR4_DQ<21> SKX_EXT_B_BGA1-IC,TBD   I172 @BASEBOARD_FAB2_LIB.BASEBOARD_FAB2(SCH_1):PAGE61
  J1A2   25 DQ<20> SCONN288_H44441004_PIP-SCONN,HA   I111 @BASEBOARD_FAB2_LIB.BASEBOARD_FAB2(SCH_1):PAGE85
  J9L2  170 DQ<21> SCONN288_H44441003_PIP-SCONN,HA    I12 @BASEBOARD_FAB2_LIB.BASEBOARD_FAB2(SCH_1):PAGE86

M_L_DQ<22> @BASEBOARD_FAB2_LIB.BASEBOARD_FAB2(SCH_1):M_L_DQ(22)
  U2D1 DW78 DDR4_DQ<22> SKX_EXT_B_BGA1-IC,TBD   I172 @BASEBOARD_FAB2_LIB.BASEBOARD_FAB2(SCH_1):PAGE61
  J1A2  177 DQ<23> SCONN288_H44441004_PIP-SCONN,HA   I111 @BASEBOARD_FAB2_LIB.BASEBOARD_FAB2(SCH_1):PAGE85
  J9L2   32 DQ<22> SCONN288_H44441003_PIP-SCONN,HA    I12 @BASEBOARD_FAB2_LIB.BASEBOARD_FAB2(SCH_1):PAGE86

M_L_DQ<23> @BASEBOARD_FAB2_LIB.BASEBOARD_FAB2(SCH_1):M_L_DQ(23)
  U2D1 EC78 DDR4_DQ<23> SKX_EXT_B_BGA1-IC,TBD   I172 @BASEBOARD_FAB2_LIB.BASEBOARD_FAB2(SCH_1):PAGE61
  J1A2   32 DQ<22> SCONN288_H44441004_PIP-SCONN,HA   I111 @BASEBOARD_FAB2_LIB.BASEBOARD_FAB2(SCH_1):PAGE85
  J9L2  177 DQ<23> SCONN288_H44441003_PIP-SCONN,HA    I12 @BASEBOARD_FAB2_LIB.BASEBOARD_FAB2(SCH_1):PAGE86

M_L_DQ<24> @BASEBOARD_FAB2_LIB.BASEBOARD_FAB2(SCH_1):M_L_DQ(24)
  U2D1 ED75 DDR4_DQ<24> SKX_EXT_B_BGA1-IC,TBD   I172 @BASEBOARD_FAB2_LIB.BASEBOARD_FAB2(SCH_1):PAGE61
  J1A2  183 DQ<25> SCONN288_H44441004_PIP-SCONN,HA   I111 @BASEBOARD_FAB2_LIB.BASEBOARD_FAB2(SCH_1):PAGE85
  J9L2   38 DQ<24> SCONN288_H44441003_PIP-SCONN,HA    I12 @BASEBOARD_FAB2_LIB.BASEBOARD_FAB2(SCH_1):PAGE86

M_L_DQ<25> @BASEBOARD_FAB2_LIB.BASEBOARD_FAB2(SCH_1):M_L_DQ(25)
  U2D1 EE74 DDR4_DQ<25> SKX_EXT_B_BGA1-IC,TBD   I172 @BASEBOARD_FAB2_LIB.BASEBOARD_FAB2(SCH_1):PAGE61
  J1A2   38 DQ<24> SCONN288_H44441004_PIP-SCONN,HA   I111 @BASEBOARD_FAB2_LIB.BASEBOARD_FAB2(SCH_1):PAGE85
  J9L2  183 DQ<25> SCONN288_H44441003_PIP-SCONN,HA    I12 @BASEBOARD_FAB2_LIB.BASEBOARD_FAB2(SCH_1):PAGE86

M_L_DQ<26> @BASEBOARD_FAB2_LIB.BASEBOARD_FAB2(SCH_1):M_L_DQ(26)
  U2D1 EB71 DDR4_DQ<26> SKX_EXT_B_BGA1-IC,TBD   I172 @BASEBOARD_FAB2_LIB.BASEBOARD_FAB2(SCH_1):PAGE61
  J1A2  190 DQ<27> SCONN288_H44441004_PIP-SCONN,HA   I111 @BASEBOARD_FAB2_LIB.BASEBOARD_FAB2(SCH_1):PAGE85
  J9L2   45 DQ<26> SCONN288_H44441003_PIP-SCONN,HA    I12 @BASEBOARD_FAB2_LIB.BASEBOARD_FAB2(SCH_1):PAGE86

M_L_DQ<27> @BASEBOARD_FAB2_LIB.BASEBOARD_FAB2(SCH_1):M_L_DQ(27)
  U2D1 ED71 DDR4_DQ<27> SKX_EXT_B_BGA1-IC,TBD   I172 @BASEBOARD_FAB2_LIB.BASEBOARD_FAB2(SCH_1):PAGE61
  J1A2   45 DQ<26> SCONN288_H44441004_PIP-SCONN,HA   I111 @BASEBOARD_FAB2_LIB.BASEBOARD_FAB2(SCH_1):PAGE85
  J9L2  190 DQ<27> SCONN288_H44441003_PIP-SCONN,HA    I12 @BASEBOARD_FAB2_LIB.BASEBOARD_FAB2(SCH_1):PAGE86

M_L_DQ<28> @BASEBOARD_FAB2_LIB.BASEBOARD_FAB2(SCH_1):M_L_DQ(28)
  U2D1 EA74 DDR4_DQ<28> SKX_EXT_B_BGA1-IC,TBD   I172 @BASEBOARD_FAB2_LIB.BASEBOARD_FAB2(SCH_1):PAGE61
  J1A2  181 DQ<29> SCONN288_H44441004_PIP-SCONN,HA   I111 @BASEBOARD_FAB2_LIB.BASEBOARD_FAB2(SCH_1):PAGE85
  J9L2   36 DQ<28> SCONN288_H44441003_PIP-SCONN,HA    I12 @BASEBOARD_FAB2_LIB.BASEBOARD_FAB2(SCH_1):PAGE86

M_L_DQ<29> @BASEBOARD_FAB2_LIB.BASEBOARD_FAB2(SCH_1):M_L_DQ(29)
  U2D1 EB75 DDR4_DQ<29> SKX_EXT_B_BGA1-IC,TBD   I172 @BASEBOARD_FAB2_LIB.BASEBOARD_FAB2(SCH_1):PAGE61
  J1A2   36 DQ<28> SCONN288_H44441004_PIP-SCONN,HA   I111 @BASEBOARD_FAB2_LIB.BASEBOARD_FAB2(SCH_1):PAGE85
  J9L2  181 DQ<29> SCONN288_H44441003_PIP-SCONN,HA    I12 @BASEBOARD_FAB2_LIB.BASEBOARD_FAB2(SCH_1):PAGE86

M_L_DQ<2> @BASEBOARD_FAB2_LIB.BASEBOARD_FAB2(SCH_1):M_L_DQ(2)
  U2D1 CT81 DDR4_DQ<2> SKX_EXT_B_BGA1-IC,TBD   I172 @BASEBOARD_FAB2_LIB.BASEBOARD_FAB2(SCH_1):PAGE61
  J1A2  157  DQ<3> SCONN288_H44441004_PIP-SCONN,HA   I111 @BASEBOARD_FAB2_LIB.BASEBOARD_FAB2(SCH_1):PAGE85
  J9L2   12  DQ<2> SCONN288_H44441003_PIP-SCONN,HA    I12 @BASEBOARD_FAB2_LIB.BASEBOARD_FAB2(SCH_1):PAGE86

M_L_DQ<30> @BASEBOARD_FAB2_LIB.BASEBOARD_FAB2(SCH_1):M_L_DQ(30)
  U2D1 EA72 DDR4_DQ<30> SKX_EXT_B_BGA1-IC,TBD   I172 @BASEBOARD_FAB2_LIB.BASEBOARD_FAB2(SCH_1):PAGE61
  J1A2  188 DQ<31> SCONN288_H44441004_PIP-SCONN,HA   I111 @BASEBOARD_FAB2_LIB.BASEBOARD_FAB2(SCH_1):PAGE85
  J9L2   43 DQ<30> SCONN288_H44441003_PIP-SCONN,HA    I12 @BASEBOARD_FAB2_LIB.BASEBOARD_FAB2(SCH_1):PAGE86

M_L_DQ<31> @BASEBOARD_FAB2_LIB.BASEBOARD_FAB2(SCH_1):M_L_DQ(31)
  U2D1 EE72 DDR4_DQ<31> SKX_EXT_B_BGA1-IC,TBD   I172 @BASEBOARD_FAB2_LIB.BASEBOARD_FAB2(SCH_1):PAGE61
  J1A2   43 DQ<30> SCONN288_H44441004_PIP-SCONN,HA   I111 @BASEBOARD_FAB2_LIB.BASEBOARD_FAB2(SCH_1):PAGE85
  J9L2  188 DQ<31> SCONN288_H44441003_PIP-SCONN,HA    I12 @BASEBOARD_FAB2_LIB.BASEBOARD_FAB2(SCH_1):PAGE86

M_L_DQ<32> @BASEBOARD_FAB2_LIB.BASEBOARD_FAB2(SCH_1):M_L_DQ(32)
  U2D1 DU42 DDR4_DQ<32> SKX_EXT_B_BGA1-IC,TBD   I172 @BASEBOARD_FAB2_LIB.BASEBOARD_FAB2(SCH_1):PAGE61
  J1A2  242 DQ<33> SCONN288_H44441004_PIP-SCONN,HA   I111 @BASEBOARD_FAB2_LIB.BASEBOARD_FAB2(SCH_1):PAGE85
  J9L2   97 DQ<32> SCONN288_H44441003_PIP-SCONN,HA    I12 @BASEBOARD_FAB2_LIB.BASEBOARD_FAB2(SCH_1):PAGE86

M_L_DQ<33> @BASEBOARD_FAB2_LIB.BASEBOARD_FAB2(SCH_1):M_L_DQ(33)
  U2D1 DW42 DDR4_DQ<33> SKX_EXT_B_BGA1-IC,TBD   I172 @BASEBOARD_FAB2_LIB.BASEBOARD_FAB2(SCH_1):PAGE61
  J1A2   97 DQ<32> SCONN288_H44441004_PIP-SCONN,HA   I111 @BASEBOARD_FAB2_LIB.BASEBOARD_FAB2(SCH_1):PAGE85
  J9L2  242 DQ<33> SCONN288_H44441003_PIP-SCONN,HA    I12 @BASEBOARD_FAB2_LIB.BASEBOARD_FAB2(SCH_1):PAGE86

M_L_DQ<34> @BASEBOARD_FAB2_LIB.BASEBOARD_FAB2(SCH_1):M_L_DQ(34)
  U2D1 DP39 DDR4_DQ<34> SKX_EXT_B_BGA1-IC,TBD   I172 @BASEBOARD_FAB2_LIB.BASEBOARD_FAB2(SCH_1):PAGE61
  J1A2  249 DQ<35> SCONN288_H44441004_PIP-SCONN,HA   I111 @BASEBOARD_FAB2_LIB.BASEBOARD_FAB2(SCH_1):PAGE85
  J9L2  104 DQ<34> SCONN288_H44441003_PIP-SCONN,HA    I12 @BASEBOARD_FAB2_LIB.BASEBOARD_FAB2(SCH_1):PAGE86

M_L_DQ<35> @BASEBOARD_FAB2_LIB.BASEBOARD_FAB2(SCH_1):M_L_DQ(35)
  U2D1 DT39 DDR4_DQ<35> SKX_EXT_B_BGA1-IC,TBD   I172 @BASEBOARD_FAB2_LIB.BASEBOARD_FAB2(SCH_1):PAGE61
  J1A2  104 DQ<34> SCONN288_H44441004_PIP-SCONN,HA   I111 @BASEBOARD_FAB2_LIB.BASEBOARD_FAB2(SCH_1):PAGE85
  J9L2  249 DQ<35> SCONN288_H44441003_PIP-SCONN,HA    I12 @BASEBOARD_FAB2_LIB.BASEBOARD_FAB2(SCH_1):PAGE86

M_L_DQ<36> @BASEBOARD_FAB2_LIB.BASEBOARD_FAB2(SCH_1):M_L_DQ(36)
  U2D1 DL42 DDR4_DQ<36> SKX_EXT_B_BGA1-IC,TBD   I172 @BASEBOARD_FAB2_LIB.BASEBOARD_FAB2(SCH_1):PAGE61
  J1A2  240 DQ<37> SCONN288_H44441004_PIP-SCONN,HA   I111 @BASEBOARD_FAB2_LIB.BASEBOARD_FAB2(SCH_1):PAGE85
  J9L2   95 DQ<36> SCONN288_H44441003_PIP-SCONN,HA    I12 @BASEBOARD_FAB2_LIB.BASEBOARD_FAB2(SCH_1):PAGE86

M_L_DQ<37> @BASEBOARD_FAB2_LIB.BASEBOARD_FAB2(SCH_1):M_L_DQ(37)
  U2D1 DN42 DDR4_DQ<37> SKX_EXT_B_BGA1-IC,TBD   I172 @BASEBOARD_FAB2_LIB.BASEBOARD_FAB2(SCH_1):PAGE61
  J1A2   95 DQ<36> SCONN288_H44441004_PIP-SCONN,HA   I111 @BASEBOARD_FAB2_LIB.BASEBOARD_FAB2(SCH_1):PAGE85
  J9L2  240 DQ<37> SCONN288_H44441003_PIP-SCONN,HA    I12 @BASEBOARD_FAB2_LIB.BASEBOARD_FAB2(SCH_1):PAGE86

M_L_DQ<38> @BASEBOARD_FAB2_LIB.BASEBOARD_FAB2(SCH_1):M_L_DQ(38)
  U2D1 DN40 DDR4_DQ<38> SKX_EXT_B_BGA1-IC,TBD   I172 @BASEBOARD_FAB2_LIB.BASEBOARD_FAB2(SCH_1):PAGE61
  J1A2  247 DQ<39> SCONN288_H44441004_PIP-SCONN,HA   I111 @BASEBOARD_FAB2_LIB.BASEBOARD_FAB2(SCH_1):PAGE85
  J9L2  102 DQ<38> SCONN288_H44441003_PIP-SCONN,HA    I12 @BASEBOARD_FAB2_LIB.BASEBOARD_FAB2(SCH_1):PAGE86

M_L_DQ<39> @BASEBOARD_FAB2_LIB.BASEBOARD_FAB2(SCH_1):M_L_DQ(39)
  U2D1 DU40 DDR4_DQ<39> SKX_EXT_B_BGA1-IC,TBD   I172 @BASEBOARD_FAB2_LIB.BASEBOARD_FAB2(SCH_1):PAGE61
  J1A2  102 DQ<38> SCONN288_H44441004_PIP-SCONN,HA   I111 @BASEBOARD_FAB2_LIB.BASEBOARD_FAB2(SCH_1):PAGE85
  J9L2  247 DQ<39> SCONN288_H44441003_PIP-SCONN,HA    I12 @BASEBOARD_FAB2_LIB.BASEBOARD_FAB2(SCH_1):PAGE86

M_L_DQ<3> @BASEBOARD_FAB2_LIB.BASEBOARD_FAB2(SCH_1):M_L_DQ(3)
  U2D1 CR82 DDR4_DQ<3> SKX_EXT_B_BGA1-IC,TBD   I172 @BASEBOARD_FAB2_LIB.BASEBOARD_FAB2(SCH_1):PAGE61
  J1A2   12  DQ<2> SCONN288_H44441004_PIP-SCONN,HA   I111 @BASEBOARD_FAB2_LIB.BASEBOARD_FAB2(SCH_1):PAGE85
  J9L2  157  DQ<3> SCONN288_H44441003_PIP-SCONN,HA    I12 @BASEBOARD_FAB2_LIB.BASEBOARD_FAB2(SCH_1):PAGE86

M_L_DQ<40> @BASEBOARD_FAB2_LIB.BASEBOARD_FAB2(SCH_1):M_L_DQ(40)
  U2D1 EC34 DDR4_DQ<40> SKX_EXT_B_BGA1-IC,TBD   I172 @BASEBOARD_FAB2_LIB.BASEBOARD_FAB2(SCH_1):PAGE61
  J1A2  253 DQ<41> SCONN288_H44441004_PIP-SCONN,HA   I111 @BASEBOARD_FAB2_LIB.BASEBOARD_FAB2(SCH_1):PAGE85
  J9L2  108 DQ<40> SCONN288_H44441003_PIP-SCONN,HA    I12 @BASEBOARD_FAB2_LIB.BASEBOARD_FAB2(SCH_1):PAGE86

M_L_DQ<41> @BASEBOARD_FAB2_LIB.BASEBOARD_FAB2(SCH_1):M_L_DQ(41)
  U2D1 ED33 DDR4_DQ<41> SKX_EXT_B_BGA1-IC,TBD   I172 @BASEBOARD_FAB2_LIB.BASEBOARD_FAB2(SCH_1):PAGE61
  J1A2  108 DQ<40> SCONN288_H44441004_PIP-SCONN,HA   I111 @BASEBOARD_FAB2_LIB.BASEBOARD_FAB2(SCH_1):PAGE85
  J9L2  253 DQ<41> SCONN288_H44441003_PIP-SCONN,HA    I12 @BASEBOARD_FAB2_LIB.BASEBOARD_FAB2(SCH_1):PAGE86

M_L_DQ<42> @BASEBOARD_FAB2_LIB.BASEBOARD_FAB2(SCH_1):M_L_DQ(42)
  U2D1 EA30 DDR4_DQ<42> SKX_EXT_B_BGA1-IC,TBD   I172 @BASEBOARD_FAB2_LIB.BASEBOARD_FAB2(SCH_1):PAGE61
  J1A2  260 DQ<43> SCONN288_H44441004_PIP-SCONN,HA   I111 @BASEBOARD_FAB2_LIB.BASEBOARD_FAB2(SCH_1):PAGE85
  J9L2  115 DQ<42> SCONN288_H44441003_PIP-SCONN,HA    I12 @BASEBOARD_FAB2_LIB.BASEBOARD_FAB2(SCH_1):PAGE86

M_L_DQ<43> @BASEBOARD_FAB2_LIB.BASEBOARD_FAB2(SCH_1):M_L_DQ(43)
  U2D1 EC30 DDR4_DQ<43> SKX_EXT_B_BGA1-IC,TBD   I172 @BASEBOARD_FAB2_LIB.BASEBOARD_FAB2(SCH_1):PAGE61
  J1A2  115 DQ<42> SCONN288_H44441004_PIP-SCONN,HA   I111 @BASEBOARD_FAB2_LIB.BASEBOARD_FAB2(SCH_1):PAGE85
  J9L2  260 DQ<43> SCONN288_H44441003_PIP-SCONN,HA    I12 @BASEBOARD_FAB2_LIB.BASEBOARD_FAB2(SCH_1):PAGE86

M_L_DQ<44> @BASEBOARD_FAB2_LIB.BASEBOARD_FAB2(SCH_1):M_L_DQ(44)
  U2D1 DY33 DDR4_DQ<44> SKX_EXT_B_BGA1-IC,TBD   I172 @BASEBOARD_FAB2_LIB.BASEBOARD_FAB2(SCH_1):PAGE61
  J1A2  251 DQ<45> SCONN288_H44441004_PIP-SCONN,HA   I111 @BASEBOARD_FAB2_LIB.BASEBOARD_FAB2(SCH_1):PAGE85
  J9L2  106 DQ<44> SCONN288_H44441003_PIP-SCONN,HA    I12 @BASEBOARD_FAB2_LIB.BASEBOARD_FAB2(SCH_1):PAGE86

M_L_DQ<45> @BASEBOARD_FAB2_LIB.BASEBOARD_FAB2(SCH_1):M_L_DQ(45)
  U2D1 EA34 DDR4_DQ<45> SKX_EXT_B_BGA1-IC,TBD   I172 @BASEBOARD_FAB2_LIB.BASEBOARD_FAB2(SCH_1):PAGE61
  J1A2  106 DQ<44> SCONN288_H44441004_PIP-SCONN,HA   I111 @BASEBOARD_FAB2_LIB.BASEBOARD_FAB2(SCH_1):PAGE85
  J9L2  251 DQ<45> SCONN288_H44441003_PIP-SCONN,HA    I12 @BASEBOARD_FAB2_LIB.BASEBOARD_FAB2(SCH_1):PAGE86

M_L_DQ<46> @BASEBOARD_FAB2_LIB.BASEBOARD_FAB2(SCH_1):M_L_DQ(46)
  U2D1 DY31 DDR4_DQ<46> SKX_EXT_B_BGA1-IC,TBD   I172 @BASEBOARD_FAB2_LIB.BASEBOARD_FAB2(SCH_1):PAGE61
  J1A2  258 DQ<47> SCONN288_H44441004_PIP-SCONN,HA   I111 @BASEBOARD_FAB2_LIB.BASEBOARD_FAB2(SCH_1):PAGE85
  J9L2  113 DQ<46> SCONN288_H44441003_PIP-SCONN,HA    I12 @BASEBOARD_FAB2_LIB.BASEBOARD_FAB2(SCH_1):PAGE86

M_L_DQ<47> @BASEBOARD_FAB2_LIB.BASEBOARD_FAB2(SCH_1):M_L_DQ(47)
  U2D1 ED31 DDR4_DQ<47> SKX_EXT_B_BGA1-IC,TBD   I172 @BASEBOARD_FAB2_LIB.BASEBOARD_FAB2(SCH_1):PAGE61
  J1A2  113 DQ<46> SCONN288_H44441004_PIP-SCONN,HA   I111 @BASEBOARD_FAB2_LIB.BASEBOARD_FAB2(SCH_1):PAGE85
  J9L2  258 DQ<47> SCONN288_H44441003_PIP-SCONN,HA    I12 @BASEBOARD_FAB2_LIB.BASEBOARD_FAB2(SCH_1):PAGE86

M_L_DQ<48> @BASEBOARD_FAB2_LIB.BASEBOARD_FAB2(SCH_1):M_L_DQ(48)
  U2D1 EC28 DDR4_DQ<48> SKX_EXT_B_BGA1-IC,TBD   I172 @BASEBOARD_FAB2_LIB.BASEBOARD_FAB2(SCH_1):PAGE61
  J1A2  264 DQ<49> SCONN288_H44441004_PIP-SCONN,HA   I111 @BASEBOARD_FAB2_LIB.BASEBOARD_FAB2(SCH_1):PAGE85
  J9L2  119 DQ<48> SCONN288_H44441003_PIP-SCONN,HA    I12 @BASEBOARD_FAB2_LIB.BASEBOARD_FAB2(SCH_1):PAGE86

M_L_DQ<49> @BASEBOARD_FAB2_LIB.BASEBOARD_FAB2(SCH_1):M_L_DQ(49)
  U2D1 ED27 DDR4_DQ<49> SKX_EXT_B_BGA1-IC,TBD   I172 @BASEBOARD_FAB2_LIB.BASEBOARD_FAB2(SCH_1):PAGE61
  J1A2  119 DQ<48> SCONN288_H44441004_PIP-SCONN,HA   I111 @BASEBOARD_FAB2_LIB.BASEBOARD_FAB2(SCH_1):PAGE85
  J9L2  264 DQ<49> SCONN288_H44441003_PIP-SCONN,HA    I12 @BASEBOARD_FAB2_LIB.BASEBOARD_FAB2(SCH_1):PAGE86

M_L_DQ<4> @BASEBOARD_FAB2_LIB.BASEBOARD_FAB2(SCH_1):M_L_DQ(4)
  U2D1 CK79 DDR4_DQ<4> SKX_EXT_B_BGA1-IC,TBD   I172 @BASEBOARD_FAB2_LIB.BASEBOARD_FAB2(SCH_1):PAGE61
  J1A2  148  DQ<5> SCONN288_H44441004_PIP-SCONN,HA   I111 @BASEBOARD_FAB2_LIB.BASEBOARD_FAB2(SCH_1):PAGE85
  J9L2    3  DQ<4> SCONN288_H44441003_PIP-SCONN,HA    I12 @BASEBOARD_FAB2_LIB.BASEBOARD_FAB2(SCH_1):PAGE86

M_L_DQ<50> @BASEBOARD_FAB2_LIB.BASEBOARD_FAB2(SCH_1):M_L_DQ(50)
  U2D1 EA24 DDR4_DQ<50> SKX_EXT_B_BGA1-IC,TBD   I172 @BASEBOARD_FAB2_LIB.BASEBOARD_FAB2(SCH_1):PAGE61
  J1A2  271 DQ<51> SCONN288_H44441004_PIP-SCONN,HA   I111 @BASEBOARD_FAB2_LIB.BASEBOARD_FAB2(SCH_1):PAGE85
  J9L2  126 DQ<50> SCONN288_H44441003_PIP-SCONN,HA    I12 @BASEBOARD_FAB2_LIB.BASEBOARD_FAB2(SCH_1):PAGE86

M_L_DQ<51> @BASEBOARD_FAB2_LIB.BASEBOARD_FAB2(SCH_1):M_L_DQ(51)
  U2D1 EC24 DDR4_DQ<51> SKX_EXT_B_BGA1-IC,TBD   I172 @BASEBOARD_FAB2_LIB.BASEBOARD_FAB2(SCH_1):PAGE61
  J1A2  126 DQ<50> SCONN288_H44441004_PIP-SCONN,HA   I111 @BASEBOARD_FAB2_LIB.BASEBOARD_FAB2(SCH_1):PAGE85
  J9L2  271 DQ<51> SCONN288_H44441003_PIP-SCONN,HA    I12 @BASEBOARD_FAB2_LIB.BASEBOARD_FAB2(SCH_1):PAGE86

M_L_DQ<52> @BASEBOARD_FAB2_LIB.BASEBOARD_FAB2(SCH_1):M_L_DQ(52)
  U2D1 DY27 DDR4_DQ<52> SKX_EXT_B_BGA1-IC,TBD   I172 @BASEBOARD_FAB2_LIB.BASEBOARD_FAB2(SCH_1):PAGE61
  J1A2  262 DQ<53> SCONN288_H44441004_PIP-SCONN,HA   I111 @BASEBOARD_FAB2_LIB.BASEBOARD_FAB2(SCH_1):PAGE85
  J9L2  117 DQ<52> SCONN288_H44441003_PIP-SCONN,HA    I12 @BASEBOARD_FAB2_LIB.BASEBOARD_FAB2(SCH_1):PAGE86

M_L_DQ<53> @BASEBOARD_FAB2_LIB.BASEBOARD_FAB2(SCH_1):M_L_DQ(53)
  U2D1 EA28 DDR4_DQ<53> SKX_EXT_B_BGA1-IC,TBD   I172 @BASEBOARD_FAB2_LIB.BASEBOARD_FAB2(SCH_1):PAGE61
  J1A2  117 DQ<52> SCONN288_H44441004_PIP-SCONN,HA   I111 @BASEBOARD_FAB2_LIB.BASEBOARD_FAB2(SCH_1):PAGE85
  J9L2  262 DQ<53> SCONN288_H44441003_PIP-SCONN,HA    I12 @BASEBOARD_FAB2_LIB.BASEBOARD_FAB2(SCH_1):PAGE86

M_L_DQ<54> @BASEBOARD_FAB2_LIB.BASEBOARD_FAB2(SCH_1):M_L_DQ(54)
  U2D1 DY25 DDR4_DQ<54> SKX_EXT_B_BGA1-IC,TBD   I172 @BASEBOARD_FAB2_LIB.BASEBOARD_FAB2(SCH_1):PAGE61
  J1A2  269 DQ<55> SCONN288_H44441004_PIP-SCONN,HA   I111 @BASEBOARD_FAB2_LIB.BASEBOARD_FAB2(SCH_1):PAGE85
  J9L2  124 DQ<54> SCONN288_H44441003_PIP-SCONN,HA    I12 @BASEBOARD_FAB2_LIB.BASEBOARD_FAB2(SCH_1):PAGE86

M_L_DQ<55> @BASEBOARD_FAB2_LIB.BASEBOARD_FAB2(SCH_1):M_L_DQ(55)
  U2D1 ED25 DDR4_DQ<55> SKX_EXT_B_BGA1-IC,TBD   I172 @BASEBOARD_FAB2_LIB.BASEBOARD_FAB2(SCH_1):PAGE61
  J1A2  124 DQ<54> SCONN288_H44441004_PIP-SCONN,HA   I111 @BASEBOARD_FAB2_LIB.BASEBOARD_FAB2(SCH_1):PAGE85
  J9L2  269 DQ<55> SCONN288_H44441003_PIP-SCONN,HA    I12 @BASEBOARD_FAB2_LIB.BASEBOARD_FAB2(SCH_1):PAGE86

M_L_DQ<56> @BASEBOARD_FAB2_LIB.BASEBOARD_FAB2(SCH_1):M_L_DQ(56)
  U2D1 DF27 DDR4_DQ<56> SKX_EXT_B_BGA1-IC,TBD   I172 @BASEBOARD_FAB2_LIB.BASEBOARD_FAB2(SCH_1):PAGE61
  J1A2  275 DQ<57> SCONN288_H44441004_PIP-SCONN,HA   I111 @BASEBOARD_FAB2_LIB.BASEBOARD_FAB2(SCH_1):PAGE85
  J9L2  130 DQ<56> SCONN288_H44441003_PIP-SCONN,HA    I12 @BASEBOARD_FAB2_LIB.BASEBOARD_FAB2(SCH_1):PAGE86

M_L_DQ<57> @BASEBOARD_FAB2_LIB.BASEBOARD_FAB2(SCH_1):M_L_DQ(57)
  U2D1 DK27 DDR4_DQ<57> SKX_EXT_B_BGA1-IC,TBD   I172 @BASEBOARD_FAB2_LIB.BASEBOARD_FAB2(SCH_1):PAGE61
  J1A2  130 DQ<56> SCONN288_H44441004_PIP-SCONN,HA   I111 @BASEBOARD_FAB2_LIB.BASEBOARD_FAB2(SCH_1):PAGE85
  J9L2  275 DQ<57> SCONN288_H44441003_PIP-SCONN,HA    I12 @BASEBOARD_FAB2_LIB.BASEBOARD_FAB2(SCH_1):PAGE86

M_L_DQ<58> @BASEBOARD_FAB2_LIB.BASEBOARD_FAB2(SCH_1):M_L_DQ(58)
  U2D1 DD25 DDR4_DQ<58> SKX_EXT_B_BGA1-IC,TBD   I172 @BASEBOARD_FAB2_LIB.BASEBOARD_FAB2(SCH_1):PAGE61
  J1A2  282 DQ<59> SCONN288_H44441004_PIP-SCONN,HA   I111 @BASEBOARD_FAB2_LIB.BASEBOARD_FAB2(SCH_1):PAGE85
  J9L2  137 DQ<58> SCONN288_H44441003_PIP-SCONN,HA    I12 @BASEBOARD_FAB2_LIB.BASEBOARD_FAB2(SCH_1):PAGE86

M_L_DQ<59> @BASEBOARD_FAB2_LIB.BASEBOARD_FAB2(SCH_1):M_L_DQ(59)
  U2D1 DJ24 DDR4_DQ<59> SKX_EXT_B_BGA1-IC,TBD   I172 @BASEBOARD_FAB2_LIB.BASEBOARD_FAB2(SCH_1):PAGE61
  J1A2  137 DQ<58> SCONN288_H44441004_PIP-SCONN,HA   I111 @BASEBOARD_FAB2_LIB.BASEBOARD_FAB2(SCH_1):PAGE85
  J9L2  282 DQ<59> SCONN288_H44441003_PIP-SCONN,HA    I12 @BASEBOARD_FAB2_LIB.BASEBOARD_FAB2(SCH_1):PAGE86

M_L_DQ<5> @BASEBOARD_FAB2_LIB.BASEBOARD_FAB2(SCH_1):M_L_DQ(5)
  U2D1 CJ80 DDR4_DQ<5> SKX_EXT_B_BGA1-IC,TBD   I172 @BASEBOARD_FAB2_LIB.BASEBOARD_FAB2(SCH_1):PAGE61
  J1A2    3  DQ<4> SCONN288_H44441004_PIP-SCONN,HA   I111 @BASEBOARD_FAB2_LIB.BASEBOARD_FAB2(SCH_1):PAGE85
  J9L2  148  DQ<5> SCONN288_H44441003_PIP-SCONN,HA    I12 @BASEBOARD_FAB2_LIB.BASEBOARD_FAB2(SCH_1):PAGE86

M_L_DQ<60> @BASEBOARD_FAB2_LIB.BASEBOARD_FAB2(SCH_1):M_L_DQ(60)
  U2D1 DG28 DDR4_DQ<60> SKX_EXT_B_BGA1-IC,TBD   I172 @BASEBOARD_FAB2_LIB.BASEBOARD_FAB2(SCH_1):PAGE61
  J1A2  273 DQ<61> SCONN288_H44441004_PIP-SCONN,HA   I111 @BASEBOARD_FAB2_LIB.BASEBOARD_FAB2(SCH_1):PAGE85
  J9L2  128 DQ<60> SCONN288_H44441003_PIP-SCONN,HA    I12 @BASEBOARD_FAB2_LIB.BASEBOARD_FAB2(SCH_1):PAGE86

M_L_DQ<61> @BASEBOARD_FAB2_LIB.BASEBOARD_FAB2(SCH_1):M_L_DQ(61)
  U2D1 DJ28 DDR4_DQ<61> SKX_EXT_B_BGA1-IC,TBD   I172 @BASEBOARD_FAB2_LIB.BASEBOARD_FAB2(SCH_1):PAGE61
  J1A2  128 DQ<60> SCONN288_H44441004_PIP-SCONN,HA   I111 @BASEBOARD_FAB2_LIB.BASEBOARD_FAB2(SCH_1):PAGE85
  J9L2  273 DQ<61> SCONN288_H44441003_PIP-SCONN,HA    I12 @BASEBOARD_FAB2_LIB.BASEBOARD_FAB2(SCH_1):PAGE86

M_L_DQ<62> @BASEBOARD_FAB2_LIB.BASEBOARD_FAB2(SCH_1):M_L_DQ(62)
  U2D1 DF25 DDR4_DQ<62> SKX_EXT_B_BGA1-IC,TBD   I172 @BASEBOARD_FAB2_LIB.BASEBOARD_FAB2(SCH_1):PAGE61
  J1A2  280 DQ<63> SCONN288_H44441004_PIP-SCONN,HA   I111 @BASEBOARD_FAB2_LIB.BASEBOARD_FAB2(SCH_1):PAGE85
  J9L2  135 DQ<62> SCONN288_H44441003_PIP-SCONN,HA    I12 @BASEBOARD_FAB2_LIB.BASEBOARD_FAB2(SCH_1):PAGE86

M_L_DQ<63> @BASEBOARD_FAB2_LIB.BASEBOARD_FAB2(SCH_1):M_L_DQ(63)
  U2D1 DK25 DDR4_DQ<63> SKX_EXT_B_BGA1-IC,TBD   I172 @BASEBOARD_FAB2_LIB.BASEBOARD_FAB2(SCH_1):PAGE61
  J1A2  135 DQ<62> SCONN288_H44441004_PIP-SCONN,HA   I111 @BASEBOARD_FAB2_LIB.BASEBOARD_FAB2(SCH_1):PAGE85
  J9L2  280 DQ<63> SCONN288_H44441003_PIP-SCONN,HA    I12 @BASEBOARD_FAB2_LIB.BASEBOARD_FAB2(SCH_1):PAGE86

M_L_DQ<6> @BASEBOARD_FAB2_LIB.BASEBOARD_FAB2(SCH_1):M_L_DQ(6)
  U2D1 CR80 DDR4_DQ<6> SKX_EXT_B_BGA1-IC,TBD   I172 @BASEBOARD_FAB2_LIB.BASEBOARD_FAB2(SCH_1):PAGE61
  J1A2  155  DQ<7> SCONN288_H44441004_PIP-SCONN,HA   I111 @BASEBOARD_FAB2_LIB.BASEBOARD_FAB2(SCH_1):PAGE85
  J9L2   10  DQ<6> SCONN288_H44441003_PIP-SCONN,HA    I12 @BASEBOARD_FAB2_LIB.BASEBOARD_FAB2(SCH_1):PAGE86

M_L_DQ<7> @BASEBOARD_FAB2_LIB.BASEBOARD_FAB2(SCH_1):M_L_DQ(7)
  U2D1 CN82 DDR4_DQ<7> SKX_EXT_B_BGA1-IC,TBD   I172 @BASEBOARD_FAB2_LIB.BASEBOARD_FAB2(SCH_1):PAGE61
  J1A2   10  DQ<6> SCONN288_H44441004_PIP-SCONN,HA   I111 @BASEBOARD_FAB2_LIB.BASEBOARD_FAB2(SCH_1):PAGE85
  J9L2  155  DQ<7> SCONN288_H44441003_PIP-SCONN,HA    I12 @BASEBOARD_FAB2_LIB.BASEBOARD_FAB2(SCH_1):PAGE86

M_L_DQ<8> @BASEBOARD_FAB2_LIB.BASEBOARD_FAB2(SCH_1):M_L_DQ(8)
  U2D1 DB79 DDR4_DQ<8> SKX_EXT_B_BGA1-IC,TBD   I172 @BASEBOARD_FAB2_LIB.BASEBOARD_FAB2(SCH_1):PAGE61
  J1A2  161  DQ<9> SCONN288_H44441004_PIP-SCONN,HA   I111 @BASEBOARD_FAB2_LIB.BASEBOARD_FAB2(SCH_1):PAGE85
  J9L2   16  DQ<8> SCONN288_H44441003_PIP-SCONN,HA    I12 @BASEBOARD_FAB2_LIB.BASEBOARD_FAB2(SCH_1):PAGE86

M_L_DQ<9> @BASEBOARD_FAB2_LIB.BASEBOARD_FAB2(SCH_1):M_L_DQ(9)
  U2D1 CY81 DDR4_DQ<9> SKX_EXT_B_BGA1-IC,TBD   I172 @BASEBOARD_FAB2_LIB.BASEBOARD_FAB2(SCH_1):PAGE61
  J1A2   16  DQ<8> SCONN288_H44441004_PIP-SCONN,HA   I111 @BASEBOARD_FAB2_LIB.BASEBOARD_FAB2(SCH_1):PAGE85
  J9L2  161  DQ<9> SCONN288_H44441003_PIP-SCONN,HA    I12 @BASEBOARD_FAB2_LIB.BASEBOARD_FAB2(SCH_1):PAGE86

M_L_DQS_DN<0> @BASEBOARD_FAB2_LIB.BASEBOARD_FAB2(SCH_1):M_L_DQS_DN(0)
  U2D1 CL82 DDR4_DQS_DN<0> SKX_EXT_B_BGA1-IC,TBD   I172 @BASEBOARD_FAB2_LIB.BASEBOARD_FAB2(SCH_1):PAGE61
  J1A2  152  DQS0N SCONN288_H44441004_PIP-SCONN,HA    I66 @BASEBOARD_FAB2_LIB.BASEBOARD_FAB2(SCH_1):PAGE85
  J9L2  152  DQS0N SCONN288_H44441003_PIP-SCONN,HA   I100 @BASEBOARD_FAB2_LIB.BASEBOARD_FAB2(SCH_1):PAGE86

M_L_DQS_DN<10> @BASEBOARD_FAB2_LIB.BASEBOARD_FAB2(SCH_1):M_L_DQS_DN(10)
  U2D1 DC80 DDR4_DQS_DN<10> SKX_EXT_B_BGA1-IC,TBD   I172 @BASEBOARD_FAB2_LIB.BASEBOARD_FAB2(SCH_1):PAGE61
  J1A2   19 DQS10N SCONN288_H44441004_PIP-SCONN,HA    I66 @BASEBOARD_FAB2_LIB.BASEBOARD_FAB2(SCH_1):PAGE85
  J9L2   19 DQS10N SCONN288_H44441003_PIP-SCONN,HA   I100 @BASEBOARD_FAB2_LIB.BASEBOARD_FAB2(SCH_1):PAGE86

M_L_DQS_DN<11> @BASEBOARD_FAB2_LIB.BASEBOARD_FAB2(SCH_1):M_L_DQS_DN(11)
  U2D1 DY79 DDR4_DQS_DN<11> SKX_EXT_B_BGA1-IC,TBD   I172 @BASEBOARD_FAB2_LIB.BASEBOARD_FAB2(SCH_1):PAGE61
  J1A2   30 DQS11N SCONN288_H44441004_PIP-SCONN,HA    I66 @BASEBOARD_FAB2_LIB.BASEBOARD_FAB2(SCH_1):PAGE85
  J9L2   30 DQS11N SCONN288_H44441003_PIP-SCONN,HA   I100 @BASEBOARD_FAB2_LIB.BASEBOARD_FAB2(SCH_1):PAGE86

M_L_DQS_DN<12> @BASEBOARD_FAB2_LIB.BASEBOARD_FAB2(SCH_1):M_L_DQS_DN(12)
  U2D1 EB73 DDR4_DQS_DN<12> SKX_EXT_B_BGA1-IC,TBD   I172 @BASEBOARD_FAB2_LIB.BASEBOARD_FAB2(SCH_1):PAGE61
  J1A2   41 DQS12N SCONN288_H44441004_PIP-SCONN,HA    I66 @BASEBOARD_FAB2_LIB.BASEBOARD_FAB2(SCH_1):PAGE85
  J9L2   41 DQS12N SCONN288_H44441003_PIP-SCONN,HA   I100 @BASEBOARD_FAB2_LIB.BASEBOARD_FAB2(SCH_1):PAGE86

M_L_DQS_DN<13> @BASEBOARD_FAB2_LIB.BASEBOARD_FAB2(SCH_1):M_L_DQS_DN(13)
  U2D1 DP41 DDR4_DQS_DN<13> SKX_EXT_B_BGA1-IC,TBD   I172 @BASEBOARD_FAB2_LIB.BASEBOARD_FAB2(SCH_1):PAGE61
  J1A2  100 DQS13N SCONN288_H44441004_PIP-SCONN,HA    I66 @BASEBOARD_FAB2_LIB.BASEBOARD_FAB2(SCH_1):PAGE85
  J9L2  100 DQS13N SCONN288_H44441003_PIP-SCONN,HA   I100 @BASEBOARD_FAB2_LIB.BASEBOARD_FAB2(SCH_1):PAGE86

M_L_DQS_DN<14> @BASEBOARD_FAB2_LIB.BASEBOARD_FAB2(SCH_1):M_L_DQS_DN(14)
  U2D1 EA32 DDR4_DQS_DN<14> SKX_EXT_B_BGA1-IC,TBD   I172 @BASEBOARD_FAB2_LIB.BASEBOARD_FAB2(SCH_1):PAGE61
  J1A2  111 DQS14N SCONN288_H44441004_PIP-SCONN,HA    I66 @BASEBOARD_FAB2_LIB.BASEBOARD_FAB2(SCH_1):PAGE85
  J9L2  111 DQS14N SCONN288_H44441003_PIP-SCONN,HA   I100 @BASEBOARD_FAB2_LIB.BASEBOARD_FAB2(SCH_1):PAGE86

M_L_DQS_DN<15> @BASEBOARD_FAB2_LIB.BASEBOARD_FAB2(SCH_1):M_L_DQS_DN(15)
  U2D1 EA26 DDR4_DQS_DN<15> SKX_EXT_B_BGA1-IC,TBD   I172 @BASEBOARD_FAB2_LIB.BASEBOARD_FAB2(SCH_1):PAGE61
  J1A2  122 DQS15N SCONN288_H44441004_PIP-SCONN,HA    I66 @BASEBOARD_FAB2_LIB.BASEBOARD_FAB2(SCH_1):PAGE85
  J9L2  122 DQS15N SCONN288_H44441003_PIP-SCONN,HA   I100 @BASEBOARD_FAB2_LIB.BASEBOARD_FAB2(SCH_1):PAGE86

M_L_DQS_DN<16> @BASEBOARD_FAB2_LIB.BASEBOARD_FAB2(SCH_1):M_L_DQS_DN(16)
  U2D1 DG26 DDR4_DQS_DN<16> SKX_EXT_B_BGA1-IC,TBD   I172 @BASEBOARD_FAB2_LIB.BASEBOARD_FAB2(SCH_1):PAGE61
  J1A2  133 DQS16N SCONN288_H44441004_PIP-SCONN,HA    I66 @BASEBOARD_FAB2_LIB.BASEBOARD_FAB2(SCH_1):PAGE85
  J9L2  133 DQS16N SCONN288_H44441003_PIP-SCONN,HA   I100 @BASEBOARD_FAB2_LIB.BASEBOARD_FAB2(SCH_1):PAGE86

M_L_DQS_DN<17> @BASEBOARD_FAB2_LIB.BASEBOARD_FAB2(SCH_1):M_L_DQS_DN(17)
  U2D1 DV67 DDR4_DQS_DN<17> SKX_EXT_B_BGA1-IC,TBD   I172 @BASEBOARD_FAB2_LIB.BASEBOARD_FAB2(SCH_1):PAGE61
  J1A2   52 DQS17N SCONN288_H44441004_PIP-SCONN,HA    I66 @BASEBOARD_FAB2_LIB.BASEBOARD_FAB2(SCH_1):PAGE85
  J9L2   52 DQS17N SCONN288_H44441003_PIP-SCONN,HA   I100 @BASEBOARD_FAB2_LIB.BASEBOARD_FAB2(SCH_1):PAGE86

M_L_DQS_DN<1> @BASEBOARD_FAB2_LIB.BASEBOARD_FAB2(SCH_1):M_L_DQS_DN(1)
  U2D1 DA82 DDR4_DQS_DN<1> SKX_EXT_B_BGA1-IC,TBD   I172 @BASEBOARD_FAB2_LIB.BASEBOARD_FAB2(SCH_1):PAGE61
  J1A2  163  DQS1N SCONN288_H44441004_PIP-SCONN,HA    I66 @BASEBOARD_FAB2_LIB.BASEBOARD_FAB2(SCH_1):PAGE85
  J9L2  163  DQS1N SCONN288_H44441003_PIP-SCONN,HA   I100 @BASEBOARD_FAB2_LIB.BASEBOARD_FAB2(SCH_1):PAGE86

M_L_DQS_DN<2> @BASEBOARD_FAB2_LIB.BASEBOARD_FAB2(SCH_1):M_L_DQS_DN(2)
  U2D1 ED79 DDR4_DQS_DN<2> SKX_EXT_B_BGA1-IC,TBD   I172 @BASEBOARD_FAB2_LIB.BASEBOARD_FAB2(SCH_1):PAGE61
  J1A2  174  DQS2N SCONN288_H44441004_PIP-SCONN,HA    I66 @BASEBOARD_FAB2_LIB.BASEBOARD_FAB2(SCH_1):PAGE85
  J9L2  174  DQS2N SCONN288_H44441003_PIP-SCONN,HA   I100 @BASEBOARD_FAB2_LIB.BASEBOARD_FAB2(SCH_1):PAGE86

M_L_DQS_DN<3> @BASEBOARD_FAB2_LIB.BASEBOARD_FAB2(SCH_1):M_L_DQS_DN(3)
  U2D1 EF73 DDR4_DQS_DN<3> SKX_EXT_B_BGA1-IC,TBD   I172 @BASEBOARD_FAB2_LIB.BASEBOARD_FAB2(SCH_1):PAGE61
  J1A2  185  DQS3N SCONN288_H44441004_PIP-SCONN,HA    I66 @BASEBOARD_FAB2_LIB.BASEBOARD_FAB2(SCH_1):PAGE85
  J9L2  185  DQS3N SCONN288_H44441003_PIP-SCONN,HA   I100 @BASEBOARD_FAB2_LIB.BASEBOARD_FAB2(SCH_1):PAGE86

M_L_DQS_DN<4> @BASEBOARD_FAB2_LIB.BASEBOARD_FAB2(SCH_1):M_L_DQS_DN(4)
  U2D1 DV41 DDR4_DQS_DN<4> SKX_EXT_B_BGA1-IC,TBD   I172 @BASEBOARD_FAB2_LIB.BASEBOARD_FAB2(SCH_1):PAGE61
  J1A2  244  DQS4N SCONN288_H44441004_PIP-SCONN,HA    I66 @BASEBOARD_FAB2_LIB.BASEBOARD_FAB2(SCH_1):PAGE85
  J9L2  244  DQS4N SCONN288_H44441003_PIP-SCONN,HA   I100 @BASEBOARD_FAB2_LIB.BASEBOARD_FAB2(SCH_1):PAGE86

M_L_DQS_DN<5> @BASEBOARD_FAB2_LIB.BASEBOARD_FAB2(SCH_1):M_L_DQS_DN(5)
  U2D1 EE32 DDR4_DQS_DN<5> SKX_EXT_B_BGA1-IC,TBD   I172 @BASEBOARD_FAB2_LIB.BASEBOARD_FAB2(SCH_1):PAGE61
  J1A2  255  DQS5N SCONN288_H44441004_PIP-SCONN,HA    I66 @BASEBOARD_FAB2_LIB.BASEBOARD_FAB2(SCH_1):PAGE85
  J9L2  255  DQS5N SCONN288_H44441003_PIP-SCONN,HA   I100 @BASEBOARD_FAB2_LIB.BASEBOARD_FAB2(SCH_1):PAGE86

M_L_DQS_DN<6> @BASEBOARD_FAB2_LIB.BASEBOARD_FAB2(SCH_1):M_L_DQS_DN(6)
  U2D1 EE26 DDR4_DQS_DN<6> SKX_EXT_B_BGA1-IC,TBD   I172 @BASEBOARD_FAB2_LIB.BASEBOARD_FAB2(SCH_1):PAGE61
  J1A2  266  DQS6N SCONN288_H44441004_PIP-SCONN,HA    I66 @BASEBOARD_FAB2_LIB.BASEBOARD_FAB2(SCH_1):PAGE85
  J9L2  266  DQS6N SCONN288_H44441003_PIP-SCONN,HA   I100 @BASEBOARD_FAB2_LIB.BASEBOARD_FAB2(SCH_1):PAGE86

M_L_DQS_DN<7> @BASEBOARD_FAB2_LIB.BASEBOARD_FAB2(SCH_1):M_L_DQS_DN(7)
  U2D1 DL26 DDR4_DQS_DN<7> SKX_EXT_B_BGA1-IC,TBD   I172 @BASEBOARD_FAB2_LIB.BASEBOARD_FAB2(SCH_1):PAGE61
  J1A2  277  DQS7N SCONN288_H44441004_PIP-SCONN,HA    I66 @BASEBOARD_FAB2_LIB.BASEBOARD_FAB2(SCH_1):PAGE85
  J9L2  277  DQS7N SCONN288_H44441003_PIP-SCONN,HA   I100 @BASEBOARD_FAB2_LIB.BASEBOARD_FAB2(SCH_1):PAGE86

M_L_DQS_DN<8> @BASEBOARD_FAB2_LIB.BASEBOARD_FAB2(SCH_1):M_L_DQS_DN(8)
  U2D1 EB67 DDR4_DQS_DN<8> SKX_EXT_B_BGA1-IC,TBD   I172 @BASEBOARD_FAB2_LIB.BASEBOARD_FAB2(SCH_1):PAGE61
  J1A2  196  DQS8N SCONN288_H44441004_PIP-SCONN,HA    I66 @BASEBOARD_FAB2_LIB.BASEBOARD_FAB2(SCH_1):PAGE85
  J9L2  196  DQS8N SCONN288_H44441003_PIP-SCONN,HA   I100 @BASEBOARD_FAB2_LIB.BASEBOARD_FAB2(SCH_1):PAGE86

M_L_DQS_DN<9> @BASEBOARD_FAB2_LIB.BASEBOARD_FAB2(SCH_1):M_L_DQS_DN(9)
  U2D1 CN80 DDR4_DQS_DN<9> SKX_EXT_B_BGA1-IC,TBD   I172 @BASEBOARD_FAB2_LIB.BASEBOARD_FAB2(SCH_1):PAGE61
  J1A2    8  DQS9N SCONN288_H44441004_PIP-SCONN,HA    I66 @BASEBOARD_FAB2_LIB.BASEBOARD_FAB2(SCH_1):PAGE85
  J9L2    8  DQS9N SCONN288_H44441003_PIP-SCONN,HA   I100 @BASEBOARD_FAB2_LIB.BASEBOARD_FAB2(SCH_1):PAGE86

M_L_DQS_DP<0> @BASEBOARD_FAB2_LIB.BASEBOARD_FAB2(SCH_1):M_L_DQS_DP(0)
  U2D1 CM81 DDR4_DQS_DP<0> SKX_EXT_B_BGA1-IC,TBD   I172 @BASEBOARD_FAB2_LIB.BASEBOARD_FAB2(SCH_1):PAGE61
  J1A2  153  DQS0P SCONN288_H44441004_PIP-SCONN,HA    I66 @BASEBOARD_FAB2_LIB.BASEBOARD_FAB2(SCH_1):PAGE85
  J9L2  153  DQS0P SCONN288_H44441003_PIP-SCONN,HA   I100 @BASEBOARD_FAB2_LIB.BASEBOARD_FAB2(SCH_1):PAGE86

M_L_DQS_DP<10> @BASEBOARD_FAB2_LIB.BASEBOARD_FAB2(SCH_1):M_L_DQS_DP(10)
  U2D1 DD79 DDR4_DQS_DP<10> SKX_EXT_B_BGA1-IC,TBD   I172 @BASEBOARD_FAB2_LIB.BASEBOARD_FAB2(SCH_1):PAGE61
  J1A2   18 DQS10P SCONN288_H44441004_PIP-SCONN,HA    I66 @BASEBOARD_FAB2_LIB.BASEBOARD_FAB2(SCH_1):PAGE85
  J9L2   18 DQS10P SCONN288_H44441003_PIP-SCONN,HA   I100 @BASEBOARD_FAB2_LIB.BASEBOARD_FAB2(SCH_1):PAGE86

M_L_DQS_DP<11> @BASEBOARD_FAB2_LIB.BASEBOARD_FAB2(SCH_1):M_L_DQS_DP(11)
  U2D1 DV79 DDR4_DQS_DP<11> SKX_EXT_B_BGA1-IC,TBD   I172 @BASEBOARD_FAB2_LIB.BASEBOARD_FAB2(SCH_1):PAGE61
  J1A2   29 DQS11P SCONN288_H44441004_PIP-SCONN,HA    I66 @BASEBOARD_FAB2_LIB.BASEBOARD_FAB2(SCH_1):PAGE85
  J9L2   29 DQS11P SCONN288_H44441003_PIP-SCONN,HA   I100 @BASEBOARD_FAB2_LIB.BASEBOARD_FAB2(SCH_1):PAGE86

M_L_DQS_DP<12> @BASEBOARD_FAB2_LIB.BASEBOARD_FAB2(SCH_1):M_L_DQS_DP(12)
  U2D1 DY73 DDR4_DQS_DP<12> SKX_EXT_B_BGA1-IC,TBD   I172 @BASEBOARD_FAB2_LIB.BASEBOARD_FAB2(SCH_1):PAGE61
  J1A2   40 DQS12P SCONN288_H44441004_PIP-SCONN,HA    I66 @BASEBOARD_FAB2_LIB.BASEBOARD_FAB2(SCH_1):PAGE85
  J9L2   40 DQS12P SCONN288_H44441003_PIP-SCONN,HA   I100 @BASEBOARD_FAB2_LIB.BASEBOARD_FAB2(SCH_1):PAGE86

M_L_DQS_DP<13> @BASEBOARD_FAB2_LIB.BASEBOARD_FAB2(SCH_1):M_L_DQS_DP(13)
  U2D1 DM41 DDR4_DQS_DP<13> SKX_EXT_B_BGA1-IC,TBD   I172 @BASEBOARD_FAB2_LIB.BASEBOARD_FAB2(SCH_1):PAGE61
  J1A2   99 DQS13P SCONN288_H44441004_PIP-SCONN,HA    I66 @BASEBOARD_FAB2_LIB.BASEBOARD_FAB2(SCH_1):PAGE85
  J9L2   99 DQS13P SCONN288_H44441003_PIP-SCONN,HA   I100 @BASEBOARD_FAB2_LIB.BASEBOARD_FAB2(SCH_1):PAGE86

M_L_DQS_DP<14> @BASEBOARD_FAB2_LIB.BASEBOARD_FAB2(SCH_1):M_L_DQS_DP(14)
  U2D1 DW32 DDR4_DQS_DP<14> SKX_EXT_B_BGA1-IC,TBD   I172 @BASEBOARD_FAB2_LIB.BASEBOARD_FAB2(SCH_1):PAGE61
  J1A2  110 DQS14P SCONN288_H44441004_PIP-SCONN,HA    I66 @BASEBOARD_FAB2_LIB.BASEBOARD_FAB2(SCH_1):PAGE85
  J9L2  110 DQS14P SCONN288_H44441003_PIP-SCONN,HA   I100 @BASEBOARD_FAB2_LIB.BASEBOARD_FAB2(SCH_1):PAGE86

M_L_DQS_DP<15> @BASEBOARD_FAB2_LIB.BASEBOARD_FAB2(SCH_1):M_L_DQS_DP(15)
  U2D1 DW26 DDR4_DQS_DP<15> SKX_EXT_B_BGA1-IC,TBD   I172 @BASEBOARD_FAB2_LIB.BASEBOARD_FAB2(SCH_1):PAGE61
  J1A2  121 DQS15P SCONN288_H44441004_PIP-SCONN,HA    I66 @BASEBOARD_FAB2_LIB.BASEBOARD_FAB2(SCH_1):PAGE85
  J9L2  121 DQS15P SCONN288_H44441003_PIP-SCONN,HA   I100 @BASEBOARD_FAB2_LIB.BASEBOARD_FAB2(SCH_1):PAGE86

M_L_DQS_DP<16> @BASEBOARD_FAB2_LIB.BASEBOARD_FAB2(SCH_1):M_L_DQS_DP(16)
  U2D1 DE26 DDR4_DQS_DP<16> SKX_EXT_B_BGA1-IC,TBD   I172 @BASEBOARD_FAB2_LIB.BASEBOARD_FAB2(SCH_1):PAGE61
  J1A2  132 DQS16P SCONN288_H44441004_PIP-SCONN,HA    I66 @BASEBOARD_FAB2_LIB.BASEBOARD_FAB2(SCH_1):PAGE85
  J9L2  132 DQS16P SCONN288_H44441003_PIP-SCONN,HA   I100 @BASEBOARD_FAB2_LIB.BASEBOARD_FAB2(SCH_1):PAGE86

M_L_DQS_DP<17> @BASEBOARD_FAB2_LIB.BASEBOARD_FAB2(SCH_1):M_L_DQS_DP(17)
  U2D1 DT67 DDR4_DQS_DP<17> SKX_EXT_B_BGA1-IC,TBD   I172 @BASEBOARD_FAB2_LIB.BASEBOARD_FAB2(SCH_1):PAGE61
  J1A2   51 DQS17P SCONN288_H44441004_PIP-SCONN,HA    I66 @BASEBOARD_FAB2_LIB.BASEBOARD_FAB2(SCH_1):PAGE85
  J9L2   51 DQS17P SCONN288_H44441003_PIP-SCONN,HA   I100 @BASEBOARD_FAB2_LIB.BASEBOARD_FAB2(SCH_1):PAGE86

M_L_DQS_DP<1> @BASEBOARD_FAB2_LIB.BASEBOARD_FAB2(SCH_1):M_L_DQS_DP(1)
  U2D1 DB81 DDR4_DQS_DP<1> SKX_EXT_B_BGA1-IC,TBD   I172 @BASEBOARD_FAB2_LIB.BASEBOARD_FAB2(SCH_1):PAGE61
  J1A2  164  DQS1P SCONN288_H44441004_PIP-SCONN,HA    I66 @BASEBOARD_FAB2_LIB.BASEBOARD_FAB2(SCH_1):PAGE85
  J9L2  164  DQS1P SCONN288_H44441003_PIP-SCONN,HA   I100 @BASEBOARD_FAB2_LIB.BASEBOARD_FAB2(SCH_1):PAGE86

M_L_DQS_DP<2> @BASEBOARD_FAB2_LIB.BASEBOARD_FAB2(SCH_1):M_L_DQS_DP(2)
  U2D1 EB79 DDR4_DQS_DP<2> SKX_EXT_B_BGA1-IC,TBD   I172 @BASEBOARD_FAB2_LIB.BASEBOARD_FAB2(SCH_1):PAGE61
  J1A2  175  DQS2P SCONN288_H44441004_PIP-SCONN,HA    I66 @BASEBOARD_FAB2_LIB.BASEBOARD_FAB2(SCH_1):PAGE85
  J9L2  175  DQS2P SCONN288_H44441003_PIP-SCONN,HA   I100 @BASEBOARD_FAB2_LIB.BASEBOARD_FAB2(SCH_1):PAGE86

M_L_DQS_DP<3> @BASEBOARD_FAB2_LIB.BASEBOARD_FAB2(SCH_1):M_L_DQS_DP(3)
  U2D1 ED73 DDR4_DQS_DP<3> SKX_EXT_B_BGA1-IC,TBD   I172 @BASEBOARD_FAB2_LIB.BASEBOARD_FAB2(SCH_1):PAGE61
  J1A2  186  DQS3P SCONN288_H44441004_PIP-SCONN,HA    I66 @BASEBOARD_FAB2_LIB.BASEBOARD_FAB2(SCH_1):PAGE85
  J9L2  186  DQS3P SCONN288_H44441003_PIP-SCONN,HA   I100 @BASEBOARD_FAB2_LIB.BASEBOARD_FAB2(SCH_1):PAGE86

M_L_DQS_DP<4> @BASEBOARD_FAB2_LIB.BASEBOARD_FAB2(SCH_1):M_L_DQS_DP(4)
  U2D1 DT41 DDR4_DQS_DP<4> SKX_EXT_B_BGA1-IC,TBD   I172 @BASEBOARD_FAB2_LIB.BASEBOARD_FAB2(SCH_1):PAGE61
  J1A2  245  DQS4P SCONN288_H44441004_PIP-SCONN,HA    I66 @BASEBOARD_FAB2_LIB.BASEBOARD_FAB2(SCH_1):PAGE85
  J9L2  245  DQS4P SCONN288_H44441003_PIP-SCONN,HA   I100 @BASEBOARD_FAB2_LIB.BASEBOARD_FAB2(SCH_1):PAGE86

M_L_DQS_DP<5> @BASEBOARD_FAB2_LIB.BASEBOARD_FAB2(SCH_1):M_L_DQS_DP(5)
  U2D1 EC32 DDR4_DQS_DP<5> SKX_EXT_B_BGA1-IC,TBD   I172 @BASEBOARD_FAB2_LIB.BASEBOARD_FAB2(SCH_1):PAGE61
  J1A2  256  DQS5P SCONN288_H44441004_PIP-SCONN,HA    I66 @BASEBOARD_FAB2_LIB.BASEBOARD_FAB2(SCH_1):PAGE85
  J9L2  256  DQS5P SCONN288_H44441003_PIP-SCONN,HA   I100 @BASEBOARD_FAB2_LIB.BASEBOARD_FAB2(SCH_1):PAGE86

M_L_DQS_DP<6> @BASEBOARD_FAB2_LIB.BASEBOARD_FAB2(SCH_1):M_L_DQS_DP(6)
  U2D1 EC26 DDR4_DQS_DP<6> SKX_EXT_B_BGA1-IC,TBD   I172 @BASEBOARD_FAB2_LIB.BASEBOARD_FAB2(SCH_1):PAGE61
  J1A2  267  DQS6P SCONN288_H44441004_PIP-SCONN,HA    I66 @BASEBOARD_FAB2_LIB.BASEBOARD_FAB2(SCH_1):PAGE85
  J9L2  267  DQS6P SCONN288_H44441003_PIP-SCONN,HA   I100 @BASEBOARD_FAB2_LIB.BASEBOARD_FAB2(SCH_1):PAGE86

M_L_DQS_DP<7> @BASEBOARD_FAB2_LIB.BASEBOARD_FAB2(SCH_1):M_L_DQS_DP(7)
  U2D1 DJ26 DDR4_DQS_DP<7> SKX_EXT_B_BGA1-IC,TBD   I172 @BASEBOARD_FAB2_LIB.BASEBOARD_FAB2(SCH_1):PAGE61
  J1A2  278  DQS7P SCONN288_H44441004_PIP-SCONN,HA    I66 @BASEBOARD_FAB2_LIB.BASEBOARD_FAB2(SCH_1):PAGE85
  J9L2  278  DQS7P SCONN288_H44441003_PIP-SCONN,HA   I100 @BASEBOARD_FAB2_LIB.BASEBOARD_FAB2(SCH_1):PAGE86

M_L_DQS_DP<8> @BASEBOARD_FAB2_LIB.BASEBOARD_FAB2(SCH_1):M_L_DQS_DP(8)
  U2D1 DY67 DDR4_DQS_DP<8> SKX_EXT_B_BGA1-IC,TBD   I172 @BASEBOARD_FAB2_LIB.BASEBOARD_FAB2(SCH_1):PAGE61
  J1A2  197  DQS8P SCONN288_H44441004_PIP-SCONN,HA    I66 @BASEBOARD_FAB2_LIB.BASEBOARD_FAB2(SCH_1):PAGE85
  J9L2  197  DQS8P SCONN288_H44441003_PIP-SCONN,HA   I100 @BASEBOARD_FAB2_LIB.BASEBOARD_FAB2(SCH_1):PAGE86

M_L_DQS_DP<9> @BASEBOARD_FAB2_LIB.BASEBOARD_FAB2(SCH_1):M_L_DQS_DP(9)
  U2D1 CP79 DDR4_DQS_DP<9> SKX_EXT_B_BGA1-IC,TBD   I172 @BASEBOARD_FAB2_LIB.BASEBOARD_FAB2(SCH_1):PAGE61
  J1A2    7  DQS9P SCONN288_H44441004_PIP-SCONN,HA    I66 @BASEBOARD_FAB2_LIB.BASEBOARD_FAB2(SCH_1):PAGE85
  J9L2    7  DQS9P SCONN288_H44441003_PIP-SCONN,HA   I100 @BASEBOARD_FAB2_LIB.BASEBOARD_FAB2(SCH_1):PAGE86

M_L_ECC<0> @BASEBOARD_FAB2_LIB.BASEBOARD_FAB2(SCH_1):M_L_ECC(0)
  U2D1 DY69 DDR4_ECC<0> SKX_EXT_B_BGA1-IC,TBD   I172 @BASEBOARD_FAB2_LIB.BASEBOARD_FAB2(SCH_1):PAGE61
  J1A2  194  CB<1> SCONN288_H44441004_PIP-SCONN,HA   I111 @BASEBOARD_FAB2_LIB.BASEBOARD_FAB2(SCH_1):PAGE85
  J9L2   49  CB<0> SCONN288_H44441003_PIP-SCONN,HA    I12 @BASEBOARD_FAB2_LIB.BASEBOARD_FAB2(SCH_1):PAGE86

M_L_ECC<1> @BASEBOARD_FAB2_LIB.BASEBOARD_FAB2(SCH_1):M_L_ECC(1)
  U2D1 EA68 DDR4_ECC<1> SKX_EXT_B_BGA1-IC,TBD   I172 @BASEBOARD_FAB2_LIB.BASEBOARD_FAB2(SCH_1):PAGE61
  J1A2   49  CB<0> SCONN288_H44441004_PIP-SCONN,HA   I111 @BASEBOARD_FAB2_LIB.BASEBOARD_FAB2(SCH_1):PAGE85
  J9L2  194  CB<1> SCONN288_H44441003_PIP-SCONN,HA    I12 @BASEBOARD_FAB2_LIB.BASEBOARD_FAB2(SCH_1):PAGE86

M_L_ECC<2> @BASEBOARD_FAB2_LIB.BASEBOARD_FAB2(SCH_1):M_L_ECC(2)
  U2D1 DV65 DDR4_ECC<2> SKX_EXT_B_BGA1-IC,TBD   I172 @BASEBOARD_FAB2_LIB.BASEBOARD_FAB2(SCH_1):PAGE61
  J1A2  201  CB<3> SCONN288_H44441004_PIP-SCONN,HA   I111 @BASEBOARD_FAB2_LIB.BASEBOARD_FAB2(SCH_1):PAGE85
  J9L2   56  CB<2> SCONN288_H44441003_PIP-SCONN,HA    I12 @BASEBOARD_FAB2_LIB.BASEBOARD_FAB2(SCH_1):PAGE86

M_L_ECC<3> @BASEBOARD_FAB2_LIB.BASEBOARD_FAB2(SCH_1):M_L_ECC(3)
  U2D1 DY65 DDR4_ECC<3> SKX_EXT_B_BGA1-IC,TBD   I172 @BASEBOARD_FAB2_LIB.BASEBOARD_FAB2(SCH_1):PAGE61
  J1A2   56  CB<2> SCONN288_H44441004_PIP-SCONN,HA   I111 @BASEBOARD_FAB2_LIB.BASEBOARD_FAB2(SCH_1):PAGE85
  J9L2  201  CB<3> SCONN288_H44441003_PIP-SCONN,HA    I12 @BASEBOARD_FAB2_LIB.BASEBOARD_FAB2(SCH_1):PAGE86

M_L_ECC<4> @BASEBOARD_FAB2_LIB.BASEBOARD_FAB2(SCH_1):M_L_ECC(4)
  U2D1 DU68 DDR4_ECC<4> SKX_EXT_B_BGA1-IC,TBD   I172 @BASEBOARD_FAB2_LIB.BASEBOARD_FAB2(SCH_1):PAGE61
  J1A2  192  CB<5> SCONN288_H44441004_PIP-SCONN,HA   I111 @BASEBOARD_FAB2_LIB.BASEBOARD_FAB2(SCH_1):PAGE85
  J9L2   47  CB<4> SCONN288_H44441003_PIP-SCONN,HA    I12 @BASEBOARD_FAB2_LIB.BASEBOARD_FAB2(SCH_1):PAGE86

M_L_ECC<5> @BASEBOARD_FAB2_LIB.BASEBOARD_FAB2(SCH_1):M_L_ECC(5)
  U2D1 DV69 DDR4_ECC<5> SKX_EXT_B_BGA1-IC,TBD   I172 @BASEBOARD_FAB2_LIB.BASEBOARD_FAB2(SCH_1):PAGE61
  J1A2   47  CB<4> SCONN288_H44441004_PIP-SCONN,HA   I111 @BASEBOARD_FAB2_LIB.BASEBOARD_FAB2(SCH_1):PAGE85
  J9L2  192  CB<5> SCONN288_H44441003_PIP-SCONN,HA    I12 @BASEBOARD_FAB2_LIB.BASEBOARD_FAB2(SCH_1):PAGE86

M_L_ECC<6> @BASEBOARD_FAB2_LIB.BASEBOARD_FAB2(SCH_1):M_L_ECC(6)
  U2D1 DU66 DDR4_ECC<6> SKX_EXT_B_BGA1-IC,TBD   I172 @BASEBOARD_FAB2_LIB.BASEBOARD_FAB2(SCH_1):PAGE61
  J1A2  199  CB<7> SCONN288_H44441004_PIP-SCONN,HA   I111 @BASEBOARD_FAB2_LIB.BASEBOARD_FAB2(SCH_1):PAGE85
  J9L2   54  CB<6> SCONN288_H44441003_PIP-SCONN,HA    I12 @BASEBOARD_FAB2_LIB.BASEBOARD_FAB2(SCH_1):PAGE86

M_L_ECC<7> @BASEBOARD_FAB2_LIB.BASEBOARD_FAB2(SCH_1):M_L_ECC(7)
  U2D1 EA66 DDR4_ECC<7> SKX_EXT_B_BGA1-IC,TBD   I172 @BASEBOARD_FAB2_LIB.BASEBOARD_FAB2(SCH_1):PAGE61
  J1A2   54  CB<6> SCONN288_H44441004_PIP-SCONN,HA   I111 @BASEBOARD_FAB2_LIB.BASEBOARD_FAB2(SCH_1):PAGE85
  J9L2  199  CB<7> SCONN288_H44441003_PIP-SCONN,HA    I12 @BASEBOARD_FAB2_LIB.BASEBOARD_FAB2(SCH_1):PAGE86

M_L_MA<0> @BASEBOARD_FAB2_LIB.BASEBOARD_FAB2(SCH_1):M_L_MA(0)
  U2D1 DW52 DDR4_MA<0> SKX_EXT_B_BGA1-IC,TBD   I172 @BASEBOARD_FAB2_LIB.BASEBOARD_FAB2(SCH_1):PAGE61
  J1A2   79     A0 SCONN288_H44441004_PIP-SCONN,HA   I111 @BASEBOARD_FAB2_LIB.BASEBOARD_FAB2(SCH_1):PAGE85
  J9L2   79     A0 SCONN288_H44441003_PIP-SCONN,HA    I12 @BASEBOARD_FAB2_LIB.BASEBOARD_FAB2(SCH_1):PAGE86

M_L_MA<10> @BASEBOARD_FAB2_LIB.BASEBOARD_FAB2(SCH_1):M_L_MA(10)
  U2D1 DT55 DDR4_MA<10> SKX_EXT_B_BGA1-IC,TBD   I172 @BASEBOARD_FAB2_LIB.BASEBOARD_FAB2(SCH_1):PAGE61
  J1A2  225    A10 SCONN288_H44441004_PIP-SCONN,HA   I111 @BASEBOARD_FAB2_LIB.BASEBOARD_FAB2(SCH_1):PAGE85
  J9L2  225    A10 SCONN288_H44441003_PIP-SCONN,HA    I12 @BASEBOARD_FAB2_LIB.BASEBOARD_FAB2(SCH_1):PAGE86

M_L_MA<11> @BASEBOARD_FAB2_LIB.BASEBOARD_FAB2(SCH_1):M_L_MA(11)
  U2D1 DR60 DDR4_MA<11> SKX_EXT_B_BGA1-IC,TBD   I172 @BASEBOARD_FAB2_LIB.BASEBOARD_FAB2(SCH_1):PAGE61
  J1A2  210    A11 SCONN288_H44441004_PIP-SCONN,HA   I111 @BASEBOARD_FAB2_LIB.BASEBOARD_FAB2(SCH_1):PAGE85
  J9L2  210    A11 SCONN288_H44441003_PIP-SCONN,HA    I12 @BASEBOARD_FAB2_LIB.BASEBOARD_FAB2(SCH_1):PAGE86

M_L_MA<12> @BASEBOARD_FAB2_LIB.BASEBOARD_FAB2(SCH_1):M_L_MA(12)
  U2D1 DN60 DDR4_MA<12> SKX_EXT_B_BGA1-IC,TBD   I172 @BASEBOARD_FAB2_LIB.BASEBOARD_FAB2(SCH_1):PAGE61
  J1A2   65    A12 SCONN288_H44441004_PIP-SCONN,HA   I111 @BASEBOARD_FAB2_LIB.BASEBOARD_FAB2(SCH_1):PAGE85
  J9L2   65    A12 SCONN288_H44441003_PIP-SCONN,HA    I12 @BASEBOARD_FAB2_LIB.BASEBOARD_FAB2(SCH_1):PAGE86

M_L_MA<13> @BASEBOARD_FAB2_LIB.BASEBOARD_FAB2(SCH_1):M_L_MA(13)
  U2D1 DT51 DDR4_MA<13> SKX_EXT_B_BGA1-IC,TBD   I172 @BASEBOARD_FAB2_LIB.BASEBOARD_FAB2(SCH_1):PAGE61
  J1A2  232    A13 SCONN288_H44441004_PIP-SCONN,HA   I111 @BASEBOARD_FAB2_LIB.BASEBOARD_FAB2(SCH_1):PAGE85
  J9L2  232    A13 SCONN288_H44441003_PIP-SCONN,HA    I12 @BASEBOARD_FAB2_LIB.BASEBOARD_FAB2(SCH_1):PAGE86

M_L_MA<14> @BASEBOARD_FAB2_LIB.BASEBOARD_FAB2(SCH_1):M_L_MA(14)
  U2D1 DM51 DDR4_MA<14> SKX_EXT_B_BGA1-IC,TBD   I172 @BASEBOARD_FAB2_LIB.BASEBOARD_FAB2(SCH_1):PAGE61
  J1A2  228 A14_WE_N SCONN288_H44441004_PIP-SCONN,HA   I111 @BASEBOARD_FAB2_LIB.BASEBOARD_FAB2(SCH_1):PAGE85
  J9L2  228 A14_WE_N SCONN288_H44441003_PIP-SCONN,HA    I12 @BASEBOARD_FAB2_LIB.BASEBOARD_FAB2(SCH_1):PAGE86

M_L_MA<15> @BASEBOARD_FAB2_LIB.BASEBOARD_FAB2(SCH_1):M_L_MA(15)
  U2D1 DR52 DDR4_MA<15> SKX_EXT_B_BGA1-IC,TBD   I172 @BASEBOARD_FAB2_LIB.BASEBOARD_FAB2(SCH_1):PAGE61
  J1A2   86 A15_CAS_N SCONN288_H44441004_PIP-SCONN,HA   I111 @BASEBOARD_FAB2_LIB.BASEBOARD_FAB2(SCH_1):PAGE85
  J9L2   86 A15_CAS_N SCONN288_H44441003_PIP-SCONN,HA    I12 @BASEBOARD_FAB2_LIB.BASEBOARD_FAB2(SCH_1):PAGE86

M_L_MA<16> @BASEBOARD_FAB2_LIB.BASEBOARD_FAB2(SCH_1):M_L_MA(16)
  U2D1 DN52 DDR4_MA<16> SKX_EXT_B_BGA1-IC,TBD   I172 @BASEBOARD_FAB2_LIB.BASEBOARD_FAB2(SCH_1):PAGE61
  J1A2   82 A16_RAS_N SCONN288_H44441004_PIP-SCONN,HA   I111 @BASEBOARD_FAB2_LIB.BASEBOARD_FAB2(SCH_1):PAGE85
  J9L2   82 A16_RAS_N SCONN288_H44441003_PIP-SCONN,HA    I12 @BASEBOARD_FAB2_LIB.BASEBOARD_FAB2(SCH_1):PAGE86

M_L_MA<17> @BASEBOARD_FAB2_LIB.BASEBOARD_FAB2(SCH_1):M_L_MA(17)
  U2D1 DR48 DDR4_MA<17> SKX_EXT_B_BGA1-IC,TBD   I172 @BASEBOARD_FAB2_LIB.BASEBOARD_FAB2(SCH_1):PAGE61
  J1A2  234    A17 SCONN288_H44441004_PIP-SCONN,HA   I111 @BASEBOARD_FAB2_LIB.BASEBOARD_FAB2(SCH_1):PAGE85
  J9L2  234    A17 SCONN288_H44441003_PIP-SCONN,HA    I12 @BASEBOARD_FAB2_LIB.BASEBOARD_FAB2(SCH_1):PAGE86

M_L_MA<1> @BASEBOARD_FAB2_LIB.BASEBOARD_FAB2(SCH_1):M_L_MA(1)
  U2D1 DW58 DDR4_MA<1> SKX_EXT_B_BGA1-IC,TBD   I172 @BASEBOARD_FAB2_LIB.BASEBOARD_FAB2(SCH_1):PAGE61
  J1A2   72     A1 SCONN288_H44441004_PIP-SCONN,HA   I111 @BASEBOARD_FAB2_LIB.BASEBOARD_FAB2(SCH_1):PAGE85
  J9L2   72     A1 SCONN288_H44441003_PIP-SCONN,HA    I12 @BASEBOARD_FAB2_LIB.BASEBOARD_FAB2(SCH_1):PAGE86

M_L_MA<2> @BASEBOARD_FAB2_LIB.BASEBOARD_FAB2(SCH_1):M_L_MA(2)
  U2D1 DV57 DDR4_MA<2> SKX_EXT_B_BGA1-IC,TBD   I172 @BASEBOARD_FAB2_LIB.BASEBOARD_FAB2(SCH_1):PAGE61
  J1A2  216     A2 SCONN288_H44441004_PIP-SCONN,HA   I111 @BASEBOARD_FAB2_LIB.BASEBOARD_FAB2(SCH_1):PAGE85
  J9L2  216     A2 SCONN288_H44441003_PIP-SCONN,HA    I12 @BASEBOARD_FAB2_LIB.BASEBOARD_FAB2(SCH_1):PAGE86

M_L_MA<3> @BASEBOARD_FAB2_LIB.BASEBOARD_FAB2(SCH_1):M_L_MA(3)
  U2D1 DR58 DDR4_MA<3> SKX_EXT_B_BGA1-IC,TBD   I172 @BASEBOARD_FAB2_LIB.BASEBOARD_FAB2(SCH_1):PAGE61
  J1A2   71     A3 SCONN288_H44441004_PIP-SCONN,HA   I111 @BASEBOARD_FAB2_LIB.BASEBOARD_FAB2(SCH_1):PAGE85
  J9L2   71     A3 SCONN288_H44441003_PIP-SCONN,HA    I12 @BASEBOARD_FAB2_LIB.BASEBOARD_FAB2(SCH_1):PAGE86

M_L_MA<4> @BASEBOARD_FAB2_LIB.BASEBOARD_FAB2(SCH_1):M_L_MA(4)
  U2D1 DT59 DDR4_MA<4> SKX_EXT_B_BGA1-IC,TBD   I172 @BASEBOARD_FAB2_LIB.BASEBOARD_FAB2(SCH_1):PAGE61
  J1A2  214     A4 SCONN288_H44441004_PIP-SCONN,HA   I111 @BASEBOARD_FAB2_LIB.BASEBOARD_FAB2(SCH_1):PAGE85
  J9L2  214     A4 SCONN288_H44441003_PIP-SCONN,HA    I12 @BASEBOARD_FAB2_LIB.BASEBOARD_FAB2(SCH_1):PAGE86

M_L_MA<5> @BASEBOARD_FAB2_LIB.BASEBOARD_FAB2(SCH_1):M_L_MA(5)
  U2D1 DN58 DDR4_MA<5> SKX_EXT_B_BGA1-IC,TBD   I172 @BASEBOARD_FAB2_LIB.BASEBOARD_FAB2(SCH_1):PAGE61
  J1A2  213     A5 SCONN288_H44441004_PIP-SCONN,HA   I111 @BASEBOARD_FAB2_LIB.BASEBOARD_FAB2(SCH_1):PAGE85
  J9L2  213     A5 SCONN288_H44441003_PIP-SCONN,HA    I12 @BASEBOARD_FAB2_LIB.BASEBOARD_FAB2(SCH_1):PAGE86

M_L_MA<6> @BASEBOARD_FAB2_LIB.BASEBOARD_FAB2(SCH_1):M_L_MA(6)
  U2D1 DM59 DDR4_MA<6> SKX_EXT_B_BGA1-IC,TBD   I172 @BASEBOARD_FAB2_LIB.BASEBOARD_FAB2(SCH_1):PAGE61
  J1A2   69     A6 SCONN288_H44441004_PIP-SCONN,HA   I111 @BASEBOARD_FAB2_LIB.BASEBOARD_FAB2(SCH_1):PAGE85
  J9L2   69     A6 SCONN288_H44441003_PIP-SCONN,HA    I12 @BASEBOARD_FAB2_LIB.BASEBOARD_FAB2(SCH_1):PAGE86

M_L_MA<7> @BASEBOARD_FAB2_LIB.BASEBOARD_FAB2(SCH_1):M_L_MA(7)
  U2D1 DK61 DDR4_MA<7> SKX_EXT_B_BGA1-IC,TBD   I172 @BASEBOARD_FAB2_LIB.BASEBOARD_FAB2(SCH_1):PAGE61
  J1A2  211     A7 SCONN288_H44441004_PIP-SCONN,HA   I111 @BASEBOARD_FAB2_LIB.BASEBOARD_FAB2(SCH_1):PAGE85
  J9L2  211     A7 SCONN288_H44441003_PIP-SCONN,HA    I12 @BASEBOARD_FAB2_LIB.BASEBOARD_FAB2(SCH_1):PAGE86

M_L_MA<8> @BASEBOARD_FAB2_LIB.BASEBOARD_FAB2(SCH_1):M_L_MA(8)
  U2D1 DJ60 DDR4_MA<8> SKX_EXT_B_BGA1-IC,TBD   I172 @BASEBOARD_FAB2_LIB.BASEBOARD_FAB2(SCH_1):PAGE61
  J1A2   68     A8 SCONN288_H44441004_PIP-SCONN,HA   I111 @BASEBOARD_FAB2_LIB.BASEBOARD_FAB2(SCH_1):PAGE85
  J9L2   68     A8 SCONN288_H44441003_PIP-SCONN,HA    I12 @BASEBOARD_FAB2_LIB.BASEBOARD_FAB2(SCH_1):PAGE86

M_L_MA<9> @BASEBOARD_FAB2_LIB.BASEBOARD_FAB2(SCH_1):M_L_MA(9)
  U2D1 DV59 DDR4_MA<9> SKX_EXT_B_BGA1-IC,TBD   I172 @BASEBOARD_FAB2_LIB.BASEBOARD_FAB2(SCH_1):PAGE61
  J1A2   66     A9 SCONN288_H44441004_PIP-SCONN,HA   I111 @BASEBOARD_FAB2_LIB.BASEBOARD_FAB2(SCH_1):PAGE85
  J9L2   66     A9 SCONN288_H44441003_PIP-SCONN,HA    I12 @BASEBOARD_FAB2_LIB.BASEBOARD_FAB2(SCH_1):PAGE86

M_L_ODT<0> @BASEBOARD_FAB2_LIB.BASEBOARD_FAB2(SCH_1):M_L_ODT(0)
  U2D1 DR50 DDR4_ODT<0> SKX_EXT_B_BGA1-IC,TBD   I172 @BASEBOARD_FAB2_LIB.BASEBOARD_FAB2(SCH_1):PAGE61
  J1A2   87 ODT<0> SCONN288_H44441004_PIP-SCONN,HA   I111 @BASEBOARD_FAB2_LIB.BASEBOARD_FAB2(SCH_1):PAGE85

M_L_ODT<1> @BASEBOARD_FAB2_LIB.BASEBOARD_FAB2(SCH_1):M_L_ODT(1)
  U2D1 DN48 DDR4_ODT<1> SKX_EXT_B_BGA1-IC,TBD   I172 @BASEBOARD_FAB2_LIB.BASEBOARD_FAB2(SCH_1):PAGE61
  J1A2   91 ODT<1> SCONN288_H44441004_PIP-SCONN,HA   I111 @BASEBOARD_FAB2_LIB.BASEBOARD_FAB2(SCH_1):PAGE85

M_L_ODT<2> @BASEBOARD_FAB2_LIB.BASEBOARD_FAB2(SCH_1):M_L_ODT(2)
  U2D1 DT49 DDR4_ODT<2> SKX_EXT_B_BGA1-IC,TBD   I172 @BASEBOARD_FAB2_LIB.BASEBOARD_FAB2(SCH_1):PAGE61
  J9L2   87 ODT<0> SCONN288_H44441003_PIP-SCONN,HA    I12 @BASEBOARD_FAB2_LIB.BASEBOARD_FAB2(SCH_1):PAGE86

M_L_ODT<3> @BASEBOARD_FAB2_LIB.BASEBOARD_FAB2(SCH_1):M_L_ODT(3)
  U2D1 DM47 DDR4_ODT<3> SKX_EXT_B_BGA1-IC,TBD   I172 @BASEBOARD_FAB2_LIB.BASEBOARD_FAB2(SCH_1):PAGE61
  J9L2   91 ODT<1> SCONN288_H44441003_PIP-SCONN,HA    I12 @BASEBOARD_FAB2_LIB.BASEBOARD_FAB2(SCH_1):PAGE86

M_L_PAR @BASEBOARD_FAB2_LIB.BASEBOARD_FAB2(SCH_1):M_L_PAR
  U2D1 DV53 DDR4_PAR SKX_EXT_B_BGA1-IC,TBD   I172 @BASEBOARD_FAB2_LIB.BASEBOARD_FAB2(SCH_1):PAGE61
  J1A2  222    PAR SCONN288_H44441004_PIP-SCONN,HA   I111 @BASEBOARD_FAB2_LIB.BASEBOARD_FAB2(SCH_1):PAGE85
  J9L2  222    PAR SCONN288_H44441003_PIP-SCONN,HA    I12 @BASEBOARD_FAB2_LIB.BASEBOARD_FAB2(SCH_1):PAGE86

M_L_VREF @BASEBOARD_FAB2_LIB.BASEBOARD_FAB2(SCH_1):M_L_VREF
  J1A2  146 VREFCA SCONN288_H44441004_PIP-SCONN,HA   I111 @BASEBOARD_FAB2_LIB.BASEBOARD_FAB2(SCH_1):PAGE85
  C9L7    1      A CAP_A_0402V-0.01UF,25V,10%,X7RA   I181 @BASEBOARD_FAB2_LIB.BASEBOARD_FAB2(SCH_1):PAGE85
  J9L2  146 VREFCA SCONN288_H44441003_PIP-SCONN,HA    I12 @BASEBOARD_FAB2_LIB.BASEBOARD_FAB2(SCH_1):PAGE86
 C1A17    1      A CAP_A_0402V-0.01UF,25V,10%,X7RA   I182 @BASEBOARD_FAB2_LIB.BASEBOARD_FAB2(SCH_1):PAGE86
  R9L7    2      B RES_0402-1.00K,1%,1/16W,CHIP,GA    I22 @BASEBOARD_FAB2_LIB.BASEBOARD_FAB2(SCH_1):PAGE100
  R9L6    1      A RES_0402-1.00K,1%,1/16W,CHIP,GA    I24 @BASEBOARD_FAB2_LIB.BASEBOARD_FAB2(SCH_1):PAGE100
  R9L8    2      B RES_0402-2,1.0%,1/16W,CHIP,G21A    I29 @BASEBOARD_FAB2_LIB.BASEBOARD_FAB2(SCH_1):PAGE100

M_M_ACT_N @BASEBOARD_FAB2_LIB.BASEBOARD_FAB2(SCH_1):M_M_ACT_N
  U2D1 DC62 DDR5_ACT_N SKX_EXT_B_BGA1-IC,TBD   I172 @BASEBOARD_FAB2_LIB.BASEBOARD_FAB2(SCH_1):PAGE62
  J1A1   62  ACT_N SCONN288_H44441004_PIP-SCONN,HA   I186 @BASEBOARD_FAB2_LIB.BASEBOARD_FAB2(SCH_1):PAGE87
  J9L1   62  ACT_N SCONN288_H44441003_PIP-SCONN,HA   I111 @BASEBOARD_FAB2_LIB.BASEBOARD_FAB2(SCH_1):PAGE88

M_M_ALERT_N @BASEBOARD_FAB2_LIB.BASEBOARD_FAB2(SCH_1):M_M_ALERT_N
  U2D1 DD61 DDR5_ALERT_N SKX_EXT_B_BGA1-IC,TBD   I172 @BASEBOARD_FAB2_LIB.BASEBOARD_FAB2(SCH_1):PAGE62
  J1A1  208 ALERT_N SCONN288_H44441004_PIP-SCONN,HA   I186 @BASEBOARD_FAB2_LIB.BASEBOARD_FAB2(SCH_1):PAGE87
  J9L1  208 ALERT_N SCONN288_H44441003_PIP-SCONN,HA   I111 @BASEBOARD_FAB2_LIB.BASEBOARD_FAB2(SCH_1):PAGE88

M_M_BA<0> @BASEBOARD_FAB2_LIB.BASEBOARD_FAB2(SCH_1):M_M_BA(0)
  U2D1 DJ52 DDR5_BA<0> SKX_EXT_B_BGA1-IC,TBD   I172 @BASEBOARD_FAB2_LIB.BASEBOARD_FAB2(SCH_1):PAGE62
  J1A1   81  BA<0> SCONN288_H44441004_PIP-SCONN,HA   I186 @BASEBOARD_FAB2_LIB.BASEBOARD_FAB2(SCH_1):PAGE87
  J9L1   81  BA<0> SCONN288_H44441003_PIP-SCONN,HA   I111 @BASEBOARD_FAB2_LIB.BASEBOARD_FAB2(SCH_1):PAGE88

M_M_BA<1> @BASEBOARD_FAB2_LIB.BASEBOARD_FAB2(SCH_1):M_M_BA(1)
  U2D1 DC56 DDR5_BA<1> SKX_EXT_B_BGA1-IC,TBD   I172 @BASEBOARD_FAB2_LIB.BASEBOARD_FAB2(SCH_1):PAGE62
  J1A1  224  BA<1> SCONN288_H44441004_PIP-SCONN,HA   I186 @BASEBOARD_FAB2_LIB.BASEBOARD_FAB2(SCH_1):PAGE87
  J9L1  224  BA<1> SCONN288_H44441003_PIP-SCONN,HA   I111 @BASEBOARD_FAB2_LIB.BASEBOARD_FAB2(SCH_1):PAGE88

M_M_BG<0> @BASEBOARD_FAB2_LIB.BASEBOARD_FAB2(SCH_1):M_M_BG(0)
  U2D1 DA62 DDR5_BG<0> SKX_EXT_B_BGA1-IC,TBD   I172 @BASEBOARD_FAB2_LIB.BASEBOARD_FAB2(SCH_1):PAGE62
  J1A1   63  BG<0> SCONN288_H44441004_PIP-SCONN,HA   I186 @BASEBOARD_FAB2_LIB.BASEBOARD_FAB2(SCH_1):PAGE87
  J9L1   63  BG<0> SCONN288_H44441003_PIP-SCONN,HA   I111 @BASEBOARD_FAB2_LIB.BASEBOARD_FAB2(SCH_1):PAGE88

M_M_BG<1> @BASEBOARD_FAB2_LIB.BASEBOARD_FAB2(SCH_1):M_M_BG(1)
  U2D1 DF61 DDR5_BG<1> SKX_EXT_B_BGA1-IC,TBD   I172 @BASEBOARD_FAB2_LIB.BASEBOARD_FAB2(SCH_1):PAGE62
  J1A1  207  BG<1> SCONN288_H44441004_PIP-SCONN,HA   I186 @BASEBOARD_FAB2_LIB.BASEBOARD_FAB2(SCH_1):PAGE87
  J9L1  207  BG<1> SCONN288_H44441003_PIP-SCONN,HA   I111 @BASEBOARD_FAB2_LIB.BASEBOARD_FAB2(SCH_1):PAGE88

M_M_C<2> @BASEBOARD_FAB2_LIB.BASEBOARD_FAB2(SCH_1):M_M_C(2)
  U2D1 DF45 DDR5_CID<2> SKX_EXT_B_BGA1-IC,TBD   I172 @BASEBOARD_FAB2_LIB.BASEBOARD_FAB2(SCH_1):PAGE62
  J1A1  235   C<2> SCONN288_H44441004_PIP-SCONN,HA   I186 @BASEBOARD_FAB2_LIB.BASEBOARD_FAB2(SCH_1):PAGE87
  J9L1  235   C<2> SCONN288_H44441003_PIP-SCONN,HA   I111 @BASEBOARD_FAB2_LIB.BASEBOARD_FAB2(SCH_1):PAGE88

M_M_CKE<0> @BASEBOARD_FAB2_LIB.BASEBOARD_FAB2(SCH_1):M_M_CKE(0)
  U2D1 DG62 DDR5_CKE<0> SKX_EXT_B_BGA1-IC,TBD   I172 @BASEBOARD_FAB2_LIB.BASEBOARD_FAB2(SCH_1):PAGE62
  J1A1   60 CKE<0> SCONN288_H44441004_PIP-SCONN,HA   I186 @BASEBOARD_FAB2_LIB.BASEBOARD_FAB2(SCH_1):PAGE87

M_M_CKE<1> @BASEBOARD_FAB2_LIB.BASEBOARD_FAB2(SCH_1):M_M_CKE(1)
  U2D1 DD63 DDR5_CKE<1> SKX_EXT_B_BGA1-IC,TBD   I172 @BASEBOARD_FAB2_LIB.BASEBOARD_FAB2(SCH_1):PAGE62
  J1A1  203 CKE<1> SCONN288_H44441004_PIP-SCONN,HA   I186 @BASEBOARD_FAB2_LIB.BASEBOARD_FAB2(SCH_1):PAGE87

M_M_CKE<2> @BASEBOARD_FAB2_LIB.BASEBOARD_FAB2(SCH_1):M_M_CKE(2)
  U2D1 DK63 DDR5_CKE<2> SKX_EXT_B_BGA1-IC,TBD   I172 @BASEBOARD_FAB2_LIB.BASEBOARD_FAB2(SCH_1):PAGE62
  J9L1   60 CKE<0> SCONN288_H44441003_PIP-SCONN,HA   I111 @BASEBOARD_FAB2_LIB.BASEBOARD_FAB2(SCH_1):PAGE88

M_M_CKE<3> @BASEBOARD_FAB2_LIB.BASEBOARD_FAB2(SCH_1):M_M_CKE(3)
  U2D1 DF63 DDR5_CKE<3> SKX_EXT_B_BGA1-IC,TBD   I172 @BASEBOARD_FAB2_LIB.BASEBOARD_FAB2(SCH_1):PAGE62
  J9L1  203 CKE<1> SCONN288_H44441003_PIP-SCONN,HA   I111 @BASEBOARD_FAB2_LIB.BASEBOARD_FAB2(SCH_1):PAGE88

M_M_CLK_DN<0> @BASEBOARD_FAB2_LIB.BASEBOARD_FAB2(SCH_1):M_M_CLK_DN(0)
  U2D1 DK55 DDR5_CLK_DN<0> SKX_EXT_B_BGA1-IC,TBD   I172 @BASEBOARD_FAB2_LIB.BASEBOARD_FAB2(SCH_1):PAGE62
  J1A1   75   CK0N SCONN288_H44441004_PIP-SCONN,HA   I186 @BASEBOARD_FAB2_LIB.BASEBOARD_FAB2(SCH_1):PAGE87

M_M_CLK_DN<1> @BASEBOARD_FAB2_LIB.BASEBOARD_FAB2(SCH_1):M_M_CLK_DN(1)
  U2D1 DF55 DDR5_CLK_DN<1> SKX_EXT_B_BGA1-IC,TBD   I172 @BASEBOARD_FAB2_LIB.BASEBOARD_FAB2(SCH_1):PAGE62
  J1A1  219   CK1N SCONN288_H44441004_PIP-SCONN,HA   I186 @BASEBOARD_FAB2_LIB.BASEBOARD_FAB2(SCH_1):PAGE87

M_M_CLK_DN<2> @BASEBOARD_FAB2_LIB.BASEBOARD_FAB2(SCH_1):M_M_CLK_DN(2)
  U2D1 DK57 DDR5_CLK_DN<2> SKX_EXT_B_BGA1-IC,TBD   I172 @BASEBOARD_FAB2_LIB.BASEBOARD_FAB2(SCH_1):PAGE62
  J9L1   75   CK0N SCONN288_H44441003_PIP-SCONN,HA   I111 @BASEBOARD_FAB2_LIB.BASEBOARD_FAB2(SCH_1):PAGE88

M_M_CLK_DN<3> @BASEBOARD_FAB2_LIB.BASEBOARD_FAB2(SCH_1):M_M_CLK_DN(3)
  U2D1 DF57 DDR5_CLK_DN<3> SKX_EXT_B_BGA1-IC,TBD   I172 @BASEBOARD_FAB2_LIB.BASEBOARD_FAB2(SCH_1):PAGE62
  J9L1  219   CK1N SCONN288_H44441003_PIP-SCONN,HA   I111 @BASEBOARD_FAB2_LIB.BASEBOARD_FAB2(SCH_1):PAGE88

M_M_CLK_DP<0> @BASEBOARD_FAB2_LIB.BASEBOARD_FAB2(SCH_1):M_M_CLK_DP(0)
  U2D1 DJ54 DDR5_CLK_DP<0> SKX_EXT_B_BGA1-IC,TBD   I172 @BASEBOARD_FAB2_LIB.BASEBOARD_FAB2(SCH_1):PAGE62
  J1A1   74   CK0P SCONN288_H44441004_PIP-SCONN,HA   I186 @BASEBOARD_FAB2_LIB.BASEBOARD_FAB2(SCH_1):PAGE87

M_M_CLK_DP<1> @BASEBOARD_FAB2_LIB.BASEBOARD_FAB2(SCH_1):M_M_CLK_DP(1)
  U2D1 DG54 DDR5_CLK_DP<1> SKX_EXT_B_BGA1-IC,TBD   I172 @BASEBOARD_FAB2_LIB.BASEBOARD_FAB2(SCH_1):PAGE62
  J1A1  218   CK1P SCONN288_H44441004_PIP-SCONN,HA   I186 @BASEBOARD_FAB2_LIB.BASEBOARD_FAB2(SCH_1):PAGE87

M_M_CLK_DP<2> @BASEBOARD_FAB2_LIB.BASEBOARD_FAB2(SCH_1):M_M_CLK_DP(2)
  U2D1 DJ56 DDR5_CLK_DP<2> SKX_EXT_B_BGA1-IC,TBD   I172 @BASEBOARD_FAB2_LIB.BASEBOARD_FAB2(SCH_1):PAGE62
  J9L1   74   CK0P SCONN288_H44441003_PIP-SCONN,HA   I111 @BASEBOARD_FAB2_LIB.BASEBOARD_FAB2(SCH_1):PAGE88

M_M_CLK_DP<3> @BASEBOARD_FAB2_LIB.BASEBOARD_FAB2(SCH_1):M_M_CLK_DP(3)
  U2D1 DG56 DDR5_CLK_DP<3> SKX_EXT_B_BGA1-IC,TBD   I172 @BASEBOARD_FAB2_LIB.BASEBOARD_FAB2(SCH_1):PAGE62
  J9L1  218   CK1P SCONN288_H44441003_PIP-SCONN,HA   I111 @BASEBOARD_FAB2_LIB.BASEBOARD_FAB2(SCH_1):PAGE88

M_M_CPU_VREF @BASEBOARD_FAB2_LIB.BASEBOARD_FAB2(SCH_1):M_M_CPU_VREF
  U2D1 CV61 DDR5_CAVREF SKX_EXT_B_BGA1-IC,TBD   I172 @BASEBOARD_FAB2_LIB.BASEBOARD_FAB2(SCH_1):PAGE55
  R9L3    1      A RES_0402-2,1.0%,1/16W,CHIP,G21A    I45 @BASEBOARD_FAB2_LIB.BASEBOARD_FAB2(SCH_1):PAGE100
  C9L3    1      A CAP_A_0402V-0.01UF,25V,10%,X7RA    I46 @BASEBOARD_FAB2_LIB.BASEBOARD_FAB2(SCH_1):PAGE100

M_M_CS_N<0> @BASEBOARD_FAB2_LIB.BASEBOARD_FAB2(SCH_1):M_M_CS_N(0)
  U2D1 DK51 DDR5_CS_N<0> SKX_EXT_B_BGA1-IC,TBD   I172 @BASEBOARD_FAB2_LIB.BASEBOARD_FAB2(SCH_1):PAGE62
  J1A1   84   S0_N SCONN288_H44441004_PIP-SCONN,HA   I186 @BASEBOARD_FAB2_LIB.BASEBOARD_FAB2(SCH_1):PAGE87

M_M_CS_N<1> @BASEBOARD_FAB2_LIB.BASEBOARD_FAB2(SCH_1):M_M_CS_N(1)
  U2D1 DF49 DDR5_CS_N<1> SKX_EXT_B_BGA1-IC,TBD   I172 @BASEBOARD_FAB2_LIB.BASEBOARD_FAB2(SCH_1):PAGE62
  J1A1   89   S1_N SCONN288_H44441004_PIP-SCONN,HA   I186 @BASEBOARD_FAB2_LIB.BASEBOARD_FAB2(SCH_1):PAGE87

M_M_CS_N<2> @BASEBOARD_FAB2_LIB.BASEBOARD_FAB2(SCH_1):M_M_CS_N(2)
  U2D1 DJ46 DDR5_CS_N<2> SKX_EXT_B_BGA1-IC,TBD   I172 @BASEBOARD_FAB2_LIB.BASEBOARD_FAB2(SCH_1):PAGE62
  J1A1   93 S2_N_C<0> SCONN288_H44441004_PIP-SCONN,HA   I186 @BASEBOARD_FAB2_LIB.BASEBOARD_FAB2(SCH_1):PAGE87

M_M_CS_N<3> @BASEBOARD_FAB2_LIB.BASEBOARD_FAB2(SCH_1):M_M_CS_N(3)
  U2D1 DG46 DDR5_CS_N<3> SKX_EXT_B_BGA1-IC,TBD   I172 @BASEBOARD_FAB2_LIB.BASEBOARD_FAB2(SCH_1):PAGE62
  J1A1  237 S3_N_C<1> SCONN288_H44441004_PIP-SCONN,HA   I186 @BASEBOARD_FAB2_LIB.BASEBOARD_FAB2(SCH_1):PAGE87

M_M_CS_N<4> @BASEBOARD_FAB2_LIB.BASEBOARD_FAB2(SCH_1):M_M_CS_N(4)
  U2D1 DF51 DDR5_CS_N<4> SKX_EXT_B_BGA1-IC,TBD   I172 @BASEBOARD_FAB2_LIB.BASEBOARD_FAB2(SCH_1):PAGE62
  J9L1   84   S0_N SCONN288_H44441003_PIP-SCONN,HA   I111 @BASEBOARD_FAB2_LIB.BASEBOARD_FAB2(SCH_1):PAGE88

M_M_CS_N<5> @BASEBOARD_FAB2_LIB.BASEBOARD_FAB2(SCH_1):M_M_CS_N(5)
  U2D1 DJ48 DDR5_CS_N<5> SKX_EXT_B_BGA1-IC,TBD   I172 @BASEBOARD_FAB2_LIB.BASEBOARD_FAB2(SCH_1):PAGE62
  J9L1   89   S1_N SCONN288_H44441003_PIP-SCONN,HA   I111 @BASEBOARD_FAB2_LIB.BASEBOARD_FAB2(SCH_1):PAGE88

M_M_CS_N<6> @BASEBOARD_FAB2_LIB.BASEBOARD_FAB2(SCH_1):M_M_CS_N(6)
  U2D1 DM45 DDR5_CS_N<6> SKX_EXT_B_BGA1-IC,TBD   I172 @BASEBOARD_FAB2_LIB.BASEBOARD_FAB2(SCH_1):PAGE62
  J9L1   93 S2_N_C<0> SCONN288_H44441003_PIP-SCONN,HA   I111 @BASEBOARD_FAB2_LIB.BASEBOARD_FAB2(SCH_1):PAGE88

M_M_CS_N<7> @BASEBOARD_FAB2_LIB.BASEBOARD_FAB2(SCH_1):M_M_CS_N(7)
  U2D1 DK45 DDR5_CS_N<7> SKX_EXT_B_BGA1-IC,TBD   I172 @BASEBOARD_FAB2_LIB.BASEBOARD_FAB2(SCH_1):PAGE62
  J9L1  237 S3_N_C<1> SCONN288_H44441003_PIP-SCONN,HA   I111 @BASEBOARD_FAB2_LIB.BASEBOARD_FAB2(SCH_1):PAGE88

M_M_DQ<0> @BASEBOARD_FAB2_LIB.BASEBOARD_FAB2(SCH_1):M_M_DQ(0)
  U2D1 CR74 DDR5_DQ<0> SKX_EXT_B_BGA1-IC,TBD   I172 @BASEBOARD_FAB2_LIB.BASEBOARD_FAB2(SCH_1):PAGE62
  J1A1  150  DQ<1> SCONN288_H44441004_PIP-SCONN,HA   I186 @BASEBOARD_FAB2_LIB.BASEBOARD_FAB2(SCH_1):PAGE87
  J9L1    5  DQ<0> SCONN288_H44441003_PIP-SCONN,HA   I111 @BASEBOARD_FAB2_LIB.BASEBOARD_FAB2(SCH_1):PAGE88

M_M_DQ<10> @BASEBOARD_FAB2_LIB.BASEBOARD_FAB2(SCH_1):M_M_DQ(10)
  U2D1 DH75 DDR5_DQ<10> SKX_EXT_B_BGA1-IC,TBD   I172 @BASEBOARD_FAB2_LIB.BASEBOARD_FAB2(SCH_1):PAGE62
  J1A1  168 DQ<11> SCONN288_H44441004_PIP-SCONN,HA   I186 @BASEBOARD_FAB2_LIB.BASEBOARD_FAB2(SCH_1):PAGE87
  J9L1   23 DQ<10> SCONN288_H44441003_PIP-SCONN,HA   I111 @BASEBOARD_FAB2_LIB.BASEBOARD_FAB2(SCH_1):PAGE88

M_M_DQ<11> @BASEBOARD_FAB2_LIB.BASEBOARD_FAB2(SCH_1):M_M_DQ(11)
  U2D1 DJ76 DDR5_DQ<11> SKX_EXT_B_BGA1-IC,TBD   I172 @BASEBOARD_FAB2_LIB.BASEBOARD_FAB2(SCH_1):PAGE62
  J1A1   23 DQ<10> SCONN288_H44441004_PIP-SCONN,HA   I186 @BASEBOARD_FAB2_LIB.BASEBOARD_FAB2(SCH_1):PAGE87
  J9L1  168 DQ<11> SCONN288_H44441003_PIP-SCONN,HA   I111 @BASEBOARD_FAB2_LIB.BASEBOARD_FAB2(SCH_1):PAGE88

M_M_DQ<12> @BASEBOARD_FAB2_LIB.BASEBOARD_FAB2(SCH_1):M_M_DQ(12)
  U2D1 DC74 DDR5_DQ<12> SKX_EXT_B_BGA1-IC,TBD   I172 @BASEBOARD_FAB2_LIB.BASEBOARD_FAB2(SCH_1):PAGE62
  J1A1  159 DQ<13> SCONN288_H44441004_PIP-SCONN,HA   I186 @BASEBOARD_FAB2_LIB.BASEBOARD_FAB2(SCH_1):PAGE87
  J9L1   14 DQ<12> SCONN288_H44441003_PIP-SCONN,HA   I111 @BASEBOARD_FAB2_LIB.BASEBOARD_FAB2(SCH_1):PAGE88

M_M_DQ<13> @BASEBOARD_FAB2_LIB.BASEBOARD_FAB2(SCH_1):M_M_DQ(13)
  U2D1 DB75 DDR5_DQ<13> SKX_EXT_B_BGA1-IC,TBD   I172 @BASEBOARD_FAB2_LIB.BASEBOARD_FAB2(SCH_1):PAGE62
  J1A1   14 DQ<12> SCONN288_H44441004_PIP-SCONN,HA   I186 @BASEBOARD_FAB2_LIB.BASEBOARD_FAB2(SCH_1):PAGE87
  J9L1  159 DQ<13> SCONN288_H44441003_PIP-SCONN,HA   I111 @BASEBOARD_FAB2_LIB.BASEBOARD_FAB2(SCH_1):PAGE88

M_M_DQ<14> @BASEBOARD_FAB2_LIB.BASEBOARD_FAB2(SCH_1):M_M_DQ(14)
  U2D1 DF77 DDR5_DQ<14> SKX_EXT_B_BGA1-IC,TBD   I172 @BASEBOARD_FAB2_LIB.BASEBOARD_FAB2(SCH_1):PAGE62
  J1A1  166 DQ<15> SCONN288_H44441004_PIP-SCONN,HA   I186 @BASEBOARD_FAB2_LIB.BASEBOARD_FAB2(SCH_1):PAGE87
  J9L1   21 DQ<14> SCONN288_H44441003_PIP-SCONN,HA   I111 @BASEBOARD_FAB2_LIB.BASEBOARD_FAB2(SCH_1):PAGE88

M_M_DQ<15> @BASEBOARD_FAB2_LIB.BASEBOARD_FAB2(SCH_1):M_M_DQ(15)
  U2D1 DH77 DDR5_DQ<15> SKX_EXT_B_BGA1-IC,TBD   I172 @BASEBOARD_FAB2_LIB.BASEBOARD_FAB2(SCH_1):PAGE62
  J1A1   21 DQ<14> SCONN288_H44441004_PIP-SCONN,HA   I186 @BASEBOARD_FAB2_LIB.BASEBOARD_FAB2(SCH_1):PAGE87
  J9L1  166 DQ<15> SCONN288_H44441003_PIP-SCONN,HA   I111 @BASEBOARD_FAB2_LIB.BASEBOARD_FAB2(SCH_1):PAGE88

M_M_DQ<16> @BASEBOARD_FAB2_LIB.BASEBOARD_FAB2(SCH_1):M_M_DQ(16)
  U2D1 DG70 DDR5_DQ<16> SKX_EXT_B_BGA1-IC,TBD   I172 @BASEBOARD_FAB2_LIB.BASEBOARD_FAB2(SCH_1):PAGE62
  J1A1  172 DQ<17> SCONN288_H44441004_PIP-SCONN,HA   I186 @BASEBOARD_FAB2_LIB.BASEBOARD_FAB2(SCH_1):PAGE87
  J9L1   27 DQ<16> SCONN288_H44441003_PIP-SCONN,HA   I111 @BASEBOARD_FAB2_LIB.BASEBOARD_FAB2(SCH_1):PAGE88

M_M_DQ<17> @BASEBOARD_FAB2_LIB.BASEBOARD_FAB2(SCH_1):M_M_DQ(17)
  U2D1 DJ72 DDR5_DQ<17> SKX_EXT_B_BGA1-IC,TBD   I172 @BASEBOARD_FAB2_LIB.BASEBOARD_FAB2(SCH_1):PAGE62
  J1A1   27 DQ<16> SCONN288_H44441004_PIP-SCONN,HA   I186 @BASEBOARD_FAB2_LIB.BASEBOARD_FAB2(SCH_1):PAGE87
  J9L1  172 DQ<17> SCONN288_H44441003_PIP-SCONN,HA   I111 @BASEBOARD_FAB2_LIB.BASEBOARD_FAB2(SCH_1):PAGE88

M_M_DQ<18> @BASEBOARD_FAB2_LIB.BASEBOARD_FAB2(SCH_1):M_M_DQ(18)
  U2D1 DM69 DDR5_DQ<18> SKX_EXT_B_BGA1-IC,TBD   I172 @BASEBOARD_FAB2_LIB.BASEBOARD_FAB2(SCH_1):PAGE62
  J1A1  179 DQ<19> SCONN288_H44441004_PIP-SCONN,HA   I186 @BASEBOARD_FAB2_LIB.BASEBOARD_FAB2(SCH_1):PAGE87
  J9L1   34 DQ<18> SCONN288_H44441003_PIP-SCONN,HA   I111 @BASEBOARD_FAB2_LIB.BASEBOARD_FAB2(SCH_1):PAGE88

M_M_DQ<19> @BASEBOARD_FAB2_LIB.BASEBOARD_FAB2(SCH_1):M_M_DQ(19)
  U2D1 DN70 DDR5_DQ<19> SKX_EXT_B_BGA1-IC,TBD   I172 @BASEBOARD_FAB2_LIB.BASEBOARD_FAB2(SCH_1):PAGE62
  J1A1   34 DQ<18> SCONN288_H44441004_PIP-SCONN,HA   I186 @BASEBOARD_FAB2_LIB.BASEBOARD_FAB2(SCH_1):PAGE87
  J9L1  179 DQ<19> SCONN288_H44441003_PIP-SCONN,HA   I111 @BASEBOARD_FAB2_LIB.BASEBOARD_FAB2(SCH_1):PAGE88

M_M_DQ<1> @BASEBOARD_FAB2_LIB.BASEBOARD_FAB2(SCH_1):M_M_DQ(1)
  U2D1 CN76 DDR5_DQ<1> SKX_EXT_B_BGA1-IC,TBD   I172 @BASEBOARD_FAB2_LIB.BASEBOARD_FAB2(SCH_1):PAGE62
  J1A1    5  DQ<0> SCONN288_H44441004_PIP-SCONN,HA   I186 @BASEBOARD_FAB2_LIB.BASEBOARD_FAB2(SCH_1):PAGE87
  J9L1  150  DQ<1> SCONN288_H44441003_PIP-SCONN,HA   I111 @BASEBOARD_FAB2_LIB.BASEBOARD_FAB2(SCH_1):PAGE88

M_M_DQ<20> @BASEBOARD_FAB2_LIB.BASEBOARD_FAB2(SCH_1):M_M_DQ(20)
  U2D1 DF71 DDR5_DQ<20> SKX_EXT_B_BGA1-IC,TBD   I172 @BASEBOARD_FAB2_LIB.BASEBOARD_FAB2(SCH_1):PAGE62
  J1A1  170 DQ<21> SCONN288_H44441004_PIP-SCONN,HA   I186 @BASEBOARD_FAB2_LIB.BASEBOARD_FAB2(SCH_1):PAGE87
  J9L1   25 DQ<20> SCONN288_H44441003_PIP-SCONN,HA   I111 @BASEBOARD_FAB2_LIB.BASEBOARD_FAB2(SCH_1):PAGE88

M_M_DQ<21> @BASEBOARD_FAB2_LIB.BASEBOARD_FAB2(SCH_1):M_M_DQ(21)
  U2D1 DG72 DDR5_DQ<21> SKX_EXT_B_BGA1-IC,TBD   I172 @BASEBOARD_FAB2_LIB.BASEBOARD_FAB2(SCH_1):PAGE62
  J1A1   25 DQ<20> SCONN288_H44441004_PIP-SCONN,HA   I186 @BASEBOARD_FAB2_LIB.BASEBOARD_FAB2(SCH_1):PAGE87
  J9L1  170 DQ<21> SCONN288_H44441003_PIP-SCONN,HA   I111 @BASEBOARD_FAB2_LIB.BASEBOARD_FAB2(SCH_1):PAGE88

M_M_DQ<22> @BASEBOARD_FAB2_LIB.BASEBOARD_FAB2(SCH_1):M_M_DQ(22)
  U2D1 DK69 DDR5_DQ<22> SKX_EXT_B_BGA1-IC,TBD   I172 @BASEBOARD_FAB2_LIB.BASEBOARD_FAB2(SCH_1):PAGE62
  J1A1  177 DQ<23> SCONN288_H44441004_PIP-SCONN,HA   I186 @BASEBOARD_FAB2_LIB.BASEBOARD_FAB2(SCH_1):PAGE87
  J9L1   32 DQ<22> SCONN288_H44441003_PIP-SCONN,HA   I111 @BASEBOARD_FAB2_LIB.BASEBOARD_FAB2(SCH_1):PAGE88

M_M_DQ<23> @BASEBOARD_FAB2_LIB.BASEBOARD_FAB2(SCH_1):M_M_DQ(23)
  U2D1 DM71 DDR5_DQ<23> SKX_EXT_B_BGA1-IC,TBD   I172 @BASEBOARD_FAB2_LIB.BASEBOARD_FAB2(SCH_1):PAGE62
  J1A1   32 DQ<22> SCONN288_H44441004_PIP-SCONN,HA   I186 @BASEBOARD_FAB2_LIB.BASEBOARD_FAB2(SCH_1):PAGE87
  J9L1  177 DQ<23> SCONN288_H44441003_PIP-SCONN,HA   I111 @BASEBOARD_FAB2_LIB.BASEBOARD_FAB2(SCH_1):PAGE88

M_M_DQ<24> @BASEBOARD_FAB2_LIB.BASEBOARD_FAB2(SCH_1):M_M_DQ(24)
  U2D1 CN66 DDR5_DQ<24> SKX_EXT_B_BGA1-IC,TBD   I172 @BASEBOARD_FAB2_LIB.BASEBOARD_FAB2(SCH_1):PAGE62
  J1A1  183 DQ<25> SCONN288_H44441004_PIP-SCONN,HA   I186 @BASEBOARD_FAB2_LIB.BASEBOARD_FAB2(SCH_1):PAGE87
  J9L1   38 DQ<24> SCONN288_H44441003_PIP-SCONN,HA   I111 @BASEBOARD_FAB2_LIB.BASEBOARD_FAB2(SCH_1):PAGE88

M_M_DQ<25> @BASEBOARD_FAB2_LIB.BASEBOARD_FAB2(SCH_1):M_M_DQ(25)
  U2D1 CU66 DDR5_DQ<25> SKX_EXT_B_BGA1-IC,TBD   I172 @BASEBOARD_FAB2_LIB.BASEBOARD_FAB2(SCH_1):PAGE62
  J1A1   38 DQ<24> SCONN288_H44441004_PIP-SCONN,HA   I186 @BASEBOARD_FAB2_LIB.BASEBOARD_FAB2(SCH_1):PAGE87
  J9L1  183 DQ<25> SCONN288_H44441003_PIP-SCONN,HA   I111 @BASEBOARD_FAB2_LIB.BASEBOARD_FAB2(SCH_1):PAGE88

M_M_DQ<26> @BASEBOARD_FAB2_LIB.BASEBOARD_FAB2(SCH_1):M_M_DQ(26)
  U2D1 CP63 DDR5_DQ<26> SKX_EXT_B_BGA1-IC,TBD   I172 @BASEBOARD_FAB2_LIB.BASEBOARD_FAB2(SCH_1):PAGE62
  J1A1  190 DQ<27> SCONN288_H44441004_PIP-SCONN,HA   I186 @BASEBOARD_FAB2_LIB.BASEBOARD_FAB2(SCH_1):PAGE87
  J9L1   45 DQ<26> SCONN288_H44441003_PIP-SCONN,HA   I111 @BASEBOARD_FAB2_LIB.BASEBOARD_FAB2(SCH_1):PAGE88

M_M_DQ<27> @BASEBOARD_FAB2_LIB.BASEBOARD_FAB2(SCH_1):M_M_DQ(27)
  U2D1 CT63 DDR5_DQ<27> SKX_EXT_B_BGA1-IC,TBD   I172 @BASEBOARD_FAB2_LIB.BASEBOARD_FAB2(SCH_1):PAGE62
  J1A1   45 DQ<26> SCONN288_H44441004_PIP-SCONN,HA   I186 @BASEBOARD_FAB2_LIB.BASEBOARD_FAB2(SCH_1):PAGE87
  J9L1  190 DQ<27> SCONN288_H44441003_PIP-SCONN,HA   I111 @BASEBOARD_FAB2_LIB.BASEBOARD_FAB2(SCH_1):PAGE88

M_M_DQ<28> @BASEBOARD_FAB2_LIB.BASEBOARD_FAB2(SCH_1):M_M_DQ(28)
  U2D1 CP67 DDR5_DQ<28> SKX_EXT_B_BGA1-IC,TBD   I172 @BASEBOARD_FAB2_LIB.BASEBOARD_FAB2(SCH_1):PAGE62
  J1A1  181 DQ<29> SCONN288_H44441004_PIP-SCONN,HA   I186 @BASEBOARD_FAB2_LIB.BASEBOARD_FAB2(SCH_1):PAGE87
  J9L1   36 DQ<28> SCONN288_H44441003_PIP-SCONN,HA   I111 @BASEBOARD_FAB2_LIB.BASEBOARD_FAB2(SCH_1):PAGE88

M_M_DQ<29> @BASEBOARD_FAB2_LIB.BASEBOARD_FAB2(SCH_1):M_M_DQ(29)
  U2D1 CT67 DDR5_DQ<29> SKX_EXT_B_BGA1-IC,TBD   I172 @BASEBOARD_FAB2_LIB.BASEBOARD_FAB2(SCH_1):PAGE62
  J1A1   36 DQ<28> SCONN288_H44441004_PIP-SCONN,HA   I186 @BASEBOARD_FAB2_LIB.BASEBOARD_FAB2(SCH_1):PAGE87
  J9L1  181 DQ<29> SCONN288_H44441003_PIP-SCONN,HA   I111 @BASEBOARD_FAB2_LIB.BASEBOARD_FAB2(SCH_1):PAGE88

M_M_DQ<2> @BASEBOARD_FAB2_LIB.BASEBOARD_FAB2(SCH_1):M_M_DQ(2)
  U2D1 CW76 DDR5_DQ<2> SKX_EXT_B_BGA1-IC,TBD   I172 @BASEBOARD_FAB2_LIB.BASEBOARD_FAB2(SCH_1):PAGE62
  J1A1  157  DQ<3> SCONN288_H44441004_PIP-SCONN,HA   I186 @BASEBOARD_FAB2_LIB.BASEBOARD_FAB2(SCH_1):PAGE87
  J9L1   12  DQ<2> SCONN288_H44441003_PIP-SCONN,HA   I111 @BASEBOARD_FAB2_LIB.BASEBOARD_FAB2(SCH_1):PAGE88

M_M_DQ<30> @BASEBOARD_FAB2_LIB.BASEBOARD_FAB2(SCH_1):M_M_DQ(30)
  U2D1 CN64 DDR5_DQ<30> SKX_EXT_B_BGA1-IC,TBD   I172 @BASEBOARD_FAB2_LIB.BASEBOARD_FAB2(SCH_1):PAGE62
  J1A1  188 DQ<31> SCONN288_H44441004_PIP-SCONN,HA   I186 @BASEBOARD_FAB2_LIB.BASEBOARD_FAB2(SCH_1):PAGE87
  J9L1   43 DQ<30> SCONN288_H44441003_PIP-SCONN,HA   I111 @BASEBOARD_FAB2_LIB.BASEBOARD_FAB2(SCH_1):PAGE88

M_M_DQ<31> @BASEBOARD_FAB2_LIB.BASEBOARD_FAB2(SCH_1):M_M_DQ(31)
  U2D1 CU64 DDR5_DQ<31> SKX_EXT_B_BGA1-IC,TBD   I172 @BASEBOARD_FAB2_LIB.BASEBOARD_FAB2(SCH_1):PAGE62
  J1A1   43 DQ<30> SCONN288_H44441004_PIP-SCONN,HA   I186 @BASEBOARD_FAB2_LIB.BASEBOARD_FAB2(SCH_1):PAGE87
  J9L1  188 DQ<31> SCONN288_H44441003_PIP-SCONN,HA   I111 @BASEBOARD_FAB2_LIB.BASEBOARD_FAB2(SCH_1):PAGE88

M_M_DQ<32> @BASEBOARD_FAB2_LIB.BASEBOARD_FAB2(SCH_1):M_M_DQ(32)
  U2D1 DD41 DDR5_DQ<32> SKX_EXT_B_BGA1-IC,TBD   I172 @BASEBOARD_FAB2_LIB.BASEBOARD_FAB2(SCH_1):PAGE62
  J1A1  242 DQ<33> SCONN288_H44441004_PIP-SCONN,HA   I186 @BASEBOARD_FAB2_LIB.BASEBOARD_FAB2(SCH_1):PAGE87
  J9L1   97 DQ<32> SCONN288_H44441003_PIP-SCONN,HA   I111 @BASEBOARD_FAB2_LIB.BASEBOARD_FAB2(SCH_1):PAGE88

M_M_DQ<33> @BASEBOARD_FAB2_LIB.BASEBOARD_FAB2(SCH_1):M_M_DQ(33)
  U2D1 DG42 DDR5_DQ<33> SKX_EXT_B_BGA1-IC,TBD   I172 @BASEBOARD_FAB2_LIB.BASEBOARD_FAB2(SCH_1):PAGE62
  J1A1   97 DQ<32> SCONN288_H44441004_PIP-SCONN,HA   I186 @BASEBOARD_FAB2_LIB.BASEBOARD_FAB2(SCH_1):PAGE87
  J9L1  242 DQ<33> SCONN288_H44441003_PIP-SCONN,HA   I111 @BASEBOARD_FAB2_LIB.BASEBOARD_FAB2(SCH_1):PAGE88

M_M_DQ<34> @BASEBOARD_FAB2_LIB.BASEBOARD_FAB2(SCH_1):M_M_DQ(34)
  U2D1 DE38 DDR5_DQ<34> SKX_EXT_B_BGA1-IC,TBD   I172 @BASEBOARD_FAB2_LIB.BASEBOARD_FAB2(SCH_1):PAGE62
  J1A1  249 DQ<35> SCONN288_H44441004_PIP-SCONN,HA   I186 @BASEBOARD_FAB2_LIB.BASEBOARD_FAB2(SCH_1):PAGE87
  J9L1  104 DQ<34> SCONN288_H44441003_PIP-SCONN,HA   I111 @BASEBOARD_FAB2_LIB.BASEBOARD_FAB2(SCH_1):PAGE88

M_M_DQ<35> @BASEBOARD_FAB2_LIB.BASEBOARD_FAB2(SCH_1):M_M_DQ(35)
  U2D1 DG38 DDR5_DQ<35> SKX_EXT_B_BGA1-IC,TBD   I172 @BASEBOARD_FAB2_LIB.BASEBOARD_FAB2(SCH_1):PAGE62
  J1A1  104 DQ<34> SCONN288_H44441004_PIP-SCONN,HA   I186 @BASEBOARD_FAB2_LIB.BASEBOARD_FAB2(SCH_1):PAGE87
  J9L1  249 DQ<35> SCONN288_H44441003_PIP-SCONN,HA   I111 @BASEBOARD_FAB2_LIB.BASEBOARD_FAB2(SCH_1):PAGE88

M_M_DQ<36> @BASEBOARD_FAB2_LIB.BASEBOARD_FAB2(SCH_1):M_M_DQ(36)
  U2D1 DA42 DDR5_DQ<36> SKX_EXT_B_BGA1-IC,TBD   I172 @BASEBOARD_FAB2_LIB.BASEBOARD_FAB2(SCH_1):PAGE62
  J1A1  240 DQ<37> SCONN288_H44441004_PIP-SCONN,HA   I186 @BASEBOARD_FAB2_LIB.BASEBOARD_FAB2(SCH_1):PAGE87
  J9L1   95 DQ<36> SCONN288_H44441003_PIP-SCONN,HA   I111 @BASEBOARD_FAB2_LIB.BASEBOARD_FAB2(SCH_1):PAGE88

M_M_DQ<37> @BASEBOARD_FAB2_LIB.BASEBOARD_FAB2(SCH_1):M_M_DQ(37)
  U2D1 DE42 DDR5_DQ<37> SKX_EXT_B_BGA1-IC,TBD   I172 @BASEBOARD_FAB2_LIB.BASEBOARD_FAB2(SCH_1):PAGE62
  J1A1   95 DQ<36> SCONN288_H44441004_PIP-SCONN,HA   I186 @BASEBOARD_FAB2_LIB.BASEBOARD_FAB2(SCH_1):PAGE87
  J9L1  240 DQ<37> SCONN288_H44441003_PIP-SCONN,HA   I111 @BASEBOARD_FAB2_LIB.BASEBOARD_FAB2(SCH_1):PAGE88

M_M_DQ<38> @BASEBOARD_FAB2_LIB.BASEBOARD_FAB2(SCH_1):M_M_DQ(38)
  U2D1 DD39 DDR5_DQ<38> SKX_EXT_B_BGA1-IC,TBD   I172 @BASEBOARD_FAB2_LIB.BASEBOARD_FAB2(SCH_1):PAGE62
  J1A1  247 DQ<39> SCONN288_H44441004_PIP-SCONN,HA   I186 @BASEBOARD_FAB2_LIB.BASEBOARD_FAB2(SCH_1):PAGE87
  J9L1  102 DQ<38> SCONN288_H44441003_PIP-SCONN,HA   I111 @BASEBOARD_FAB2_LIB.BASEBOARD_FAB2(SCH_1):PAGE88

M_M_DQ<39> @BASEBOARD_FAB2_LIB.BASEBOARD_FAB2(SCH_1):M_M_DQ(39)
  U2D1 DH39 DDR5_DQ<39> SKX_EXT_B_BGA1-IC,TBD   I172 @BASEBOARD_FAB2_LIB.BASEBOARD_FAB2(SCH_1):PAGE62
  J1A1  102 DQ<38> SCONN288_H44441004_PIP-SCONN,HA   I186 @BASEBOARD_FAB2_LIB.BASEBOARD_FAB2(SCH_1):PAGE87
  J9L1  247 DQ<39> SCONN288_H44441003_PIP-SCONN,HA   I111 @BASEBOARD_FAB2_LIB.BASEBOARD_FAB2(SCH_1):PAGE88

M_M_DQ<3> @BASEBOARD_FAB2_LIB.BASEBOARD_FAB2(SCH_1):M_M_DQ(3)
  U2D1 CV77 DDR5_DQ<3> SKX_EXT_B_BGA1-IC,TBD   I172 @BASEBOARD_FAB2_LIB.BASEBOARD_FAB2(SCH_1):PAGE62
  J1A1   12  DQ<2> SCONN288_H44441004_PIP-SCONN,HA   I186 @BASEBOARD_FAB2_LIB.BASEBOARD_FAB2(SCH_1):PAGE87
  J9L1  157  DQ<3> SCONN288_H44441003_PIP-SCONN,HA   I111 @BASEBOARD_FAB2_LIB.BASEBOARD_FAB2(SCH_1):PAGE88

M_M_DQ<40> @BASEBOARD_FAB2_LIB.BASEBOARD_FAB2(SCH_1):M_M_DQ(40)
  U2D1 DF33 DDR5_DQ<40> SKX_EXT_B_BGA1-IC,TBD   I172 @BASEBOARD_FAB2_LIB.BASEBOARD_FAB2(SCH_1):PAGE62
  J1A1  253 DQ<41> SCONN288_H44441004_PIP-SCONN,HA   I186 @BASEBOARD_FAB2_LIB.BASEBOARD_FAB2(SCH_1):PAGE87
  J9L1  108 DQ<40> SCONN288_H44441003_PIP-SCONN,HA   I111 @BASEBOARD_FAB2_LIB.BASEBOARD_FAB2(SCH_1):PAGE88

M_M_DQ<41> @BASEBOARD_FAB2_LIB.BASEBOARD_FAB2(SCH_1):M_M_DQ(41)
  U2D1 DK33 DDR5_DQ<41> SKX_EXT_B_BGA1-IC,TBD   I172 @BASEBOARD_FAB2_LIB.BASEBOARD_FAB2(SCH_1):PAGE62
  J1A1  108 DQ<40> SCONN288_H44441004_PIP-SCONN,HA   I186 @BASEBOARD_FAB2_LIB.BASEBOARD_FAB2(SCH_1):PAGE87
  J9L1  253 DQ<41> SCONN288_H44441003_PIP-SCONN,HA   I111 @BASEBOARD_FAB2_LIB.BASEBOARD_FAB2(SCH_1):PAGE88

M_M_DQ<42> @BASEBOARD_FAB2_LIB.BASEBOARD_FAB2(SCH_1):M_M_DQ(42)
  U2D1 DG30 DDR5_DQ<42> SKX_EXT_B_BGA1-IC,TBD   I172 @BASEBOARD_FAB2_LIB.BASEBOARD_FAB2(SCH_1):PAGE62
  J1A1  260 DQ<43> SCONN288_H44441004_PIP-SCONN,HA   I186 @BASEBOARD_FAB2_LIB.BASEBOARD_FAB2(SCH_1):PAGE87
  J9L1  115 DQ<42> SCONN288_H44441003_PIP-SCONN,HA   I111 @BASEBOARD_FAB2_LIB.BASEBOARD_FAB2(SCH_1):PAGE88

M_M_DQ<43> @BASEBOARD_FAB2_LIB.BASEBOARD_FAB2(SCH_1):M_M_DQ(43)
  U2D1 DJ30 DDR5_DQ<43> SKX_EXT_B_BGA1-IC,TBD   I172 @BASEBOARD_FAB2_LIB.BASEBOARD_FAB2(SCH_1):PAGE62
  J1A1  115 DQ<42> SCONN288_H44441004_PIP-SCONN,HA   I186 @BASEBOARD_FAB2_LIB.BASEBOARD_FAB2(SCH_1):PAGE87
  J9L1  260 DQ<43> SCONN288_H44441003_PIP-SCONN,HA   I111 @BASEBOARD_FAB2_LIB.BASEBOARD_FAB2(SCH_1):PAGE88

M_M_DQ<44> @BASEBOARD_FAB2_LIB.BASEBOARD_FAB2(SCH_1):M_M_DQ(44)
  U2D1 DG34 DDR5_DQ<44> SKX_EXT_B_BGA1-IC,TBD   I172 @BASEBOARD_FAB2_LIB.BASEBOARD_FAB2(SCH_1):PAGE62
  J1A1  251 DQ<45> SCONN288_H44441004_PIP-SCONN,HA   I186 @BASEBOARD_FAB2_LIB.BASEBOARD_FAB2(SCH_1):PAGE87
  J9L1  106 DQ<44> SCONN288_H44441003_PIP-SCONN,HA   I111 @BASEBOARD_FAB2_LIB.BASEBOARD_FAB2(SCH_1):PAGE88

M_M_DQ<45> @BASEBOARD_FAB2_LIB.BASEBOARD_FAB2(SCH_1):M_M_DQ(45)
  U2D1 DJ34 DDR5_DQ<45> SKX_EXT_B_BGA1-IC,TBD   I172 @BASEBOARD_FAB2_LIB.BASEBOARD_FAB2(SCH_1):PAGE62
  J1A1  106 DQ<44> SCONN288_H44441004_PIP-SCONN,HA   I186 @BASEBOARD_FAB2_LIB.BASEBOARD_FAB2(SCH_1):PAGE87
  J9L1  251 DQ<45> SCONN288_H44441003_PIP-SCONN,HA   I111 @BASEBOARD_FAB2_LIB.BASEBOARD_FAB2(SCH_1):PAGE88

M_M_DQ<46> @BASEBOARD_FAB2_LIB.BASEBOARD_FAB2(SCH_1):M_M_DQ(46)
  U2D1 DF31 DDR5_DQ<46> SKX_EXT_B_BGA1-IC,TBD   I172 @BASEBOARD_FAB2_LIB.BASEBOARD_FAB2(SCH_1):PAGE62
  J1A1  258 DQ<47> SCONN288_H44441004_PIP-SCONN,HA   I186 @BASEBOARD_FAB2_LIB.BASEBOARD_FAB2(SCH_1):PAGE87
  J9L1  113 DQ<46> SCONN288_H44441003_PIP-SCONN,HA   I111 @BASEBOARD_FAB2_LIB.BASEBOARD_FAB2(SCH_1):PAGE88

M_M_DQ<47> @BASEBOARD_FAB2_LIB.BASEBOARD_FAB2(SCH_1):M_M_DQ(47)
  U2D1 DK31 DDR5_DQ<47> SKX_EXT_B_BGA1-IC,TBD   I172 @BASEBOARD_FAB2_LIB.BASEBOARD_FAB2(SCH_1):PAGE62
  J1A1  113 DQ<46> SCONN288_H44441004_PIP-SCONN,HA   I186 @BASEBOARD_FAB2_LIB.BASEBOARD_FAB2(SCH_1):PAGE87
  J9L1  258 DQ<47> SCONN288_H44441003_PIP-SCONN,HA   I111 @BASEBOARD_FAB2_LIB.BASEBOARD_FAB2(SCH_1):PAGE88

M_M_DQ<48> @BASEBOARD_FAB2_LIB.BASEBOARD_FAB2(SCH_1):M_M_DQ(48)
  U2D1 CW36 DDR5_DQ<48> SKX_EXT_B_BGA1-IC,TBD   I172 @BASEBOARD_FAB2_LIB.BASEBOARD_FAB2(SCH_1):PAGE62
  J1A1  264 DQ<49> SCONN288_H44441004_PIP-SCONN,HA   I186 @BASEBOARD_FAB2_LIB.BASEBOARD_FAB2(SCH_1):PAGE87
  J9L1  119 DQ<48> SCONN288_H44441003_PIP-SCONN,HA   I111 @BASEBOARD_FAB2_LIB.BASEBOARD_FAB2(SCH_1):PAGE88

M_M_DQ<49> @BASEBOARD_FAB2_LIB.BASEBOARD_FAB2(SCH_1):M_M_DQ(49)
  U2D1 DC36 DDR5_DQ<49> SKX_EXT_B_BGA1-IC,TBD   I172 @BASEBOARD_FAB2_LIB.BASEBOARD_FAB2(SCH_1):PAGE62
  J1A1  119 DQ<48> SCONN288_H44441004_PIP-SCONN,HA   I186 @BASEBOARD_FAB2_LIB.BASEBOARD_FAB2(SCH_1):PAGE87
  J9L1  264 DQ<49> SCONN288_H44441003_PIP-SCONN,HA   I111 @BASEBOARD_FAB2_LIB.BASEBOARD_FAB2(SCH_1):PAGE88

M_M_DQ<4> @BASEBOARD_FAB2_LIB.BASEBOARD_FAB2(SCH_1):M_M_DQ(4)
  U2D1 CN74 DDR5_DQ<4> SKX_EXT_B_BGA1-IC,TBD   I172 @BASEBOARD_FAB2_LIB.BASEBOARD_FAB2(SCH_1):PAGE62
  J1A1  148  DQ<5> SCONN288_H44441004_PIP-SCONN,HA   I186 @BASEBOARD_FAB2_LIB.BASEBOARD_FAB2(SCH_1):PAGE87
  J9L1    3  DQ<4> SCONN288_H44441003_PIP-SCONN,HA   I111 @BASEBOARD_FAB2_LIB.BASEBOARD_FAB2(SCH_1):PAGE88

M_M_DQ<50> @BASEBOARD_FAB2_LIB.BASEBOARD_FAB2(SCH_1):M_M_DQ(50)
  U2D1 CY33 DDR5_DQ<50> SKX_EXT_B_BGA1-IC,TBD   I172 @BASEBOARD_FAB2_LIB.BASEBOARD_FAB2(SCH_1):PAGE62
  J1A1  271 DQ<51> SCONN288_H44441004_PIP-SCONN,HA   I186 @BASEBOARD_FAB2_LIB.BASEBOARD_FAB2(SCH_1):PAGE87
  J9L1  126 DQ<50> SCONN288_H44441003_PIP-SCONN,HA   I111 @BASEBOARD_FAB2_LIB.BASEBOARD_FAB2(SCH_1):PAGE88

M_M_DQ<51> @BASEBOARD_FAB2_LIB.BASEBOARD_FAB2(SCH_1):M_M_DQ(51)
  U2D1 DB33 DDR5_DQ<51> SKX_EXT_B_BGA1-IC,TBD   I172 @BASEBOARD_FAB2_LIB.BASEBOARD_FAB2(SCH_1):PAGE62
  J1A1  126 DQ<50> SCONN288_H44441004_PIP-SCONN,HA   I186 @BASEBOARD_FAB2_LIB.BASEBOARD_FAB2(SCH_1):PAGE87
  J9L1  271 DQ<51> SCONN288_H44441003_PIP-SCONN,HA   I111 @BASEBOARD_FAB2_LIB.BASEBOARD_FAB2(SCH_1):PAGE88

M_M_DQ<52> @BASEBOARD_FAB2_LIB.BASEBOARD_FAB2(SCH_1):M_M_DQ(52)
  U2D1 CY37 DDR5_DQ<52> SKX_EXT_B_BGA1-IC,TBD   I172 @BASEBOARD_FAB2_LIB.BASEBOARD_FAB2(SCH_1):PAGE62
  J1A1  262 DQ<53> SCONN288_H44441004_PIP-SCONN,HA   I186 @BASEBOARD_FAB2_LIB.BASEBOARD_FAB2(SCH_1):PAGE87
  J9L1  117 DQ<52> SCONN288_H44441003_PIP-SCONN,HA   I111 @BASEBOARD_FAB2_LIB.BASEBOARD_FAB2(SCH_1):PAGE88

M_M_DQ<53> @BASEBOARD_FAB2_LIB.BASEBOARD_FAB2(SCH_1):M_M_DQ(53)
  U2D1 DB37 DDR5_DQ<53> SKX_EXT_B_BGA1-IC,TBD   I172 @BASEBOARD_FAB2_LIB.BASEBOARD_FAB2(SCH_1):PAGE62
  J1A1  117 DQ<52> SCONN288_H44441004_PIP-SCONN,HA   I186 @BASEBOARD_FAB2_LIB.BASEBOARD_FAB2(SCH_1):PAGE87
  J9L1  262 DQ<53> SCONN288_H44441003_PIP-SCONN,HA   I111 @BASEBOARD_FAB2_LIB.BASEBOARD_FAB2(SCH_1):PAGE88

M_M_DQ<54> @BASEBOARD_FAB2_LIB.BASEBOARD_FAB2(SCH_1):M_M_DQ(54)
  U2D1 CW34 DDR5_DQ<54> SKX_EXT_B_BGA1-IC,TBD   I172 @BASEBOARD_FAB2_LIB.BASEBOARD_FAB2(SCH_1):PAGE62
  J1A1  269 DQ<55> SCONN288_H44441004_PIP-SCONN,HA   I186 @BASEBOARD_FAB2_LIB.BASEBOARD_FAB2(SCH_1):PAGE87
  J9L1  124 DQ<54> SCONN288_H44441003_PIP-SCONN,HA   I111 @BASEBOARD_FAB2_LIB.BASEBOARD_FAB2(SCH_1):PAGE88

M_M_DQ<55> @BASEBOARD_FAB2_LIB.BASEBOARD_FAB2(SCH_1):M_M_DQ(55)
  U2D1 DC34 DDR5_DQ<55> SKX_EXT_B_BGA1-IC,TBD   I172 @BASEBOARD_FAB2_LIB.BASEBOARD_FAB2(SCH_1):PAGE62
  J1A1  124 DQ<54> SCONN288_H44441004_PIP-SCONN,HA   I186 @BASEBOARD_FAB2_LIB.BASEBOARD_FAB2(SCH_1):PAGE87
  J9L1  269 DQ<55> SCONN288_H44441003_PIP-SCONN,HA   I111 @BASEBOARD_FAB2_LIB.BASEBOARD_FAB2(SCH_1):PAGE88

M_M_DQ<56> @BASEBOARD_FAB2_LIB.BASEBOARD_FAB2(SCH_1):M_M_DQ(56)
  U2D1 CW30 DDR5_DQ<56> SKX_EXT_B_BGA1-IC,TBD   I172 @BASEBOARD_FAB2_LIB.BASEBOARD_FAB2(SCH_1):PAGE62
  J1A1  275 DQ<57> SCONN288_H44441004_PIP-SCONN,HA   I186 @BASEBOARD_FAB2_LIB.BASEBOARD_FAB2(SCH_1):PAGE87
  J9L1  130 DQ<56> SCONN288_H44441003_PIP-SCONN,HA   I111 @BASEBOARD_FAB2_LIB.BASEBOARD_FAB2(SCH_1):PAGE88

M_M_DQ<57> @BASEBOARD_FAB2_LIB.BASEBOARD_FAB2(SCH_1):M_M_DQ(57)
  U2D1 DC30 DDR5_DQ<57> SKX_EXT_B_BGA1-IC,TBD   I172 @BASEBOARD_FAB2_LIB.BASEBOARD_FAB2(SCH_1):PAGE62
  J1A1  130 DQ<56> SCONN288_H44441004_PIP-SCONN,HA   I186 @BASEBOARD_FAB2_LIB.BASEBOARD_FAB2(SCH_1):PAGE87
  J9L1  275 DQ<57> SCONN288_H44441003_PIP-SCONN,HA   I111 @BASEBOARD_FAB2_LIB.BASEBOARD_FAB2(SCH_1):PAGE88

M_M_DQ<58> @BASEBOARD_FAB2_LIB.BASEBOARD_FAB2(SCH_1):M_M_DQ(58)
  U2D1 CY27 DDR5_DQ<58> SKX_EXT_B_BGA1-IC,TBD   I172 @BASEBOARD_FAB2_LIB.BASEBOARD_FAB2(SCH_1):PAGE62
  J1A1  282 DQ<59> SCONN288_H44441004_PIP-SCONN,HA   I186 @BASEBOARD_FAB2_LIB.BASEBOARD_FAB2(SCH_1):PAGE87
  J9L1  137 DQ<58> SCONN288_H44441003_PIP-SCONN,HA   I111 @BASEBOARD_FAB2_LIB.BASEBOARD_FAB2(SCH_1):PAGE88

M_M_DQ<59> @BASEBOARD_FAB2_LIB.BASEBOARD_FAB2(SCH_1):M_M_DQ(59)
  U2D1 DB27 DDR5_DQ<59> SKX_EXT_B_BGA1-IC,TBD   I172 @BASEBOARD_FAB2_LIB.BASEBOARD_FAB2(SCH_1):PAGE62
  J1A1  137 DQ<58> SCONN288_H44441004_PIP-SCONN,HA   I186 @BASEBOARD_FAB2_LIB.BASEBOARD_FAB2(SCH_1):PAGE87
  J9L1  282 DQ<59> SCONN288_H44441003_PIP-SCONN,HA   I111 @BASEBOARD_FAB2_LIB.BASEBOARD_FAB2(SCH_1):PAGE88

M_M_DQ<5> @BASEBOARD_FAB2_LIB.BASEBOARD_FAB2(SCH_1):M_M_DQ(5)
  U2D1 CM75 DDR5_DQ<5> SKX_EXT_B_BGA1-IC,TBD   I172 @BASEBOARD_FAB2_LIB.BASEBOARD_FAB2(SCH_1):PAGE62
  J1A1    3  DQ<4> SCONN288_H44441004_PIP-SCONN,HA   I186 @BASEBOARD_FAB2_LIB.BASEBOARD_FAB2(SCH_1):PAGE87
  J9L1  148  DQ<5> SCONN288_H44441003_PIP-SCONN,HA   I111 @BASEBOARD_FAB2_LIB.BASEBOARD_FAB2(SCH_1):PAGE88

M_M_DQ<60> @BASEBOARD_FAB2_LIB.BASEBOARD_FAB2(SCH_1):M_M_DQ(60)
  U2D1 CY31 DDR5_DQ<60> SKX_EXT_B_BGA1-IC,TBD   I172 @BASEBOARD_FAB2_LIB.BASEBOARD_FAB2(SCH_1):PAGE62
  J1A1  273 DQ<61> SCONN288_H44441004_PIP-SCONN,HA   I186 @BASEBOARD_FAB2_LIB.BASEBOARD_FAB2(SCH_1):PAGE87
  J9L1  128 DQ<60> SCONN288_H44441003_PIP-SCONN,HA   I111 @BASEBOARD_FAB2_LIB.BASEBOARD_FAB2(SCH_1):PAGE88

M_M_DQ<61> @BASEBOARD_FAB2_LIB.BASEBOARD_FAB2(SCH_1):M_M_DQ(61)
  U2D1 DB31 DDR5_DQ<61> SKX_EXT_B_BGA1-IC,TBD   I172 @BASEBOARD_FAB2_LIB.BASEBOARD_FAB2(SCH_1):PAGE62
  J1A1  128 DQ<60> SCONN288_H44441004_PIP-SCONN,HA   I186 @BASEBOARD_FAB2_LIB.BASEBOARD_FAB2(SCH_1):PAGE87
  J9L1  273 DQ<61> SCONN288_H44441003_PIP-SCONN,HA   I111 @BASEBOARD_FAB2_LIB.BASEBOARD_FAB2(SCH_1):PAGE88

M_M_DQ<62> @BASEBOARD_FAB2_LIB.BASEBOARD_FAB2(SCH_1):M_M_DQ(62)
  U2D1 CW28 DDR5_DQ<62> SKX_EXT_B_BGA1-IC,TBD   I172 @BASEBOARD_FAB2_LIB.BASEBOARD_FAB2(SCH_1):PAGE62
  J1A1  280 DQ<63> SCONN288_H44441004_PIP-SCONN,HA   I186 @BASEBOARD_FAB2_LIB.BASEBOARD_FAB2(SCH_1):PAGE87
  J9L1  135 DQ<62> SCONN288_H44441003_PIP-SCONN,HA   I111 @BASEBOARD_FAB2_LIB.BASEBOARD_FAB2(SCH_1):PAGE88

M_M_DQ<63> @BASEBOARD_FAB2_LIB.BASEBOARD_FAB2(SCH_1):M_M_DQ(63)
  U2D1 DC28 DDR5_DQ<63> SKX_EXT_B_BGA1-IC,TBD   I172 @BASEBOARD_FAB2_LIB.BASEBOARD_FAB2(SCH_1):PAGE62
  J1A1  135 DQ<62> SCONN288_H44441004_PIP-SCONN,HA   I186 @BASEBOARD_FAB2_LIB.BASEBOARD_FAB2(SCH_1):PAGE87
  J9L1  280 DQ<63> SCONN288_H44441003_PIP-SCONN,HA   I111 @BASEBOARD_FAB2_LIB.BASEBOARD_FAB2(SCH_1):PAGE88

M_M_DQ<6> @BASEBOARD_FAB2_LIB.BASEBOARD_FAB2(SCH_1):M_M_DQ(6)
  U2D1 CV75 DDR5_DQ<6> SKX_EXT_B_BGA1-IC,TBD   I172 @BASEBOARD_FAB2_LIB.BASEBOARD_FAB2(SCH_1):PAGE62
  J1A1  155  DQ<7> SCONN288_H44441004_PIP-SCONN,HA   I186 @BASEBOARD_FAB2_LIB.BASEBOARD_FAB2(SCH_1):PAGE87
  J9L1   10  DQ<6> SCONN288_H44441003_PIP-SCONN,HA   I111 @BASEBOARD_FAB2_LIB.BASEBOARD_FAB2(SCH_1):PAGE88

M_M_DQ<7> @BASEBOARD_FAB2_LIB.BASEBOARD_FAB2(SCH_1):M_M_DQ(7)
  U2D1 CT77 DDR5_DQ<7> SKX_EXT_B_BGA1-IC,TBD   I172 @BASEBOARD_FAB2_LIB.BASEBOARD_FAB2(SCH_1):PAGE62
  J1A1   10  DQ<6> SCONN288_H44441004_PIP-SCONN,HA   I186 @BASEBOARD_FAB2_LIB.BASEBOARD_FAB2(SCH_1):PAGE87
  J9L1  155  DQ<7> SCONN288_H44441003_PIP-SCONN,HA   I111 @BASEBOARD_FAB2_LIB.BASEBOARD_FAB2(SCH_1):PAGE88

M_M_DQ<8> @BASEBOARD_FAB2_LIB.BASEBOARD_FAB2(SCH_1):M_M_DQ(8)
  U2D1 DE74 DDR5_DQ<8> SKX_EXT_B_BGA1-IC,TBD   I172 @BASEBOARD_FAB2_LIB.BASEBOARD_FAB2(SCH_1):PAGE62
  J1A1  161  DQ<9> SCONN288_H44441004_PIP-SCONN,HA   I186 @BASEBOARD_FAB2_LIB.BASEBOARD_FAB2(SCH_1):PAGE87
  J9L1   16  DQ<8> SCONN288_H44441003_PIP-SCONN,HA   I111 @BASEBOARD_FAB2_LIB.BASEBOARD_FAB2(SCH_1):PAGE88

M_M_DQ<9> @BASEBOARD_FAB2_LIB.BASEBOARD_FAB2(SCH_1):M_M_DQ(9)
  U2D1 DC76 DDR5_DQ<9> SKX_EXT_B_BGA1-IC,TBD   I172 @BASEBOARD_FAB2_LIB.BASEBOARD_FAB2(SCH_1):PAGE62
  J1A1   16  DQ<8> SCONN288_H44441004_PIP-SCONN,HA   I186 @BASEBOARD_FAB2_LIB.BASEBOARD_FAB2(SCH_1):PAGE87
  J9L1  161  DQ<9> SCONN288_H44441003_PIP-SCONN,HA   I111 @BASEBOARD_FAB2_LIB.BASEBOARD_FAB2(SCH_1):PAGE88

M_M_DQS_DN<0> @BASEBOARD_FAB2_LIB.BASEBOARD_FAB2(SCH_1):M_M_DQS_DN(0)
  U2D1 CP77 DDR5_DQS_DN<0> SKX_EXT_B_BGA1-IC,TBD   I172 @BASEBOARD_FAB2_LIB.BASEBOARD_FAB2(SCH_1):PAGE62
  J1A1  152  DQS0N SCONN288_H44441004_PIP-SCONN,HA   I187 @BASEBOARD_FAB2_LIB.BASEBOARD_FAB2(SCH_1):PAGE87
  J9L1  152  DQS0N SCONN288_H44441003_PIP-SCONN,HA    I87 @BASEBOARD_FAB2_LIB.BASEBOARD_FAB2(SCH_1):PAGE88

M_M_DQS_DN<10> @BASEBOARD_FAB2_LIB.BASEBOARD_FAB2(SCH_1):M_M_DQS_DN(10)
  U2D1 DF75 DDR5_DQS_DN<10> SKX_EXT_B_BGA1-IC,TBD   I172 @BASEBOARD_FAB2_LIB.BASEBOARD_FAB2(SCH_1):PAGE62
  J1A1   19 DQS10N SCONN288_H44441004_PIP-SCONN,HA   I187 @BASEBOARD_FAB2_LIB.BASEBOARD_FAB2(SCH_1):PAGE87
  J9L1   19 DQS10N SCONN288_H44441003_PIP-SCONN,HA    I87 @BASEBOARD_FAB2_LIB.BASEBOARD_FAB2(SCH_1):PAGE88

M_M_DQS_DN<11> @BASEBOARD_FAB2_LIB.BASEBOARD_FAB2(SCH_1):M_M_DQS_DN(11)
  U2D1 DJ70 DDR5_DQS_DN<11> SKX_EXT_B_BGA1-IC,TBD   I172 @BASEBOARD_FAB2_LIB.BASEBOARD_FAB2(SCH_1):PAGE62
  J1A1   30 DQS11N SCONN288_H44441004_PIP-SCONN,HA   I187 @BASEBOARD_FAB2_LIB.BASEBOARD_FAB2(SCH_1):PAGE87
  J9L1   30 DQS11N SCONN288_H44441003_PIP-SCONN,HA    I87 @BASEBOARD_FAB2_LIB.BASEBOARD_FAB2(SCH_1):PAGE88

M_M_DQS_DN<12> @BASEBOARD_FAB2_LIB.BASEBOARD_FAB2(SCH_1):M_M_DQS_DN(12)
  U2D1 CP65 DDR5_DQS_DN<12> SKX_EXT_B_BGA1-IC,TBD   I172 @BASEBOARD_FAB2_LIB.BASEBOARD_FAB2(SCH_1):PAGE62
  J1A1   41 DQS12N SCONN288_H44441004_PIP-SCONN,HA   I187 @BASEBOARD_FAB2_LIB.BASEBOARD_FAB2(SCH_1):PAGE87
  J9L1   41 DQS12N SCONN288_H44441003_PIP-SCONN,HA    I87 @BASEBOARD_FAB2_LIB.BASEBOARD_FAB2(SCH_1):PAGE88

M_M_DQS_DN<13> @BASEBOARD_FAB2_LIB.BASEBOARD_FAB2(SCH_1):M_M_DQS_DN(13)
  U2D1 DE40 DDR5_DQS_DN<13> SKX_EXT_B_BGA1-IC,TBD   I172 @BASEBOARD_FAB2_LIB.BASEBOARD_FAB2(SCH_1):PAGE62
  J1A1  100 DQS13N SCONN288_H44441004_PIP-SCONN,HA   I187 @BASEBOARD_FAB2_LIB.BASEBOARD_FAB2(SCH_1):PAGE87
  J9L1  100 DQS13N SCONN288_H44441003_PIP-SCONN,HA    I87 @BASEBOARD_FAB2_LIB.BASEBOARD_FAB2(SCH_1):PAGE88

M_M_DQS_DN<14> @BASEBOARD_FAB2_LIB.BASEBOARD_FAB2(SCH_1):M_M_DQS_DN(14)
  U2D1 DG32 DDR5_DQS_DN<14> SKX_EXT_B_BGA1-IC,TBD   I172 @BASEBOARD_FAB2_LIB.BASEBOARD_FAB2(SCH_1):PAGE62
  J1A1  111 DQS14N SCONN288_H44441004_PIP-SCONN,HA   I187 @BASEBOARD_FAB2_LIB.BASEBOARD_FAB2(SCH_1):PAGE87
  J9L1  111 DQS14N SCONN288_H44441003_PIP-SCONN,HA    I87 @BASEBOARD_FAB2_LIB.BASEBOARD_FAB2(SCH_1):PAGE88

M_M_DQS_DN<15> @BASEBOARD_FAB2_LIB.BASEBOARD_FAB2(SCH_1):M_M_DQS_DN(15)
  U2D1 CY35 DDR5_DQS_DN<15> SKX_EXT_B_BGA1-IC,TBD   I172 @BASEBOARD_FAB2_LIB.BASEBOARD_FAB2(SCH_1):PAGE62
  J1A1  122 DQS15N SCONN288_H44441004_PIP-SCONN,HA   I187 @BASEBOARD_FAB2_LIB.BASEBOARD_FAB2(SCH_1):PAGE87
  J9L1  122 DQS15N SCONN288_H44441003_PIP-SCONN,HA    I87 @BASEBOARD_FAB2_LIB.BASEBOARD_FAB2(SCH_1):PAGE88

M_M_DQS_DN<16> @BASEBOARD_FAB2_LIB.BASEBOARD_FAB2(SCH_1):M_M_DQS_DN(16)
  U2D1 CY29 DDR5_DQS_DN<16> SKX_EXT_B_BGA1-IC,TBD   I172 @BASEBOARD_FAB2_LIB.BASEBOARD_FAB2(SCH_1):PAGE62
  J1A1  133 DQS16N SCONN288_H44441004_PIP-SCONN,HA   I187 @BASEBOARD_FAB2_LIB.BASEBOARD_FAB2(SCH_1):PAGE87
  J9L1  133 DQS16N SCONN288_H44441003_PIP-SCONN,HA    I87 @BASEBOARD_FAB2_LIB.BASEBOARD_FAB2(SCH_1):PAGE88

M_M_DQS_DN<17> @BASEBOARD_FAB2_LIB.BASEBOARD_FAB2(SCH_1):M_M_DQS_DN(17)
  U2D1 CJ70 DDR5_DQS_DN<17> SKX_EXT_B_BGA1-IC,TBD   I172 @BASEBOARD_FAB2_LIB.BASEBOARD_FAB2(SCH_1):PAGE62
  J1A1   52 DQS17N SCONN288_H44441004_PIP-SCONN,HA   I187 @BASEBOARD_FAB2_LIB.BASEBOARD_FAB2(SCH_1):PAGE87
  J9L1   52 DQS17N SCONN288_H44441003_PIP-SCONN,HA    I87 @BASEBOARD_FAB2_LIB.BASEBOARD_FAB2(SCH_1):PAGE88

M_M_DQS_DN<1> @BASEBOARD_FAB2_LIB.BASEBOARD_FAB2(SCH_1):M_M_DQS_DN(1)
  U2D1 DD77 DDR5_DQS_DN<1> SKX_EXT_B_BGA1-IC,TBD   I172 @BASEBOARD_FAB2_LIB.BASEBOARD_FAB2(SCH_1):PAGE62
  J1A1  163  DQS1N SCONN288_H44441004_PIP-SCONN,HA   I187 @BASEBOARD_FAB2_LIB.BASEBOARD_FAB2(SCH_1):PAGE87
  J9L1  163  DQS1N SCONN288_H44441003_PIP-SCONN,HA    I87 @BASEBOARD_FAB2_LIB.BASEBOARD_FAB2(SCH_1):PAGE88

M_M_DQS_DN<2> @BASEBOARD_FAB2_LIB.BASEBOARD_FAB2(SCH_1):M_M_DQS_DN(2)
  U2D1 DL72 DDR5_DQS_DN<2> SKX_EXT_B_BGA1-IC,TBD   I172 @BASEBOARD_FAB2_LIB.BASEBOARD_FAB2(SCH_1):PAGE62
  J1A1  174  DQS2N SCONN288_H44441004_PIP-SCONN,HA   I187 @BASEBOARD_FAB2_LIB.BASEBOARD_FAB2(SCH_1):PAGE87
  J9L1  174  DQS2N SCONN288_H44441003_PIP-SCONN,HA    I87 @BASEBOARD_FAB2_LIB.BASEBOARD_FAB2(SCH_1):PAGE88

M_M_DQS_DN<3> @BASEBOARD_FAB2_LIB.BASEBOARD_FAB2(SCH_1):M_M_DQS_DN(3)
  U2D1 CV65 DDR5_DQS_DN<3> SKX_EXT_B_BGA1-IC,TBD   I172 @BASEBOARD_FAB2_LIB.BASEBOARD_FAB2(SCH_1):PAGE62
  J1A1  185  DQS3N SCONN288_H44441004_PIP-SCONN,HA   I187 @BASEBOARD_FAB2_LIB.BASEBOARD_FAB2(SCH_1):PAGE87
  J9L1  185  DQS3N SCONN288_H44441003_PIP-SCONN,HA    I87 @BASEBOARD_FAB2_LIB.BASEBOARD_FAB2(SCH_1):PAGE88

M_M_DQS_DN<4> @BASEBOARD_FAB2_LIB.BASEBOARD_FAB2(SCH_1):M_M_DQS_DN(4)
  U2D1 DG40 DDR5_DQS_DN<4> SKX_EXT_B_BGA1-IC,TBD   I172 @BASEBOARD_FAB2_LIB.BASEBOARD_FAB2(SCH_1):PAGE62
  J1A1  244  DQS4N SCONN288_H44441004_PIP-SCONN,HA   I187 @BASEBOARD_FAB2_LIB.BASEBOARD_FAB2(SCH_1):PAGE87
  J9L1  244  DQS4N SCONN288_H44441003_PIP-SCONN,HA    I87 @BASEBOARD_FAB2_LIB.BASEBOARD_FAB2(SCH_1):PAGE88

M_M_DQS_DN<5> @BASEBOARD_FAB2_LIB.BASEBOARD_FAB2(SCH_1):M_M_DQS_DN(5)
  U2D1 DL32 DDR5_DQS_DN<5> SKX_EXT_B_BGA1-IC,TBD   I172 @BASEBOARD_FAB2_LIB.BASEBOARD_FAB2(SCH_1):PAGE62
  J1A1  255  DQS5N SCONN288_H44441004_PIP-SCONN,HA   I187 @BASEBOARD_FAB2_LIB.BASEBOARD_FAB2(SCH_1):PAGE87
  J9L1  255  DQS5N SCONN288_H44441003_PIP-SCONN,HA    I87 @BASEBOARD_FAB2_LIB.BASEBOARD_FAB2(SCH_1):PAGE88

M_M_DQS_DN<6> @BASEBOARD_FAB2_LIB.BASEBOARD_FAB2(SCH_1):M_M_DQS_DN(6)
  U2D1 DD35 DDR5_DQS_DN<6> SKX_EXT_B_BGA1-IC,TBD   I172 @BASEBOARD_FAB2_LIB.BASEBOARD_FAB2(SCH_1):PAGE62
  J1A1  266  DQS6N SCONN288_H44441004_PIP-SCONN,HA   I187 @BASEBOARD_FAB2_LIB.BASEBOARD_FAB2(SCH_1):PAGE87
  J9L1  266  DQS6N SCONN288_H44441003_PIP-SCONN,HA    I87 @BASEBOARD_FAB2_LIB.BASEBOARD_FAB2(SCH_1):PAGE88

M_M_DQS_DN<7> @BASEBOARD_FAB2_LIB.BASEBOARD_FAB2(SCH_1):M_M_DQS_DN(7)
  U2D1 DD29 DDR5_DQS_DN<7> SKX_EXT_B_BGA1-IC,TBD   I172 @BASEBOARD_FAB2_LIB.BASEBOARD_FAB2(SCH_1):PAGE62
  J1A1  277  DQS7N SCONN288_H44441004_PIP-SCONN,HA   I187 @BASEBOARD_FAB2_LIB.BASEBOARD_FAB2(SCH_1):PAGE87
  J9L1  277  DQS7N SCONN288_H44441003_PIP-SCONN,HA    I87 @BASEBOARD_FAB2_LIB.BASEBOARD_FAB2(SCH_1):PAGE88

M_M_DQS_DN<8> @BASEBOARD_FAB2_LIB.BASEBOARD_FAB2(SCH_1):M_M_DQS_DN(8)
  U2D1 CN70 DDR5_DQS_DN<8> SKX_EXT_B_BGA1-IC,TBD   I172 @BASEBOARD_FAB2_LIB.BASEBOARD_FAB2(SCH_1):PAGE62
  J1A1  196  DQS8N SCONN288_H44441004_PIP-SCONN,HA   I187 @BASEBOARD_FAB2_LIB.BASEBOARD_FAB2(SCH_1):PAGE87
  J9L1  196  DQS8N SCONN288_H44441003_PIP-SCONN,HA    I87 @BASEBOARD_FAB2_LIB.BASEBOARD_FAB2(SCH_1):PAGE88

M_M_DQS_DN<9> @BASEBOARD_FAB2_LIB.BASEBOARD_FAB2(SCH_1):M_M_DQS_DN(9)
  U2D1 CT75 DDR5_DQS_DN<9> SKX_EXT_B_BGA1-IC,TBD   I172 @BASEBOARD_FAB2_LIB.BASEBOARD_FAB2(SCH_1):PAGE62
  J1A1    8  DQS9N SCONN288_H44441004_PIP-SCONN,HA   I187 @BASEBOARD_FAB2_LIB.BASEBOARD_FAB2(SCH_1):PAGE87
  J9L1    8  DQS9N SCONN288_H44441003_PIP-SCONN,HA    I87 @BASEBOARD_FAB2_LIB.BASEBOARD_FAB2(SCH_1):PAGE88

M_M_DQS_DP<0> @BASEBOARD_FAB2_LIB.BASEBOARD_FAB2(SCH_1):M_M_DQS_DP(0)
  U2D1 CR76 DDR5_DQS_DP<0> SKX_EXT_B_BGA1-IC,TBD   I172 @BASEBOARD_FAB2_LIB.BASEBOARD_FAB2(SCH_1):PAGE62
  J1A1  153  DQS0P SCONN288_H44441004_PIP-SCONN,HA   I187 @BASEBOARD_FAB2_LIB.BASEBOARD_FAB2(SCH_1):PAGE87
  J9L1  153  DQS0P SCONN288_H44441003_PIP-SCONN,HA    I87 @BASEBOARD_FAB2_LIB.BASEBOARD_FAB2(SCH_1):PAGE88

M_M_DQS_DP<10> @BASEBOARD_FAB2_LIB.BASEBOARD_FAB2(SCH_1):M_M_DQS_DP(10)
  U2D1 DG74 DDR5_DQS_DP<10> SKX_EXT_B_BGA1-IC,TBD   I172 @BASEBOARD_FAB2_LIB.BASEBOARD_FAB2(SCH_1):PAGE62
  J1A1   18 DQS10P SCONN288_H44441004_PIP-SCONN,HA   I187 @BASEBOARD_FAB2_LIB.BASEBOARD_FAB2(SCH_1):PAGE87
  J9L1   18 DQS10P SCONN288_H44441003_PIP-SCONN,HA    I87 @BASEBOARD_FAB2_LIB.BASEBOARD_FAB2(SCH_1):PAGE88

M_M_DQS_DP<11> @BASEBOARD_FAB2_LIB.BASEBOARD_FAB2(SCH_1):M_M_DQS_DP(11)
  U2D1 DH69 DDR5_DQS_DP<11> SKX_EXT_B_BGA1-IC,TBD   I172 @BASEBOARD_FAB2_LIB.BASEBOARD_FAB2(SCH_1):PAGE62
  J1A1   29 DQS11P SCONN288_H44441004_PIP-SCONN,HA   I187 @BASEBOARD_FAB2_LIB.BASEBOARD_FAB2(SCH_1):PAGE87
  J9L1   29 DQS11P SCONN288_H44441003_PIP-SCONN,HA    I87 @BASEBOARD_FAB2_LIB.BASEBOARD_FAB2(SCH_1):PAGE88

M_M_DQS_DP<12> @BASEBOARD_FAB2_LIB.BASEBOARD_FAB2(SCH_1):M_M_DQS_DP(12)
  U2D1 CM65 DDR5_DQS_DP<12> SKX_EXT_B_BGA1-IC,TBD   I172 @BASEBOARD_FAB2_LIB.BASEBOARD_FAB2(SCH_1):PAGE62
  J1A1   40 DQS12P SCONN288_H44441004_PIP-SCONN,HA   I187 @BASEBOARD_FAB2_LIB.BASEBOARD_FAB2(SCH_1):PAGE87
  J9L1   40 DQS12P SCONN288_H44441003_PIP-SCONN,HA    I87 @BASEBOARD_FAB2_LIB.BASEBOARD_FAB2(SCH_1):PAGE88

M_M_DQS_DP<13> @BASEBOARD_FAB2_LIB.BASEBOARD_FAB2(SCH_1):M_M_DQS_DP(13)
  U2D1 DC40 DDR5_DQS_DP<13> SKX_EXT_B_BGA1-IC,TBD   I172 @BASEBOARD_FAB2_LIB.BASEBOARD_FAB2(SCH_1):PAGE62
  J1A1   99 DQS13P SCONN288_H44441004_PIP-SCONN,HA   I187 @BASEBOARD_FAB2_LIB.BASEBOARD_FAB2(SCH_1):PAGE87
  J9L1   99 DQS13P SCONN288_H44441003_PIP-SCONN,HA    I87 @BASEBOARD_FAB2_LIB.BASEBOARD_FAB2(SCH_1):PAGE88

M_M_DQS_DP<14> @BASEBOARD_FAB2_LIB.BASEBOARD_FAB2(SCH_1):M_M_DQS_DP(14)
  U2D1 DE32 DDR5_DQS_DP<14> SKX_EXT_B_BGA1-IC,TBD   I172 @BASEBOARD_FAB2_LIB.BASEBOARD_FAB2(SCH_1):PAGE62
  J1A1  110 DQS14P SCONN288_H44441004_PIP-SCONN,HA   I187 @BASEBOARD_FAB2_LIB.BASEBOARD_FAB2(SCH_1):PAGE87
  J9L1  110 DQS14P SCONN288_H44441003_PIP-SCONN,HA    I87 @BASEBOARD_FAB2_LIB.BASEBOARD_FAB2(SCH_1):PAGE88

M_M_DQS_DP<15> @BASEBOARD_FAB2_LIB.BASEBOARD_FAB2(SCH_1):M_M_DQS_DP(15)
  U2D1 CV35 DDR5_DQS_DP<15> SKX_EXT_B_BGA1-IC,TBD   I172 @BASEBOARD_FAB2_LIB.BASEBOARD_FAB2(SCH_1):PAGE62
  J1A1  121 DQS15P SCONN288_H44441004_PIP-SCONN,HA   I187 @BASEBOARD_FAB2_LIB.BASEBOARD_FAB2(SCH_1):PAGE87
  J9L1  121 DQS15P SCONN288_H44441003_PIP-SCONN,HA    I87 @BASEBOARD_FAB2_LIB.BASEBOARD_FAB2(SCH_1):PAGE88

M_M_DQS_DP<16> @BASEBOARD_FAB2_LIB.BASEBOARD_FAB2(SCH_1):M_M_DQS_DP(16)
  U2D1 CV29 DDR5_DQS_DP<16> SKX_EXT_B_BGA1-IC,TBD   I172 @BASEBOARD_FAB2_LIB.BASEBOARD_FAB2(SCH_1):PAGE62
  J1A1  132 DQS16P SCONN288_H44441004_PIP-SCONN,HA   I187 @BASEBOARD_FAB2_LIB.BASEBOARD_FAB2(SCH_1):PAGE87
  J9L1  132 DQS16P SCONN288_H44441003_PIP-SCONN,HA    I87 @BASEBOARD_FAB2_LIB.BASEBOARD_FAB2(SCH_1):PAGE88

M_M_DQS_DP<17> @BASEBOARD_FAB2_LIB.BASEBOARD_FAB2(SCH_1):M_M_DQS_DP(17)
  U2D1 CG70 DDR5_DQS_DP<17> SKX_EXT_B_BGA1-IC,TBD   I172 @BASEBOARD_FAB2_LIB.BASEBOARD_FAB2(SCH_1):PAGE62
  J1A1   51 DQS17P SCONN288_H44441004_PIP-SCONN,HA   I187 @BASEBOARD_FAB2_LIB.BASEBOARD_FAB2(SCH_1):PAGE87
  J9L1   51 DQS17P SCONN288_H44441003_PIP-SCONN,HA    I87 @BASEBOARD_FAB2_LIB.BASEBOARD_FAB2(SCH_1):PAGE88

M_M_DQS_DP<1> @BASEBOARD_FAB2_LIB.BASEBOARD_FAB2(SCH_1):M_M_DQS_DP(1)
  U2D1 DE76 DDR5_DQS_DP<1> SKX_EXT_B_BGA1-IC,TBD   I172 @BASEBOARD_FAB2_LIB.BASEBOARD_FAB2(SCH_1):PAGE62
  J1A1  164  DQS1P SCONN288_H44441004_PIP-SCONN,HA   I187 @BASEBOARD_FAB2_LIB.BASEBOARD_FAB2(SCH_1):PAGE87
  J9L1  164  DQS1P SCONN288_H44441003_PIP-SCONN,HA    I87 @BASEBOARD_FAB2_LIB.BASEBOARD_FAB2(SCH_1):PAGE88

M_M_DQS_DP<2> @BASEBOARD_FAB2_LIB.BASEBOARD_FAB2(SCH_1):M_M_DQS_DP(2)
  U2D1 DK71 DDR5_DQS_DP<2> SKX_EXT_B_BGA1-IC,TBD   I172 @BASEBOARD_FAB2_LIB.BASEBOARD_FAB2(SCH_1):PAGE62
  J1A1  175  DQS2P SCONN288_H44441004_PIP-SCONN,HA   I187 @BASEBOARD_FAB2_LIB.BASEBOARD_FAB2(SCH_1):PAGE87
  J9L1  175  DQS2P SCONN288_H44441003_PIP-SCONN,HA    I87 @BASEBOARD_FAB2_LIB.BASEBOARD_FAB2(SCH_1):PAGE88

M_M_DQS_DP<3> @BASEBOARD_FAB2_LIB.BASEBOARD_FAB2(SCH_1):M_M_DQS_DP(3)
  U2D1 CT65 DDR5_DQS_DP<3> SKX_EXT_B_BGA1-IC,TBD   I172 @BASEBOARD_FAB2_LIB.BASEBOARD_FAB2(SCH_1):PAGE62
  J1A1  186  DQS3P SCONN288_H44441004_PIP-SCONN,HA   I187 @BASEBOARD_FAB2_LIB.BASEBOARD_FAB2(SCH_1):PAGE87
  J9L1  186  DQS3P SCONN288_H44441003_PIP-SCONN,HA    I87 @BASEBOARD_FAB2_LIB.BASEBOARD_FAB2(SCH_1):PAGE88

M_M_DQS_DP<4> @BASEBOARD_FAB2_LIB.BASEBOARD_FAB2(SCH_1):M_M_DQS_DP(4)
  U2D1 DJ40 DDR5_DQS_DP<4> SKX_EXT_B_BGA1-IC,TBD   I172 @BASEBOARD_FAB2_LIB.BASEBOARD_FAB2(SCH_1):PAGE62
  J1A1  245  DQS4P SCONN288_H44441004_PIP-SCONN,HA   I187 @BASEBOARD_FAB2_LIB.BASEBOARD_FAB2(SCH_1):PAGE87
  J9L1  245  DQS4P SCONN288_H44441003_PIP-SCONN,HA    I87 @BASEBOARD_FAB2_LIB.BASEBOARD_FAB2(SCH_1):PAGE88

M_M_DQS_DP<5> @BASEBOARD_FAB2_LIB.BASEBOARD_FAB2(SCH_1):M_M_DQS_DP(5)
  U2D1 DJ32 DDR5_DQS_DP<5> SKX_EXT_B_BGA1-IC,TBD   I172 @BASEBOARD_FAB2_LIB.BASEBOARD_FAB2(SCH_1):PAGE62
  J1A1  256  DQS5P SCONN288_H44441004_PIP-SCONN,HA   I187 @BASEBOARD_FAB2_LIB.BASEBOARD_FAB2(SCH_1):PAGE87
  J9L1  256  DQS5P SCONN288_H44441003_PIP-SCONN,HA    I87 @BASEBOARD_FAB2_LIB.BASEBOARD_FAB2(SCH_1):PAGE88

M_M_DQS_DP<6> @BASEBOARD_FAB2_LIB.BASEBOARD_FAB2(SCH_1):M_M_DQS_DP(6)
  U2D1 DB35 DDR5_DQS_DP<6> SKX_EXT_B_BGA1-IC,TBD   I172 @BASEBOARD_FAB2_LIB.BASEBOARD_FAB2(SCH_1):PAGE62
  J1A1  267  DQS6P SCONN288_H44441004_PIP-SCONN,HA   I187 @BASEBOARD_FAB2_LIB.BASEBOARD_FAB2(SCH_1):PAGE87
  J9L1  267  DQS6P SCONN288_H44441003_PIP-SCONN,HA    I87 @BASEBOARD_FAB2_LIB.BASEBOARD_FAB2(SCH_1):PAGE88

M_M_DQS_DP<7> @BASEBOARD_FAB2_LIB.BASEBOARD_FAB2(SCH_1):M_M_DQS_DP(7)
  U2D1 DB29 DDR5_DQS_DP<7> SKX_EXT_B_BGA1-IC,TBD   I172 @BASEBOARD_FAB2_LIB.BASEBOARD_FAB2(SCH_1):PAGE62
  J1A1  278  DQS7P SCONN288_H44441004_PIP-SCONN,HA   I187 @BASEBOARD_FAB2_LIB.BASEBOARD_FAB2(SCH_1):PAGE87
  J9L1  278  DQS7P SCONN288_H44441003_PIP-SCONN,HA    I87 @BASEBOARD_FAB2_LIB.BASEBOARD_FAB2(SCH_1):PAGE88

M_M_DQS_DP<8> @BASEBOARD_FAB2_LIB.BASEBOARD_FAB2(SCH_1):M_M_DQS_DP(8)
  U2D1 CL70 DDR5_DQS_DP<8> SKX_EXT_B_BGA1-IC,TBD   I172 @BASEBOARD_FAB2_LIB.BASEBOARD_FAB2(SCH_1):PAGE62
  J1A1  197  DQS8P SCONN288_H44441004_PIP-SCONN,HA   I187 @BASEBOARD_FAB2_LIB.BASEBOARD_FAB2(SCH_1):PAGE87
  J9L1  197  DQS8P SCONN288_H44441003_PIP-SCONN,HA    I87 @BASEBOARD_FAB2_LIB.BASEBOARD_FAB2(SCH_1):PAGE88

M_M_DQS_DP<9> @BASEBOARD_FAB2_LIB.BASEBOARD_FAB2(SCH_1):M_M_DQS_DP(9)
  U2D1 CU74 DDR5_DQS_DP<9> SKX_EXT_B_BGA1-IC,TBD   I172 @BASEBOARD_FAB2_LIB.BASEBOARD_FAB2(SCH_1):PAGE62
  J1A1    7  DQS9P SCONN288_H44441004_PIP-SCONN,HA   I187 @BASEBOARD_FAB2_LIB.BASEBOARD_FAB2(SCH_1):PAGE87
  J9L1    7  DQS9P SCONN288_H44441003_PIP-SCONN,HA    I87 @BASEBOARD_FAB2_LIB.BASEBOARD_FAB2(SCH_1):PAGE88

M_M_ECC<0> @BASEBOARD_FAB2_LIB.BASEBOARD_FAB2(SCH_1):M_M_ECC(0)
  U2D1 CH71 DDR5_ECC<0> SKX_EXT_B_BGA1-IC,TBD   I172 @BASEBOARD_FAB2_LIB.BASEBOARD_FAB2(SCH_1):PAGE62
  J1A1  194  CB<1> SCONN288_H44441004_PIP-SCONN,HA   I186 @BASEBOARD_FAB2_LIB.BASEBOARD_FAB2(SCH_1):PAGE87
  J9L1   49  CB<0> SCONN288_H44441003_PIP-SCONN,HA   I111 @BASEBOARD_FAB2_LIB.BASEBOARD_FAB2(SCH_1):PAGE88

M_M_ECC<1> @BASEBOARD_FAB2_LIB.BASEBOARD_FAB2(SCH_1):M_M_ECC(1)
  U2D1 CM71 DDR5_ECC<1> SKX_EXT_B_BGA1-IC,TBD   I172 @BASEBOARD_FAB2_LIB.BASEBOARD_FAB2(SCH_1):PAGE62
  J1A1   49  CB<0> SCONN288_H44441004_PIP-SCONN,HA   I186 @BASEBOARD_FAB2_LIB.BASEBOARD_FAB2(SCH_1):PAGE87
  J9L1  194  CB<1> SCONN288_H44441003_PIP-SCONN,HA   I111 @BASEBOARD_FAB2_LIB.BASEBOARD_FAB2(SCH_1):PAGE88

M_M_ECC<2> @BASEBOARD_FAB2_LIB.BASEBOARD_FAB2(SCH_1):M_M_ECC(2)
  U2D1 CJ68 DDR5_ECC<2> SKX_EXT_B_BGA1-IC,TBD   I172 @BASEBOARD_FAB2_LIB.BASEBOARD_FAB2(SCH_1):PAGE62
  J1A1  201  CB<3> SCONN288_H44441004_PIP-SCONN,HA   I186 @BASEBOARD_FAB2_LIB.BASEBOARD_FAB2(SCH_1):PAGE87
  J9L1   56  CB<2> SCONN288_H44441003_PIP-SCONN,HA   I111 @BASEBOARD_FAB2_LIB.BASEBOARD_FAB2(SCH_1):PAGE88

M_M_ECC<3> @BASEBOARD_FAB2_LIB.BASEBOARD_FAB2(SCH_1):M_M_ECC(3)
  U2D1 CL68 DDR5_ECC<3> SKX_EXT_B_BGA1-IC,TBD   I172 @BASEBOARD_FAB2_LIB.BASEBOARD_FAB2(SCH_1):PAGE62
  J1A1   56  CB<2> SCONN288_H44441004_PIP-SCONN,HA   I186 @BASEBOARD_FAB2_LIB.BASEBOARD_FAB2(SCH_1):PAGE87
  J9L1  201  CB<3> SCONN288_H44441003_PIP-SCONN,HA   I111 @BASEBOARD_FAB2_LIB.BASEBOARD_FAB2(SCH_1):PAGE88

M_M_ECC<4> @BASEBOARD_FAB2_LIB.BASEBOARD_FAB2(SCH_1):M_M_ECC(4)
  U2D1 CJ72 DDR5_ECC<4> SKX_EXT_B_BGA1-IC,TBD   I172 @BASEBOARD_FAB2_LIB.BASEBOARD_FAB2(SCH_1):PAGE62
  J1A1  192  CB<5> SCONN288_H44441004_PIP-SCONN,HA   I186 @BASEBOARD_FAB2_LIB.BASEBOARD_FAB2(SCH_1):PAGE87
  J9L1   47  CB<4> SCONN288_H44441003_PIP-SCONN,HA   I111 @BASEBOARD_FAB2_LIB.BASEBOARD_FAB2(SCH_1):PAGE88

M_M_ECC<5> @BASEBOARD_FAB2_LIB.BASEBOARD_FAB2(SCH_1):M_M_ECC(5)
  U2D1 CL72 DDR5_ECC<5> SKX_EXT_B_BGA1-IC,TBD   I172 @BASEBOARD_FAB2_LIB.BASEBOARD_FAB2(SCH_1):PAGE62
  J1A1   47  CB<4> SCONN288_H44441004_PIP-SCONN,HA   I186 @BASEBOARD_FAB2_LIB.BASEBOARD_FAB2(SCH_1):PAGE87
  J9L1  192  CB<5> SCONN288_H44441003_PIP-SCONN,HA   I111 @BASEBOARD_FAB2_LIB.BASEBOARD_FAB2(SCH_1):PAGE88

M_M_ECC<6> @BASEBOARD_FAB2_LIB.BASEBOARD_FAB2(SCH_1):M_M_ECC(6)
  U2D1 CH69 DDR5_ECC<6> SKX_EXT_B_BGA1-IC,TBD   I172 @BASEBOARD_FAB2_LIB.BASEBOARD_FAB2(SCH_1):PAGE62
  J1A1  199  CB<7> SCONN288_H44441004_PIP-SCONN,HA   I186 @BASEBOARD_FAB2_LIB.BASEBOARD_FAB2(SCH_1):PAGE87
  J9L1   54  CB<6> SCONN288_H44441003_PIP-SCONN,HA   I111 @BASEBOARD_FAB2_LIB.BASEBOARD_FAB2(SCH_1):PAGE88

M_M_ECC<7> @BASEBOARD_FAB2_LIB.BASEBOARD_FAB2(SCH_1):M_M_ECC(7)
  U2D1 CM69 DDR5_ECC<7> SKX_EXT_B_BGA1-IC,TBD   I172 @BASEBOARD_FAB2_LIB.BASEBOARD_FAB2(SCH_1):PAGE62
  J1A1   54  CB<6> SCONN288_H44441004_PIP-SCONN,HA   I186 @BASEBOARD_FAB2_LIB.BASEBOARD_FAB2(SCH_1):PAGE87
  J9L1  199  CB<7> SCONN288_H44441003_PIP-SCONN,HA   I111 @BASEBOARD_FAB2_LIB.BASEBOARD_FAB2(SCH_1):PAGE88

M_M_MA<0> @BASEBOARD_FAB2_LIB.BASEBOARD_FAB2(SCH_1):M_M_MA(0)
  U2D1 DF53 DDR5_MA<0> SKX_EXT_B_BGA1-IC,TBD   I172 @BASEBOARD_FAB2_LIB.BASEBOARD_FAB2(SCH_1):PAGE62
  J1A1   79     A0 SCONN288_H44441004_PIP-SCONN,HA   I186 @BASEBOARD_FAB2_LIB.BASEBOARD_FAB2(SCH_1):PAGE87
  J9L1   79     A0 SCONN288_H44441003_PIP-SCONN,HA   I111 @BASEBOARD_FAB2_LIB.BASEBOARD_FAB2(SCH_1):PAGE88

M_M_MA<10> @BASEBOARD_FAB2_LIB.BASEBOARD_FAB2(SCH_1):M_M_MA(10)
  U2D1 DD55 DDR5_MA<10> SKX_EXT_B_BGA1-IC,TBD   I172 @BASEBOARD_FAB2_LIB.BASEBOARD_FAB2(SCH_1):PAGE62
  J1A1  225    A10 SCONN288_H44441004_PIP-SCONN,HA   I186 @BASEBOARD_FAB2_LIB.BASEBOARD_FAB2(SCH_1):PAGE87
  J9L1  225    A10 SCONN288_H44441003_PIP-SCONN,HA   I111 @BASEBOARD_FAB2_LIB.BASEBOARD_FAB2(SCH_1):PAGE88

M_M_MA<11> @BASEBOARD_FAB2_LIB.BASEBOARD_FAB2(SCH_1):M_M_MA(11)
  U2D1 DA60 DDR5_MA<11> SKX_EXT_B_BGA1-IC,TBD   I172 @BASEBOARD_FAB2_LIB.BASEBOARD_FAB2(SCH_1):PAGE62
  J1A1  210    A11 SCONN288_H44441004_PIP-SCONN,HA   I186 @BASEBOARD_FAB2_LIB.BASEBOARD_FAB2(SCH_1):PAGE87
  J9L1  210    A11 SCONN288_H44441003_PIP-SCONN,HA   I111 @BASEBOARD_FAB2_LIB.BASEBOARD_FAB2(SCH_1):PAGE88

M_M_MA<12> @BASEBOARD_FAB2_LIB.BASEBOARD_FAB2(SCH_1):M_M_MA(12)
  U2D1 DG60 DDR5_MA<12> SKX_EXT_B_BGA1-IC,TBD   I172 @BASEBOARD_FAB2_LIB.BASEBOARD_FAB2(SCH_1):PAGE62
  J1A1   65    A12 SCONN288_H44441004_PIP-SCONN,HA   I186 @BASEBOARD_FAB2_LIB.BASEBOARD_FAB2(SCH_1):PAGE87
  J9L1   65    A12 SCONN288_H44441003_PIP-SCONN,HA   I111 @BASEBOARD_FAB2_LIB.BASEBOARD_FAB2(SCH_1):PAGE88

M_M_MA<13> @BASEBOARD_FAB2_LIB.BASEBOARD_FAB2(SCH_1):M_M_MA(13)
  U2D1 DD53 DDR5_MA<13> SKX_EXT_B_BGA1-IC,TBD   I172 @BASEBOARD_FAB2_LIB.BASEBOARD_FAB2(SCH_1):PAGE62
  J1A1  232    A13 SCONN288_H44441004_PIP-SCONN,HA   I186 @BASEBOARD_FAB2_LIB.BASEBOARD_FAB2(SCH_1):PAGE87
  J9L1  232    A13 SCONN288_H44441003_PIP-SCONN,HA   I111 @BASEBOARD_FAB2_LIB.BASEBOARD_FAB2(SCH_1):PAGE88

M_M_MA<14> @BASEBOARD_FAB2_LIB.BASEBOARD_FAB2(SCH_1):M_M_MA(14)
  U2D1 DJ50 DDR5_MA<14> SKX_EXT_B_BGA1-IC,TBD   I172 @BASEBOARD_FAB2_LIB.BASEBOARD_FAB2(SCH_1):PAGE62
  J1A1  228 A14_WE_N SCONN288_H44441004_PIP-SCONN,HA   I186 @BASEBOARD_FAB2_LIB.BASEBOARD_FAB2(SCH_1):PAGE87
  J9L1  228 A14_WE_N SCONN288_H44441003_PIP-SCONN,HA   I111 @BASEBOARD_FAB2_LIB.BASEBOARD_FAB2(SCH_1):PAGE88

M_M_MA<15> @BASEBOARD_FAB2_LIB.BASEBOARD_FAB2(SCH_1):M_M_MA(15)
  U2D1 DC54 DDR5_MA<15> SKX_EXT_B_BGA1-IC,TBD   I172 @BASEBOARD_FAB2_LIB.BASEBOARD_FAB2(SCH_1):PAGE62
  J1A1   86 A15_CAS_N SCONN288_H44441004_PIP-SCONN,HA   I186 @BASEBOARD_FAB2_LIB.BASEBOARD_FAB2(SCH_1):PAGE87
  J9L1   86 A15_CAS_N SCONN288_H44441003_PIP-SCONN,HA   I111 @BASEBOARD_FAB2_LIB.BASEBOARD_FAB2(SCH_1):PAGE88

M_M_MA<16> @BASEBOARD_FAB2_LIB.BASEBOARD_FAB2(SCH_1):M_M_MA(16)
  U2D1 DG52 DDR5_MA<16> SKX_EXT_B_BGA1-IC,TBD   I172 @BASEBOARD_FAB2_LIB.BASEBOARD_FAB2(SCH_1):PAGE62
  J1A1   82 A16_RAS_N SCONN288_H44441004_PIP-SCONN,HA   I186 @BASEBOARD_FAB2_LIB.BASEBOARD_FAB2(SCH_1):PAGE87
  J9L1   82 A16_RAS_N SCONN288_H44441003_PIP-SCONN,HA   I111 @BASEBOARD_FAB2_LIB.BASEBOARD_FAB2(SCH_1):PAGE88

M_M_MA<17> @BASEBOARD_FAB2_LIB.BASEBOARD_FAB2(SCH_1):M_M_MA(17)
  U2D1 DE46 DDR5_MA<17> SKX_EXT_B_BGA1-IC,TBD   I172 @BASEBOARD_FAB2_LIB.BASEBOARD_FAB2(SCH_1):PAGE62
  J1A1  234    A17 SCONN288_H44441004_PIP-SCONN,HA   I186 @BASEBOARD_FAB2_LIB.BASEBOARD_FAB2(SCH_1):PAGE87
  J9L1  234    A17 SCONN288_H44441003_PIP-SCONN,HA   I111 @BASEBOARD_FAB2_LIB.BASEBOARD_FAB2(SCH_1):PAGE88

M_M_MA<1> @BASEBOARD_FAB2_LIB.BASEBOARD_FAB2(SCH_1):M_M_MA(1)
  U2D1 DC58 DDR5_MA<1> SKX_EXT_B_BGA1-IC,TBD   I172 @BASEBOARD_FAB2_LIB.BASEBOARD_FAB2(SCH_1):PAGE62
  J1A1   72     A1 SCONN288_H44441004_PIP-SCONN,HA   I186 @BASEBOARD_FAB2_LIB.BASEBOARD_FAB2(SCH_1):PAGE87
  J9L1   72     A1 SCONN288_H44441003_PIP-SCONN,HA   I111 @BASEBOARD_FAB2_LIB.BASEBOARD_FAB2(SCH_1):PAGE88

M_M_MA<2> @BASEBOARD_FAB2_LIB.BASEBOARD_FAB2(SCH_1):M_M_MA(2)
  U2D1 DD57 DDR5_MA<2> SKX_EXT_B_BGA1-IC,TBD   I172 @BASEBOARD_FAB2_LIB.BASEBOARD_FAB2(SCH_1):PAGE62
  J1A1  216     A2 SCONN288_H44441004_PIP-SCONN,HA   I186 @BASEBOARD_FAB2_LIB.BASEBOARD_FAB2(SCH_1):PAGE87
  J9L1  216     A2 SCONN288_H44441003_PIP-SCONN,HA   I111 @BASEBOARD_FAB2_LIB.BASEBOARD_FAB2(SCH_1):PAGE88

M_M_MA<3> @BASEBOARD_FAB2_LIB.BASEBOARD_FAB2(SCH_1):M_M_MA(3)
  U2D1 DG58 DDR5_MA<3> SKX_EXT_B_BGA1-IC,TBD   I172 @BASEBOARD_FAB2_LIB.BASEBOARD_FAB2(SCH_1):PAGE62
  J1A1   71     A3 SCONN288_H44441004_PIP-SCONN,HA   I186 @BASEBOARD_FAB2_LIB.BASEBOARD_FAB2(SCH_1):PAGE87
  J9L1   71     A3 SCONN288_H44441003_PIP-SCONN,HA   I111 @BASEBOARD_FAB2_LIB.BASEBOARD_FAB2(SCH_1):PAGE88

M_M_MA<4> @BASEBOARD_FAB2_LIB.BASEBOARD_FAB2(SCH_1):M_M_MA(4)
  U2D1 DJ58 DDR5_MA<4> SKX_EXT_B_BGA1-IC,TBD   I172 @BASEBOARD_FAB2_LIB.BASEBOARD_FAB2(SCH_1):PAGE62
  J1A1  214     A4 SCONN288_H44441004_PIP-SCONN,HA   I186 @BASEBOARD_FAB2_LIB.BASEBOARD_FAB2(SCH_1):PAGE87
  J9L1  214     A4 SCONN288_H44441003_PIP-SCONN,HA   I111 @BASEBOARD_FAB2_LIB.BASEBOARD_FAB2(SCH_1):PAGE88

M_M_MA<5> @BASEBOARD_FAB2_LIB.BASEBOARD_FAB2(SCH_1):M_M_MA(5)
  U2D1 DF59 DDR5_MA<5> SKX_EXT_B_BGA1-IC,TBD   I172 @BASEBOARD_FAB2_LIB.BASEBOARD_FAB2(SCH_1):PAGE62
  J1A1  213     A5 SCONN288_H44441004_PIP-SCONN,HA   I186 @BASEBOARD_FAB2_LIB.BASEBOARD_FAB2(SCH_1):PAGE87
  J9L1  213     A5 SCONN288_H44441003_PIP-SCONN,HA   I111 @BASEBOARD_FAB2_LIB.BASEBOARD_FAB2(SCH_1):PAGE88

M_M_MA<6> @BASEBOARD_FAB2_LIB.BASEBOARD_FAB2(SCH_1):M_M_MA(6)
  U2D1 DK59 DDR5_MA<6> SKX_EXT_B_BGA1-IC,TBD   I172 @BASEBOARD_FAB2_LIB.BASEBOARD_FAB2(SCH_1):PAGE62
  J1A1   69     A6 SCONN288_H44441004_PIP-SCONN,HA   I186 @BASEBOARD_FAB2_LIB.BASEBOARD_FAB2(SCH_1):PAGE87
  J9L1   69     A6 SCONN288_H44441003_PIP-SCONN,HA   I111 @BASEBOARD_FAB2_LIB.BASEBOARD_FAB2(SCH_1):PAGE88

M_M_MA<7> @BASEBOARD_FAB2_LIB.BASEBOARD_FAB2(SCH_1):M_M_MA(7)
  U2D1 DC60 DDR5_MA<7> SKX_EXT_B_BGA1-IC,TBD   I172 @BASEBOARD_FAB2_LIB.BASEBOARD_FAB2(SCH_1):PAGE62
  J1A1  211     A7 SCONN288_H44441004_PIP-SCONN,HA   I186 @BASEBOARD_FAB2_LIB.BASEBOARD_FAB2(SCH_1):PAGE87
  J9L1  211     A7 SCONN288_H44441003_PIP-SCONN,HA   I111 @BASEBOARD_FAB2_LIB.BASEBOARD_FAB2(SCH_1):PAGE88

M_M_MA<8> @BASEBOARD_FAB2_LIB.BASEBOARD_FAB2(SCH_1):M_M_MA(8)
  U2D1 DD59 DDR5_MA<8> SKX_EXT_B_BGA1-IC,TBD   I172 @BASEBOARD_FAB2_LIB.BASEBOARD_FAB2(SCH_1):PAGE62
  J1A1   68     A8 SCONN288_H44441004_PIP-SCONN,HA   I186 @BASEBOARD_FAB2_LIB.BASEBOARD_FAB2(SCH_1):PAGE87
  J9L1   68     A8 SCONN288_H44441003_PIP-SCONN,HA   I111 @BASEBOARD_FAB2_LIB.BASEBOARD_FAB2(SCH_1):PAGE88

M_M_MA<9> @BASEBOARD_FAB2_LIB.BASEBOARD_FAB2(SCH_1):M_M_MA(9)
  U2D1 DA58 DDR5_MA<9> SKX_EXT_B_BGA1-IC,TBD   I172 @BASEBOARD_FAB2_LIB.BASEBOARD_FAB2(SCH_1):PAGE62
  J1A1   66     A9 SCONN288_H44441004_PIP-SCONN,HA   I186 @BASEBOARD_FAB2_LIB.BASEBOARD_FAB2(SCH_1):PAGE87
  J9L1   66     A9 SCONN288_H44441003_PIP-SCONN,HA   I111 @BASEBOARD_FAB2_LIB.BASEBOARD_FAB2(SCH_1):PAGE88

M_M_ODT<0> @BASEBOARD_FAB2_LIB.BASEBOARD_FAB2(SCH_1):M_M_ODT(0)
  U2D1 DG50 DDR5_ODT<0> SKX_EXT_B_BGA1-IC,TBD   I172 @BASEBOARD_FAB2_LIB.BASEBOARD_FAB2(SCH_1):PAGE62
  J1A1   87 ODT<0> SCONN288_H44441004_PIP-SCONN,HA   I186 @BASEBOARD_FAB2_LIB.BASEBOARD_FAB2(SCH_1):PAGE87

M_M_ODT<1> @BASEBOARD_FAB2_LIB.BASEBOARD_FAB2(SCH_1):M_M_ODT(1)
  U2D1 DG48 DDR5_ODT<1> SKX_EXT_B_BGA1-IC,TBD   I172 @BASEBOARD_FAB2_LIB.BASEBOARD_FAB2(SCH_1):PAGE62
  J1A1   91 ODT<1> SCONN288_H44441004_PIP-SCONN,HA   I186 @BASEBOARD_FAB2_LIB.BASEBOARD_FAB2(SCH_1):PAGE87

M_M_ODT<2> @BASEBOARD_FAB2_LIB.BASEBOARD_FAB2(SCH_1):M_M_ODT(2)
  U2D1 DK49 DDR5_ODT<2> SKX_EXT_B_BGA1-IC,TBD   I172 @BASEBOARD_FAB2_LIB.BASEBOARD_FAB2(SCH_1):PAGE62
  J9L1   87 ODT<0> SCONN288_H44441003_PIP-SCONN,HA   I111 @BASEBOARD_FAB2_LIB.BASEBOARD_FAB2(SCH_1):PAGE88

M_M_ODT<3> @BASEBOARD_FAB2_LIB.BASEBOARD_FAB2(SCH_1):M_M_ODT(3)
  U2D1 DF47 DDR5_ODT<3> SKX_EXT_B_BGA1-IC,TBD   I172 @BASEBOARD_FAB2_LIB.BASEBOARD_FAB2(SCH_1):PAGE62
  J9L1   91 ODT<1> SCONN288_H44441003_PIP-SCONN,HA   I111 @BASEBOARD_FAB2_LIB.BASEBOARD_FAB2(SCH_1):PAGE88

M_M_PAR @BASEBOARD_FAB2_LIB.BASEBOARD_FAB2(SCH_1):M_M_PAR
  U2D1 DK53 DDR5_PAR SKX_EXT_B_BGA1-IC,TBD   I172 @BASEBOARD_FAB2_LIB.BASEBOARD_FAB2(SCH_1):PAGE62
  J1A1  222    PAR SCONN288_H44441004_PIP-SCONN,HA   I186 @BASEBOARD_FAB2_LIB.BASEBOARD_FAB2(SCH_1):PAGE87
  J9L1  222    PAR SCONN288_H44441003_PIP-SCONN,HA   I111 @BASEBOARD_FAB2_LIB.BASEBOARD_FAB2(SCH_1):PAGE88

M_M_VREF @BASEBOARD_FAB2_LIB.BASEBOARD_FAB2(SCH_1):M_M_VREF
  C1A5    1      A CAP_A_0402V-0.01UF,25V,10%,X7RA   I178 @BASEBOARD_FAB2_LIB.BASEBOARD_FAB2(SCH_1):PAGE87
  J1A1  146 VREFCA SCONN288_H44441004_PIP-SCONN,HA   I186 @BASEBOARD_FAB2_LIB.BASEBOARD_FAB2(SCH_1):PAGE87
  J9L1  146 VREFCA SCONN288_H44441003_PIP-SCONN,HA   I111 @BASEBOARD_FAB2_LIB.BASEBOARD_FAB2(SCH_1):PAGE88
  C9L1    1      A CAP_A_0402V-0.01UF,25V,10%,X7RA   I177 @BASEBOARD_FAB2_LIB.BASEBOARD_FAB2(SCH_1):PAGE88
  R9L2    2      B RES_0402-1.00K,1%,1/16W,CHIP,GA    I38 @BASEBOARD_FAB2_LIB.BASEBOARD_FAB2(SCH_1):PAGE100
  R9L1    1      A RES_0402-1.00K,1%,1/16W,CHIP,GA    I40 @BASEBOARD_FAB2_LIB.BASEBOARD_FAB2(SCH_1):PAGE100
  R9L3    2      B RES_0402-2,1.0%,1/16W,CHIP,G21A    I45 @BASEBOARD_FAB2_LIB.BASEBOARD_FAB2(SCH_1):PAGE100

NC         NC
 EU4D2    3  NC<0> NB3W1200L_LCC-IC,H13585-001     I1 @BASEBOARD_FAB2_LIB.BASEBOARD_FAB2(SCH_1):PAGE102
 EU4D2   16  NC<1> NB3W1200L_LCC-IC,H13585-001     I1 @BASEBOARD_FAB2_LIB.BASEBOARD_FAB2(SCH_1):PAGE102
 EU4D2   15  NC<2> NB3W1200L_LCC-IC,H13585-001     I1 @BASEBOARD_FAB2_LIB.BASEBOARD_FAB2(SCH_1):PAGE102
  U7C1  K24 CLKOUT_SRCN<12> LBG_CORE_QAT_EXT_D_BGA1-IC,H91A    I40 @BASEBOARD_FAB2_LIB.BASEBOARD_FAB2(SCH_1):PAGE114
  U7C1  C24 CLKOUT_SRCN<13> LBG_CORE_QAT_EXT_D_BGA1-IC,H91A    I40 @BASEBOARD_FAB2_LIB.BASEBOARD_FAB2(SCH_1):PAGE114
  U7C1  H24 CLKOUT_SRCP<12> LBG_CORE_QAT_EXT_D_BGA1-IC,H91A    I40 @BASEBOARD_FAB2_LIB.BASEBOARD_FAB2(SCH_1):PAGE114
  U7C1  A24 CLKOUT_SRCP<13> LBG_CORE_QAT_EXT_D_BGA1-IC,H91A    I40 @BASEBOARD_FAB2_LIB.BASEBOARD_FAB2(SCH_1):PAGE114
  U7C1 BA65 PCIE8_SSATA2_GBE_RXN LBG_CORE_QAT_EXT_D_BGA1-IC,H91A   I220 @BASEBOARD_FAB2_LIB.BASEBOARD_FAB2(SCH_1):PAGE116
  U7C1 BD65 PCIE8_SSATA2_GBE_RXP LBG_CORE_QAT_EXT_D_BGA1-IC,H91A   I220 @BASEBOARD_FAB2_LIB.BASEBOARD_FAB2(SCH_1):PAGE116
  U7C1 AF70 PCIE8_SSATA2_GBE_TXN LBG_CORE_QAT_EXT_D_BGA1-IC,H91A   I220 @BASEBOARD_FAB2_LIB.BASEBOARD_FAB2(SCH_1):PAGE116
  U7C1 AF72 PCIE8_SSATA2_GBE_TXP LBG_CORE_QAT_EXT_D_BGA1-IC,H91A   I220 @BASEBOARD_FAB2_LIB.BASEBOARD_FAB2(SCH_1):PAGE116
  U7C1 AW65 PCIE9_SSATA3_RXN LBG_CORE_QAT_EXT_D_BGA1-IC,H91A   I220 @BASEBOARD_FAB2_LIB.BASEBOARD_FAB2(SCH_1):PAGE116
  U7C1 AY66 PCIE9_SSATA3_RXP LBG_CORE_QAT_EXT_D_BGA1-IC,H91A   I220 @BASEBOARD_FAB2_LIB.BASEBOARD_FAB2(SCH_1):PAGE116
  U7C1 AE69 PCIE9_SSATA3_TXN LBG_CORE_QAT_EXT_D_BGA1-IC,H91A   I220 @BASEBOARD_FAB2_LIB.BASEBOARD_FAB2(SCH_1):PAGE116
  U7C1 AE71 PCIE9_SSATA3_TXP LBG_CORE_QAT_EXT_D_BGA1-IC,H91A   I220 @BASEBOARD_FAB2_LIB.BASEBOARD_FAB2(SCH_1):PAGE116
  U7C1 AV63 PCIE10_SSATA4_RXN LBG_CORE_QAT_EXT_D_BGA1-IC,H91A   I220 @BASEBOARD_FAB2_LIB.BASEBOARD_FAB2(SCH_1):PAGE116
  U7C1 AU65 PCIE10_SSATA4_RXP LBG_CORE_QAT_EXT_D_BGA1-IC,H91A   I220 @BASEBOARD_FAB2_LIB.BASEBOARD_FAB2(SCH_1):PAGE116
  U7C1 AD70 PCIE10_SSATA4_TXN LBG_CORE_QAT_EXT_D_BGA1-IC,H91A   I220 @BASEBOARD_FAB2_LIB.BASEBOARD_FAB2(SCH_1):PAGE116
  U7C1 AD72 PCIE10_SSATA4_TXP LBG_CORE_QAT_EXT_D_BGA1-IC,H91A   I220 @BASEBOARD_FAB2_LIB.BASEBOARD_FAB2(SCH_1):PAGE116
  U7C1 AT66 PCIE11_SSATA5_GBE_RXN LBG_CORE_QAT_EXT_D_BGA1-IC,H91A   I220 @BASEBOARD_FAB2_LIB.BASEBOARD_FAB2(SCH_1):PAGE116
  U7C1 AV66 PCIE11_SSATA5_GBE_RXP LBG_CORE_QAT_EXT_D_BGA1-IC,H91A   I220 @BASEBOARD_FAB2_LIB.BASEBOARD_FAB2(SCH_1):PAGE116
  U7C1 AC69 PCIE11_SSATA5_GBE_TXN LBG_CORE_QAT_EXT_D_BGA1-IC,H91A   I220 @BASEBOARD_FAB2_LIB.BASEBOARD_FAB2(SCH_1):PAGE116
  U7C1 AC71 PCIE11_SSATA5_GBE_TXP LBG_CORE_QAT_EXT_D_BGA1-IC,H91A   I220 @BASEBOARD_FAB2_LIB.BASEBOARD_FAB2(SCH_1):PAGE116
  U7C1 BJ37 LAN_RX_P2N LBG_CORE_QAT_EXT_D_BGA1-IC,H91A    I73 @BASEBOARD_FAB2_LIB.BASEBOARD_FAB2(SCH_1):PAGE118
  U7C1 BG37 LAN_RX_P2P LBG_CORE_QAT_EXT_D_BGA1-IC,H91A    I73 @BASEBOARD_FAB2_LIB.BASEBOARD_FAB2(SCH_1):PAGE118
  U7C1 BF35 LAN_RX_P3N LBG_CORE_QAT_EXT_D_BGA1-IC,H91A    I73 @BASEBOARD_FAB2_LIB.BASEBOARD_FAB2(SCH_1):PAGE118
  U7C1 BH35 LAN_RX_P3P LBG_CORE_QAT_EXT_D_BGA1-IC,H91A    I73 @BASEBOARD_FAB2_LIB.BASEBOARD_FAB2(SCH_1):PAGE118
  U7C1 BM35 LAN_TX_P2N LBG_CORE_QAT_EXT_D_BGA1-IC,H91A    I73 @BASEBOARD_FAB2_LIB.BASEBOARD_FAB2(SCH_1):PAGE118
  U7C1 BR35 LAN_TX_P2P LBG_CORE_QAT_EXT_D_BGA1-IC,H91A    I73 @BASEBOARD_FAB2_LIB.BASEBOARD_FAB2(SCH_1):PAGE118
  U7C1 BR31 LAN_TX_P3N LBG_CORE_QAT_EXT_D_BGA1-IC,H91A    I73 @BASEBOARD_FAB2_LIB.BASEBOARD_FAB2(SCH_1):PAGE118
  U7C1 BM31 LAN_TX_P3P LBG_CORE_QAT_EXT_D_BGA1-IC,H91A    I73 @BASEBOARD_FAB2_LIB.BASEBOARD_FAB2(SCH_1):PAGE118
  U7C1  AA4 GPP_A10_CLKOUT_LPC1 LBG_CORE_QAT_EXT_D_BGA1-IC,H91A   I115 @BASEBOARD_FAB2_LIB.BASEBOARD_FAB2(SCH_1):PAGE119
  U7C1   W4 GPP_A20 LBG_CORE_QAT_EXT_D_BGA1-IC,H91A   I115 @BASEBOARD_FAB2_LIB.BASEBOARD_FAB2(SCH_1):PAGE119
  U7C1 BV44 GPP_D21_IE_UART_RX LBG_CORE_QAT_EXT_D_BGA1-IC,H91A   I115 @BASEBOARD_FAB2_LIB.BASEBOARD_FAB2(SCH_1):PAGE119
  U7C1 BR46 GPP_D22_IE_UART_TX LBG_CORE_QAT_EXT_D_BGA1-IC,H91A   I115 @BASEBOARD_FAB2_LIB.BASEBOARD_FAB2(SCH_1):PAGE119
  U7C1 AY11 GPP_G0_FANTACH0_FANTACH0IE LBG_CORE_QAT_EXT_D_BGA1-IC,H91A   I147 @BASEBOARD_FAB2_LIB.BASEBOARD_FAB2(SCH_1):PAGE120
  U7C1 AV15 GPP_G1_FANTACH1_FANTACH1IE LBG_CORE_QAT_EXT_D_BGA1-IC,H91A   I147 @BASEBOARD_FAB2_LIB.BASEBOARD_FAB2(SCH_1):PAGE120
  U7C1 BE22 GPP_G2_FANTACH2_FANTACH2IE LBG_CORE_QAT_EXT_D_BGA1-IC,H91A   I147 @BASEBOARD_FAB2_LIB.BASEBOARD_FAB2(SCH_1):PAGE120
  U7C1  AY7 GPP_G3_FANTACH3_FANTACH3IE LBG_CORE_QAT_EXT_D_BGA1-IC,H91A   I147 @BASEBOARD_FAB2_LIB.BASEBOARD_FAB2(SCH_1):PAGE120
  U7C1  BA9 GPP_G4_FANTACH4_FANTACH4IE LBG_CORE_QAT_EXT_D_BGA1-IC,H91A   I147 @BASEBOARD_FAB2_LIB.BASEBOARD_FAB2(SCH_1):PAGE120
  U7C1 AW20 GPP_G5_FANTACH5_FANTACH5IE LBG_CORE_QAT_EXT_D_BGA1-IC,H91A   I147 @BASEBOARD_FAB2_LIB.BASEBOARD_FAB2(SCH_1):PAGE120
  U7C1 AY15 GPP_G7_FANTACH7_FANTACH7IE LBG_CORE_QAT_EXT_D_BGA1-IC,H91A   I147 @BASEBOARD_FAB2_LIB.BASEBOARD_FAB2(SCH_1):PAGE120
  U7C1 BG11 GPP_G8_FANPWM0_FANPWM0IE LBG_CORE_QAT_EXT_D_BGA1-IC,H91A   I147 @BASEBOARD_FAB2_LIB.BASEBOARD_FAB2(SCH_1):PAGE120
  U7C1 AV11 GPP_G9_FANPWM1_FAMPWM1IE LBG_CORE_QAT_EXT_D_BGA1-IC,H91A   I147 @BASEBOARD_FAB2_LIB.BASEBOARD_FAB2(SCH_1):PAGE120
  U7C1 BE11 GPP_G10_FANPWM2_FANPWM2IE LBG_CORE_QAT_EXT_D_BGA1-IC,H91A   I147 @BASEBOARD_FAB2_LIB.BASEBOARD_FAB2(SCH_1):PAGE120
  U7C1 BA20 GPP_G11_FANPWM3_FANPMW3IE LBG_CORE_QAT_EXT_D_BGA1-IC,H91A   I147 @BASEBOARD_FAB2_LIB.BASEBOARD_FAB2(SCH_1):PAGE120
  U7C1  AV3 GPP_H2_SRCCLKREQ8_N LBG_CORE_QAT_EXT_D_BGA1-IC,H91A   I147 @BASEBOARD_FAB2_LIB.BASEBOARD_FAB2(SCH_1):PAGE120
  U7C1  AR1 GPP_H3_SRCCLKREQ9_N LBG_CORE_QAT_EXT_D_BGA1-IC,H91A   I147 @BASEBOARD_FAB2_LIB.BASEBOARD_FAB2(SCH_1):PAGE120
  U7C1  AT2 GPP_H4_SRCCLKREQ10_N LBG_CORE_QAT_EXT_D_BGA1-IC,H91A   I147 @BASEBOARD_FAB2_LIB.BASEBOARD_FAB2(SCH_1):PAGE120
  U7C1  AY3 GPP_H5_SRCCLKREQ11_N LBG_CORE_QAT_EXT_D_BGA1-IC,H91A   I147 @BASEBOARD_FAB2_LIB.BASEBOARD_FAB2(SCH_1):PAGE120
  U7C1  AW2 GPP_H6_SRCCLKREQ12_N LBG_CORE_QAT_EXT_D_BGA1-IC,H91A   I147 @BASEBOARD_FAB2_LIB.BASEBOARD_FAB2(SCH_1):PAGE120
  U7C1  AV1 GPP_H7_SRCCLKREQ13_N LBG_CORE_QAT_EXT_D_BGA1-IC,H91A   I147 @BASEBOARD_FAB2_LIB.BASEBOARD_FAB2(SCH_1):PAGE120
  U7C1  AR3 GPP_H8_SRCCLKREQ14_N LBG_CORE_QAT_EXT_D_BGA1-IC,H91A   I147 @BASEBOARD_FAB2_LIB.BASEBOARD_FAB2(SCH_1):PAGE120
  U7C1  BE2 GPP_H9_SRCCLKREQ15_N LBG_CORE_QAT_EXT_D_BGA1-IC,H91A   I147 @BASEBOARD_FAB2_LIB.BASEBOARD_FAB2(SCH_1):PAGE120
  U7C1  AY1 GPP_H13_SML3CLK_IE LBG_CORE_QAT_EXT_D_BGA1-IC,H91A   I147 @BASEBOARD_FAB2_LIB.BASEBOARD_FAB2(SCH_1):PAGE120
  U7C1  BC2 GPP_H14_SML3DATA_IE LBG_CORE_QAT_EXT_D_BGA1-IC,H91A   I147 @BASEBOARD_FAB2_LIB.BASEBOARD_FAB2(SCH_1):PAGE120
 EU9E1   22     NC SPRINGVILLE_SM1-IC,G47144-004    I72 @BASEBOARD_FAB2_LIB.BASEBOARD_FAB2(SCH_1):PAGE139
  J8E4    5    IO5 SCONN64_H87568002_A_SMT-CONN,HA    I27 @BASEBOARD_FAB2_LIB.BASEBOARD_FAB2(SCH_1):PAGE188
  J8E4    6    IO6 SCONN64_H87568002_A_SMT-CONN,HA    I27 @BASEBOARD_FAB2_LIB.BASEBOARD_FAB2(SCH_1):PAGE188
  J8E4   11   IO11 SCONN64_H87568002_A_SMT-CONN,HA    I27 @BASEBOARD_FAB2_LIB.BASEBOARD_FAB2(SCH_1):PAGE188
  J8E4   12   IO12 SCONN64_H87568002_A_SMT-CONN,HA    I27 @BASEBOARD_FAB2_LIB.BASEBOARD_FAB2(SCH_1):PAGE188
  J8E4   17   IO17 SCONN64_H87568002_A_SMT-CONN,HA    I27 @BASEBOARD_FAB2_LIB.BASEBOARD_FAB2(SCH_1):PAGE188
  J8E4   18   IO18 SCONN64_H87568002_A_SMT-CONN,HA    I27 @BASEBOARD_FAB2_LIB.BASEBOARD_FAB2(SCH_1):PAGE188
  J8E4   23   IO23 SCONN64_H87568002_A_SMT-CONN,HA    I27 @BASEBOARD_FAB2_LIB.BASEBOARD_FAB2(SCH_1):PAGE188
  J8E4   24   IO24 SCONN64_H87568002_A_SMT-CONN,HA    I27 @BASEBOARD_FAB2_LIB.BASEBOARD_FAB2(SCH_1):PAGE188
  U8D7   H5   PL9C LCMXO2_A_256BGA-IC,H63395-001   I179 @BASEBOARD_FAB2_LIB.BASEBOARD_FAB2(SCH_1):PAGE190
  U8D7   J4   PL9D LCMXO2_A_256BGA-IC,H63395-001   I179 @BASEBOARD_FAB2_LIB.BASEBOARD_FAB2(SCH_1):PAGE190
  U8D7   A2  NC<0> LCMXO2_A_256BGA-IC,H63395-001    I14 @BASEBOARD_FAB2_LIB.BASEBOARD_FAB2(SCH_1):PAGE192
 EU4D4   33 AIREF6 PXE1610B_QFN-IC,H79206-001   I155 @BASEBOARD_FAB2_LIB.BASEBOARD_FAB2(SCH_1):PAGE201
 EU4D4   34 AISEN6 PXE1610B_QFN-IC,H79206-001   I155 @BASEBOARD_FAB2_LIB.BASEBOARD_FAB2(SCH_1):PAGE201
 EU4D4    2  APWM6 PXE1610B_QFN-IC,H79206-001   I155 @BASEBOARD_FAB2_LIB.BASEBOARD_FAB2(SCH_1):PAGE201
 EU4D4   46 IINSEN PXE1610B_QFN-IC,H79206-001   I155 @BASEBOARD_FAB2_LIB.BASEBOARD_FAB2(SCH_1):PAGE201
 EU4D4   16    MP1 PXE1610B_QFN-IC,H79206-001   I155 @BASEBOARD_FAB2_LIB.BASEBOARD_FAB2(SCH_1):PAGE201
 EU4D4   40    MP4 PXE1610B_QFN-IC,H79206-001   I155 @BASEBOARD_FAB2_LIB.BASEBOARD_FAB2(SCH_1):PAGE201
 EU4D4   10 RESET_N PXE1610B_QFN-IC,H79206-001   I155 @BASEBOARD_FAB2_LIB.BASEBOARD_FAB2(SCH_1):PAGE201
 EU4E1   31     NC IR354XX_SM-IR35411,IC,H73688-0A    I63 @BASEBOARD_FAB2_LIB.BASEBOARD_FAB2(SCH_1):PAGE202
 EU4D6   31     NC IR354XX_SM-IR35411,IC,H73688-0A    I64 @BASEBOARD_FAB2_LIB.BASEBOARD_FAB2(SCH_1):PAGE202
 EU4D3   31     NC IR354XX_SM-IR35411,IC,H73688-0A    I70 @BASEBOARD_FAB2_LIB.BASEBOARD_FAB2(SCH_1):PAGE203
 EU4D1   31     NC IR354XX_SM-IR35411,IC,H73688-0A    I71 @BASEBOARD_FAB2_LIB.BASEBOARD_FAB2(SCH_1):PAGE203
 EU4C2   31     NC IR354XX_SM-IR35411,IC,H73688-0A    I71 @BASEBOARD_FAB2_LIB.BASEBOARD_FAB2(SCH_1):PAGE204
 EU4C1   31     NC IR354XX_SM-IR35412,IC,H73684-0A    I46 @BASEBOARD_FAB2_LIB.BASEBOARD_FAB2(SCH_1):PAGE205
 EU1C2   33 AIREF6 PXE1610B_QFN-IC,H79206-001   I130 @BASEBOARD_FAB2_LIB.BASEBOARD_FAB2(SCH_1):PAGE206
 EU1C2   34 AISEN6 PXE1610B_QFN-IC,H79206-001   I130 @BASEBOARD_FAB2_LIB.BASEBOARD_FAB2(SCH_1):PAGE206
 EU1C2    2  APWM6 PXE1610B_QFN-IC,H79206-001   I130 @BASEBOARD_FAB2_LIB.BASEBOARD_FAB2(SCH_1):PAGE206
 EU1C2   46 IINSEN PXE1610B_QFN-IC,H79206-001   I130 @BASEBOARD_FAB2_LIB.BASEBOARD_FAB2(SCH_1):PAGE206
 EU1C2   16    MP1 PXE1610B_QFN-IC,H79206-001   I130 @BASEBOARD_FAB2_LIB.BASEBOARD_FAB2(SCH_1):PAGE206
 EU1C2   40    MP4 PXE1610B_QFN-IC,H79206-001   I130 @BASEBOARD_FAB2_LIB.BASEBOARD_FAB2(SCH_1):PAGE206
 EU1C2   10 RESET_N PXE1610B_QFN-IC,H79206-001   I130 @BASEBOARD_FAB2_LIB.BASEBOARD_FAB2(SCH_1):PAGE206
 EU1E2   31     NC IR354XX_SM-IR35411,IC,H73688-0A    I20 @BASEBOARD_FAB2_LIB.BASEBOARD_FAB2(SCH_1):PAGE207
 EU1D3   31     NC IR354XX_SM-IR35411,IC,H73688-0A    I27 @BASEBOARD_FAB2_LIB.BASEBOARD_FAB2(SCH_1):PAGE208
 EU1D1   31     NC IR354XX_SM-IR35411,IC,H73688-0A    I71 @BASEBOARD_FAB2_LIB.BASEBOARD_FAB2(SCH_1):PAGE208
 EU1C3   31     NC IR354XX_SM-IR35411,IC,H73688-0A    I56 @BASEBOARD_FAB2_LIB.BASEBOARD_FAB2(SCH_1):PAGE209
 EU1C1   31     NC IR354XX_SM-IR35412,IC,H73684-0A    I51 @BASEBOARD_FAB2_LIB.BASEBOARD_FAB2(SCH_1):PAGE210
 EU3P1   25 BIREF1 PXE1110B_QFN-IC,H89187-001    I93 @BASEBOARD_FAB2_LIB.BASEBOARD_FAB2(SCH_1):PAGE211
 EU3P1    3  BPWM1 PXE1110B_QFN-IC,H89187-001    I93 @BASEBOARD_FAB2_LIB.BASEBOARD_FAB2(SCH_1):PAGE211
 EU3P1   34  BTSEN PXE1110B_QFN-IC,H89187-001    I93 @BASEBOARD_FAB2_LIB.BASEBOARD_FAB2(SCH_1):PAGE211
 EU3P1   30  BVREF PXE1110B_QFN-IC,H89187-001    I93 @BASEBOARD_FAB2_LIB.BASEBOARD_FAB2(SCH_1):PAGE211
 EU3P1   29  BVSEN PXE1110B_QFN-IC,H89187-001    I93 @BASEBOARD_FAB2_LIB.BASEBOARD_FAB2(SCH_1):PAGE211
 EU3P1    1 DNC<0> PXE1110B_QFN-IC,H89187-001    I93 @BASEBOARD_FAB2_LIB.BASEBOARD_FAB2(SCH_1):PAGE211
 EU3P1    2 DNC<1> PXE1110B_QFN-IC,H89187-001    I93 @BASEBOARD_FAB2_LIB.BASEBOARD_FAB2(SCH_1):PAGE211
 EU3P1    4 DNC<2> PXE1110B_QFN-IC,H89187-001    I93 @BASEBOARD_FAB2_LIB.BASEBOARD_FAB2(SCH_1):PAGE211
 EU3P1   24 DNC<3> PXE1110B_QFN-IC,H89187-001    I93 @BASEBOARD_FAB2_LIB.BASEBOARD_FAB2(SCH_1):PAGE211
 EU3P1   28 DNC<4> PXE1110B_QFN-IC,H89187-001    I93 @BASEBOARD_FAB2_LIB.BASEBOARD_FAB2(SCH_1):PAGE211
 EU3P1   38 IINSEN PXE1110B_QFN-IC,H89187-001    I93 @BASEBOARD_FAB2_LIB.BASEBOARD_FAB2(SCH_1):PAGE211
 EU3P1   13    MP0 PXE1110B_QFN-IC,H89187-001    I93 @BASEBOARD_FAB2_LIB.BASEBOARD_FAB2(SCH_1):PAGE211
 EU3P1   14    MP1 PXE1110B_QFN-IC,H89187-001    I93 @BASEBOARD_FAB2_LIB.BASEBOARD_FAB2(SCH_1):PAGE211
 EU3P1   18    MP2 PXE1110B_QFN-IC,H89187-001    I93 @BASEBOARD_FAB2_LIB.BASEBOARD_FAB2(SCH_1):PAGE211
 EU3P1   31    MP3 PXE1110B_QFN-IC,H89187-001    I93 @BASEBOARD_FAB2_LIB.BASEBOARD_FAB2(SCH_1):PAGE211
 EU3P1   12 PINALRT_N PXE1110B_QFN-IC,H89187-001    I93 @BASEBOARD_FAB2_LIB.BASEBOARD_FAB2(SCH_1):PAGE211
 EU3P1    8 RESET_N PXE1110B_QFN-IC,H89187-001    I93 @BASEBOARD_FAB2_LIB.BASEBOARD_FAB2(SCH_1):PAGE211
 EU7C1   31     NC IR354XX_SM-IR35412,IC,H73684-0A   I101 @BASEBOARD_FAB2_LIB.BASEBOARD_FAB2(SCH_1):PAGE212
 EU4D5   25 BIREF1 PXE1110B_QFN-IC,H89187-001    I96 @BASEBOARD_FAB2_LIB.BASEBOARD_FAB2(SCH_1):PAGE213
 EU4D5    3  BPWM1 PXE1110B_QFN-IC,H89187-001    I96 @BASEBOARD_FAB2_LIB.BASEBOARD_FAB2(SCH_1):PAGE213
 EU4D5   34  BTSEN PXE1110B_QFN-IC,H89187-001    I96 @BASEBOARD_FAB2_LIB.BASEBOARD_FAB2(SCH_1):PAGE213
 EU4D5   30  BVREF PXE1110B_QFN-IC,H89187-001    I96 @BASEBOARD_FAB2_LIB.BASEBOARD_FAB2(SCH_1):PAGE213
 EU4D5   29  BVSEN PXE1110B_QFN-IC,H89187-001    I96 @BASEBOARD_FAB2_LIB.BASEBOARD_FAB2(SCH_1):PAGE213
 EU4D5    1 DNC<0> PXE1110B_QFN-IC,H89187-001    I96 @BASEBOARD_FAB2_LIB.BASEBOARD_FAB2(SCH_1):PAGE213
 EU4D5    2 DNC<1> PXE1110B_QFN-IC,H89187-001    I96 @BASEBOARD_FAB2_LIB.BASEBOARD_FAB2(SCH_1):PAGE213
 EU4D5    4 DNC<2> PXE1110B_QFN-IC,H89187-001    I96 @BASEBOARD_FAB2_LIB.BASEBOARD_FAB2(SCH_1):PAGE213
 EU4D5   24 DNC<3> PXE1110B_QFN-IC,H89187-001    I96 @BASEBOARD_FAB2_LIB.BASEBOARD_FAB2(SCH_1):PAGE213
 EU4D5   28 DNC<4> PXE1110B_QFN-IC,H89187-001    I96 @BASEBOARD_FAB2_LIB.BASEBOARD_FAB2(SCH_1):PAGE213
 EU4D5   38 IINSEN PXE1110B_QFN-IC,H89187-001    I96 @BASEBOARD_FAB2_LIB.BASEBOARD_FAB2(SCH_1):PAGE213
 EU4D5   13    MP0 PXE1110B_QFN-IC,H89187-001    I96 @BASEBOARD_FAB2_LIB.BASEBOARD_FAB2(SCH_1):PAGE213
 EU4D5   14    MP1 PXE1110B_QFN-IC,H89187-001    I96 @BASEBOARD_FAB2_LIB.BASEBOARD_FAB2(SCH_1):PAGE213
 EU4D5   18    MP2 PXE1110B_QFN-IC,H89187-001    I96 @BASEBOARD_FAB2_LIB.BASEBOARD_FAB2(SCH_1):PAGE213
 EU4D5   31    MP3 PXE1110B_QFN-IC,H89187-001    I96 @BASEBOARD_FAB2_LIB.BASEBOARD_FAB2(SCH_1):PAGE213
 EU4D5   12 PINALRT_N PXE1110B_QFN-IC,H89187-001    I96 @BASEBOARD_FAB2_LIB.BASEBOARD_FAB2(SCH_1):PAGE213
 EU4D5    8 RESET_N PXE1110B_QFN-IC,H89187-001    I96 @BASEBOARD_FAB2_LIB.BASEBOARD_FAB2(SCH_1):PAGE213
 EU4E2   31     NC IR354XX_SM-IR35412,IC,H73684-0A   I126 @BASEBOARD_FAB2_LIB.BASEBOARD_FAB2(SCH_1):PAGE214
 EU7G2   31     NC IR354XX_SM-IR35411,IC,H73688-0A   I102 @BASEBOARD_FAB2_LIB.BASEBOARD_FAB2(SCH_1):PAGE216
 EU7G3   31     NC IR354XX_SM-IR35411,IC,H73688-0A   I103 @BASEBOARD_FAB2_LIB.BASEBOARD_FAB2(SCH_1):PAGE216
 EU7A1   31     NC IR354XX_SM-IR35411,IC,H73688-0A   I106 @BASEBOARD_FAB2_LIB.BASEBOARD_FAB2(SCH_1):PAGE219
 EU7A4   31     NC IR354XX_SM-IR35411,IC,H73688-0A   I107 @BASEBOARD_FAB2_LIB.BASEBOARD_FAB2(SCH_1):PAGE219
 EU1G1   31     NC IR354XX_SM-IR35411,IC,H73688-0A   I110 @BASEBOARD_FAB2_LIB.BASEBOARD_FAB2(SCH_1):PAGE224
 EU1F1   31     NC IR354XX_SM-IR35411,IC,H73688-0A   I111 @BASEBOARD_FAB2_LIB.BASEBOARD_FAB2(SCH_1):PAGE224
 EU1A2   31     NC IR354XX_SM-IR35411,IC,H73688-0A   I101 @BASEBOARD_FAB2_LIB.BASEBOARD_FAB2(SCH_1):PAGE227
 EU1A1   31     NC IR354XX_SM-IR35411,IC,H73688-0A   I102 @BASEBOARD_FAB2_LIB.BASEBOARD_FAB2(SCH_1):PAGE227
 EU8A1    1 DNC<0> PXE1110B_QFN-IC,H89187-001   I229 @BASEBOARD_FAB2_LIB.BASEBOARD_FAB2(SCH_1):PAGE235
 EU8A1    2 DNC<1> PXE1110B_QFN-IC,H89187-001   I229 @BASEBOARD_FAB2_LIB.BASEBOARD_FAB2(SCH_1):PAGE235
 EU8A1    4 DNC<2> PXE1110B_QFN-IC,H89187-001   I229 @BASEBOARD_FAB2_LIB.BASEBOARD_FAB2(SCH_1):PAGE235
 EU8A1   24 DNC<3> PXE1110B_QFN-IC,H89187-001   I229 @BASEBOARD_FAB2_LIB.BASEBOARD_FAB2(SCH_1):PAGE235
 EU8A1   28 DNC<4> PXE1110B_QFN-IC,H89187-001   I229 @BASEBOARD_FAB2_LIB.BASEBOARD_FAB2(SCH_1):PAGE235
 EU8A1   38 IINSEN PXE1110B_QFN-IC,H89187-001   I229 @BASEBOARD_FAB2_LIB.BASEBOARD_FAB2(SCH_1):PAGE235
 EU8A1   18    MP2 PXE1110B_QFN-IC,H89187-001   I229 @BASEBOARD_FAB2_LIB.BASEBOARD_FAB2(SCH_1):PAGE235
 EU8A1   31    MP3 PXE1110B_QFN-IC,H89187-001   I229 @BASEBOARD_FAB2_LIB.BASEBOARD_FAB2(SCH_1):PAGE235
 EU8A1    8 RESET_N PXE1110B_QFN-IC,H89187-001   I229 @BASEBOARD_FAB2_LIB.BASEBOARD_FAB2(SCH_1):PAGE235
 EU8A1   17 VALRT_N PXE1110B_QFN-IC,H89187-001   I229 @BASEBOARD_FAB2_LIB.BASEBOARD_FAB2(SCH_1):PAGE235
 EU7A3   31     NC IR354XX_SM-IR35412,IC,H73684-0A   I116 @BASEBOARD_FAB2_LIB.BASEBOARD_FAB2(SCH_1):PAGE236
 EU7A2   31     NC IR354XX_SM-IR35412,IC,H73684-0A   I117 @BASEBOARD_FAB2_LIB.BASEBOARD_FAB2(SCH_1):PAGE236
 CONX8    2      2 SMC-CONN60A-22-GP_CONN-G7-SMC-A    I48 @BASEBOARD_FAB2_LIB.BASEBOARD_FAB2(SCH_1):PAGE245
 CONX8  NP1    NP1 SMC-CONN60A-22-GP_CONN-G7-SMC-A    I48 @BASEBOARD_FAB2_LIB.BASEBOARD_FAB2(SCH_1):PAGE245
 CONX8  NP2    NP2 SMC-CONN60A-22-GP_CONN-G7-SMC-A    I48 @BASEBOARD_FAB2_LIB.BASEBOARD_FAB2(SCH_1):PAGE245
 U25W4  W20 GPIOS5_VPOB7 AST2520A1-GP-GP_ASIC2-GB1-AST2A   I104 @BASEBOARD_FAB2_LIB.BASEBOARD_FAB2(SCH_1):PAGE146
 U25W4  R20 GPIOAB3_VPOCLK_WDTRST2 AST2520A1-GP-GP_ASIC2-GB1-AST2A   I105 @BASEBOARD_FAB2_LIB.BASEBOARD_FAB2(SCH_1):PAGE146
 U25W4   B5 RGMII1TXCK_RMII1RCLKO_GPIOT0 AST2520A1-GP-GP_ASIC2-GB1-AST2A   I106 @BASEBOARD_FAB2_LIB.BASEBOARD_FAB2(SCH_1):PAGE147
 U25W4   B2 RGMII2TXCK_RMII2RCLKO_GPIOT6 AST2520A1-GP-GP_ASIC2-GB1-AST2A   I106 @BASEBOARD_FAB2_LIB.BASEBOARD_FAB2(SCH_1):PAGE147
 U25W4   D3 RGMIICK AST2520A1-GP-GP_ASIC2-GB1-AST2A   I106 @BASEBOARD_FAB2_LIB.BASEBOARD_FAB2(SCH_1):PAGE147
 U25W5   T7  NC#T7 H5AN4G6NAFR-TFC-GP_MEMORY-G2-HA    I49 @BASEBOARD_FAB2_LIB.BASEBOARD_FAB2(SCH_1):PAGE151
CR25W1    5    AC3 DIODEAC_DUAL_ARRAY_SM9-ESD3V3UA   I129 @BASEBOARD_FAB2_LIB.BASEBOARD_FAB2(SCH_1):PAGE255
CR25W1    6   OUT3 DIODEAC_DUAL_ARRAY_SM9-ESD3V3UA   I129 @BASEBOARD_FAB2_LIB.BASEBOARD_FAB2(SCH_1):PAGE255
  J2W1  NP1    NP1 SKT-SATA7P-6P-165-GP-U1_SOCKETA    I67 @BASEBOARD_FAB2_LIB.BASEBOARD_FAB2(SCH_1):PAGE172
  J2W1  NP2    NP2 SKT-SATA7P-6P-165-GP-U1_SOCKETA    I67 @BASEBOARD_FAB2_LIB.BASEBOARD_FAB2(SCH_1):PAGE172
  J2W2  NP1    NP1 SKT-SATA7P-6P-165-GP-U1_SOCKETA    I68 @BASEBOARD_FAB2_LIB.BASEBOARD_FAB2(SCH_1):PAGE172
  J2W2  NP2    NP2 SKT-SATA7P-6P-165-GP-U1_SOCKETA    I68 @BASEBOARD_FAB2_LIB.BASEBOARD_FAB2(SCH_1):PAGE172
  J8F1   20     20 SKT-MINI67P-41-GP_SOCKET-G4-SKA   I143 @BASEBOARD_FAB2_LIB.BASEBOARD_FAB2(SCH_1):PAGE185
  J8F1   22     22 SKT-MINI67P-41-GP_SOCKET-G4-SKA   I143 @BASEBOARD_FAB2_LIB.BASEBOARD_FAB2(SCH_1):PAGE185
  J8F1   24     24 SKT-MINI67P-41-GP_SOCKET-G4-SKA   I143 @BASEBOARD_FAB2_LIB.BASEBOARD_FAB2(SCH_1):PAGE185
  J8F1   26     26 SKT-MINI67P-41-GP_SOCKET-G4-SKA   I143 @BASEBOARD_FAB2_LIB.BASEBOARD_FAB2(SCH_1):PAGE185
  J8F1   28     28 SKT-MINI67P-41-GP_SOCKET-G4-SKA   I143 @BASEBOARD_FAB2_LIB.BASEBOARD_FAB2(SCH_1):PAGE185
  J8F1   30     30 SKT-MINI67P-41-GP_SOCKET-G4-SKA   I143 @BASEBOARD_FAB2_LIB.BASEBOARD_FAB2(SCH_1):PAGE185
  J8F1   32     32 SKT-MINI67P-41-GP_SOCKET-G4-SKA   I143 @BASEBOARD_FAB2_LIB.BASEBOARD_FAB2(SCH_1):PAGE185
  J8F1   34     34 SKT-MINI67P-41-GP_SOCKET-G4-SKA   I143 @BASEBOARD_FAB2_LIB.BASEBOARD_FAB2(SCH_1):PAGE185
  J8F1   36     36 SKT-MINI67P-41-GP_SOCKET-G4-SKA   I143 @BASEBOARD_FAB2_LIB.BASEBOARD_FAB2(SCH_1):PAGE185
  J8F1   46     46 SKT-MINI67P-41-GP_SOCKET-G4-SKA   I143 @BASEBOARD_FAB2_LIB.BASEBOARD_FAB2(SCH_1):PAGE185
  J8F1   48     48 SKT-MINI67P-41-GP_SOCKET-G4-SKA   I143 @BASEBOARD_FAB2_LIB.BASEBOARD_FAB2(SCH_1):PAGE185
  J8F1   56     56 SKT-MINI67P-41-GP_SOCKET-G4-SKA   I143 @BASEBOARD_FAB2_LIB.BASEBOARD_FAB2(SCH_1):PAGE185
  J8F1   58     58 SKT-MINI67P-41-GP_SOCKET-G4-SKA   I143 @BASEBOARD_FAB2_LIB.BASEBOARD_FAB2(SCH_1):PAGE185
  J8F1   67     67 SKT-MINI67P-41-GP_SOCKET-G4-SKA   I143 @BASEBOARD_FAB2_LIB.BASEBOARD_FAB2(SCH_1):PAGE185
  J8F1  NP1    NP1 SKT-MINI67P-41-GP_SOCKET-G4-SKA   I143 @BASEBOARD_FAB2_LIB.BASEBOARD_FAB2(SCH_1):PAGE185
  J8F1  NP2    NP2 SKT-MINI67P-41-GP_SOCKET-G4-SKA   I143 @BASEBOARD_FAB2_LIB.BASEBOARD_FAB2(SCH_1):PAGE185
  J1E1  NP1    NP1 FCI-CONN12-2R-GP_CONN-G5-FCI-CA   I114 @BASEBOARD_FAB2_LIB.BASEBOARD_FAB2(SCH_1):PAGE195
  J1D1  NP1    NP1 FCI-CONN12-2R-GP_CONN-G5-FCI-CA   I115 @BASEBOARD_FAB2_LIB.BASEBOARD_FAB2(SCH_1):PAGE195
 J30W1   A5    CC1 SKT-USB32-8-GP_SOCKET-G4-SKT-UA    I26 @BASEBOARD_FAB2_LIB.BASEBOARD_FAB2(SCH_1):PAGE253
 J30W1   B5    CC2 SKT-USB32-8-GP_SOCKET-G4-SKT-UA    I26 @BASEBOARD_FAB2_LIB.BASEBOARD_FAB2(SCH_1):PAGE253
 J30W1   A7    DN1 SKT-USB32-8-GP_SOCKET-G4-SKT-UA    I26 @BASEBOARD_FAB2_LIB.BASEBOARD_FAB2(SCH_1):PAGE253
 J30W1   B7    DN2 SKT-USB32-8-GP_SOCKET-G4-SKT-UA    I26 @BASEBOARD_FAB2_LIB.BASEBOARD_FAB2(SCH_1):PAGE253
 J30W1   A6    DP1 SKT-USB32-8-GP_SOCKET-G4-SKT-UA    I26 @BASEBOARD_FAB2_LIB.BASEBOARD_FAB2(SCH_1):PAGE253
 J30W1   B6    DP2 SKT-USB32-8-GP_SOCKET-G4-SKT-UA    I26 @BASEBOARD_FAB2_LIB.BASEBOARD_FAB2(SCH_1):PAGE253
 J30W1  NP1    NP1 SKT-USB32-8-GP_SOCKET-G4-SKT-UA    I26 @BASEBOARD_FAB2_LIB.BASEBOARD_FAB2(SCH_1):PAGE253
 J30W1  NP2    NP2 SKT-USB32-8-GP_SOCKET-G4-SKT-UA    I26 @BASEBOARD_FAB2_LIB.BASEBOARD_FAB2(SCH_1):PAGE253
 J30W1   A8   SBU1 SKT-USB32-8-GP_SOCKET-G4-SKT-UA    I26 @BASEBOARD_FAB2_LIB.BASEBOARD_FAB2(SCH_1):PAGE253
 J30W1   B8   SBU2 SKT-USB32-8-GP_SOCKET-G4-SKT-UA    I26 @BASEBOARD_FAB2_LIB.BASEBOARD_FAB2(SCH_1):PAGE253
 J30W1  A10 SSRXN2 SKT-USB32-8-GP_SOCKET-G4-SKT-UA    I26 @BASEBOARD_FAB2_LIB.BASEBOARD_FAB2(SCH_1):PAGE253
 J30W1  A11 SSRXP2 SKT-USB32-8-GP_SOCKET-G4-SKT-UA    I26 @BASEBOARD_FAB2_LIB.BASEBOARD_FAB2(SCH_1):PAGE253
 J30W1   B3 SSTXN2 SKT-USB32-8-GP_SOCKET-G4-SKT-UA    I26 @BASEBOARD_FAB2_LIB.BASEBOARD_FAB2(SCH_1):PAGE253
 J30W1   B2 SSTXP2 SKT-USB32-8-GP_SOCKET-G4-SKT-UA    I26 @BASEBOARD_FAB2_LIB.BASEBOARD_FAB2(SCH_1):PAGE253
 EU7G1   25 AIREF3 PXM1310B_QFN-IC,H89186-001    I69 @BASEBOARD_FAB2_LIB.BASEBOARD_FAB2(SCH_1):PAGE215
 EU7G1   26 AISEN3 PXM1310B_QFN-IC,H89186-001    I69 @BASEBOARD_FAB2_LIB.BASEBOARD_FAB2(SCH_1):PAGE215
 EU7G1    3  APWM3 PXM1310B_QFN-IC,H89186-001    I69 @BASEBOARD_FAB2_LIB.BASEBOARD_FAB2(SCH_1):PAGE215
 EU7G1   31 BIREF1 PXM1310B_QFN-IC,H89186-001    I69 @BASEBOARD_FAB2_LIB.BASEBOARD_FAB2(SCH_1):PAGE215
 EU7G1    1  BPWM1 PXM1310B_QFN-IC,H89186-001    I69 @BASEBOARD_FAB2_LIB.BASEBOARD_FAB2(SCH_1):PAGE215
 EU7G1   34  BTSEN PXM1310B_QFN-IC,H89186-001    I69 @BASEBOARD_FAB2_LIB.BASEBOARD_FAB2(SCH_1):PAGE215
 EU7G1   30  BVREF PXM1310B_QFN-IC,H89186-001    I69 @BASEBOARD_FAB2_LIB.BASEBOARD_FAB2(SCH_1):PAGE215
 EU7G1   29  BVSEN PXM1310B_QFN-IC,H89186-001    I69 @BASEBOARD_FAB2_LIB.BASEBOARD_FAB2(SCH_1):PAGE215
 EU7G1    2 DNC<0> PXM1310B_QFN-IC,H89186-001    I69 @BASEBOARD_FAB2_LIB.BASEBOARD_FAB2(SCH_1):PAGE215
 EU7G1   28 DNC<1> PXM1310B_QFN-IC,H89186-001    I69 @BASEBOARD_FAB2_LIB.BASEBOARD_FAB2(SCH_1):PAGE215
 EU7G1   12 PINALRT_N PXM1310B_QFN-IC,H89186-001    I69 @BASEBOARD_FAB2_LIB.BASEBOARD_FAB2(SCH_1):PAGE215
 EU7G1    8 RESET_N PXM1310B_QFN-IC,H89186-001    I69 @BASEBOARD_FAB2_LIB.BASEBOARD_FAB2(SCH_1):PAGE215
 EU7A5   25 AIREF3 PXM1310B_QFN-IC,H89186-001    I69 @BASEBOARD_FAB2_LIB.BASEBOARD_FAB2(SCH_1):PAGE218
 EU7A5   26 AISEN3 PXM1310B_QFN-IC,H89186-001    I69 @BASEBOARD_FAB2_LIB.BASEBOARD_FAB2(SCH_1):PAGE218
 EU7A5    3  APWM3 PXM1310B_QFN-IC,H89186-001    I69 @BASEBOARD_FAB2_LIB.BASEBOARD_FAB2(SCH_1):PAGE218
 EU7A5   31 BIREF1 PXM1310B_QFN-IC,H89186-001    I69 @BASEBOARD_FAB2_LIB.BASEBOARD_FAB2(SCH_1):PAGE218
 EU7A5    1  BPWM1 PXM1310B_QFN-IC,H89186-001    I69 @BASEBOARD_FAB2_LIB.BASEBOARD_FAB2(SCH_1):PAGE218
 EU7A5   34  BTSEN PXM1310B_QFN-IC,H89186-001    I69 @BASEBOARD_FAB2_LIB.BASEBOARD_FAB2(SCH_1):PAGE218
 EU7A5   30  BVREF PXM1310B_QFN-IC,H89186-001    I69 @BASEBOARD_FAB2_LIB.BASEBOARD_FAB2(SCH_1):PAGE218
 EU7A5   29  BVSEN PXM1310B_QFN-IC,H89186-001    I69 @BASEBOARD_FAB2_LIB.BASEBOARD_FAB2(SCH_1):PAGE218
 EU7A5    2 DNC<0> PXM1310B_QFN-IC,H89186-001    I69 @BASEBOARD_FAB2_LIB.BASEBOARD_FAB2(SCH_1):PAGE218
 EU7A5   28 DNC<1> PXM1310B_QFN-IC,H89186-001    I69 @BASEBOARD_FAB2_LIB.BASEBOARD_FAB2(SCH_1):PAGE218
 EU7A5   12 PINALRT_N PXM1310B_QFN-IC,H89186-001    I69 @BASEBOARD_FAB2_LIB.BASEBOARD_FAB2(SCH_1):PAGE218
 EU7A5    8 RESET_N PXM1310B_QFN-IC,H89186-001    I69 @BASEBOARD_FAB2_LIB.BASEBOARD_FAB2(SCH_1):PAGE218
 EU1G2   25 AIREF3 PXM1310B_QFN-IC,H89186-001    I69 @BASEBOARD_FAB2_LIB.BASEBOARD_FAB2(SCH_1):PAGE223
 EU1G2   26 AISEN3 PXM1310B_QFN-IC,H89186-001    I69 @BASEBOARD_FAB2_LIB.BASEBOARD_FAB2(SCH_1):PAGE223
 EU1G2    3  APWM3 PXM1310B_QFN-IC,H89186-001    I69 @BASEBOARD_FAB2_LIB.BASEBOARD_FAB2(SCH_1):PAGE223
 EU1G2   31 BIREF1 PXM1310B_QFN-IC,H89186-001    I69 @BASEBOARD_FAB2_LIB.BASEBOARD_FAB2(SCH_1):PAGE223
 EU1G2    1  BPWM1 PXM1310B_QFN-IC,H89186-001    I69 @BASEBOARD_FAB2_LIB.BASEBOARD_FAB2(SCH_1):PAGE223
 EU1G2   34  BTSEN PXM1310B_QFN-IC,H89186-001    I69 @BASEBOARD_FAB2_LIB.BASEBOARD_FAB2(SCH_1):PAGE223
 EU1G2   30  BVREF PXM1310B_QFN-IC,H89186-001    I69 @BASEBOARD_FAB2_LIB.BASEBOARD_FAB2(SCH_1):PAGE223
 EU1G2   29  BVSEN PXM1310B_QFN-IC,H89186-001    I69 @BASEBOARD_FAB2_LIB.BASEBOARD_FAB2(SCH_1):PAGE223
 EU1G2    2 DNC<0> PXM1310B_QFN-IC,H89186-001    I69 @BASEBOARD_FAB2_LIB.BASEBOARD_FAB2(SCH_1):PAGE223
 EU1G2   28 DNC<1> PXM1310B_QFN-IC,H89186-001    I69 @BASEBOARD_FAB2_LIB.BASEBOARD_FAB2(SCH_1):PAGE223
 EU1G2   12 PINALRT_N PXM1310B_QFN-IC,H89186-001    I69 @BASEBOARD_FAB2_LIB.BASEBOARD_FAB2(SCH_1):PAGE223
 EU1G2    8 RESET_N PXM1310B_QFN-IC,H89186-001    I69 @BASEBOARD_FAB2_LIB.BASEBOARD_FAB2(SCH_1):PAGE223
 EU1B1   25 AIREF3 PXM1310B_QFN-IC,H89186-001    I69 @BASEBOARD_FAB2_LIB.BASEBOARD_FAB2(SCH_1):PAGE226
 EU1B1   26 AISEN3 PXM1310B_QFN-IC,H89186-001    I69 @BASEBOARD_FAB2_LIB.BASEBOARD_FAB2(SCH_1):PAGE226
 EU1B1    3  APWM3 PXM1310B_QFN-IC,H89186-001    I69 @BASEBOARD_FAB2_LIB.BASEBOARD_FAB2(SCH_1):PAGE226
 EU1B1   31 BIREF1 PXM1310B_QFN-IC,H89186-001    I69 @BASEBOARD_FAB2_LIB.BASEBOARD_FAB2(SCH_1):PAGE226
 EU1B1    1  BPWM1 PXM1310B_QFN-IC,H89186-001    I69 @BASEBOARD_FAB2_LIB.BASEBOARD_FAB2(SCH_1):PAGE226
 EU1B1   34  BTSEN PXM1310B_QFN-IC,H89186-001    I69 @BASEBOARD_FAB2_LIB.BASEBOARD_FAB2(SCH_1):PAGE226
 EU1B1   30  BVREF PXM1310B_QFN-IC,H89186-001    I69 @BASEBOARD_FAB2_LIB.BASEBOARD_FAB2(SCH_1):PAGE226
 EU1B1   29  BVSEN PXM1310B_QFN-IC,H89186-001    I69 @BASEBOARD_FAB2_LIB.BASEBOARD_FAB2(SCH_1):PAGE226
 EU1B1    2 DNC<0> PXM1310B_QFN-IC,H89186-001    I69 @BASEBOARD_FAB2_LIB.BASEBOARD_FAB2(SCH_1):PAGE226
 EU1B1   28 DNC<1> PXM1310B_QFN-IC,H89186-001    I69 @BASEBOARD_FAB2_LIB.BASEBOARD_FAB2(SCH_1):PAGE226
 EU1B1   12 PINALRT_N PXM1310B_QFN-IC,H89186-001    I69 @BASEBOARD_FAB2_LIB.BASEBOARD_FAB2(SCH_1):PAGE226
 EU1B1    8 RESET_N PXM1310B_QFN-IC,H89186-001    I69 @BASEBOARD_FAB2_LIB.BASEBOARD_FAB2(SCH_1):PAGE226
  J1F2  NP1    NP1 LOTES-CON4-S1-GP_CONN-G7-LOTESA   I139 @BASEBOARD_FAB2_LIB.BASEBOARD_FAB2(SCH_1):PAGE161
 J10W1  NP1    NP1 LOTES-CON4-S1-GP_CONN-G7-LOTESA   I140 @BASEBOARD_FAB2_LIB.BASEBOARD_FAB2(SCH_1):PAGE161
 U32W2    3   SDAA TCA9517DGKR-GP_DISCRET-G8-TCA9A   I204 @BASEBOARD_FAB2_LIB.BASEBOARD_FAB2(SCH_1):PAGE185
 U32W2    6   SDAB TCA9517DGKR-GP_DISCRET-G8-TCA9A   I204 @BASEBOARD_FAB2_LIB.BASEBOARD_FAB2(SCH_1):PAGE185
 U6W11    9     P4 PCA9554PWR-GP_DISCRET-G1-PCA95A    I97 @BASEBOARD_FAB2_LIB.BASEBOARD_FAB2(SCH_1):PAGE164
 U6W11   10     P5 PCA9554PWR-GP_DISCRET-G1-PCA95A    I97 @BASEBOARD_FAB2_LIB.BASEBOARD_FAB2(SCH_1):PAGE164
 U6W11   11     P6 PCA9554PWR-GP_DISCRET-G1-PCA95A    I97 @BASEBOARD_FAB2_LIB.BASEBOARD_FAB2(SCH_1):PAGE164
 U6W11   12     P7 PCA9554PWR-GP_DISCRET-G1-PCA95A    I97 @BASEBOARD_FAB2_LIB.BASEBOARD_FAB2(SCH_1):PAGE164
 EU1D4   31     NC IR354XX_SM-IR35411,IC,H73688-0A   I113 @BASEBOARD_FAB2_LIB.BASEBOARD_FAB2(SCH_1):PAGE207
  S9W1    1      1 SW-SLIDE75-GP_DISCRET-G6-SW-SLA    I63 @BASEBOARD_FAB2_LIB.BASEBOARD_FAB2(SCH_1):PAGE268
  S9W1  NP1    NP1 SW-SLIDE75-GP_DISCRET-G6-SW-SLA    I63 @BASEBOARD_FAB2_LIB.BASEBOARD_FAB2(SCH_1):PAGE268
  S9W1  NP2    NP2 SW-SLIDE75-GP_DISCRET-G6-SW-SLA    I63 @BASEBOARD_FAB2_LIB.BASEBOARD_FAB2(SCH_1):PAGE268

NC_CLK_156M_CPU0_OSC @BASEBOARD_FAB2_LIB.BASEBOARD_FAB2(SCH_1):NC_CLK_156M_CPU0_OSC
  Y6F1    2 NC_GND OSC_C_6P10-156.25MHZ,OSC,G6383A    I71 @BASEBOARD_FAB2_LIB.BASEBOARD_FAB2(SCH_1):PAGE104

NC_CLK_156M_CPU1_OSC @BASEBOARD_FAB2_LIB.BASEBOARD_FAB2(SCH_1):NC_CLK_156M_CPU1_OSC
  Y3F1    2 NC_GND OSC_C_6P10-156.25MHZ,OSC,G6383A    I72 @BASEBOARD_FAB2_LIB.BASEBOARD_FAB2(SCH_1):PAGE104

NC_M2<0> @BASEBOARD_FAB2_LIB.BASEBOARD_FAB2(SCH_1):NC_M2(0)
  J8F1    6      6 SKT-MINI67P-41-GP_SOCKET-G4-SKA   I143 @BASEBOARD_FAB2_LIB.BASEBOARD_FAB2(SCH_1):PAGE185

NC_M2<1> @BASEBOARD_FAB2_LIB.BASEBOARD_FAB2(SCH_1):NC_M2(1)
  J8F1    8      8 SKT-MINI67P-41-GP_SOCKET-G4-SKA   I143 @BASEBOARD_FAB2_LIB.BASEBOARD_FAB2(SCH_1):PAGE185

NC_PVDDQ_KLM_GP0 @BASEBOARD_FAB2_LIB.BASEBOARD_FAB2(SCH_1):NC_PVDDQ_KLM_GP0
R12W36    1      A RES_0402-0.0,5%,1/16W,EMPTY,G2A    I53 @BASEBOARD_FAB2_LIB.BASEBOARD_FAB2(SCH_1):PAGE226
 EU1B1   18    MP2 PXM1310B_QFN-IC,H89186-001    I69 @BASEBOARD_FAB2_LIB.BASEBOARD_FAB2(SCH_1):PAGE226

NC_PVDDQ_KLM_GP1 @BASEBOARD_FAB2_LIB.BASEBOARD_FAB2(SCH_1):NC_PVDDQ_KLM_GP1
R12W35    1      A RES_0402-0.0,5%,1/16W,EMPTY,G2A    I46 @BASEBOARD_FAB2_LIB.BASEBOARD_FAB2(SCH_1):PAGE226
 EU1B1   14    MP1 PXM1310B_QFN-IC,H89186-001    I69 @BASEBOARD_FAB2_LIB.BASEBOARD_FAB2(SCH_1):PAGE226

NIC_LED_ACT_ANODE_R @BASEBOARD_FAB2_LIB.BASEBOARD_FAB2(SCH_1):NIC_LED_ACT_ANODE_R
 JA9G1   L4     L4 SKT-RJ45-LED-XFOR-1-GP_SOCKET-A   I129 @BASEBOARD_FAB2_LIB.BASEBOARD_FAB2(SCH_1):PAGE141
  R9G4    1      A RES_0402-0.0,5%,1/16W,CHIP,G21A   I156 @BASEBOARD_FAB2_LIB.BASEBOARD_FAB2(SCH_1):PAGE141

NIC_MDI_MNG_RX_DN @BASEBOARD_FAB2_LIB.BASEBOARD_FAB2(SCH_1):NIC_MDI_MNG_RX_DN
 C9G12    2      B CAP_0402LF-4700PF,50V,10%,EMPTA   I100 @BASEBOARD_FAB2_LIB.BASEBOARD_FAB2(SCH_1):PAGE141
  J1F1   E5 MNG_RX_DN DM-FCI-CONN76-8R-GP-U-01_CONN-A   I134 @BASEBOARD_FAB2_LIB.BASEBOARD_FAB2(SCH_1):PAGE181

NIC_MDI_MNG_RX_DP @BASEBOARD_FAB2_LIB.BASEBOARD_FAB2(SCH_1):NIC_MDI_MNG_RX_DP
  C9G9    2      B CAP_0402LF-4700PF,50V,10%,EMPTA    I99 @BASEBOARD_FAB2_LIB.BASEBOARD_FAB2(SCH_1):PAGE141
  J1F1   D5 MNG_RX_DP DM-FCI-CONN76-8R-GP-U-01_CONN-A   I134 @BASEBOARD_FAB2_LIB.BASEBOARD_FAB2(SCH_1):PAGE181

NIC_MDI_MNG_TX_DN @BASEBOARD_FAB2_LIB.BASEBOARD_FAB2(SCH_1):NIC_MDI_MNG_TX_DN
 C9G13    2      B CAP_0402LF-4700PF,50V,10%,EMPTA   I102 @BASEBOARD_FAB2_LIB.BASEBOARD_FAB2(SCH_1):PAGE141
  J1F1   B5 MNG_TX_DN DM-FCI-CONN76-8R-GP-U-01_CONN-A   I134 @BASEBOARD_FAB2_LIB.BASEBOARD_FAB2(SCH_1):PAGE181

NIC_MDI_MNG_TX_DP @BASEBOARD_FAB2_LIB.BASEBOARD_FAB2(SCH_1):NIC_MDI_MNG_TX_DP
 C9G16    2      B CAP_0402LF-4700PF,50V,10%,EMPTA   I101 @BASEBOARD_FAB2_LIB.BASEBOARD_FAB2(SCH_1):PAGE141
  J1F1   A5 MNG_TX_DP DM-FCI-CONN76-8R-GP-U-01_CONN-A   I134 @BASEBOARD_FAB2_LIB.BASEBOARD_FAB2(SCH_1):PAGE181

NIC_MDI_SPRV_RJ45_0_DN @BASEBOARD_FAB2_LIB.BASEBOARD_FAB2(SCH_1):NIC_MDI_SPRV_RJ45_0_DN
 EU9E1   57 MDI_MINUS0_SFP_I2C_DATA SPRINGVILLE_SM1-IC,G47144-004    I72 @BASEBOARD_FAB2_LIB.BASEBOARD_FAB2(SCH_1):PAGE139
 R9G22    1      A RES_0402-0.0,5%,1/16W,CHIP,G21A    I82 @BASEBOARD_FAB2_LIB.BASEBOARD_FAB2(SCH_1):PAGE141

NIC_MDI_SPRV_RJ45_0_DP @BASEBOARD_FAB2_LIB.BASEBOARD_FAB2(SCH_1):NIC_MDI_SPRV_RJ45_0_DP
 EU9E1   58 MDI_PLUS0_NC SPRINGVILLE_SM1-IC,G47144-004    I72 @BASEBOARD_FAB2_LIB.BASEBOARD_FAB2(SCH_1):PAGE139
 R9G24    1      A RES_0402-0.0,5%,1/16W,CHIP,G21A    I81 @BASEBOARD_FAB2_LIB.BASEBOARD_FAB2(SCH_1):PAGE141

NIC_MDI_SPRV_RJ45_0_R_DN @BASEBOARD_FAB2_LIB.BASEBOARD_FAB2(SCH_1):NIC_MDI_SPRV_RJ45_0_R_DN
 R9G22    2      B RES_0402-0.0,5%,1/16W,CHIP,G21A    I82 @BASEBOARD_FAB2_LIB.BASEBOARD_FAB2(SCH_1):PAGE141
 JA9G1   R3     R3 SKT-RJ45-LED-XFOR-1-GP_SOCKET-A   I129 @BASEBOARD_FAB2_LIB.BASEBOARD_FAB2(SCH_1):PAGE141

NIC_MDI_SPRV_RJ45_0_R_DP @BASEBOARD_FAB2_LIB.BASEBOARD_FAB2(SCH_1):NIC_MDI_SPRV_RJ45_0_R_DP
 R9G24    2      B RES_0402-0.0,5%,1/16W,CHIP,G21A    I81 @BASEBOARD_FAB2_LIB.BASEBOARD_FAB2(SCH_1):PAGE141
 JA9G1   R2     R2 SKT-RJ45-LED-XFOR-1-GP_SOCKET-A   I129 @BASEBOARD_FAB2_LIB.BASEBOARD_FAB2(SCH_1):PAGE141

NIC_MDI_SPRV_RJ45_1_DN @BASEBOARD_FAB2_LIB.BASEBOARD_FAB2(SCH_1):NIC_MDI_SPRV_RJ45_1_DN
 EU9E1   54 MDI_MINUS1_SRDS_SIG_DET SPRINGVILLE_SM1-IC,G47144-004    I72 @BASEBOARD_FAB2_LIB.BASEBOARD_FAB2(SCH_1):PAGE139
 R9G20    1      A RES_0402-0.0,5%,1/16W,CHIP,G21A    I80 @BASEBOARD_FAB2_LIB.BASEBOARD_FAB2(SCH_1):PAGE141

NIC_MDI_SPRV_RJ45_1_DP @BASEBOARD_FAB2_LIB.BASEBOARD_FAB2(SCH_1):NIC_MDI_SPRV_RJ45_1_DP
 EU9E1   55 MDI_PLUS1_SFP_I2C_CLK SPRINGVILLE_SM1-IC,G47144-004    I72 @BASEBOARD_FAB2_LIB.BASEBOARD_FAB2(SCH_1):PAGE139
 R9G19    1      A RES_0402-0.0,5%,1/16W,CHIP,G21A    I79 @BASEBOARD_FAB2_LIB.BASEBOARD_FAB2(SCH_1):PAGE141

NIC_MDI_SPRV_RJ45_1_R_DN @BASEBOARD_FAB2_LIB.BASEBOARD_FAB2(SCH_1):NIC_MDI_SPRV_RJ45_1_R_DN
 R9G20    2      B RES_0402-0.0,5%,1/16W,CHIP,G21A    I80 @BASEBOARD_FAB2_LIB.BASEBOARD_FAB2(SCH_1):PAGE141
 JA9G1   R5     R5 SKT-RJ45-LED-XFOR-1-GP_SOCKET-A   I129 @BASEBOARD_FAB2_LIB.BASEBOARD_FAB2(SCH_1):PAGE141

NIC_MDI_SPRV_RJ45_1_R_DP @BASEBOARD_FAB2_LIB.BASEBOARD_FAB2(SCH_1):NIC_MDI_SPRV_RJ45_1_R_DP
 R9G19    2      B RES_0402-0.0,5%,1/16W,CHIP,G21A    I79 @BASEBOARD_FAB2_LIB.BASEBOARD_FAB2(SCH_1):PAGE141
 JA9G1   R4     R4 SKT-RJ45-LED-XFOR-1-GP_SOCKET-A   I129 @BASEBOARD_FAB2_LIB.BASEBOARD_FAB2(SCH_1):PAGE141

NIC_MDI_SPRV_RJ45_2_R_DN @BASEBOARD_FAB2_LIB.BASEBOARD_FAB2(SCH_1):NIC_MDI_SPRV_RJ45_2_R_DN
 R9G17    2      B RES_0402-0.0,5%,1/16W,CHIP,G21A    I78 @BASEBOARD_FAB2_LIB.BASEBOARD_FAB2(SCH_1):PAGE141
 JA9G1   R8     R8 SKT-RJ45-LED-XFOR-1-GP_SOCKET-A   I129 @BASEBOARD_FAB2_LIB.BASEBOARD_FAB2(SCH_1):PAGE141

NIC_MDI_SPRV_RJ45_2_R_DP @BASEBOARD_FAB2_LIB.BASEBOARD_FAB2(SCH_1):NIC_MDI_SPRV_RJ45_2_R_DP
 R9G18    2      B RES_0402-0.0,5%,1/16W,CHIP,G21A    I77 @BASEBOARD_FAB2_LIB.BASEBOARD_FAB2(SCH_1):PAGE141
 JA9G1   R7     R7 SKT-RJ45-LED-XFOR-1-GP_SOCKET-A   I129 @BASEBOARD_FAB2_LIB.BASEBOARD_FAB2(SCH_1):PAGE141

NIC_MDI_SPRV_RJ45_3_R_DN @BASEBOARD_FAB2_LIB.BASEBOARD_FAB2(SCH_1):NIC_MDI_SPRV_RJ45_3_R_DN
 R9G11    2      B RES_0402-0.0,5%,1/16W,CHIP,G21A    I76 @BASEBOARD_FAB2_LIB.BASEBOARD_FAB2(SCH_1):PAGE141
 JA9G1  R10    R10 SKT-RJ45-LED-XFOR-1-GP_SOCKET-A   I129 @BASEBOARD_FAB2_LIB.BASEBOARD_FAB2(SCH_1):PAGE141

NIC_MDI_SPRV_RJ45_3_R_DP @BASEBOARD_FAB2_LIB.BASEBOARD_FAB2(SCH_1):NIC_MDI_SPRV_RJ45_3_R_DP
  R9G9    2      B RES_0402-0.0,5%,1/16W,CHIP,G21A    I75 @BASEBOARD_FAB2_LIB.BASEBOARD_FAB2(SCH_1):PAGE141
 JA9G1   R9     R9 SKT-RJ45-LED-XFOR-1-GP_SOCKET-A   I129 @BASEBOARD_FAB2_LIB.BASEBOARD_FAB2(SCH_1):PAGE141

NIC_SER_N_MDI_3_DN @BASEBOARD_FAB2_LIB.BASEBOARD_FAB2(SCH_1):NIC_SER_N_MDI_3_DN
 EU9E1   49 MDI_MINUS3_SERN SPRINGVILLE_SM1-IC,G47144-004    I72 @BASEBOARD_FAB2_LIB.BASEBOARD_FAB2(SCH_1):PAGE139
 R9G11    1      A RES_0402-0.0,5%,1/16W,CHIP,G21A    I76 @BASEBOARD_FAB2_LIB.BASEBOARD_FAB2(SCH_1):PAGE141
 C9G12    1      A CAP_0402LF-4700PF,50V,10%,EMPTA   I100 @BASEBOARD_FAB2_LIB.BASEBOARD_FAB2(SCH_1):PAGE141

NIC_SER_P_MDI_3_DP @BASEBOARD_FAB2_LIB.BASEBOARD_FAB2(SCH_1):NIC_SER_P_MDI_3_DP
 EU9E1   50 MDI_PLUS3_SERP SPRINGVILLE_SM1-IC,G47144-004    I72 @BASEBOARD_FAB2_LIB.BASEBOARD_FAB2(SCH_1):PAGE139
  R9G9    1      A RES_0402-0.0,5%,1/16W,CHIP,G21A    I75 @BASEBOARD_FAB2_LIB.BASEBOARD_FAB2(SCH_1):PAGE141
  C9G9    1      A CAP_0402LF-4700PF,50V,10%,EMPTA    I99 @BASEBOARD_FAB2_LIB.BASEBOARD_FAB2(SCH_1):PAGE141

NIC_SET_N_MDI_2_DN @BASEBOARD_FAB2_LIB.BASEBOARD_FAB2(SCH_1):NIC_SET_N_MDI_2_DN
 EU9E1   52 MDI_MINUS2_SETN SPRINGVILLE_SM1-IC,G47144-004    I72 @BASEBOARD_FAB2_LIB.BASEBOARD_FAB2(SCH_1):PAGE139
 R9G17    1      A RES_0402-0.0,5%,1/16W,CHIP,G21A    I78 @BASEBOARD_FAB2_LIB.BASEBOARD_FAB2(SCH_1):PAGE141
 C9G13    1      A CAP_0402LF-4700PF,50V,10%,EMPTA   I102 @BASEBOARD_FAB2_LIB.BASEBOARD_FAB2(SCH_1):PAGE141

NIC_SET_P_MDI_2_DP @BASEBOARD_FAB2_LIB.BASEBOARD_FAB2(SCH_1):NIC_SET_P_MDI_2_DP
 EU9E1   53 MDI_PLUS2_SETP SPRINGVILLE_SM1-IC,G47144-004    I72 @BASEBOARD_FAB2_LIB.BASEBOARD_FAB2(SCH_1):PAGE139
 R9G18    1      A RES_0402-0.0,5%,1/16W,CHIP,G21A    I77 @BASEBOARD_FAB2_LIB.BASEBOARD_FAB2(SCH_1):PAGE141
 C9G16    1      A CAP_0402LF-4700PF,50V,10%,EMPTA   I101 @BASEBOARD_FAB2_LIB.BASEBOARD_FAB2(SCH_1):PAGE141

P0V7_GTL2014_2 @BASEBOARD_FAB2_LIB.BASEBOARD_FAB2(SCH_1):P0V7_GTL2014_2
  U9G1    4   VREF GTL2014_SM-IC,D66151-001     I1 @BASEBOARD_FAB2_LIB.BASEBOARD_FAB2(SCH_1):PAGE152
 R1U37    1      A RES_0402-100.0,1%,1/16W,CHIP,GA    I26 @BASEBOARD_FAB2_LIB.BASEBOARD_FAB2(SCH_1):PAGE152
 C1U22    1      A CAP_A_0402V-0.1UF,16V,10%,X7R,A    I27 @BASEBOARD_FAB2_LIB.BASEBOARD_FAB2(SCH_1):PAGE152
 R1W35    2      B RES_0402-49.9,1%,1/16W,EMPTY,GA   I105 @BASEBOARD_FAB2_LIB.BASEBOARD_FAB2(SCH_1):PAGE152
 R1U43    2      2 374R2F-1-GP_SMD-RG-374R2F-1-GPA   I106 @BASEBOARD_FAB2_LIB.BASEBOARD_FAB2(SCH_1):PAGE152

P0V7_GTL2014_VREF_6 @BASEBOARD_FAB2_LIB.BASEBOARD_FAB2(SCH_1):P0V7_GTL2014_VREF_6
C25W93    1      A CAP_A_0402V-0.1UF,16V,10%,X7R,A    I27 @BASEBOARD_FAB2_LIB.BASEBOARD_FAB2(SCH_1):PAGE268
R25W165    1      A RES_0402-100.0,1%,1/16W,CHIP,GA    I28 @BASEBOARD_FAB2_LIB.BASEBOARD_FAB2(SCH_1):PAGE268
R25W164    2      B RES_0402-49.9,1%,1/16W,CHIP,G2A    I29 @BASEBOARD_FAB2_LIB.BASEBOARD_FAB2(SCH_1):PAGE268
U25W11    4   VREF GTL2014_SM-IC,D66151-001    I33 @BASEBOARD_FAB2_LIB.BASEBOARD_FAB2(SCH_1):PAGE268
R25W183    2      2 374R2F-1-GP_SMD-RG-374R2F-1-GPA    I36 @BASEBOARD_FAB2_LIB.BASEBOARD_FAB2(SCH_1):PAGE268

P0V7_GTL2104_5_VREF @BASEBOARD_FAB2_LIB.BASEBOARD_FAB2(SCH_1):P0V7_GTL2104_5_VREF
  U2T4    4   VREF GTL2014_SM-IC,D66151-001    I30 @BASEBOARD_FAB2_LIB.BASEBOARD_FAB2(SCH_1):PAGE93
 C2T32    1      A CAP_A_0402V-0.1UF,16V,10%,X7R,A    I95 @BASEBOARD_FAB2_LIB.BASEBOARD_FAB2(SCH_1):PAGE93
 R2T39    1      A RES_0402-100.0,1%,1/16W,CHIP,GA    I98 @BASEBOARD_FAB2_LIB.BASEBOARD_FAB2(SCH_1):PAGE93
  R2W2    2      B RES_0402-49.9,1%,1/16W,EMPTY,GA   I147 @BASEBOARD_FAB2_LIB.BASEBOARD_FAB2(SCH_1):PAGE93
 R2T36    2      2 374R2F-1-GP_SMD-RG-374R2F-1-GPA   I148 @BASEBOARD_FAB2_LIB.BASEBOARD_FAB2(SCH_1):PAGE93

P0V7_GTL2104_VREF_0 @BASEBOARD_FAB2_LIB.BASEBOARD_FAB2(SCH_1):P0V7_GTL2104_VREF_0
  U7D2    4   VREF GTL2014_SM-IC,D66151-001    I32 @BASEBOARD_FAB2_LIB.BASEBOARD_FAB2(SCH_1):PAGE92
 R7D32    1      A RES_0402-100.0,1%,1/16W,CHIP,GA    I48 @BASEBOARD_FAB2_LIB.BASEBOARD_FAB2(SCH_1):PAGE92
  C7D5    1      A CAP_A_0402V-0.1UF,16V,10%,X7R,A    I52 @BASEBOARD_FAB2_LIB.BASEBOARD_FAB2(SCH_1):PAGE92
  R7W4    2      B RES_0402-49.9,1%,1/16W,EMPTY,GA   I106 @BASEBOARD_FAB2_LIB.BASEBOARD_FAB2(SCH_1):PAGE92
 R7D33    2      2 374R2F-1-GP_SMD-RG-374R2F-1-GPA   I111 @BASEBOARD_FAB2_LIB.BASEBOARD_FAB2(SCH_1):PAGE92

P0V7_GTL2104_VREF_1 @BASEBOARD_FAB2_LIB.BASEBOARD_FAB2(SCH_1):P0V7_GTL2104_VREF_1
  U3P2    4   VREF GTL2014_SM-IC,D66151-001     I1 @BASEBOARD_FAB2_LIB.BASEBOARD_FAB2(SCH_1):PAGE92
 C3P49    1      A CAP_A_0402V-0.1UF,16V,10%,X7R,A    I37 @BASEBOARD_FAB2_LIB.BASEBOARD_FAB2(SCH_1):PAGE92
 R3P49    1      A RES_0402-100.0,1%,1/16W,CHIP,GA    I38 @BASEBOARD_FAB2_LIB.BASEBOARD_FAB2(SCH_1):PAGE92
 R3W10    2      B RES_0402-49.9,1%,1/16W,EMPTY,GA   I108 @BASEBOARD_FAB2_LIB.BASEBOARD_FAB2(SCH_1):PAGE92
 R3P45    2      2 374R2F-1-GP_SMD-RG-374R2F-1-GPA   I110 @BASEBOARD_FAB2_LIB.BASEBOARD_FAB2(SCH_1):PAGE92

P0V9_LAN @BASEBOARD_FAB2_LIB.BASEBOARD_FAB2(SCH_1):P0V9_LAN
 EU9E1   59 VDD0P9<0> SPRINGVILLE_SM1-IC,G47144-004    I72 @BASEBOARD_FAB2_LIB.BASEBOARD_FAB2(SCH_1):PAGE139
 EU9E1   32 VDD0P9<1> SPRINGVILLE_SM1-IC,G47144-004    I72 @BASEBOARD_FAB2_LIB.BASEBOARD_FAB2(SCH_1):PAGE139
 EU9E1   11 VDD0P9<2> SPRINGVILLE_SM1-IC,G47144-004    I72 @BASEBOARD_FAB2_LIB.BASEBOARD_FAB2(SCH_1):PAGE139
 EU9E1   42 VDD0P9<3> SPRINGVILLE_SM1-IC,G47144-004    I72 @BASEBOARD_FAB2_LIB.BASEBOARD_FAB2(SCH_1):PAGE139
  C1T4    1      A CAP_0603-10UF,6.3V,20%,X6S,E15A   I134 @BASEBOARD_FAB2_LIB.BASEBOARD_FAB2(SCH_1):PAGE139
 C1R18    1      A CAP_A_0402V-0.1UF,16V,10%,X7R,A   I157 @BASEBOARD_FAB2_LIB.BASEBOARD_FAB2(SCH_1):PAGE139
  C1T5    1      A CAP_A_0402V-0.1UF,16V,10%,X7R,A   I158 @BASEBOARD_FAB2_LIB.BASEBOARD_FAB2(SCH_1):PAGE139
 C1R24    1      A CAP_A_0402V-0.1UF,16V,10%,X7R,A   I159 @BASEBOARD_FAB2_LIB.BASEBOARD_FAB2(SCH_1):PAGE139
 C1R15    1      A CAP_A_0402V-0.1UF,16V,10%,X7R,A   I160 @BASEBOARD_FAB2_LIB.BASEBOARD_FAB2(SCH_1):PAGE139
 C1R16    1      A CAP_0603-10UF,6.3V,20%,X6S,E15A   I161 @BASEBOARD_FAB2_LIB.BASEBOARD_FAB2(SCH_1):PAGE139
  C9E1    1      A CAP_A_0603V-22.0UF,4V,20%,EMPTA   I163 @BASEBOARD_FAB2_LIB.BASEBOARD_FAB2(SCH_1):PAGE139
 R1R15    1      A RES_0603-0,5.0%,1/10W,CHIP,G22A   I237 @BASEBOARD_FAB2_LIB.BASEBOARD_FAB2(SCH_1):PAGE139
 C9E12    1      A CAP_A_0603V-22.0UF,4V,20%,EMPTA   I241 @BASEBOARD_FAB2_LIB.BASEBOARD_FAB2(SCH_1):PAGE139

P0V9_LAN_I210 @BASEBOARD_FAB2_LIB.BASEBOARD_FAB2(SCH_1):P0V9_LAN_I210
 EU9E1   38 VDD0P9_OUT SPRINGVILLE_SM1-IC,G47144-004    I72 @BASEBOARD_FAB2_LIB.BASEBOARD_FAB2(SCH_1):PAGE139
 R1R15    2      B RES_0603-0,5.0%,1/10W,CHIP,G22A   I237 @BASEBOARD_FAB2_LIB.BASEBOARD_FAB2(SCH_1):PAGE139

P12V @BASEBOARD_FAB2_LIB.BASEBOARD_FAB2(SCH_1):P12V
 C2U20    1      A CAP_A_0402V-0.1UF,16V,10%,X7R,A     I1 @BASEBOARD_FAB2_LIB.BASEBOARD_FAB2(SCH_1):PAGE108
 C2U24    1      A CAP_A_0402V-0.1UF,16V,10%,X7R,A     I2 @BASEBOARD_FAB2_LIB.BASEBOARD_FAB2(SCH_1):PAGE108
  J8G1    1    IO1 SCONN200_H68296001_SM-CONN,H68A   I258 @BASEBOARD_FAB2_LIB.BASEBOARD_FAB2(SCH_1):PAGE108
  J8G1    2    IO2 SCONN200_H68296001_SM-CONN,H68A   I258 @BASEBOARD_FAB2_LIB.BASEBOARD_FAB2(SCH_1):PAGE108
  J8G1    3    IO3 SCONN200_H68296001_SM-CONN,H68A   I258 @BASEBOARD_FAB2_LIB.BASEBOARD_FAB2(SCH_1):PAGE108
  J8G1    4    IO4 SCONN200_H68296001_SM-CONN,H68A   I258 @BASEBOARD_FAB2_LIB.BASEBOARD_FAB2(SCH_1):PAGE108
  J8G1    5    IO5 SCONN200_H68296001_SM-CONN,H68A   I258 @BASEBOARD_FAB2_LIB.BASEBOARD_FAB2(SCH_1):PAGE108
  J8G1    6    IO6 SCONN200_H68296001_SM-CONN,H68A   I258 @BASEBOARD_FAB2_LIB.BASEBOARD_FAB2(SCH_1):PAGE108
  J8G1    7    IO7 SCONN200_H68296001_SM-CONN,H68A   I258 @BASEBOARD_FAB2_LIB.BASEBOARD_FAB2(SCH_1):PAGE108
  J8G1    8    IO8 SCONN200_H68296001_SM-CONN,H68A   I258 @BASEBOARD_FAB2_LIB.BASEBOARD_FAB2(SCH_1):PAGE108
  J8G1    9    IO9 SCONN200_H68296001_SM-CONN,H68A   I258 @BASEBOARD_FAB2_LIB.BASEBOARD_FAB2(SCH_1):PAGE108
  J8G1   10   IO10 SCONN200_H68296001_SM-CONN,H68A   I258 @BASEBOARD_FAB2_LIB.BASEBOARD_FAB2(SCH_1):PAGE108
  J8G1   11   IO11 SCONN200_H68296001_SM-CONN,H68A   I258 @BASEBOARD_FAB2_LIB.BASEBOARD_FAB2(SCH_1):PAGE108
  J8G1   12   IO12 SCONN200_H68296001_SM-CONN,H68A   I258 @BASEBOARD_FAB2_LIB.BASEBOARD_FAB2(SCH_1):PAGE108
 R8D38    1      A RES_0402-100.0K,1%,1/16W,CHIP,A   I112 @BASEBOARD_FAB2_LIB.BASEBOARD_FAB2(SCH_1):PAGE196
 EU7E1    6      S SLG55021_SM-IC,G56246-001    I19 @BASEBOARD_FAB2_LIB.BASEBOARD_FAB2(SCH_1):PAGE198
  C7E9    1      A CAP_A_0402V-0.1UF,16V,10%,X7R,A    I49 @BASEBOARD_FAB2_LIB.BASEBOARD_FAB2(SCH_1):PAGE198
  C7E8    1      A CAP_0805-10UF,16V,10%,X6S,C953A    I50 @BASEBOARD_FAB2_LIB.BASEBOARD_FAB2(SCH_1):PAGE198
  Q7E7    1    SRC MOSFET_N_LCC3-BSZ019N03LS,NFETA    I88 @BASEBOARD_FAB2_LIB.BASEBOARD_FAB2(SCH_1):PAGE198
  F9B1    1   A<0> FUSE_SM-IC,C94311-016    I66 @BASEBOARD_FAB2_LIB.BASEBOARD_FAB2(SCH_1):PAGE172

P12V_FAN @BASEBOARD_FAB2_LIB.BASEBOARD_FAB2(SCH_1):P12V_FAN
 C1E21    1      A CAP_0805-10UF,16V,10%,X6S,C953A     I3 @BASEBOARD_FAB2_LIB.BASEBOARD_FAB2(SCH_1):PAGE161
 C1E20    1      A CAP_A_0402V-0.1UF,16V,10%,X7R,A     I4 @BASEBOARD_FAB2_LIB.BASEBOARD_FAB2(SCH_1):PAGE161
  C9M5    1      A CAP_A_0402V-0.1UF,16V,10%,X7R,A    I26 @BASEBOARD_FAB2_LIB.BASEBOARD_FAB2(SCH_1):PAGE161
  C9M4    1      A CAP_0805-10UF,16V,10%,X6S,C953A    I27 @BASEBOARD_FAB2_LIB.BASEBOARD_FAB2(SCH_1):PAGE161
 C1B18    1      A CAP_0805-10UF,16V,10%,X6S,C953A    I61 @BASEBOARD_FAB2_LIB.BASEBOARD_FAB2(SCH_1):PAGE198
 C1B19    1      A CAP_A_0402V-0.1UF,16V,10%,X7R,A    I64 @BASEBOARD_FAB2_LIB.BASEBOARD_FAB2(SCH_1):PAGE198
 EU9M1    6      S SLG55021_SM-IC,G56246-001    I69 @BASEBOARD_FAB2_LIB.BASEBOARD_FAB2(SCH_1):PAGE198
  Q1B1    1    SRC MOSFET_N_LCC3-BSZ019N03LS,NFETA    I86 @BASEBOARD_FAB2_LIB.BASEBOARD_FAB2(SCH_1):PAGE198
 R10W5    1      A RES_0805-0.0,5%,1/8W,CHIP,G221A     I5 @BASEBOARD_FAB2_LIB.BASEBOARD_FAB2(SCH_1):PAGE251
  J1F2    2      2 LOTES-CON4-S1-GP_CONN-G7-LOTESA   I139 @BASEBOARD_FAB2_LIB.BASEBOARD_FAB2(SCH_1):PAGE161
 J10W1    2      2 LOTES-CON4-S1-GP_CONN-G7-LOTESA   I140 @BASEBOARD_FAB2_LIB.BASEBOARD_FAB2(SCH_1):PAGE161

P12V_FAN_SWITCH_G @BASEBOARD_FAB2_LIB.BASEBOARD_FAB2(SCH_1):P12V_FAN_SWITCH_G
 EU9M1    7      G SLG55021_SM-IC,G56246-001    I69 @BASEBOARD_FAB2_LIB.BASEBOARD_FAB2(SCH_1):PAGE198
  Q1B1    4   GATE MOSFET_N_LCC3-BSZ019N03LS,NFETA    I86 @BASEBOARD_FAB2_LIB.BASEBOARD_FAB2(SCH_1):PAGE198

P12V_HDD_SATA @BASEBOARD_FAB2_LIB.BASEBOARD_FAB2(SCH_1):P12V_HDD_SATA
  C9B2    1      A CAP_0805-10UF,16V,10%,X6S,C953A    I36 @BASEBOARD_FAB2_LIB.BASEBOARD_FAB2(SCH_1):PAGE172
  F9B1    2   B<0> FUSE_SM-IC,C94311-016    I66 @BASEBOARD_FAB2_LIB.BASEBOARD_FAB2(SCH_1):PAGE172
  J2W1   P5     P5 SKT-SATA7P-6P-165-GP-U1_SOCKETA    I67 @BASEBOARD_FAB2_LIB.BASEBOARD_FAB2(SCH_1):PAGE172
  J2W1   P6     P6 SKT-SATA7P-6P-165-GP-U1_SOCKETA    I67 @BASEBOARD_FAB2_LIB.BASEBOARD_FAB2(SCH_1):PAGE172
  J2W2   P5     P5 SKT-SATA7P-6P-165-GP-U1_SOCKETA    I68 @BASEBOARD_FAB2_LIB.BASEBOARD_FAB2(SCH_1):PAGE172
  J2W2   P6     P6 SKT-SATA7P-6P-165-GP-U1_SOCKETA    I68 @BASEBOARD_FAB2_LIB.BASEBOARD_FAB2(SCH_1):PAGE172

P12V_HSC_SENN0 @BASEBOARD_FAB2_LIB.BASEBOARD_FAB2(SCH_1):P12V_HSC_SENN0
 R1D49    4      4 RES_PWR_6PAD-0.001,1%,3W,CHIP,A    I50 @BASEBOARD_FAB2_LIB.BASEBOARD_FAB2(SCH_1):PAGE200
 R1D47    1      A RES_0402-10.0,1%,1/16W,CHIP,G2A    I52 @BASEBOARD_FAB2_LIB.BASEBOARD_FAB2(SCH_1):PAGE200

P12V_HSC_SENN1 @BASEBOARD_FAB2_LIB.BASEBOARD_FAB2(SCH_1):P12V_HSC_SENN1
  R9R1    4      4 RES_PWR_6PAD-0.001,1%,3W,CHIP,A    I49 @BASEBOARD_FAB2_LIB.BASEBOARD_FAB2(SCH_1):PAGE200
 R9P26    1      A RES_0402-10.0,1%,1/16W,CHIP,G2A    I51 @BASEBOARD_FAB2_LIB.BASEBOARD_FAB2(SCH_1):PAGE200

P12V_HSC_SENP0 @BASEBOARD_FAB2_LIB.BASEBOARD_FAB2(SCH_1):P12V_HSC_SENP0
 R1D46    1      A RES_0402-10.0,1%,1/16W,CHIP,G2A    I48 @BASEBOARD_FAB2_LIB.BASEBOARD_FAB2(SCH_1):PAGE200
 R1D49    3      3 RES_PWR_6PAD-0.001,1%,3W,CHIP,A    I50 @BASEBOARD_FAB2_LIB.BASEBOARD_FAB2(SCH_1):PAGE200

P12V_HSC_SENP1 @BASEBOARD_FAB2_LIB.BASEBOARD_FAB2(SCH_1):P12V_HSC_SENP1
 R9P27    1      A RES_0402-10.0,1%,1/16W,CHIP,G2A    I47 @BASEBOARD_FAB2_LIB.BASEBOARD_FAB2(SCH_1):PAGE200
  R9R1    3      3 RES_PWR_6PAD-0.001,1%,3W,CHIP,A    I49 @BASEBOARD_FAB2_LIB.BASEBOARD_FAB2(SCH_1):PAGE200

P12V_HSC_VCC @BASEBOARD_FAB2_LIB.BASEBOARD_FAB2(SCH_1):P12V_HSC_VCC
 R9P30    2      B RES_0603-10.0,1%,1/10W,CHIP,G2A     I2 @BASEBOARD_FAB2_LIB.BASEBOARD_FAB2(SCH_1):PAGE199
 C1D25    1      A CAP_0402-1.0UF,16V,10%,X6S,D97A     I3 @BASEBOARD_FAB2_LIB.BASEBOARD_FAB2(SCH_1):PAGE199
 EU1D2   30    VCC ADM1278_SM-IC,G99251-001    I10 @BASEBOARD_FAB2_LIB.BASEBOARD_FAB2(SCH_1):PAGE199

P12V_MB0_SW @BASEBOARD_FAB2_LIB.BASEBOARD_FAB2(SCH_1):P12V_MB0_SW
  R9R1    2      2 RES_PWR_6PAD-0.001,1%,3W,CHIP,A    I49 @BASEBOARD_FAB2_LIB.BASEBOARD_FAB2(SCH_1):PAGE200
  R9R1    6      6 RES_PWR_6PAD-0.001,1%,3W,CHIP,A    I49 @BASEBOARD_FAB2_LIB.BASEBOARD_FAB2(SCH_1):PAGE200
 R1D49    2      2 RES_PWR_6PAD-0.001,1%,3W,CHIP,A    I50 @BASEBOARD_FAB2_LIB.BASEBOARD_FAB2(SCH_1):PAGE200
 R1D49    6      6 RES_PWR_6PAD-0.001,1%,3W,CHIP,A    I50 @BASEBOARD_FAB2_LIB.BASEBOARD_FAB2(SCH_1):PAGE200
 EU1E3    5      D MOSFETN_1D3S_SOT5-IC,G68777-001    I54 @BASEBOARD_FAB2_LIB.BASEBOARD_FAB2(SCH_1):PAGE200
 EU9R1    5      D MOSFETN_1D3S_SOT5-IC,G68777-001    I57 @BASEBOARD_FAB2_LIB.BASEBOARD_FAB2(SCH_1):PAGE200
 EU1E1    5      D MOSFETN_1D3S_SOT5-IC,G68777-001    I59 @BASEBOARD_FAB2_LIB.BASEBOARD_FAB2(SCH_1):PAGE200

P12V_NVDIMM_ABC @BASEBOARD_FAB2_LIB.BASEBOARD_FAB2(SCH_1):P12V_NVDIMM_ABC
  J4G1  145 12V<0> SCONN288_H44441004_PIP-SCONN,HA   I260 @BASEBOARD_FAB2_LIB.BASEBOARD_FAB2(SCH_1):PAGE43
  J4G1    1 12V<1> SCONN288_H44441004_PIP-SCONN,HA   I260 @BASEBOARD_FAB2_LIB.BASEBOARD_FAB2(SCH_1):PAGE43
  J6T1  145 12V<0> SCONN288_H44441003_PIP-SCONN,HA    I75 @BASEBOARD_FAB2_LIB.BASEBOARD_FAB2(SCH_1):PAGE44
  J6T1    1 12V<1> SCONN288_H44441003_PIP-SCONN,HA    I75 @BASEBOARD_FAB2_LIB.BASEBOARD_FAB2(SCH_1):PAGE44
  J4G2  145 12V<0> SCONN288_H44441004_PIP-SCONN,HA   I169 @BASEBOARD_FAB2_LIB.BASEBOARD_FAB2(SCH_1):PAGE45
  J4G2    1 12V<1> SCONN288_H44441004_PIP-SCONN,HA   I169 @BASEBOARD_FAB2_LIB.BASEBOARD_FAB2(SCH_1):PAGE45
  J6U1  145 12V<0> SCONN288_H44441003_PIP-SCONN,HA    I67 @BASEBOARD_FAB2_LIB.BASEBOARD_FAB2(SCH_1):PAGE46
  J6U1    1 12V<1> SCONN288_H44441003_PIP-SCONN,HA    I67 @BASEBOARD_FAB2_LIB.BASEBOARD_FAB2(SCH_1):PAGE46
  J4G3  145 12V<0> SCONN288_H44441004_PIP-SCONN,HA   I179 @BASEBOARD_FAB2_LIB.BASEBOARD_FAB2(SCH_1):PAGE47
  J4G3    1 12V<1> SCONN288_H44441004_PIP-SCONN,HA   I179 @BASEBOARD_FAB2_LIB.BASEBOARD_FAB2(SCH_1):PAGE47
  J6U2  145 12V<0> SCONN288_H44441003_PIP-SCONN,HA   I171 @BASEBOARD_FAB2_LIB.BASEBOARD_FAB2(SCH_1):PAGE48
  J6U2    1 12V<1> SCONN288_H44441003_PIP-SCONN,HA   I171 @BASEBOARD_FAB2_LIB.BASEBOARD_FAB2(SCH_1):PAGE48
  R4F2    2      B RES_1206-0.002,1%,1W,CHIP,G521A    I14 @BASEBOARD_FAB2_LIB.BASEBOARD_FAB2(SCH_1):PAGE197
 Q12W1    2 SOURCE#2 BSL308C-H6327-GP_DISCRET-GB1-BA    I43 @BASEBOARD_FAB2_LIB.BASEBOARD_FAB2(SCH_1):PAGE197
 R12W4    1      A RES_0603-100.0K,1%,1/10W,CHIP,A    I45 @BASEBOARD_FAB2_LIB.BASEBOARD_FAB2(SCH_1):PAGE197
 C6U18    1      A CAP_0805-10UF,16V,10%,X7R,G106A    I69 @BASEBOARD_FAB2_LIB.BASEBOARD_FAB2(SCH_1):PAGE197
  C6T2    1      A CAP_0805-10UF,16V,10%,X7R,G106A    I71 @BASEBOARD_FAB2_LIB.BASEBOARD_FAB2(SCH_1):PAGE197
 C6U10    1      A CAP_0805-10UF,16V,10%,X7R,G106A    I84 @BASEBOARD_FAB2_LIB.BASEBOARD_FAB2(SCH_1):PAGE197

P12V_NVDIMM_ABC_D @BASEBOARD_FAB2_LIB.BASEBOARD_FAB2(SCH_1):P12V_NVDIMM_ABC_D
 Q12W1    4 DRAIN#4 BSL308C-H6327-GP_DISCRET-GB1-BA    I43 @BASEBOARD_FAB2_LIB.BASEBOARD_FAB2(SCH_1):PAGE197
 R12W3    2      2 4D02R2F-GP_SMD-RG2-4D02R2F-GP,A   I115 @BASEBOARD_FAB2_LIB.BASEBOARD_FAB2(SCH_1):PAGE197
 R12W2    1      1 665KR5B-1-GP_SMD-RG3-665KR5B-1A   I117 @BASEBOARD_FAB2_LIB.BASEBOARD_FAB2(SCH_1):PAGE197

P12V_NVDIMM_DEF @BASEBOARD_FAB2_LIB.BASEBOARD_FAB2(SCH_1):P12V_NVDIMM_DEF
  J4B1  145 12V<0> SCONN288_H44441004_PIP-SCONN,HA   I169 @BASEBOARD_FAB2_LIB.BASEBOARD_FAB2(SCH_1):PAGE49
  J4B1    1 12V<1> SCONN288_H44441004_PIP-SCONN,HA   I169 @BASEBOARD_FAB2_LIB.BASEBOARD_FAB2(SCH_1):PAGE49
  J6M1  145 12V<0> SCONN288_H44441003_PIP-SCONN,HA    I50 @BASEBOARD_FAB2_LIB.BASEBOARD_FAB2(SCH_1):PAGE50
  J6M1    1 12V<1> SCONN288_H44441003_PIP-SCONN,HA    I50 @BASEBOARD_FAB2_LIB.BASEBOARD_FAB2(SCH_1):PAGE50
  J4A2  145 12V<0> SCONN288_H44441004_PIP-SCONN,HA   I167 @BASEBOARD_FAB2_LIB.BASEBOARD_FAB2(SCH_1):PAGE51
  J4A2    1 12V<1> SCONN288_H44441004_PIP-SCONN,HA   I167 @BASEBOARD_FAB2_LIB.BASEBOARD_FAB2(SCH_1):PAGE51
  J6L2  145 12V<0> SCONN288_H44441003_PIP-SCONN,HA    I55 @BASEBOARD_FAB2_LIB.BASEBOARD_FAB2(SCH_1):PAGE52
  J6L2    1 12V<1> SCONN288_H44441003_PIP-SCONN,HA    I55 @BASEBOARD_FAB2_LIB.BASEBOARD_FAB2(SCH_1):PAGE52
  J4A1  145 12V<0> SCONN288_H44441004_PIP-SCONN,HA   I171 @BASEBOARD_FAB2_LIB.BASEBOARD_FAB2(SCH_1):PAGE53
  J4A1    1 12V<1> SCONN288_H44441004_PIP-SCONN,HA   I171 @BASEBOARD_FAB2_LIB.BASEBOARD_FAB2(SCH_1):PAGE53
  J6L1  145 12V<0> SCONN288_H44441003_PIP-SCONN,HA   I170 @BASEBOARD_FAB2_LIB.BASEBOARD_FAB2(SCH_1):PAGE54
  J6L1    1 12V<1> SCONN288_H44441003_PIP-SCONN,HA   I170 @BASEBOARD_FAB2_LIB.BASEBOARD_FAB2(SCH_1):PAGE54
 R4B12    2      B RES_1206-0.002,1%,1W,CHIP,G521A     I6 @BASEBOARD_FAB2_LIB.BASEBOARD_FAB2(SCH_1):PAGE197
 Q12W2    2 SOURCE#2 BSL308C-H6327-GP_DISCRET-GB1-BA    I19 @BASEBOARD_FAB2_LIB.BASEBOARD_FAB2(SCH_1):PAGE197
 R12W9    1      A RES_0603-100.0K,1%,1/10W,CHIP,A    I21 @BASEBOARD_FAB2_LIB.BASEBOARD_FAB2(SCH_1):PAGE197
 C4B11    1      A CAP_0805-10UF,16V,10%,X7R,G106A    I78 @BASEBOARD_FAB2_LIB.BASEBOARD_FAB2(SCH_1):PAGE197
  C4A4    1      A CAP_0805-10UF,16V,10%,X7R,G106A    I81 @BASEBOARD_FAB2_LIB.BASEBOARD_FAB2(SCH_1):PAGE197
 C4A17    1      A CAP_0805-10UF,16V,10%,X7R,G106A    I88 @BASEBOARD_FAB2_LIB.BASEBOARD_FAB2(SCH_1):PAGE197

P12V_NVDIMM_DEF_D @BASEBOARD_FAB2_LIB.BASEBOARD_FAB2(SCH_1):P12V_NVDIMM_DEF_D
 Q12W2    4 DRAIN#4 BSL308C-H6327-GP_DISCRET-GB1-BA    I19 @BASEBOARD_FAB2_LIB.BASEBOARD_FAB2(SCH_1):PAGE197
 R12W8    2      2 4D02R2F-GP_SMD-RG2-4D02R2F-GP,A   I113 @BASEBOARD_FAB2_LIB.BASEBOARD_FAB2(SCH_1):PAGE197
 R12W7    1      1 665KR5B-1-GP_SMD-RG3-665KR5B-1A   I121 @BASEBOARD_FAB2_LIB.BASEBOARD_FAB2(SCH_1):PAGE197

P12V_NVDIMM_GHJ @BASEBOARD_FAB2_LIB.BASEBOARD_FAB2(SCH_1):P12V_NVDIMM_GHJ
  J1G1  145 12V<0> SCONN288_H44441004_PIP-SCONN,HA   I171 @BASEBOARD_FAB2_LIB.BASEBOARD_FAB2(SCH_1):PAGE77
  J1G1    1 12V<1> SCONN288_H44441004_PIP-SCONN,HA   I171 @BASEBOARD_FAB2_LIB.BASEBOARD_FAB2(SCH_1):PAGE77
  J9T1  145 12V<0> SCONN288_H44441003_PIP-SCONN,HA    I75 @BASEBOARD_FAB2_LIB.BASEBOARD_FAB2(SCH_1):PAGE78
  J9T1    1 12V<1> SCONN288_H44441003_PIP-SCONN,HA    I75 @BASEBOARD_FAB2_LIB.BASEBOARD_FAB2(SCH_1):PAGE78
  J1G2  145 12V<0> SCONN288_H44441004_PIP-SCONN,HA   I169 @BASEBOARD_FAB2_LIB.BASEBOARD_FAB2(SCH_1):PAGE79
  J1G2    1 12V<1> SCONN288_H44441004_PIP-SCONN,HA   I169 @BASEBOARD_FAB2_LIB.BASEBOARD_FAB2(SCH_1):PAGE79
  J9U1  145 12V<0> SCONN288_H44441003_PIP-SCONN,HA    I56 @BASEBOARD_FAB2_LIB.BASEBOARD_FAB2(SCH_1):PAGE80
  J9U1    1 12V<1> SCONN288_H44441003_PIP-SCONN,HA    I56 @BASEBOARD_FAB2_LIB.BASEBOARD_FAB2(SCH_1):PAGE80
  J1G3  145 12V<0> SCONN288_H44441004_PIP-SCONN,HA   I169 @BASEBOARD_FAB2_LIB.BASEBOARD_FAB2(SCH_1):PAGE81
  J1G3    1 12V<1> SCONN288_H44441004_PIP-SCONN,HA   I169 @BASEBOARD_FAB2_LIB.BASEBOARD_FAB2(SCH_1):PAGE81
  J9U2  145 12V<0> SCONN288_H44441003_PIP-SCONN,HA   I171 @BASEBOARD_FAB2_LIB.BASEBOARD_FAB2(SCH_1):PAGE82
  J9U2    1 12V<1> SCONN288_H44441003_PIP-SCONN,HA   I171 @BASEBOARD_FAB2_LIB.BASEBOARD_FAB2(SCH_1):PAGE82
  R1F3    2      B RES_1206-0.002,1%,1W,CHIP,G521A    I50 @BASEBOARD_FAB2_LIB.BASEBOARD_FAB2(SCH_1):PAGE197
R12W14    1      A RES_0603-100.0K,1%,1/10W,CHIP,A    I53 @BASEBOARD_FAB2_LIB.BASEBOARD_FAB2(SCH_1):PAGE197
  C9T8    1      A CAP_0805-10UF,16V,10%,X7R,G106A    I56 @BASEBOARD_FAB2_LIB.BASEBOARD_FAB2(SCH_1):PAGE197
 C9U11    1      A CAP_0805-10UF,16V,10%,X7R,G106A    I63 @BASEBOARD_FAB2_LIB.BASEBOARD_FAB2(SCH_1):PAGE197
  C9U8    1      A CAP_0805-10UF,16V,10%,X7R,G106A    I66 @BASEBOARD_FAB2_LIB.BASEBOARD_FAB2(SCH_1):PAGE197
 Q12W3    2 SOURCE#2 BSL308C-H6327-GP_DISCRET-GB1-BA    I91 @BASEBOARD_FAB2_LIB.BASEBOARD_FAB2(SCH_1):PAGE197

P12V_NVDIMM_GHJ_D @BASEBOARD_FAB2_LIB.BASEBOARD_FAB2(SCH_1):P12V_NVDIMM_GHJ_D
 Q12W3    4 DRAIN#4 BSL308C-H6327-GP_DISCRET-GB1-BA    I91 @BASEBOARD_FAB2_LIB.BASEBOARD_FAB2(SCH_1):PAGE197
R12W13    2      2 4D02R2F-GP_SMD-RG2-4D02R2F-GP,A   I116 @BASEBOARD_FAB2_LIB.BASEBOARD_FAB2(SCH_1):PAGE197
R12W12    1      1 665KR5B-1-GP_SMD-RG3-665KR5B-1A   I119 @BASEBOARD_FAB2_LIB.BASEBOARD_FAB2(SCH_1):PAGE197

P12V_NVDIMM_KLM @BASEBOARD_FAB2_LIB.BASEBOARD_FAB2(SCH_1):P12V_NVDIMM_KLM
  J1B1  145 12V<0> SCONN288_H44441004_PIP-SCONN,HA   I167 @BASEBOARD_FAB2_LIB.BASEBOARD_FAB2(SCH_1):PAGE83
  J1B1    1 12V<1> SCONN288_H44441004_PIP-SCONN,HA   I167 @BASEBOARD_FAB2_LIB.BASEBOARD_FAB2(SCH_1):PAGE83
  J9M1  145 12V<0> SCONN288_H44441003_PIP-SCONN,HA    I57 @BASEBOARD_FAB2_LIB.BASEBOARD_FAB2(SCH_1):PAGE84
  J9M1    1 12V<1> SCONN288_H44441003_PIP-SCONN,HA    I57 @BASEBOARD_FAB2_LIB.BASEBOARD_FAB2(SCH_1):PAGE84
  J1A2  145 12V<0> SCONN288_H44441004_PIP-SCONN,HA   I172 @BASEBOARD_FAB2_LIB.BASEBOARD_FAB2(SCH_1):PAGE85
  J1A2    1 12V<1> SCONN288_H44441004_PIP-SCONN,HA   I172 @BASEBOARD_FAB2_LIB.BASEBOARD_FAB2(SCH_1):PAGE85
  J9L2  145 12V<0> SCONN288_H44441003_PIP-SCONN,HA    I55 @BASEBOARD_FAB2_LIB.BASEBOARD_FAB2(SCH_1):PAGE86
  J9L2    1 12V<1> SCONN288_H44441003_PIP-SCONN,HA    I55 @BASEBOARD_FAB2_LIB.BASEBOARD_FAB2(SCH_1):PAGE86
  J1A1  145 12V<0> SCONN288_H44441004_PIP-SCONN,HA   I169 @BASEBOARD_FAB2_LIB.BASEBOARD_FAB2(SCH_1):PAGE87
  J1A1    1 12V<1> SCONN288_H44441004_PIP-SCONN,HA   I169 @BASEBOARD_FAB2_LIB.BASEBOARD_FAB2(SCH_1):PAGE87
  J9L1  145 12V<0> SCONN288_H44441003_PIP-SCONN,HA   I168 @BASEBOARD_FAB2_LIB.BASEBOARD_FAB2(SCH_1):PAGE88
  J9L1    1 12V<1> SCONN288_H44441003_PIP-SCONN,HA   I168 @BASEBOARD_FAB2_LIB.BASEBOARD_FAB2(SCH_1):PAGE88
  R9M4    2      B RES_1206-0.002,1%,1W,CHIP,G521A    I29 @BASEBOARD_FAB2_LIB.BASEBOARD_FAB2(SCH_1):PAGE197
 Q12W4    2 SOURCE#2 BSL308C-H6327-GP_DISCRET-GB1-BA    I35 @BASEBOARD_FAB2_LIB.BASEBOARD_FAB2(SCH_1):PAGE197
R12W19    1      A RES_0603-100.0K,1%,1/10W,CHIP,A    I37 @BASEBOARD_FAB2_LIB.BASEBOARD_FAB2(SCH_1):PAGE197
  C1A4    1      A CAP_0805-10UF,16V,10%,X7R,G106A    I60 @BASEBOARD_FAB2_LIB.BASEBOARD_FAB2(SCH_1):PAGE197
  C1B7    1      A CAP_0805-10UF,16V,10%,X7R,G106A    I72 @BASEBOARD_FAB2_LIB.BASEBOARD_FAB2(SCH_1):PAGE197
 C1A16    1      A CAP_0805-10UF,16V,10%,X7R,G106A    I75 @BASEBOARD_FAB2_LIB.BASEBOARD_FAB2(SCH_1):PAGE197

P12V_NVDIMM_KLM_D @BASEBOARD_FAB2_LIB.BASEBOARD_FAB2(SCH_1):P12V_NVDIMM_KLM_D
 Q12W4    4 DRAIN#4 BSL308C-H6327-GP_DISCRET-GB1-BA    I35 @BASEBOARD_FAB2_LIB.BASEBOARD_FAB2(SCH_1):PAGE197
R12W18    2      2 4D02R2F-GP_SMD-RG2-4D02R2F-GP,A   I114 @BASEBOARD_FAB2_LIB.BASEBOARD_FAB2(SCH_1):PAGE197
R12W17    1      1 665KR5B-1-GP_SMD-RG3-665KR5B-1A   I123 @BASEBOARD_FAB2_LIB.BASEBOARD_FAB2(SCH_1):PAGE197

P12V_PSU @BASEBOARD_FAB2_LIB.BASEBOARD_FAB2(SCH_1):P12V_PSU
  C9R5    1      A CAP_0805-10UF,16V,10%,X6S,C953A    I31 @BASEBOARD_FAB2_LIB.BASEBOARD_FAB2(SCH_1):PAGE195
 C1E12    1      A CAP_0805-10UF,16V,10%,X6S,C953A    I32 @BASEBOARD_FAB2_LIB.BASEBOARD_FAB2(SCH_1):PAGE195
 C1E15    1      A CAP_0805-10UF,16V,10%,X6S,C953A    I35 @BASEBOARD_FAB2_LIB.BASEBOARD_FAB2(SCH_1):PAGE195
 C9R12    1      A CAP_A_0402V-0.1UF,16V,10%,X7R,A    I36 @BASEBOARD_FAB2_LIB.BASEBOARD_FAB2(SCH_1):PAGE195
  C9R6    1      A CAP_A_0402V-0.1UF,16V,10%,X7R,A    I37 @BASEBOARD_FAB2_LIB.BASEBOARD_FAB2(SCH_1):PAGE195
 C1E17    1      A CAP_A_0402V-0.1UF,16V,10%,X7R,A    I38 @BASEBOARD_FAB2_LIB.BASEBOARD_FAB2(SCH_1):PAGE195
 C1E16    1      A CAP_A_0402V-0.1UF,16V,10%,X7R,A    I39 @BASEBOARD_FAB2_LIB.BASEBOARD_FAB2(SCH_1):PAGE195
 R9P30    1      A RES_0603-10.0,1%,1/10W,CHIP,G2A     I2 @BASEBOARD_FAB2_LIB.BASEBOARD_FAB2(SCH_1):PAGE199
 R9P29    1      A RES_0402-100.0K,1%,1/16W,CHIP,A    I12 @BASEBOARD_FAB2_LIB.BASEBOARD_FAB2(SCH_1):PAGE199
 R1D15    1      A RES_0402-100.0K,1%,1/16W,CHIP,A    I92 @BASEBOARD_FAB2_LIB.BASEBOARD_FAB2(SCH_1):PAGE199
 VR1D1    1      C ZENER_SM-13V,IC,H69095-001    I99 @BASEBOARD_FAB2_LIB.BASEBOARD_FAB2(SCH_1):PAGE199
  R9R1    1      1 RES_PWR_6PAD-0.001,1%,3W,CHIP,A    I49 @BASEBOARD_FAB2_LIB.BASEBOARD_FAB2(SCH_1):PAGE200
  R9R1    5      5 RES_PWR_6PAD-0.001,1%,3W,CHIP,A    I49 @BASEBOARD_FAB2_LIB.BASEBOARD_FAB2(SCH_1):PAGE200
 R1D49    1      1 RES_PWR_6PAD-0.001,1%,3W,CHIP,A    I50 @BASEBOARD_FAB2_LIB.BASEBOARD_FAB2(SCH_1):PAGE200
 R1D49    5      5 RES_PWR_6PAD-0.001,1%,3W,CHIP,A    I50 @BASEBOARD_FAB2_LIB.BASEBOARD_FAB2(SCH_1):PAGE200
  J1E1  1_1    1_1 FCI-CONN12-2R-GP_CONN-G5-FCI-CA   I114 @BASEBOARD_FAB2_LIB.BASEBOARD_FAB2(SCH_1):PAGE195
  J1E1  1_2    1_2 FCI-CONN12-2R-GP_CONN-G5-FCI-CA   I114 @BASEBOARD_FAB2_LIB.BASEBOARD_FAB2(SCH_1):PAGE195
  J1E1  1_3    1_3 FCI-CONN12-2R-GP_CONN-G5-FCI-CA   I114 @BASEBOARD_FAB2_LIB.BASEBOARD_FAB2(SCH_1):PAGE195
  J1E1  2_1    2_1 FCI-CONN12-2R-GP_CONN-G5-FCI-CA   I114 @BASEBOARD_FAB2_LIB.BASEBOARD_FAB2(SCH_1):PAGE195
  J1E1  2_2    2_2 FCI-CONN12-2R-GP_CONN-G5-FCI-CA   I114 @BASEBOARD_FAB2_LIB.BASEBOARD_FAB2(SCH_1):PAGE195
  J1E1  2_3    2_3 FCI-CONN12-2R-GP_CONN-G5-FCI-CA   I114 @BASEBOARD_FAB2_LIB.BASEBOARD_FAB2(SCH_1):PAGE195
  J1D1  1_1    1_1 FCI-CONN12-2R-GP_CONN-G5-FCI-CA   I115 @BASEBOARD_FAB2_LIB.BASEBOARD_FAB2(SCH_1):PAGE195
  J1D1  1_2    1_2 FCI-CONN12-2R-GP_CONN-G5-FCI-CA   I115 @BASEBOARD_FAB2_LIB.BASEBOARD_FAB2(SCH_1):PAGE195
  J1D1  1_3    1_3 FCI-CONN12-2R-GP_CONN-G5-FCI-CA   I115 @BASEBOARD_FAB2_LIB.BASEBOARD_FAB2(SCH_1):PAGE195
  J1D1  2_1    2_1 FCI-CONN12-2R-GP_CONN-G5-FCI-CA   I115 @BASEBOARD_FAB2_LIB.BASEBOARD_FAB2(SCH_1):PAGE195
  J1D1  2_2    2_2 FCI-CONN12-2R-GP_CONN-G5-FCI-CA   I115 @BASEBOARD_FAB2_LIB.BASEBOARD_FAB2(SCH_1):PAGE195
  J1D1  2_3    2_3 FCI-CONN12-2R-GP_CONN-G5-FCI-CA   I115 @BASEBOARD_FAB2_LIB.BASEBOARD_FAB2(SCH_1):PAGE195
  R9T9    1      A RES_0402-4.75K,1%,1/16W,CHIP,GA     I4 @BASEBOARD_FAB2_LIB.BASEBOARD_FAB2(SCH_1):PAGE181
  R9T6    1      A RES_0402-15.0K,1%,1/16W,CHIP,GA    I68 @BASEBOARD_FAB2_LIB.BASEBOARD_FAB2(SCH_1):PAGE181
 R9P28    1      A RES_0402-100.0K,1%,1/16W,CHIP,A   I138 @BASEBOARD_FAB2_LIB.BASEBOARD_FAB2(SCH_1):PAGE199

P12V_PUMP @BASEBOARD_FAB2_LIB.BASEBOARD_FAB2(SCH_1):P12V_PUMP
 C10W2    1      A CAP_A_0402V-0.1UF,16V,10%,X7R,A     I1 @BASEBOARD_FAB2_LIB.BASEBOARD_FAB2(SCH_1):PAGE251
 C10W1    1      A CAP_0805-10UF,16V,10%,X6S,C953A     I3 @BASEBOARD_FAB2_LIB.BASEBOARD_FAB2(SCH_1):PAGE251
 R10W5    2      B RES_0805-0.0,5%,1/8W,CHIP,G221A     I5 @BASEBOARD_FAB2_LIB.BASEBOARD_FAB2(SCH_1):PAGE251
  J1B2    2    IO2 CONN6_C74770005_PIP-HDR,C74770A    I25 @BASEBOARD_FAB2_LIB.BASEBOARD_FAB2(SCH_1):PAGE251

P12V_STBY @BASEBOARD_FAB2_LIB.BASEBOARD_FAB2(SCH_1):P12V_STBY
  R1L9    1      A RES_0402-100.0K,1%,1/16W,CHIP,A   I130 @BASEBOARD_FAB2_LIB.BASEBOARD_FAB2(SCH_1):PAGE155
 R1U32    1      A RES_0402-5.11K,1%,1/16W,CHIP,GA    I82 @BASEBOARD_FAB2_LIB.BASEBOARD_FAB2(SCH_1):PAGE169
 C1M27    1      A CAP_0805-10UF,16V,10%,X6S,C953A     I3 @BASEBOARD_FAB2_LIB.BASEBOARD_FAB2(SCH_1):PAGE186
 C1M26    1      A CAP_0805-10UF,16V,10%,X6S,C953A     I6 @BASEBOARD_FAB2_LIB.BASEBOARD_FAB2(SCH_1):PAGE186
 C1M23    1      A CAP_A_0402V-0.1UF,16V,10%,X7R,A     I7 @BASEBOARD_FAB2_LIB.BASEBOARD_FAB2(SCH_1):PAGE186
 C1M22    1      A CAP_A_0402V-0.1UF,16V,10%,X7R,A     I8 @BASEBOARD_FAB2_LIB.BASEBOARD_FAB2(SCH_1):PAGE186
  J9B3    2    IO2 SCONN120_A28699018_SM-SCONN,A2A   I336 @BASEBOARD_FAB2_LIB.BASEBOARD_FAB2(SCH_1):PAGE186
  J9B3    4    IO4 SCONN120_A28699018_SM-SCONN,A2A   I336 @BASEBOARD_FAB2_LIB.BASEBOARD_FAB2(SCH_1):PAGE186
  J9B3    6    IO6 SCONN120_A28699018_SM-SCONN,A2A   I336 @BASEBOARD_FAB2_LIB.BASEBOARD_FAB2(SCH_1):PAGE186
  J8E3    2    IO2 SCONN80_E67482007_SM-CONN,E674A   I119 @BASEBOARD_FAB2_LIB.BASEBOARD_FAB2(SCH_1):PAGE187
  J8E3    4    IO4 SCONN80_E67482007_SM-CONN,E674A   I119 @BASEBOARD_FAB2_LIB.BASEBOARD_FAB2(SCH_1):PAGE187
 C2R15    1      A CAP_A_0402V-0.1UF,16V,10%,X7R,A     I2 @BASEBOARD_FAB2_LIB.BASEBOARD_FAB2(SCH_1):PAGE188
 C2R18    1      A CAP_A_0402V-0.1UF,16V,10%,X7R,A     I3 @BASEBOARD_FAB2_LIB.BASEBOARD_FAB2(SCH_1):PAGE188
 C2P11    1      A CAP_A_0402V-0.1UF,16V,10%,X7R,A    I21 @BASEBOARD_FAB2_LIB.BASEBOARD_FAB2(SCH_1):PAGE188
 C2P12    1      A CAP_A_0402V-0.1UF,16V,10%,X7R,A    I23 @BASEBOARD_FAB2_LIB.BASEBOARD_FAB2(SCH_1):PAGE188
 C2R17    1      A CAP_A_0402V-0.1UF,16V,10%,X7R,A    I25 @BASEBOARD_FAB2_LIB.BASEBOARD_FAB2(SCH_1):PAGE188
  J8E4   33   IO33 SCONN64_H87568002_A_SMT-CONN,HA    I27 @BASEBOARD_FAB2_LIB.BASEBOARD_FAB2(SCH_1):PAGE188
  J8E4   34   IO34 SCONN64_H87568002_A_SMT-CONN,HA    I27 @BASEBOARD_FAB2_LIB.BASEBOARD_FAB2(SCH_1):PAGE188
  J8E4   35   IO35 SCONN64_H87568002_A_SMT-CONN,HA    I27 @BASEBOARD_FAB2_LIB.BASEBOARD_FAB2(SCH_1):PAGE188
 C2R16    1      A CAP_A_0402V-0.1UF,16V,10%,X7R,A    I40 @BASEBOARD_FAB2_LIB.BASEBOARD_FAB2(SCH_1):PAGE188
 C2P10    1      A CAP_1206LF-22UF,16V,10%,X6S,D3A    I41 @BASEBOARD_FAB2_LIB.BASEBOARD_FAB2(SCH_1):PAGE188
 C2P16    1      A CAP_A_0402V-0.1UF,16V,10%,X7R,A    I53 @BASEBOARD_FAB2_LIB.BASEBOARD_FAB2(SCH_1):PAGE188
 C2P15    1      A CAP_A_0402V-0.1UF,16V,10%,X7R,A    I55 @BASEBOARD_FAB2_LIB.BASEBOARD_FAB2(SCH_1):PAGE188
 C2P14    1      A CAP_A_0402V-0.1UF,16V,10%,X7R,A    I56 @BASEBOARD_FAB2_LIB.BASEBOARD_FAB2(SCH_1):PAGE188
 C2P13    1      A CAP_A_0402V-0.1UF,16V,10%,X7R,A    I57 @BASEBOARD_FAB2_LIB.BASEBOARD_FAB2(SCH_1):PAGE188
  J4B2   A1   IOA1 SCONN120_H61426002_SM-CONN,H61A    I46 @BASEBOARD_FAB2_LIB.BASEBOARD_FAB2(SCH_1):PAGE193
  J4B2   A2   IOA2 SCONN120_H61426002_SM-CONN,H61A    I46 @BASEBOARD_FAB2_LIB.BASEBOARD_FAB2(SCH_1):PAGE193
  J4B2   A3   IOA3 SCONN120_H61426002_SM-CONN,H61A    I46 @BASEBOARD_FAB2_LIB.BASEBOARD_FAB2(SCH_1):PAGE193
  J4B2   A4   IOA4 SCONN120_H61426002_SM-CONN,H61A    I46 @BASEBOARD_FAB2_LIB.BASEBOARD_FAB2(SCH_1):PAGE193
  J4B2   A5   IOA5 SCONN120_H61426002_SM-CONN,H61A    I46 @BASEBOARD_FAB2_LIB.BASEBOARD_FAB2(SCH_1):PAGE193
  J4B2   A6   IOA6 SCONN120_H61426002_SM-CONN,H61A    I46 @BASEBOARD_FAB2_LIB.BASEBOARD_FAB2(SCH_1):PAGE193
  J4B2   A7   IOA7 SCONN120_H61426002_SM-CONN,H61A    I46 @BASEBOARD_FAB2_LIB.BASEBOARD_FAB2(SCH_1):PAGE193
  J4B2   A8   IOA8 SCONN120_H61426002_SM-CONN,H61A    I46 @BASEBOARD_FAB2_LIB.BASEBOARD_FAB2(SCH_1):PAGE193
  J4B2   B1   IOB1 SCONN120_H61426002_SM-CONN,H61A    I46 @BASEBOARD_FAB2_LIB.BASEBOARD_FAB2(SCH_1):PAGE193
  J4B2   B2   IOB2 SCONN120_H61426002_SM-CONN,H61A    I46 @BASEBOARD_FAB2_LIB.BASEBOARD_FAB2(SCH_1):PAGE193
  J4B2   B3   IOB3 SCONN120_H61426002_SM-CONN,H61A    I46 @BASEBOARD_FAB2_LIB.BASEBOARD_FAB2(SCH_1):PAGE193
  J4B2   B4   IOB4 SCONN120_H61426002_SM-CONN,H61A    I46 @BASEBOARD_FAB2_LIB.BASEBOARD_FAB2(SCH_1):PAGE193
  J4B2   B5   IOB5 SCONN120_H61426002_SM-CONN,H61A    I46 @BASEBOARD_FAB2_LIB.BASEBOARD_FAB2(SCH_1):PAGE193
  J4B2   B6   IOB6 SCONN120_H61426002_SM-CONN,H61A    I46 @BASEBOARD_FAB2_LIB.BASEBOARD_FAB2(SCH_1):PAGE193
  J4B2   B7   IOB7 SCONN120_H61426002_SM-CONN,H61A    I46 @BASEBOARD_FAB2_LIB.BASEBOARD_FAB2(SCH_1):PAGE193
  J4B2   B8   IOB8 SCONN120_H61426002_SM-CONN,H61A    I46 @BASEBOARD_FAB2_LIB.BASEBOARD_FAB2(SCH_1):PAGE193
  J6B1   A1   IOA1 SCONN120_H61426002_SM-CONN,H61A    I56 @BASEBOARD_FAB2_LIB.BASEBOARD_FAB2(SCH_1):PAGE194
  J6B1   A2   IOA2 SCONN120_H61426002_SM-CONN,H61A    I56 @BASEBOARD_FAB2_LIB.BASEBOARD_FAB2(SCH_1):PAGE194
  J6B1   A3   IOA3 SCONN120_H61426002_SM-CONN,H61A    I56 @BASEBOARD_FAB2_LIB.BASEBOARD_FAB2(SCH_1):PAGE194
  J6B1   A4   IOA4 SCONN120_H61426002_SM-CONN,H61A    I56 @BASEBOARD_FAB2_LIB.BASEBOARD_FAB2(SCH_1):PAGE194
  J6B1   A5   IOA5 SCONN120_H61426002_SM-CONN,H61A    I56 @BASEBOARD_FAB2_LIB.BASEBOARD_FAB2(SCH_1):PAGE194
  J6B1   A6   IOA6 SCONN120_H61426002_SM-CONN,H61A    I56 @BASEBOARD_FAB2_LIB.BASEBOARD_FAB2(SCH_1):PAGE194
  J6B1   A7   IOA7 SCONN120_H61426002_SM-CONN,H61A    I56 @BASEBOARD_FAB2_LIB.BASEBOARD_FAB2(SCH_1):PAGE194
  J6B1   A8   IOA8 SCONN120_H61426002_SM-CONN,H61A    I56 @BASEBOARD_FAB2_LIB.BASEBOARD_FAB2(SCH_1):PAGE194
  J6B1   B1   IOB1 SCONN120_H61426002_SM-CONN,H61A    I56 @BASEBOARD_FAB2_LIB.BASEBOARD_FAB2(SCH_1):PAGE194
  J6B1   B2   IOB2 SCONN120_H61426002_SM-CONN,H61A    I56 @BASEBOARD_FAB2_LIB.BASEBOARD_FAB2(SCH_1):PAGE194
  J6B1   B3   IOB3 SCONN120_H61426002_SM-CONN,H61A    I56 @BASEBOARD_FAB2_LIB.BASEBOARD_FAB2(SCH_1):PAGE194
  J6B1   B4   IOB4 SCONN120_H61426002_SM-CONN,H61A    I56 @BASEBOARD_FAB2_LIB.BASEBOARD_FAB2(SCH_1):PAGE194
  J6B1   B5   IOB5 SCONN120_H61426002_SM-CONN,H61A    I56 @BASEBOARD_FAB2_LIB.BASEBOARD_FAB2(SCH_1):PAGE194
  J6B1   B6   IOB6 SCONN120_H61426002_SM-CONN,H61A    I56 @BASEBOARD_FAB2_LIB.BASEBOARD_FAB2(SCH_1):PAGE194
  J6B1   B7   IOB7 SCONN120_H61426002_SM-CONN,H61A    I56 @BASEBOARD_FAB2_LIB.BASEBOARD_FAB2(SCH_1):PAGE194
  J6B1   B8   IOB8 SCONN120_H61426002_SM-CONN,H61A    I56 @BASEBOARD_FAB2_LIB.BASEBOARD_FAB2(SCH_1):PAGE194
  C4F6    1      A CAPP_4040LF-470UF,16V,20%,ALUMA    I82 @BASEBOARD_FAB2_LIB.BASEBOARD_FAB2(SCH_1):PAGE195
 C4B13    1      A CAPP_4040LF-470UF,16V,20%,ALUMA    I83 @BASEBOARD_FAB2_LIB.BASEBOARD_FAB2(SCH_1):PAGE195
 C1B14    1      A CAPP_4040LF-470UF,16V,20%,ALUMA    I84 @BASEBOARD_FAB2_LIB.BASEBOARD_FAB2(SCH_1):PAGE195
  C1F7    1      A CAPP_4040LF-470UF,16V,20%,ALUMA    I85 @BASEBOARD_FAB2_LIB.BASEBOARD_FAB2(SCH_1):PAGE195
  C4F5    1      A CAPP_3018-68UF,16V,20%,TANT,72A    I96 @BASEBOARD_FAB2_LIB.BASEBOARD_FAB2(SCH_1):PAGE195
 C4B14    1      A CAPP_3018-68UF,16V,20%,TANT,72A    I97 @BASEBOARD_FAB2_LIB.BASEBOARD_FAB2(SCH_1):PAGE195
  C3T6    1      A CAPP_3018-68UF,16V,20%,TANT,72A    I98 @BASEBOARD_FAB2_LIB.BASEBOARD_FAB2(SCH_1):PAGE195
  C9M3    1      A CAPP_3018-68UF,16V,20%,TANT,72A    I99 @BASEBOARD_FAB2_LIB.BASEBOARD_FAB2(SCH_1):PAGE195
  C3B6    1      A CAPP_3018-68UF,16V,20%,TANT,72A   I100 @BASEBOARD_FAB2_LIB.BASEBOARD_FAB2(SCH_1):PAGE195
 C1R23    1      A CAPP_3018-68UF,16V,20%,TANT,72A   I101 @BASEBOARD_FAB2_LIB.BASEBOARD_FAB2(SCH_1):PAGE195
  C4M6    1      A CAPP_3018-68UF,16V,20%,TANT,72A   I102 @BASEBOARD_FAB2_LIB.BASEBOARD_FAB2(SCH_1):PAGE195
  C1M5    1      A CAPP_3018-68UF,16V,20%,TANT,72A   I103 @BASEBOARD_FAB2_LIB.BASEBOARD_FAB2(SCH_1):PAGE195
 C3T13    1      A CAPP_3018-68UF,16V,20%,TANT,72A   I104 @BASEBOARD_FAB2_LIB.BASEBOARD_FAB2(SCH_1):PAGE195
  C4M7    1      A CAPP_3018-68UF,16V,20%,TANT,72A   I105 @BASEBOARD_FAB2_LIB.BASEBOARD_FAB2(SCH_1):PAGE195
 C3T15    1      A CAPP_3018-68UF,16V,20%,TANT,72A   I106 @BASEBOARD_FAB2_LIB.BASEBOARD_FAB2(SCH_1):PAGE195
  C7M6    1      A CAPP_3018-68UF,16V,20%,TANT,72A   I108 @BASEBOARD_FAB2_LIB.BASEBOARD_FAB2(SCH_1):PAGE195
  C6N5    1      A CAPP_3018-68UF,16V,20%,TANT,72A   I109 @BASEBOARD_FAB2_LIB.BASEBOARD_FAB2(SCH_1):PAGE195
  C9T3    1      A CAPP_3018-68UF,16V,20%,TANT,72A   I111 @BASEBOARD_FAB2_LIB.BASEBOARD_FAB2(SCH_1):PAGE195
  C4F4    1      A CAPP_3018-68UF,16V,20%,TANT,72A   I112 @BASEBOARD_FAB2_LIB.BASEBOARD_FAB2(SCH_1):PAGE195
  C3T3    1      A CAPP_3018-68UF,16V,20%,TANT,72A   I113 @BASEBOARD_FAB2_LIB.BASEBOARD_FAB2(SCH_1):PAGE195
 R3P48    1      A RES_0402-90.9K,1%,1/16W,CHIP,GA    I74 @BASEBOARD_FAB2_LIB.BASEBOARD_FAB2(SCH_1):PAGE196
 EU7E1    5      D SLG55021_SM-IC,G56246-001    I19 @BASEBOARD_FAB2_LIB.BASEBOARD_FAB2(SCH_1):PAGE198
  C7E5    1      A CAP_A_0402V-0.1UF,16V,10%,X7R,A    I52 @BASEBOARD_FAB2_LIB.BASEBOARD_FAB2(SCH_1):PAGE198
  C7E6    1      A CAP_0805-10UF,16V,10%,X6S,C953A    I53 @BASEBOARD_FAB2_LIB.BASEBOARD_FAB2(SCH_1):PAGE198
 EU9M1    5      D SLG55021_SM-IC,G56246-001    I69 @BASEBOARD_FAB2_LIB.BASEBOARD_FAB2(SCH_1):PAGE198
 C9M10    1      A CAP_0805-10UF,16V,10%,X6S,C953A    I74 @BASEBOARD_FAB2_LIB.BASEBOARD_FAB2(SCH_1):PAGE198
  C9M9    1      A CAP_A_0402V-0.1UF,16V,10%,X7R,A    I76 @BASEBOARD_FAB2_LIB.BASEBOARD_FAB2(SCH_1):PAGE198
  Q1B1    5    DRN MOSFET_N_LCC3-BSZ019N03LS,NFETA    I86 @BASEBOARD_FAB2_LIB.BASEBOARD_FAB2(SCH_1):PAGE198
  Q7E7    5    DRN MOSFET_N_LCC3-BSZ019N03LS,NFETA    I88 @BASEBOARD_FAB2_LIB.BASEBOARD_FAB2(SCH_1):PAGE198
 R9P18    1      A RES_0402-15.0K,1%,1/16W,CHIP,GA    I41 @BASEBOARD_FAB2_LIB.BASEBOARD_FAB2(SCH_1):PAGE199
 R9P23    1      A RES_0402-100.0K,1%,1/16W,CHIP,A    I54 @BASEBOARD_FAB2_LIB.BASEBOARD_FAB2(SCH_1):PAGE199
 R1D36    1      A RES_0402-1.00K,1%,1/16W,CHIP,GA    I65 @BASEBOARD_FAB2_LIB.BASEBOARD_FAB2(SCH_1):PAGE199
 EU1E3    1     S1 MOSFETN_1D3S_SOT5-IC,G68777-001    I54 @BASEBOARD_FAB2_LIB.BASEBOARD_FAB2(SCH_1):PAGE200
 EU1E3    2     S2 MOSFETN_1D3S_SOT5-IC,G68777-001    I54 @BASEBOARD_FAB2_LIB.BASEBOARD_FAB2(SCH_1):PAGE200
 EU1E3    3     S3 MOSFETN_1D3S_SOT5-IC,G68777-001    I54 @BASEBOARD_FAB2_LIB.BASEBOARD_FAB2(SCH_1):PAGE200
 EU9R1    1     S1 MOSFETN_1D3S_SOT5-IC,G68777-001    I57 @BASEBOARD_FAB2_LIB.BASEBOARD_FAB2(SCH_1):PAGE200
 EU9R1    2     S2 MOSFETN_1D3S_SOT5-IC,G68777-001    I57 @BASEBOARD_FAB2_LIB.BASEBOARD_FAB2(SCH_1):PAGE200
 EU9R1    3     S3 MOSFETN_1D3S_SOT5-IC,G68777-001    I57 @BASEBOARD_FAB2_LIB.BASEBOARD_FAB2(SCH_1):PAGE200
 EU1E1    1     S1 MOSFETN_1D3S_SOT5-IC,G68777-001    I59 @BASEBOARD_FAB2_LIB.BASEBOARD_FAB2(SCH_1):PAGE200
 EU1E1    2     S2 MOSFETN_1D3S_SOT5-IC,G68777-001    I59 @BASEBOARD_FAB2_LIB.BASEBOARD_FAB2(SCH_1):PAGE200
 EU1E1    3     S3 MOSFETN_1D3S_SOT5-IC,G68777-001    I59 @BASEBOARD_FAB2_LIB.BASEBOARD_FAB2(SCH_1):PAGE200
  U9P1    2    VDD TPS3700_SM-IC,H69492-001   I163 @BASEBOARD_FAB2_LIB.BASEBOARD_FAB2(SCH_1):PAGE200
  U1D2    2    VDD TPS3700_SM-IC,H69492-001   I170 @BASEBOARD_FAB2_LIB.BASEBOARD_FAB2(SCH_1):PAGE200
  C9P6    1      A CAP_A_0402V-0.1UF,16V,10%,X7R,A   I185 @BASEBOARD_FAB2_LIB.BASEBOARD_FAB2(SCH_1):PAGE200
  C1D9    1      A CAP_A_0402V-0.1UF,16V,10%,X7R,A   I187 @BASEBOARD_FAB2_LIB.BASEBOARD_FAB2(SCH_1):PAGE200
 CR1F5    1      C DIODE_SM-MBRS340T3G,EMPTY,C819A   I220 @BASEBOARD_FAB2_LIB.BASEBOARD_FAB2(SCH_1):PAGE200
 R9P33    1      A RES_0402-100.0K,1%,1/16W,CHIP,A   I222 @BASEBOARD_FAB2_LIB.BASEBOARD_FAB2(SCH_1):PAGE200
 FB7F1    1      A FERRITE_SM-22,FB,656554-051   I162 @BASEBOARD_FAB2_LIB.BASEBOARD_FAB2(SCH_1):PAGE231
 FB7B1    1      A FERRITE_SM-22,FB,656554-051   I200 @BASEBOARD_FAB2_LIB.BASEBOARD_FAB2(SCH_1):PAGE232
 FB4G1    1      A FERRITE_SM-22,FB,656554-051   I198 @BASEBOARD_FAB2_LIB.BASEBOARD_FAB2(SCH_1):PAGE233
 FB4A1    1      A FERRITE_SM-22,FB,656554-051   I154 @BASEBOARD_FAB2_LIB.BASEBOARD_FAB2(SCH_1):PAGE234
 FB7E1    1      A FERRITE_SM-22,FB,656554-051    I82 @BASEBOARD_FAB2_LIB.BASEBOARD_FAB2(SCH_1):PAGE241
  L7C1    1      S IND-100NH-35-GP_DISCRET-G8-INDA   I142 @BASEBOARD_FAB2_LIB.BASEBOARD_FAB2(SCH_1):PAGE212
  L4C1    1      S IND-80NH-1-GP_DISCRET-GC2-IND-A   I105 @BASEBOARD_FAB2_LIB.BASEBOARD_FAB2(SCH_1):PAGE204
  L1B2    1      S IND-80NH-1-GP_DISCRET-GC2-IND-A    I81 @BASEBOARD_FAB2_LIB.BASEBOARD_FAB2(SCH_1):PAGE209
  L7F2    1      S IND-100NH-35-GP_DISCRET-G8-INDA   I261 @BASEBOARD_FAB2_LIB.BASEBOARD_FAB2(SCH_1):PAGE217
  L7A5    1      S IND-100NH-35-GP_DISCRET-G8-INDA   I241 @BASEBOARD_FAB2_LIB.BASEBOARD_FAB2(SCH_1):PAGE220
  L1F1    1      S IND-100NH-35-GP_DISCRET-G8-INDA   I253 @BASEBOARD_FAB2_LIB.BASEBOARD_FAB2(SCH_1):PAGE225
  L1B1    1      S IND-100NH-35-GP_DISCRET-G8-INDA   I247 @BASEBOARD_FAB2_LIB.BASEBOARD_FAB2(SCH_1):PAGE228
 R4B12    1      A RES_1206-0.002,1%,1W,CHIP,G521A     I6 @BASEBOARD_FAB2_LIB.BASEBOARD_FAB2(SCH_1):PAGE197
  R4F2    1      A RES_1206-0.002,1%,1W,CHIP,G521A    I14 @BASEBOARD_FAB2_LIB.BASEBOARD_FAB2(SCH_1):PAGE197
  R9M4    1      A RES_1206-0.002,1%,1W,CHIP,G521A    I29 @BASEBOARD_FAB2_LIB.BASEBOARD_FAB2(SCH_1):PAGE197
  R1F3    1      A RES_1206-0.002,1%,1W,CHIP,G521A    I50 @BASEBOARD_FAB2_LIB.BASEBOARD_FAB2(SCH_1):PAGE197
 R12W1    1      1 665KR5B-1-GP_SMD-RG3-665KR5B-1A   I101 @BASEBOARD_FAB2_LIB.BASEBOARD_FAB2(SCH_1):PAGE197
 FB9E1    1      1 BLM31SN500SN1L-GP_DISCRET-GB1-A   I193 @BASEBOARD_FAB2_LIB.BASEBOARD_FAB2(SCH_1):PAGE240
 R9P13    1      1 270KR2F-GP_RCL_GP-270KR2F-GP,6A   I249 @BASEBOARD_FAB2_LIB.BASEBOARD_FAB2(SCH_1):PAGE200
 R12W8    1      1 4D02R2F-GP_SMD-RG2-4D02R2F-GP,A   I113 @BASEBOARD_FAB2_LIB.BASEBOARD_FAB2(SCH_1):PAGE197
R12W18    1      1 4D02R2F-GP_SMD-RG2-4D02R2F-GP,A   I114 @BASEBOARD_FAB2_LIB.BASEBOARD_FAB2(SCH_1):PAGE197
 R12W3    1      1 4D02R2F-GP_SMD-RG2-4D02R2F-GP,A   I115 @BASEBOARD_FAB2_LIB.BASEBOARD_FAB2(SCH_1):PAGE197
R12W13    1      1 4D02R2F-GP_SMD-RG2-4D02R2F-GP,A   I116 @BASEBOARD_FAB2_LIB.BASEBOARD_FAB2(SCH_1):PAGE197
R12W11    1      1 665KR5B-1-GP_SMD-RG3-665KR5B-1A   I118 @BASEBOARD_FAB2_LIB.BASEBOARD_FAB2(SCH_1):PAGE197
 R12W6    1      1 665KR5B-1-GP_SMD-RG3-665KR5B-1A   I120 @BASEBOARD_FAB2_LIB.BASEBOARD_FAB2(SCH_1):PAGE197
R12W16    1      1 665KR5B-1-GP_SMD-RG3-665KR5B-1A   I122 @BASEBOARD_FAB2_LIB.BASEBOARD_FAB2(SCH_1):PAGE197
  R9P7    1      A RES_0402-100.0K,1%,1/16W,CHIP,A   I252 @BASEBOARD_FAB2_LIB.BASEBOARD_FAB2(SCH_1):PAGE200

P12V_SWITCH_G @BASEBOARD_FAB2_LIB.BASEBOARD_FAB2(SCH_1):P12V_SWITCH_G
 EU7E1    7      G SLG55021_SM-IC,G56246-001    I19 @BASEBOARD_FAB2_LIB.BASEBOARD_FAB2(SCH_1):PAGE198
  Q7E7    4   GATE MOSFET_N_LCC3-BSZ019N03LS,NFETA    I88 @BASEBOARD_FAB2_LIB.BASEBOARD_FAB2(SCH_1):PAGE198

P1V05_PCH_STBY @BASEBOARD_FAB2_LIB.BASEBOARD_FAB2(SCH_1):P1V05_PCH_STBY
  C9A6    1      A CAP_A_0402V-1.0UF,6.3V,10%,X6SA    I25 @BASEBOARD_FAB2_LIB.BASEBOARD_FAB2(SCH_1):PAGE111
  J9A3   43   IO43 SCONN60_C21100002_SMLF-CONN,C2A    I26 @BASEBOARD_FAB2_LIB.BASEBOARD_FAB2(SCH_1):PAGE111
  J9A3   44   IO44 SCONN60_C21100002_SMLF-CONN,C2A    I26 @BASEBOARD_FAB2_LIB.BASEBOARD_FAB2(SCH_1):PAGE111
  C1L5    1      A CAP_A_0402V-1.0UF,6.3V,10%,X6SA    I30 @BASEBOARD_FAB2_LIB.BASEBOARD_FAB2(SCH_1):PAGE111
 R9A17    2      B RES_0402-1.00K,1%,1/16W,CHIP,GA    I57 @BASEBOARD_FAB2_LIB.BASEBOARD_FAB2(SCH_1):PAGE111
 R1L39    1      A RES_0402-100.0,1%,1/16W,CHIP,GA    I76 @BASEBOARD_FAB2_LIB.BASEBOARD_FAB2(SCH_1):PAGE112
 R1L41    1      A RES_0402-100.0,1%,1/16W,CHIP,GA    I77 @BASEBOARD_FAB2_LIB.BASEBOARD_FAB2(SCH_1):PAGE112
 R9A11    1      A RES_0402-150.0,1%,1/16W,CHIP,GA    I78 @BASEBOARD_FAB2_LIB.BASEBOARD_FAB2(SCH_1):PAGE112
 R8A13    1      A RES_0402-150.0,1%,1/16W,CHIP,GA    I79 @BASEBOARD_FAB2_LIB.BASEBOARD_FAB2(SCH_1):PAGE112
 R8A14    1      A RES_0402-150.0,1%,1/16W,CHIP,GA    I80 @BASEBOARD_FAB2_LIB.BASEBOARD_FAB2(SCH_1):PAGE112
  U7C1 AH50 VCCA_CLKUNF_1P05<0> LBG_CORE_QAT_EXT_D_BGA1-IC,H91A    I63 @BASEBOARD_FAB2_LIB.BASEBOARD_FAB2(SCH_1):PAGE122
  U7C1  U50 VCCA_CLKUNF_1P05<1> LBG_CORE_QAT_EXT_D_BGA1-IC,H91A    I63 @BASEBOARD_FAB2_LIB.BASEBOARD_FAB2(SCH_1):PAGE122
  U7C1 AW45 VCCMPHY_1P05<0> LBG_CORE_QAT_EXT_D_BGA1-IC,H91A    I63 @BASEBOARD_FAB2_LIB.BASEBOARD_FAB2(SCH_1):PAGE122
  U7C1 AW43 VCCMPHY_1P05<1> LBG_CORE_QAT_EXT_D_BGA1-IC,H91A    I63 @BASEBOARD_FAB2_LIB.BASEBOARD_FAB2(SCH_1):PAGE122
  U7C1 AJ43 VCCMPHY_1P05<2> LBG_CORE_QAT_EXT_D_BGA1-IC,H91A    I63 @BASEBOARD_FAB2_LIB.BASEBOARD_FAB2(SCH_1):PAGE122
  U7C1 AU45 VCCMPHY_1P05<3> LBG_CORE_QAT_EXT_D_BGA1-IC,H91A    I63 @BASEBOARD_FAB2_LIB.BASEBOARD_FAB2(SCH_1):PAGE122
  U7C1 AU43 VCCMPHY_1P05<4> LBG_CORE_QAT_EXT_D_BGA1-IC,H91A    I63 @BASEBOARD_FAB2_LIB.BASEBOARD_FAB2(SCH_1):PAGE122
  U7C1 AT45 VCCMPHY_1P05<5> LBG_CORE_QAT_EXT_D_BGA1-IC,H91A    I63 @BASEBOARD_FAB2_LIB.BASEBOARD_FAB2(SCH_1):PAGE122
  U7C1 AT43 VCCMPHY_1P05<6> LBG_CORE_QAT_EXT_D_BGA1-IC,H91A    I63 @BASEBOARD_FAB2_LIB.BASEBOARD_FAB2(SCH_1):PAGE122
  U7C1 AP45 VCCMPHY_1P05<7> LBG_CORE_QAT_EXT_D_BGA1-IC,H91A    I63 @BASEBOARD_FAB2_LIB.BASEBOARD_FAB2(SCH_1):PAGE122
  U7C1 AP43 VCCMPHY_1P05<8> LBG_CORE_QAT_EXT_D_BGA1-IC,H91A    I63 @BASEBOARD_FAB2_LIB.BASEBOARD_FAB2(SCH_1):PAGE122
  U7C1 AM45 VCCMPHY_1P05<9> LBG_CORE_QAT_EXT_D_BGA1-IC,H91A    I63 @BASEBOARD_FAB2_LIB.BASEBOARD_FAB2(SCH_1):PAGE122
  U7C1 AM43 VCCMPHY_1P05<10> LBG_CORE_QAT_EXT_D_BGA1-IC,H91A    I63 @BASEBOARD_FAB2_LIB.BASEBOARD_FAB2(SCH_1):PAGE122
  U7C1 AK45 VCCMPHY_1P05<11> LBG_CORE_QAT_EXT_D_BGA1-IC,H91A    I63 @BASEBOARD_FAB2_LIB.BASEBOARD_FAB2(SCH_1):PAGE122
  U7C1 AK43 VCCMPHY_1P05<12> LBG_CORE_QAT_EXT_D_BGA1-IC,H91A    I63 @BASEBOARD_FAB2_LIB.BASEBOARD_FAB2(SCH_1):PAGE122
  U7C1 BB37 VCCP10GBE_LV_1P05<0> LBG_CORE_QAT_EXT_D_BGA1-IC,H91A    I63 @BASEBOARD_FAB2_LIB.BASEBOARD_FAB2(SCH_1):PAGE122
  U7C1 BB33 VCCP10GBE_LV_1P05<1> LBG_CORE_QAT_EXT_D_BGA1-IC,H91A    I63 @BASEBOARD_FAB2_LIB.BASEBOARD_FAB2(SCH_1):PAGE122
  U7C1 BA37 VCCP10GBE_LV_1P05<2> LBG_CORE_QAT_EXT_D_BGA1-IC,H91A    I63 @BASEBOARD_FAB2_LIB.BASEBOARD_FAB2(SCH_1):PAGE122
  U7C1 BA36 VCCP10GBE_LV_1P05<3> LBG_CORE_QAT_EXT_D_BGA1-IC,H91A    I63 @BASEBOARD_FAB2_LIB.BASEBOARD_FAB2(SCH_1):PAGE122
  U7C1 BA34 VCCP10GBE_LV_1P05<4> LBG_CORE_QAT_EXT_D_BGA1-IC,H91A    I63 @BASEBOARD_FAB2_LIB.BASEBOARD_FAB2(SCH_1):PAGE122
  U7C1 BA32 VCCP10GBE_LV_1P05<5> LBG_CORE_QAT_EXT_D_BGA1-IC,H91A    I63 @BASEBOARD_FAB2_LIB.BASEBOARD_FAB2(SCH_1):PAGE122
  U7C1 BA30 VCCP10GBE_LV_1P05<6> LBG_CORE_QAT_EXT_D_BGA1-IC,H91A    I63 @BASEBOARD_FAB2_LIB.BASEBOARD_FAB2(SCH_1):PAGE122
  U7C1 AT48 VCCP_HSIOPLLUNF_1P05 LBG_CORE_QAT_EXT_D_BGA1-IC,H91A    I63 @BASEBOARD_FAB2_LIB.BASEBOARD_FAB2(SCH_1):PAGE122
  U7C1 AM48 VCCP_UPPLLUNF_1P05 LBG_CORE_QAT_EXT_D_BGA1-IC,H91A    I63 @BASEBOARD_FAB2_LIB.BASEBOARD_FAB2(SCH_1):PAGE122
  U7C1 BF46 VCCPRIM_1P05<0> LBG_CORE_QAT_EXT_D_BGA1-IC,H91A    I63 @BASEBOARD_FAB2_LIB.BASEBOARD_FAB2(SCH_1):PAGE122
  U7C1 BE48 VCCPRIM_1P05<1> LBG_CORE_QAT_EXT_D_BGA1-IC,H91A    I63 @BASEBOARD_FAB2_LIB.BASEBOARD_FAB2(SCH_1):PAGE122
  U7C1 AU39 VCCPRIM_1P05<2> LBG_CORE_QAT_EXT_D_BGA1-IC,H91A    I63 @BASEBOARD_FAB2_LIB.BASEBOARD_FAB2(SCH_1):PAGE122
  U7C1 AU37 VCCPRIM_1P05<3> LBG_CORE_QAT_EXT_D_BGA1-IC,H91A    I63 @BASEBOARD_FAB2_LIB.BASEBOARD_FAB2(SCH_1):PAGE122
  U7C1 AT39 VCCPRIM_1P05<4> LBG_CORE_QAT_EXT_D_BGA1-IC,H91A    I63 @BASEBOARD_FAB2_LIB.BASEBOARD_FAB2(SCH_1):PAGE122
  U7C1 AM27 VCCPRIM_1P05<5> LBG_CORE_QAT_EXT_D_BGA1-IC,H91A    I63 @BASEBOARD_FAB2_LIB.BASEBOARD_FAB2(SCH_1):PAGE122
  U7C1 AJ29 VCCPRIM_1P05<6> LBG_CORE_QAT_EXT_D_BGA1-IC,H91A    I63 @BASEBOARD_FAB2_LIB.BASEBOARD_FAB2(SCH_1):PAGE122
  U7C1 AC26 VCCPRIM_1P05<7> LBG_CORE_QAT_EXT_D_BGA1-IC,H91A    I63 @BASEBOARD_FAB2_LIB.BASEBOARD_FAB2(SCH_1):PAGE122
  U7C1 AA46 VCCPRIM_1P05<8> LBG_CORE_QAT_EXT_D_BGA1-IC,H91A    I63 @BASEBOARD_FAB2_LIB.BASEBOARD_FAB2(SCH_1):PAGE122
  U7C1 AA45 VCCPRIM_1P05<9> LBG_CORE_QAT_EXT_D_BGA1-IC,H91A    I63 @BASEBOARD_FAB2_LIB.BASEBOARD_FAB2(SCH_1):PAGE122
  U7C1  Y46 VCCPRIM_1P05<10> LBG_CORE_QAT_EXT_D_BGA1-IC,H91A    I63 @BASEBOARD_FAB2_LIB.BASEBOARD_FAB2(SCH_1):PAGE122
  U7C1  Y45 VCCPRIM_1P05<11> LBG_CORE_QAT_EXT_D_BGA1-IC,H91A    I63 @BASEBOARD_FAB2_LIB.BASEBOARD_FAB2(SCH_1):PAGE122
  U7C1  V44 VCCPRIM_1P05<12> LBG_CORE_QAT_EXT_D_BGA1-IC,H91A    I63 @BASEBOARD_FAB2_LIB.BASEBOARD_FAB2(SCH_1):PAGE122
  U7C1  U46 VCCPRIM_1P05<13> LBG_CORE_QAT_EXT_D_BGA1-IC,H91A    I63 @BASEBOARD_FAB2_LIB.BASEBOARD_FAB2(SCH_1):PAGE122
  U7C1  T44 VCCPRIM_1P05<14> LBG_CORE_QAT_EXT_D_BGA1-IC,H91A    I63 @BASEBOARD_FAB2_LIB.BASEBOARD_FAB2(SCH_1):PAGE122
  U7C1  R46 VCCPRIM_1P05<15> LBG_CORE_QAT_EXT_D_BGA1-IC,H91A    I63 @BASEBOARD_FAB2_LIB.BASEBOARD_FAB2(SCH_1):PAGE122
  U7C1  R42 VCCPRIM_1P05<16> LBG_CORE_QAT_EXT_D_BGA1-IC,H91A    I63 @BASEBOARD_FAB2_LIB.BASEBOARD_FAB2(SCH_1):PAGE122
  U7C1 AK27 VCCPRIM_1P05<17> LBG_CORE_QAT_EXT_D_BGA1-IC,H91A    I63 @BASEBOARD_FAB2_LIB.BASEBOARD_FAB2(SCH_1):PAGE122
  U7C1 AA24 VCCPRIM_1P05<18> LBG_CORE_QAT_EXT_D_BGA1-IC,H91A    I63 @BASEBOARD_FAB2_LIB.BASEBOARD_FAB2(SCH_1):PAGE122
  U7C1  Y26 VCCPRIM_1P05<19> LBG_CORE_QAT_EXT_D_BGA1-IC,H91A    I63 @BASEBOARD_FAB2_LIB.BASEBOARD_FAB2(SCH_1):PAGE122
  U7C1 AE27 VCCMPHY_1P05<13> LBG_CORE_QAT_EXT_D_BGA1-IC,H91A    I21 @BASEBOARD_FAB2_LIB.BASEBOARD_FAB2(SCH_1):PAGE123
 FB3M1    1      A FERRITE_SM-120,FB,693286-027     I8 @BASEBOARD_FAB2_LIB.BASEBOARD_FAB2(SCH_1):PAGE127
 C3M21    1      A CAP_A_0402V-1.0UF,6.3V,10%,X6SA     I9 @BASEBOARD_FAB2_LIB.BASEBOARD_FAB2(SCH_1):PAGE127
 FB3M2    1      A FERRITE_SM-120,FB,693286-027    I17 @BASEBOARD_FAB2_LIB.BASEBOARD_FAB2(SCH_1):PAGE127
 C3M22    1      A CAP_A_0402V-1.0UF,6.3V,10%,X6SA    I18 @BASEBOARD_FAB2_LIB.BASEBOARD_FAB2(SCH_1):PAGE127
 FB3M3    1      A FERRITE_SM-120,FB,693286-027    I26 @BASEBOARD_FAB2_LIB.BASEBOARD_FAB2(SCH_1):PAGE127
 C3M30    1      A CAP_A_0402V-1.0UF,6.3V,10%,X6SA    I27 @BASEBOARD_FAB2_LIB.BASEBOARD_FAB2(SCH_1):PAGE127
 FB2M1    1      A FERRITE_SM-120,FB,693286-027    I46 @BASEBOARD_FAB2_LIB.BASEBOARD_FAB2(SCH_1):PAGE127
 FB3M4    1      A FERRITE_SM-120,FB,693286-027    I56 @BASEBOARD_FAB2_LIB.BASEBOARD_FAB2(SCH_1):PAGE127
 C3M31    1      A CAP_A_0402V-1.0UF,6.3V,10%,X6SA    I57 @BASEBOARD_FAB2_LIB.BASEBOARD_FAB2(SCH_1):PAGE127
 FB2M2    1      A FERRITE_SM-120,FB,693286-027    I69 @BASEBOARD_FAB2_LIB.BASEBOARD_FAB2(SCH_1):PAGE127
  L2M1    1    INA INDUCTOR_SMT-0.022UH,IND,72189A    I71 @BASEBOARD_FAB2_LIB.BASEBOARD_FAB2(SCH_1):PAGE127
  C2M8    1      A CAP_A_0402V-1.0UF,6.3V,10%,X6SA    I74 @BASEBOARD_FAB2_LIB.BASEBOARD_FAB2(SCH_1):PAGE127
  C2M6    1      A CAP_A_0402V-1.0UF,6.3V,10%,X6SA    I76 @BASEBOARD_FAB2_LIB.BASEBOARD_FAB2(SCH_1):PAGE127
 C2M25    1      A CAP_A_0402V-1.0UF,6.3V,10%,X6SA    I78 @BASEBOARD_FAB2_LIB.BASEBOARD_FAB2(SCH_1):PAGE127
 C7B15    1      A CAP_A_0603V-22.0UF,4V,20%,X6S,A     I1 @BASEBOARD_FAB2_LIB.BASEBOARD_FAB2(SCH_1):PAGE131
 C7B19    1      A CAP_A_0603V-22.0UF,4V,20%,X6S,A     I2 @BASEBOARD_FAB2_LIB.BASEBOARD_FAB2(SCH_1):PAGE131
 C7B16    1      A CAP_A_0603V-22.0UF,4V,20%,X6S,A     I3 @BASEBOARD_FAB2_LIB.BASEBOARD_FAB2(SCH_1):PAGE131
 C7B21    1      A CAP_A_0603V-22.0UF,4V,20%,X6S,A     I4 @BASEBOARD_FAB2_LIB.BASEBOARD_FAB2(SCH_1):PAGE131
 C7B20    1      A CAP_A_0603V-22.0UF,4V,20%,X6S,A     I6 @BASEBOARD_FAB2_LIB.BASEBOARD_FAB2(SCH_1):PAGE131
 C7B23    1      A CAP_A_0603V-22.0UF,4V,20%,X6S,A     I7 @BASEBOARD_FAB2_LIB.BASEBOARD_FAB2(SCH_1):PAGE131
 C8B10    1      A CAP_A_0603V-22.0UF,4V,20%,X6S,A     I8 @BASEBOARD_FAB2_LIB.BASEBOARD_FAB2(SCH_1):PAGE131
 C7B22    1      A CAP_A_0603V-22.0UF,4V,20%,X6S,A    I10 @BASEBOARD_FAB2_LIB.BASEBOARD_FAB2(SCH_1):PAGE131
 C7B24    1      A CAP_A_0603V-22.0UF,4V,20%,X6S,A    I11 @BASEBOARD_FAB2_LIB.BASEBOARD_FAB2(SCH_1):PAGE131
 C7B18    1      A CAP_A_0603V-22.0UF,4V,20%,X6S,A    I12 @BASEBOARD_FAB2_LIB.BASEBOARD_FAB2(SCH_1):PAGE131
  C8B9    1      A CAP_A_0603V-22.0UF,4V,20%,X6S,A    I14 @BASEBOARD_FAB2_LIB.BASEBOARD_FAB2(SCH_1):PAGE131
 C8B11    1      A CAP_A_0603V-22.0UF,4V,20%,X6S,A    I15 @BASEBOARD_FAB2_LIB.BASEBOARD_FAB2(SCH_1):PAGE131
 C8B14    1      A CAP_A_0603V-22.0UF,4V,20%,X6S,A    I16 @BASEBOARD_FAB2_LIB.BASEBOARD_FAB2(SCH_1):PAGE131
 C7B17    1      A CAP_A_0603V-22.0UF,4V,20%,X6S,A    I18 @BASEBOARD_FAB2_LIB.BASEBOARD_FAB2(SCH_1):PAGE131
 C8B13    1      A CAP_A_0603V-22.0UF,4V,20%,X6S,A    I20 @BASEBOARD_FAB2_LIB.BASEBOARD_FAB2(SCH_1):PAGE131
 C8B16    1      A CAP_0805-47UF,4V,20%,X6S,C9533A    I22 @BASEBOARD_FAB2_LIB.BASEBOARD_FAB2(SCH_1):PAGE131
 C8B15    1      A CAP_0805-47UF,4V,20%,X6S,C9533A    I24 @BASEBOARD_FAB2_LIB.BASEBOARD_FAB2(SCH_1):PAGE131
 C2M22    1      A CAP_A_0402V-1.0UF,6.3V,10%,X6SA    I27 @BASEBOARD_FAB2_LIB.BASEBOARD_FAB2(SCH_1):PAGE131
 C2M21    1      A CAP_A_0402V-1.0UF,6.3V,10%,X6SA    I28 @BASEBOARD_FAB2_LIB.BASEBOARD_FAB2(SCH_1):PAGE131
 C2M18    1      A CAP_A_0402V-1.0UF,6.3V,10%,X6SA    I29 @BASEBOARD_FAB2_LIB.BASEBOARD_FAB2(SCH_1):PAGE131
 C2M19    1      A CAP_A_0402V-1.0UF,6.3V,10%,X6SA    I31 @BASEBOARD_FAB2_LIB.BASEBOARD_FAB2(SCH_1):PAGE131
 C3M38    1      A CAP_A_0402V-1.0UF,6.3V,10%,X6SA    I32 @BASEBOARD_FAB2_LIB.BASEBOARD_FAB2(SCH_1):PAGE131
 C2M17    1      A CAP_0805-47UF,4V,20%,X6S,C9533A    I34 @BASEBOARD_FAB2_LIB.BASEBOARD_FAB2(SCH_1):PAGE131
 C2M11    1      A CAP_0805-47UF,4V,20%,X6S,C9533A    I35 @BASEBOARD_FAB2_LIB.BASEBOARD_FAB2(SCH_1):PAGE131
 C8A13    1      A CAP_0805-47UF,4V,20%,X6S,C9533A    I37 @BASEBOARD_FAB2_LIB.BASEBOARD_FAB2(SCH_1):PAGE131
 C2M20    1      A CAP_A_0402V-1.0UF,6.3V,10%,X6SA    I39 @BASEBOARD_FAB2_LIB.BASEBOARD_FAB2(SCH_1):PAGE131
 C2N13    1      A CAP_A_0402V-1.0UF,6.3V,10%,X6SA    I40 @BASEBOARD_FAB2_LIB.BASEBOARD_FAB2(SCH_1):PAGE131
  C2N2    1      A CAP_A_0402V-1.0UF,6.3V,10%,X6SA    I41 @BASEBOARD_FAB2_LIB.BASEBOARD_FAB2(SCH_1):PAGE131
 C3M43    1      A CAP_A_0402V-1.0UF,6.3V,10%,X6SA    I42 @BASEBOARD_FAB2_LIB.BASEBOARD_FAB2(SCH_1):PAGE131
  C2N7    1      A CAP_A_0402V-1.0UF,6.3V,10%,X6SA    I43 @BASEBOARD_FAB2_LIB.BASEBOARD_FAB2(SCH_1):PAGE131
 C3M39    1      A CAP_A_0402V-1.0UF,6.3V,10%,X6SA    I44 @BASEBOARD_FAB2_LIB.BASEBOARD_FAB2(SCH_1):PAGE131
 C3M42    1      A CAP_A_0402V-1.0UF,6.3V,10%,X6SA    I45 @BASEBOARD_FAB2_LIB.BASEBOARD_FAB2(SCH_1):PAGE131
  C2N8    1      A CAP_A_0402V-1.0UF,6.3V,10%,X6SA    I47 @BASEBOARD_FAB2_LIB.BASEBOARD_FAB2(SCH_1):PAGE131
 C2M13    1      A CAP_A_0603V-22.0UF,4V,20%,X6S,A    I48 @BASEBOARD_FAB2_LIB.BASEBOARD_FAB2(SCH_1):PAGE131
 C2N10    1      A CAP_A_0603V-22.0UF,4V,20%,X6S,A    I50 @BASEBOARD_FAB2_LIB.BASEBOARD_FAB2(SCH_1):PAGE131
 C2M12    1      A CAP_A_0603V-22.0UF,4V,20%,X6S,A    I52 @BASEBOARD_FAB2_LIB.BASEBOARD_FAB2(SCH_1):PAGE131
  R3P8    1      A RES_0402-1.00K,1%,1/16W,CHIP,GA   I322 @BASEBOARD_FAB2_LIB.BASEBOARD_FAB2(SCH_1):PAGE133
 R7D44    1      A RES_0402-4.75K,1%,1/16W,CHIP,GA   I356 @BASEBOARD_FAB2_LIB.BASEBOARD_FAB2(SCH_1):PAGE133
 R7C21    1      A RES_0402-10.0K,1%,1/16W,CHIP,GA     I9 @BASEBOARD_FAB2_LIB.BASEBOARD_FAB2(SCH_1):PAGE134
 FB1U3    2      B FERRITE_SMLF-30,FB,693286-021    I57 @BASEBOARD_FAB2_LIB.BASEBOARD_FAB2(SCH_1):PAGE169
 C7A42    1      A CAP_0805LF-22UF,4V,20%,X6S,C95A    I46 @BASEBOARD_FAB2_LIB.BASEBOARD_FAB2(SCH_1):PAGE236
 R8B14    2      B RES_0402-0.0,5%,1/16W,CHIP,G21A    I56 @BASEBOARD_FAB2_LIB.BASEBOARD_FAB2(SCH_1):PAGE236
 C3L19    1      A CAPP_SM-470UF,2V,20%,ALUM,6990A    I76 @BASEBOARD_FAB2_LIB.BASEBOARD_FAB2(SCH_1):PAGE236
 C2L46    1      A CAPP_SM-470UF,2V,20%,ALUM,6990A    I77 @BASEBOARD_FAB2_LIB.BASEBOARD_FAB2(SCH_1):PAGE236
 C8A15    1      A CAPP_SM-470UF,2V,20%,ALUM,6990A    I78 @BASEBOARD_FAB2_LIB.BASEBOARD_FAB2(SCH_1):PAGE236
 C2L25    1      A CAPP_SM-470UF,2V,20%,ALUM,6990A    I79 @BASEBOARD_FAB2_LIB.BASEBOARD_FAB2(SCH_1):PAGE236
 EU7A2    1    VOS IR354XX_SM-IR35412,IC,H73684-0A   I117 @BASEBOARD_FAB2_LIB.BASEBOARD_FAB2(SCH_1):PAGE236
 R3P53    1      A RES_0402-4.75K,1%,1/16W,CHIP,GA   I365 @BASEBOARD_FAB2_LIB.BASEBOARD_FAB2(SCH_1):PAGE133
  L7A4    2      F IND-300NH-20-GP_DISCRET-GB1-INA   I179 @BASEBOARD_FAB2_LIB.BASEBOARD_FAB2(SCH_1):PAGE236
  R3P5    1      A RES_0402-1.00K,1%,1/16W,EMPTY,A   I366 @BASEBOARD_FAB2_LIB.BASEBOARD_FAB2(SCH_1):PAGE133
  R3P6    1      A RES_0402-1.00K,1%,1/16W,EMPTY,A   I367 @BASEBOARD_FAB2_LIB.BASEBOARD_FAB2(SCH_1):PAGE133
 R3N15    1      A RES_0402-1.00K,1%,1/16W,EMPTY,A   I368 @BASEBOARD_FAB2_LIB.BASEBOARD_FAB2(SCH_1):PAGE133
 R3N16    1      A RES_0402-1.00K,1%,1/16W,EMPTY,A   I369 @BASEBOARD_FAB2_LIB.BASEBOARD_FAB2(SCH_1):PAGE133
  R3P7    1      A RES_0402-1.00K,1%,1/16W,EMPTY,A   I370 @BASEBOARD_FAB2_LIB.BASEBOARD_FAB2(SCH_1):PAGE133
U25W12   12   A<0> TTL3126_QFNLF-74CBTLV3126,IC,DB    I33 @BASEBOARD_FAB2_LIB.BASEBOARD_FAB2(SCH_1):PAGE269
U25W12    9   A<1> TTL3126_QFNLF-74CBTLV3126,IC,DB    I33 @BASEBOARD_FAB2_LIB.BASEBOARD_FAB2(SCH_1):PAGE269
U25W12    5   A<2> TTL3126_QFNLF-74CBTLV3126,IC,DB    I33 @BASEBOARD_FAB2_LIB.BASEBOARD_FAB2(SCH_1):PAGE269
R25W164    1      A RES_0402-49.9,1%,1/16W,CHIP,G2A    I29 @BASEBOARD_FAB2_LIB.BASEBOARD_FAB2(SCH_1):PAGE268

P1V05_PCH_STBY_ISCLK_PLL @BASEBOARD_FAB2_LIB.BASEBOARD_FAB2(SCH_1):P1V05_PCH_STBY_ISCLK_PLL
  U7C1  W50 VCCA_CLKFILT_1P05<0> LBG_CORE_QAT_EXT_D_BGA1-IC,H91A    I63 @BASEBOARD_FAB2_LIB.BASEBOARD_FAB2(SCH_1):PAGE122
  U7C1 AG45 VCCA_CLKFILT_1P05<1> LBG_CORE_QAT_EXT_D_BGA1-IC,H91A    I63 @BASEBOARD_FAB2_LIB.BASEBOARD_FAB2(SCH_1):PAGE122
  U7C1 AJ46 VCCA_CLKFILT_1P05<2> LBG_CORE_QAT_EXT_D_BGA1-IC,H91A    I63 @BASEBOARD_FAB2_LIB.BASEBOARD_FAB2(SCH_1):PAGE122
  U7C1 AJ48 VCCA_CLKFILT_1P05<3> LBG_CORE_QAT_EXT_D_BGA1-IC,H91A    I63 @BASEBOARD_FAB2_LIB.BASEBOARD_FAB2(SCH_1):PAGE122
  U7C1 AE46 VCCA_CLKFILT_1P05<4> LBG_CORE_QAT_EXT_D_BGA1-IC,H91A    I63 @BASEBOARD_FAB2_LIB.BASEBOARD_FAB2(SCH_1):PAGE122
 FB3M4    2      B FERRITE_SM-120,FB,693286-027    I56 @BASEBOARD_FAB2_LIB.BASEBOARD_FAB2(SCH_1):PAGE127
 C3M29    1      A CAP_A_0402V-1.0UF,6.3V,10%,X6SA    I80 @BASEBOARD_FAB2_LIB.BASEBOARD_FAB2(SCH_1):PAGE127
 C3M24    1      A CAP_0603LF-10UF,4V,20%,X6S,E15A    I81 @BASEBOARD_FAB2_LIB.BASEBOARD_FAB2(SCH_1):PAGE127

P1V05_PCH_STBY_KR_PLL @BASEBOARD_FAB2_LIB.BASEBOARD_FAB2(SCH_1):P1V05_PCH_STBY_KR_PLL
  R2N4    1      A RES_0402-1.0K,0.1%,1/16W,CHIP,A    I96 @BASEBOARD_FAB2_LIB.BASEBOARD_FAB2(SCH_1):PAGE118
  R2M6    2      B RES_0402-1.0K,0.1%,1/16W,CHIP,A    I99 @BASEBOARD_FAB2_LIB.BASEBOARD_FAB2(SCH_1):PAGE118
  U7C1 BD38 VCCP10GBEPLL_1P05<0> LBG_CORE_QAT_EXT_D_BGA1-IC,H91A    I63 @BASEBOARD_FAB2_LIB.BASEBOARD_FAB2(SCH_1):PAGE122
  U7C1 BB40 VCCP10GBEPLL_1P05<1> LBG_CORE_QAT_EXT_D_BGA1-IC,H91A    I63 @BASEBOARD_FAB2_LIB.BASEBOARD_FAB2(SCH_1):PAGE122
  U7C1 BA41 VCCP10GBEPLL_1P05<2> LBG_CORE_QAT_EXT_D_BGA1-IC,H91A    I63 @BASEBOARD_FAB2_LIB.BASEBOARD_FAB2(SCH_1):PAGE122
  U7C1 BA39 VCCP10GBEPLL_1P05<3> LBG_CORE_QAT_EXT_D_BGA1-IC,H91A    I63 @BASEBOARD_FAB2_LIB.BASEBOARD_FAB2(SCH_1):PAGE122
  C2N6    1      A CAP_0603LF-10UF,4V,20%,X6S,E15A    I64 @BASEBOARD_FAB2_LIB.BASEBOARD_FAB2(SCH_1):PAGE127
  C2N5    1      A CAP_A_0402V-1.0UF,6.3V,10%,X6SA    I65 @BASEBOARD_FAB2_LIB.BASEBOARD_FAB2(SCH_1):PAGE127
  L2M1    2    INB INDUCTOR_SMT-0.022UH,IND,72189A    I71 @BASEBOARD_FAB2_LIB.BASEBOARD_FAB2(SCH_1):PAGE127

P1V05_PCH_STBY_VCCA_PLL0 @BASEBOARD_FAB2_LIB.BASEBOARD_FAB2(SCH_1):P1V05_PCH_STBY_VCCA_PLL0
  U7C1 AG48 VCCA_PLL0_1P05 LBG_CORE_QAT_EXT_D_BGA1-IC,H91A    I63 @BASEBOARD_FAB2_LIB.BASEBOARD_FAB2(SCH_1):PAGE122
 FB3M2    2      B FERRITE_SM-120,FB,693286-027    I17 @BASEBOARD_FAB2_LIB.BASEBOARD_FAB2(SCH_1):PAGE127
 C3M20    1      A CAP_A_0402V-1.0UF,6.3V,10%,X6SA    I84 @BASEBOARD_FAB2_LIB.BASEBOARD_FAB2(SCH_1):PAGE127
 C3M18    1      A CAP_0603LF-10UF,4V,20%,X6S,E15A    I85 @BASEBOARD_FAB2_LIB.BASEBOARD_FAB2(SCH_1):PAGE127

P1V05_PCH_STBY_VCCA_PLL1 @BASEBOARD_FAB2_LIB.BASEBOARD_FAB2(SCH_1):P1V05_PCH_STBY_VCCA_PLL1
  U7C1 AE45 VCCA_PLL1_1P05 LBG_CORE_QAT_EXT_D_BGA1-IC,H91A    I63 @BASEBOARD_FAB2_LIB.BASEBOARD_FAB2(SCH_1):PAGE122
 FB3M1    2      B FERRITE_SM-120,FB,693286-027     I8 @BASEBOARD_FAB2_LIB.BASEBOARD_FAB2(SCH_1):PAGE127
 C3M17    1      A CAP_0603LF-10UF,4V,20%,X6S,E15A    I86 @BASEBOARD_FAB2_LIB.BASEBOARD_FAB2(SCH_1):PAGE127
 C3M19    1      A CAP_A_0402V-1.0UF,6.3V,10%,X6SA    I87 @BASEBOARD_FAB2_LIB.BASEBOARD_FAB2(SCH_1):PAGE127

P1V05_PCH_STBY_VCCA_XTAL @BASEBOARD_FAB2_LIB.BASEBOARD_FAB2(SCH_1):P1V05_PCH_STBY_VCCA_XTAL
  U7C1 AD50 VCCA_CLKXTAL_1P05 LBG_CORE_QAT_EXT_D_BGA1-IC,H91A    I63 @BASEBOARD_FAB2_LIB.BASEBOARD_FAB2(SCH_1):PAGE122
 FB3M3    2      B FERRITE_SM-120,FB,693286-027    I26 @BASEBOARD_FAB2_LIB.BASEBOARD_FAB2(SCH_1):PAGE127
 C3M23    1      A CAP_0603LF-10UF,4V,20%,X6S,E15A    I82 @BASEBOARD_FAB2_LIB.BASEBOARD_FAB2(SCH_1):PAGE127
 C3M27    1      A CAP_A_0402V-1.0UF,6.3V,10%,X6SA    I83 @BASEBOARD_FAB2_LIB.BASEBOARD_FAB2(SCH_1):PAGE127

P1V05_PCH_STBY_WM20_PLL @BASEBOARD_FAB2_LIB.BASEBOARD_FAB2(SCH_1):P1V05_PCH_STBY_WM20_PLL
  U7C1 AN50 VCCP_UPPLL_1P05<0> LBG_CORE_QAT_EXT_D_BGA1-IC,H91A    I63 @BASEBOARD_FAB2_LIB.BASEBOARD_FAB2(SCH_1):PAGE122
  U7C1 AK50 VCCP_UPPLL_1P05<2> LBG_CORE_QAT_EXT_D_BGA1-IC,H91A    I63 @BASEBOARD_FAB2_LIB.BASEBOARD_FAB2(SCH_1):PAGE122
  C2M5    1      A CAP_0603LF-10UF,4V,20%,X6S,E15A    I43 @BASEBOARD_FAB2_LIB.BASEBOARD_FAB2(SCH_1):PAGE127
  C2M7    1      A CAP_A_0402V-1.0UF,6.3V,10%,X6SA    I44 @BASEBOARD_FAB2_LIB.BASEBOARD_FAB2(SCH_1):PAGE127
 FB2M1    2      B FERRITE_SM-120,FB,693286-027    I46 @BASEBOARD_FAB2_LIB.BASEBOARD_FAB2(SCH_1):PAGE127

P1V05_PCH_STBY_WM26_PLL @BASEBOARD_FAB2_LIB.BASEBOARD_FAB2(SCH_1):P1V05_PCH_STBY_WM26_PLL
  U7C1 AW48 VCCP_HSIOPLL_1P05<0> LBG_CORE_QAT_EXT_D_BGA1-IC,H91A    I63 @BASEBOARD_FAB2_LIB.BASEBOARD_FAB2(SCH_1):PAGE122
  U7C1 AU48 VCCP_HSIOPLL_1P05<2> LBG_CORE_QAT_EXT_D_BGA1-IC,H91A    I63 @BASEBOARD_FAB2_LIB.BASEBOARD_FAB2(SCH_1):PAGE122
  U7C1 AP48 VCCP_HSIOPLL_1P05<3> LBG_CORE_QAT_EXT_D_BGA1-IC,H91A    I63 @BASEBOARD_FAB2_LIB.BASEBOARD_FAB2(SCH_1):PAGE122
 C2M10    1      A CAP_0603LF-10UF,4V,20%,X6S,E15A    I49 @BASEBOARD_FAB2_LIB.BASEBOARD_FAB2(SCH_1):PAGE127
  C2M9    1      A CAP_A_0402V-1.0UF,6.3V,10%,X6SA    I50 @BASEBOARD_FAB2_LIB.BASEBOARD_FAB2(SCH_1):PAGE127
 FB2M2    2      B FERRITE_SM-120,FB,693286-027    I69 @BASEBOARD_FAB2_LIB.BASEBOARD_FAB2(SCH_1):PAGE127

P1V15_AUX_BMC @BASEBOARD_FAB2_LIB.BASEBOARD_FAB2(SCH_1):P1V15_AUX_BMC
 C9E10    1      A CAP_0603-10UF,6.3V,20%,X6S,E15A    I23 @BASEBOARD_FAB2_LIB.BASEBOARD_FAB2(SCH_1):PAGE238
  C9F4    1      A CAP_0805LF-22UF,4V,20%,X6S,C95A    I30 @BASEBOARD_FAB2_LIB.BASEBOARD_FAB2(SCH_1):PAGE238
 EU9F1    1 VOUT<0> RT9059_DFN-IC,H65765-001    I40 @BASEBOARD_FAB2_LIB.BASEBOARD_FAB2(SCH_1):PAGE238
 EU9F1    2 VOUT<1> RT9059_DFN-IC,H65765-001    I40 @BASEBOARD_FAB2_LIB.BASEBOARD_FAB2(SCH_1):PAGE238
 EU9F1    3 VOUT<2> RT9059_DFN-IC,H65765-001    I40 @BASEBOARD_FAB2_LIB.BASEBOARD_FAB2(SCH_1):PAGE238
  R9F6    1      1 4K42R2F-GP_SMD-RG-4K42R2F-GP,6A    I45 @BASEBOARD_FAB2_LIB.BASEBOARD_FAB2(SCH_1):PAGE238
 U25W4   F6 IV11D0 AST2520A1-GP-GP_ASIC2-GB1-AST2A    I28 @BASEBOARD_FAB2_LIB.BASEBOARD_FAB2(SCH_1):PAGE148
 U25W4  G10 IV11D1 AST2520A1-GP-GP_ASIC2-GB1-AST2A    I28 @BASEBOARD_FAB2_LIB.BASEBOARD_FAB2(SCH_1):PAGE148
 U25W4  G11 IV11D2 AST2520A1-GP-GP_ASIC2-GB1-AST2A    I28 @BASEBOARD_FAB2_LIB.BASEBOARD_FAB2(SCH_1):PAGE148
 U25W4  G12 IV11D3 AST2520A1-GP-GP_ASIC2-GB1-AST2A    I28 @BASEBOARD_FAB2_LIB.BASEBOARD_FAB2(SCH_1):PAGE148
 U25W4  G13 IV11D4 AST2520A1-GP-GP_ASIC2-GB1-AST2A    I28 @BASEBOARD_FAB2_LIB.BASEBOARD_FAB2(SCH_1):PAGE148
 U25W4  G14 IV11D5 AST2520A1-GP-GP_ASIC2-GB1-AST2A    I28 @BASEBOARD_FAB2_LIB.BASEBOARD_FAB2(SCH_1):PAGE148
 U25W4  G15 IV11D6 AST2520A1-GP-GP_ASIC2-GB1-AST2A    I28 @BASEBOARD_FAB2_LIB.BASEBOARD_FAB2(SCH_1):PAGE148
 U25W4   G7 IV11D7 AST2520A1-GP-GP_ASIC2-GB1-AST2A    I28 @BASEBOARD_FAB2_LIB.BASEBOARD_FAB2(SCH_1):PAGE148
 U25W4   G8 IV11D8 AST2520A1-GP-GP_ASIC2-GB1-AST2A    I28 @BASEBOARD_FAB2_LIB.BASEBOARD_FAB2(SCH_1):PAGE148
 U25W4   G9 IV11D9 AST2520A1-GP-GP_ASIC2-GB1-AST2A    I28 @BASEBOARD_FAB2_LIB.BASEBOARD_FAB2(SCH_1):PAGE148
 U25W4  H16 IV11D10 AST2520A1-GP-GP_ASIC2-GB1-AST2A    I28 @BASEBOARD_FAB2_LIB.BASEBOARD_FAB2(SCH_1):PAGE148
 U25W4  J16 IV11D11 AST2520A1-GP-GP_ASIC2-GB1-AST2A    I28 @BASEBOARD_FAB2_LIB.BASEBOARD_FAB2(SCH_1):PAGE148
 U25W4   L7 IV11D12 AST2520A1-GP-GP_ASIC2-GB1-AST2A    I28 @BASEBOARD_FAB2_LIB.BASEBOARD_FAB2(SCH_1):PAGE148
 U25W4  N16 IV11D13 AST2520A1-GP-GP_ASIC2-GB1-AST2A    I28 @BASEBOARD_FAB2_LIB.BASEBOARD_FAB2(SCH_1):PAGE148
 U25W4   N7 IV11D14 AST2520A1-GP-GP_ASIC2-GB1-AST2A    I28 @BASEBOARD_FAB2_LIB.BASEBOARD_FAB2(SCH_1):PAGE148
 U25W4  P10 IV11D15 AST2520A1-GP-GP_ASIC2-GB1-AST2A    I28 @BASEBOARD_FAB2_LIB.BASEBOARD_FAB2(SCH_1):PAGE148
 U25W4  P11 IV11D16 AST2520A1-GP-GP_ASIC2-GB1-AST2A    I28 @BASEBOARD_FAB2_LIB.BASEBOARD_FAB2(SCH_1):PAGE148
 U25W4  P12 IV11D17 AST2520A1-GP-GP_ASIC2-GB1-AST2A    I28 @BASEBOARD_FAB2_LIB.BASEBOARD_FAB2(SCH_1):PAGE148
 U25W4  P13 IV11D18 AST2520A1-GP-GP_ASIC2-GB1-AST2A    I28 @BASEBOARD_FAB2_LIB.BASEBOARD_FAB2(SCH_1):PAGE148
 U25W4  P14 IV11D19 AST2520A1-GP-GP_ASIC2-GB1-AST2A    I28 @BASEBOARD_FAB2_LIB.BASEBOARD_FAB2(SCH_1):PAGE148
 U25W4  P16 IV11D20 AST2520A1-GP-GP_ASIC2-GB1-AST2A    I28 @BASEBOARD_FAB2_LIB.BASEBOARD_FAB2(SCH_1):PAGE148
 U25W4   P7 IV11D21 AST2520A1-GP-GP_ASIC2-GB1-AST2A    I28 @BASEBOARD_FAB2_LIB.BASEBOARD_FAB2(SCH_1):PAGE148
 U25W4   P9 IV11D22 AST2520A1-GP-GP_ASIC2-GB1-AST2A    I28 @BASEBOARD_FAB2_LIB.BASEBOARD_FAB2(SCH_1):PAGE148
 U25W4  R16 IV11D23 AST2520A1-GP-GP_ASIC2-GB1-AST2A    I28 @BASEBOARD_FAB2_LIB.BASEBOARD_FAB2(SCH_1):PAGE148
 U25W4   R7 IV11D24 AST2520A1-GP-GP_ASIC2-GB1-AST2A    I28 @BASEBOARD_FAB2_LIB.BASEBOARD_FAB2(SCH_1):PAGE148
 U25W4  L17 PEAV11 AST2520A1-GP-GP_ASIC2-GB1-AST2A    I28 @BASEBOARD_FAB2_LIB.BASEBOARD_FAB2(SCH_1):PAGE148
 U25W4  V17 PLLDV11 AST2520A1-GP-GP_ASIC2-GB1-AST2A    I28 @BASEBOARD_FAB2_LIB.BASEBOARD_FAB2(SCH_1):PAGE148
 FB2T7    1      1 HCB1608KF-800T30-GP_DISCRET-G9A    I42 @BASEBOARD_FAB2_LIB.BASEBOARD_FAB2(SCH_1):PAGE149
C25W30    1      A CAP_0603-4.7UF,6.3V,10%,X6S,E1A     I1 @BASEBOARD_FAB2_LIB.BASEBOARD_FAB2(SCH_1):PAGE149
C25W23    1      A CAP_0402-1.0UF,16V,10%,X6S,D97A   I103 @BASEBOARD_FAB2_LIB.BASEBOARD_FAB2(SCH_1):PAGE149
C25W24    1      A CAP_0402-1.0UF,16V,10%,X6S,D97A   I104 @BASEBOARD_FAB2_LIB.BASEBOARD_FAB2(SCH_1):PAGE149
C25W25    1      A CAP_0402-1.0UF,16V,10%,X6S,D97A   I105 @BASEBOARD_FAB2_LIB.BASEBOARD_FAB2(SCH_1):PAGE149
C25W26    1      A CAP_0402-1.0UF,16V,10%,X6S,D97A   I106 @BASEBOARD_FAB2_LIB.BASEBOARD_FAB2(SCH_1):PAGE149
C25W27    1      A CAP_0402-1.0UF,16V,10%,X6S,D97A   I107 @BASEBOARD_FAB2_LIB.BASEBOARD_FAB2(SCH_1):PAGE149
C25W28    1      A CAP_0402-1.0UF,16V,10%,X6S,D97A   I108 @BASEBOARD_FAB2_LIB.BASEBOARD_FAB2(SCH_1):PAGE149
C25W29    1      A CAP_0603LF-10UF,4V,20%,X6S,E15A   I129 @BASEBOARD_FAB2_LIB.BASEBOARD_FAB2(SCH_1):PAGE149
 C9W16    1      A CAP_A_0603V-22.0UF,4V,20%,X6S,A    I50 @BASEBOARD_FAB2_LIB.BASEBOARD_FAB2(SCH_1):PAGE238

P1V2_AUX_BMC @BASEBOARD_FAB2_LIB.BASEBOARD_FAB2(SCH_1):P1V2_AUX_BMC
 C9F13    1      A CAP_0805LF-22UF,4V,20%,X6S,C95A     I7 @BASEBOARD_FAB2_LIB.BASEBOARD_FAB2(SCH_1):PAGE239
 C1T15    1      A CAP_0603-10UF,6.3V,20%,X6S,E15A    I12 @BASEBOARD_FAB2_LIB.BASEBOARD_FAB2(SCH_1):PAGE239
 EU9F2    1 VOUT<0> RT9059_DFN-IC,H65765-001    I70 @BASEBOARD_FAB2_LIB.BASEBOARD_FAB2(SCH_1):PAGE239
 EU9F2    2 VOUT<1> RT9059_DFN-IC,H65765-001    I70 @BASEBOARD_FAB2_LIB.BASEBOARD_FAB2(SCH_1):PAGE239
 EU9F2    3 VOUT<2> RT9059_DFN-IC,H65765-001    I70 @BASEBOARD_FAB2_LIB.BASEBOARD_FAB2(SCH_1):PAGE239
 R9F31    1      1 5K1R2F-2-GP_SMD-RG-5K1R2F-2-GPA    I98 @BASEBOARD_FAB2_LIB.BASEBOARD_FAB2(SCH_1):PAGE239
 U25W4  T10  MVDD0 AST2520A1-GP-GP_ASIC2-GB1-AST2A    I28 @BASEBOARD_FAB2_LIB.BASEBOARD_FAB2(SCH_1):PAGE148
 U25W4  T12  MVDD1 AST2520A1-GP-GP_ASIC2-GB1-AST2A    I28 @BASEBOARD_FAB2_LIB.BASEBOARD_FAB2(SCH_1):PAGE148
 U25W4  T13  MVDD2 AST2520A1-GP-GP_ASIC2-GB1-AST2A    I28 @BASEBOARD_FAB2_LIB.BASEBOARD_FAB2(SCH_1):PAGE148
 U25W4  T14  MVDD3 AST2520A1-GP-GP_ASIC2-GB1-AST2A    I28 @BASEBOARD_FAB2_LIB.BASEBOARD_FAB2(SCH_1):PAGE148
 U25W4   T8  MVDD4 AST2520A1-GP-GP_ASIC2-GB1-AST2A    I28 @BASEBOARD_FAB2_LIB.BASEBOARD_FAB2(SCH_1):PAGE148
 U25W5   B3 VDD<0> H5AN4G6NAFR-TFC-GP_MEMORY-G2-HA    I49 @BASEBOARD_FAB2_LIB.BASEBOARD_FAB2(SCH_1):PAGE151
 U25W5   B9 VDD<1> H5AN4G6NAFR-TFC-GP_MEMORY-G2-HA    I49 @BASEBOARD_FAB2_LIB.BASEBOARD_FAB2(SCH_1):PAGE151
 U25W5   D1 VDD<2> H5AN4G6NAFR-TFC-GP_MEMORY-G2-HA    I49 @BASEBOARD_FAB2_LIB.BASEBOARD_FAB2(SCH_1):PAGE151
 U25W5   G7 VDD<3> H5AN4G6NAFR-TFC-GP_MEMORY-G2-HA    I49 @BASEBOARD_FAB2_LIB.BASEBOARD_FAB2(SCH_1):PAGE151
 U25W5   J1 VDD<4> H5AN4G6NAFR-TFC-GP_MEMORY-G2-HA    I49 @BASEBOARD_FAB2_LIB.BASEBOARD_FAB2(SCH_1):PAGE151
 U25W5   J9 VDD<5> H5AN4G6NAFR-TFC-GP_MEMORY-G2-HA    I49 @BASEBOARD_FAB2_LIB.BASEBOARD_FAB2(SCH_1):PAGE151
 U25W5   L1 VDD<6> H5AN4G6NAFR-TFC-GP_MEMORY-G2-HA    I49 @BASEBOARD_FAB2_LIB.BASEBOARD_FAB2(SCH_1):PAGE151
 U25W5   L9 VDD<7> H5AN4G6NAFR-TFC-GP_MEMORY-G2-HA    I49 @BASEBOARD_FAB2_LIB.BASEBOARD_FAB2(SCH_1):PAGE151
 U25W5   R1 VDD<8> H5AN4G6NAFR-TFC-GP_MEMORY-G2-HA    I49 @BASEBOARD_FAB2_LIB.BASEBOARD_FAB2(SCH_1):PAGE151
 U25W5   T9 VDD<9> H5AN4G6NAFR-TFC-GP_MEMORY-G2-HA    I49 @BASEBOARD_FAB2_LIB.BASEBOARD_FAB2(SCH_1):PAGE151
 U25W5   A1 VDDQ<0> H5AN4G6NAFR-TFC-GP_MEMORY-G2-HA    I49 @BASEBOARD_FAB2_LIB.BASEBOARD_FAB2(SCH_1):PAGE151
 U25W5   A9 VDDQ<1> H5AN4G6NAFR-TFC-GP_MEMORY-G2-HA    I49 @BASEBOARD_FAB2_LIB.BASEBOARD_FAB2(SCH_1):PAGE151
 U25W5   C1 VDDQ<2> H5AN4G6NAFR-TFC-GP_MEMORY-G2-HA    I49 @BASEBOARD_FAB2_LIB.BASEBOARD_FAB2(SCH_1):PAGE151
 U25W5   D9 VDDQ<3> H5AN4G6NAFR-TFC-GP_MEMORY-G2-HA    I49 @BASEBOARD_FAB2_LIB.BASEBOARD_FAB2(SCH_1):PAGE151
 U25W5   F2 VDDQ<4> H5AN4G6NAFR-TFC-GP_MEMORY-G2-HA    I49 @BASEBOARD_FAB2_LIB.BASEBOARD_FAB2(SCH_1):PAGE151
 U25W5   F8 VDDQ<5> H5AN4G6NAFR-TFC-GP_MEMORY-G2-HA    I49 @BASEBOARD_FAB2_LIB.BASEBOARD_FAB2(SCH_1):PAGE151
 U25W5   G1 VDDQ<6> H5AN4G6NAFR-TFC-GP_MEMORY-G2-HA    I49 @BASEBOARD_FAB2_LIB.BASEBOARD_FAB2(SCH_1):PAGE151
 U25W5   G9 VDDQ<7> H5AN4G6NAFR-TFC-GP_MEMORY-G2-HA    I49 @BASEBOARD_FAB2_LIB.BASEBOARD_FAB2(SCH_1):PAGE151
 U25W5   J2 VDDQ<8> H5AN4G6NAFR-TFC-GP_MEMORY-G2-HA    I49 @BASEBOARD_FAB2_LIB.BASEBOARD_FAB2(SCH_1):PAGE151
 U25W5   J8 VDDQ<9> H5AN4G6NAFR-TFC-GP_MEMORY-G2-HA    I49 @BASEBOARD_FAB2_LIB.BASEBOARD_FAB2(SCH_1):PAGE151
 R9F29    1      A RES_0402-4.75K,1%,1/16W,CHIP,GA    I55 @BASEBOARD_FAB2_LIB.BASEBOARD_FAB2(SCH_1):PAGE151
C25W16    1      A CAP_0402LF-100.0PF,50V,5%,COG,A    I58 @BASEBOARD_FAB2_LIB.BASEBOARD_FAB2(SCH_1):PAGE151
C25W17    1      1 SC1U16V3KX-2GP_SMD-BCG-SC1U16VA   I120 @BASEBOARD_FAB2_LIB.BASEBOARD_FAB2(SCH_1):PAGE151
C25W18    1      1 SC1U16V3KX-2GP_SMD-BCG-SC1U16VA   I121 @BASEBOARD_FAB2_LIB.BASEBOARD_FAB2(SCH_1):PAGE151
C25W19    1      A CAP_0603-4.7UF,6.3V,10%,X6S,E1A   I123 @BASEBOARD_FAB2_LIB.BASEBOARD_FAB2(SCH_1):PAGE151
 C25W1    1      A CAP_0402-1.0UF,16V,10%,X6S,D97A   I125 @BASEBOARD_FAB2_LIB.BASEBOARD_FAB2(SCH_1):PAGE151
 C25W2    1      A CAP_0402-1.0UF,16V,10%,X6S,D97A   I139 @BASEBOARD_FAB2_LIB.BASEBOARD_FAB2(SCH_1):PAGE151
 C25W3    1      A CAP_0402-1.0UF,16V,10%,X6S,D97A   I140 @BASEBOARD_FAB2_LIB.BASEBOARD_FAB2(SCH_1):PAGE151
 C25W4    1      A CAP_0402-1.0UF,16V,10%,X6S,D97A   I141 @BASEBOARD_FAB2_LIB.BASEBOARD_FAB2(SCH_1):PAGE151
 C25W5    1      A CAP_0402-1.0UF,16V,10%,X6S,D97A   I142 @BASEBOARD_FAB2_LIB.BASEBOARD_FAB2(SCH_1):PAGE151
 C25W6    1      A CAP_0402-1.0UF,16V,10%,X6S,D97A   I143 @BASEBOARD_FAB2_LIB.BASEBOARD_FAB2(SCH_1):PAGE151
 R1T30    1      A RES_0402-1.00K,1%,1/16W,CHIP,GA   I201 @BASEBOARD_FAB2_LIB.BASEBOARD_FAB2(SCH_1):PAGE151
C25W53    1      A CAP_0402-1.0UF,16V,10%,X6S,D97A    I92 @BASEBOARD_FAB2_LIB.BASEBOARD_FAB2(SCH_1):PAGE149
C25W54    1      A CAP_0402-1.0UF,16V,10%,X6S,D97A    I95 @BASEBOARD_FAB2_LIB.BASEBOARD_FAB2(SCH_1):PAGE149
C25W51    1      A CAP_0402-1.0UF,16V,10%,X6S,D97A   I114 @BASEBOARD_FAB2_LIB.BASEBOARD_FAB2(SCH_1):PAGE149
C25W52    1      A CAP_0402-1.0UF,16V,10%,X6S,D97A   I118 @BASEBOARD_FAB2_LIB.BASEBOARD_FAB2(SCH_1):PAGE149
R25W119    1      A RES_0402-4.75K,1%,1/16W,EMPTY,A   I210 @BASEBOARD_FAB2_LIB.BASEBOARD_FAB2(SCH_1):PAGE151
C25W10    1      A CAP_A_0402V-0.01UF,25V,10%,X7RA   I213 @BASEBOARD_FAB2_LIB.BASEBOARD_FAB2(SCH_1):PAGE151
C25W55    1      A CAP_A_0402V-0.1UF,16V,10%,X7R,A   I124 @BASEBOARD_FAB2_LIB.BASEBOARD_FAB2(SCH_1):PAGE149
R25W30    2      B RES_0402-2.7K,1%,1/16W,CHIP,G2A   I222 @BASEBOARD_FAB2_LIB.BASEBOARD_FAB2(SCH_1):PAGE151
R25W27    2      2 120R2F-GP_RCL_GP-120R2F-GP,64.A   I223 @BASEBOARD_FAB2_LIB.BASEBOARD_FAB2(SCH_1):PAGE151
R25W28    2      2 120R2F-GP_RCL_GP-120R2F-GP,64.A   I224 @BASEBOARD_FAB2_LIB.BASEBOARD_FAB2(SCH_1):PAGE151
R25W29    2      2 120R2F-GP_RCL_GP-120R2F-GP,64.A   I225 @BASEBOARD_FAB2_LIB.BASEBOARD_FAB2(SCH_1):PAGE151
R25W31    2      2 120R2F-GP_RCL_GP-120R2F-GP,64.A   I226 @BASEBOARD_FAB2_LIB.BASEBOARD_FAB2(SCH_1):PAGE151
R25W32    2      2 120R2F-GP_RCL_GP-120R2F-GP,64.A   I227 @BASEBOARD_FAB2_LIB.BASEBOARD_FAB2(SCH_1):PAGE151
R25W33    2      2 120R2F-GP_RCL_GP-120R2F-GP,64.A   I228 @BASEBOARD_FAB2_LIB.BASEBOARD_FAB2(SCH_1):PAGE151
R25W34    2      2 120R2F-GP_RCL_GP-120R2F-GP,64.A   I229 @BASEBOARD_FAB2_LIB.BASEBOARD_FAB2(SCH_1):PAGE151
R25W35    2      2 120R2F-GP_RCL_GP-120R2F-GP,64.A   I230 @BASEBOARD_FAB2_LIB.BASEBOARD_FAB2(SCH_1):PAGE151
R25W36    2      2 120R2F-GP_RCL_GP-120R2F-GP,64.A   I231 @BASEBOARD_FAB2_LIB.BASEBOARD_FAB2(SCH_1):PAGE151
R25W37    2      2 120R2F-GP_RCL_GP-120R2F-GP,64.A   I232 @BASEBOARD_FAB2_LIB.BASEBOARD_FAB2(SCH_1):PAGE151
R25W38    2      2 120R2F-GP_RCL_GP-120R2F-GP,64.A   I233 @BASEBOARD_FAB2_LIB.BASEBOARD_FAB2(SCH_1):PAGE151
R25W39    2      2 120R2F-GP_RCL_GP-120R2F-GP,64.A   I234 @BASEBOARD_FAB2_LIB.BASEBOARD_FAB2(SCH_1):PAGE151
R25W41    2      2 120R2F-GP_RCL_GP-120R2F-GP,64.A   I235 @BASEBOARD_FAB2_LIB.BASEBOARD_FAB2(SCH_1):PAGE151
R25W42    2      2 120R2F-GP_RCL_GP-120R2F-GP,64.A   I236 @BASEBOARD_FAB2_LIB.BASEBOARD_FAB2(SCH_1):PAGE151
R25W44    2      2 120R2F-GP_RCL_GP-120R2F-GP,64.A   I237 @BASEBOARD_FAB2_LIB.BASEBOARD_FAB2(SCH_1):PAGE151
R25W43    2      2 120R2F-GP_RCL_GP-120R2F-GP,64.A   I238 @BASEBOARD_FAB2_LIB.BASEBOARD_FAB2(SCH_1):PAGE151
R25W47    2      2 120R2F-GP_RCL_GP-120R2F-GP,64.A   I239 @BASEBOARD_FAB2_LIB.BASEBOARD_FAB2(SCH_1):PAGE151
R25W48    2      2 120R2F-GP_RCL_GP-120R2F-GP,64.A   I240 @BASEBOARD_FAB2_LIB.BASEBOARD_FAB2(SCH_1):PAGE151
R25W46    2      2 120R2F-GP_RCL_GP-120R2F-GP,64.A   I241 @BASEBOARD_FAB2_LIB.BASEBOARD_FAB2(SCH_1):PAGE151
R25W45    2      2 120R2F-GP_RCL_GP-120R2F-GP,64.A   I242 @BASEBOARD_FAB2_LIB.BASEBOARD_FAB2(SCH_1):PAGE151
R25W49    2      2 120R2F-GP_RCL_GP-120R2F-GP,64.A   I243 @BASEBOARD_FAB2_LIB.BASEBOARD_FAB2(SCH_1):PAGE151
R25W50    2      2 120R2F-GP_RCL_GP-120R2F-GP,64.A   I244 @BASEBOARD_FAB2_LIB.BASEBOARD_FAB2(SCH_1):PAGE151
R25W51    2      2 120R2F-GP_RCL_GP-120R2F-GP,64.A   I245 @BASEBOARD_FAB2_LIB.BASEBOARD_FAB2(SCH_1):PAGE151
R25W52    2      2 120R2F-GP_RCL_GP-120R2F-GP,64.A   I246 @BASEBOARD_FAB2_LIB.BASEBOARD_FAB2(SCH_1):PAGE151
R25W40    2      2 120R2F-GP_RCL_GP-120R2F-GP,64.A   I247 @BASEBOARD_FAB2_LIB.BASEBOARD_FAB2(SCH_1):PAGE151
 C9W19    1      A CAP_A_0603V-22.0UF,4V,20%,X6S,A   I111 @BASEBOARD_FAB2_LIB.BASEBOARD_FAB2(SCH_1):PAGE239

P1V5_LAN @BASEBOARD_FAB2_LIB.BASEBOARD_FAB2(SCH_1):P1V5_LAN
 EU9E1   47 VDD1P5<1> SPRINGVILLE_SM1-IC,G47144-004    I72 @BASEBOARD_FAB2_LIB.BASEBOARD_FAB2(SCH_1):PAGE139
 EU9E1   39 VDD1P5_OUT SPRINGVILLE_SM1-IC,G47144-004    I72 @BASEBOARD_FAB2_LIB.BASEBOARD_FAB2(SCH_1):PAGE139
 C1R30    1      A CAP_0603-10UF,6.3V,20%,X6S,E15A   I135 @BASEBOARD_FAB2_LIB.BASEBOARD_FAB2(SCH_1):PAGE139
 C1R26    1      A CAP_A_0402V-0.1UF,16V,10%,X7R,A   I149 @BASEBOARD_FAB2_LIB.BASEBOARD_FAB2(SCH_1):PAGE139
 C1R29    1      A CAP_A_0402V-0.1UF,16V,10%,X7R,A   I150 @BASEBOARD_FAB2_LIB.BASEBOARD_FAB2(SCH_1):PAGE139
 C1R19    1      A CAP_A_0402V-0.1UF,16V,10%,X7R,A   I151 @BASEBOARD_FAB2_LIB.BASEBOARD_FAB2(SCH_1):PAGE139
 C1R31    1      A CAP_A_0402V-0.1UF,16V,10%,X7R,A   I152 @BASEBOARD_FAB2_LIB.BASEBOARD_FAB2(SCH_1):PAGE139
 C1R17    1      A CAP_0603-10UF,6.3V,20%,X6S,E15A   I153 @BASEBOARD_FAB2_LIB.BASEBOARD_FAB2(SCH_1):PAGE139
 R1T32    1      A RES_0603-0,5.0%,1/10W,CHIP,G22A   I238 @BASEBOARD_FAB2_LIB.BASEBOARD_FAB2(SCH_1):PAGE139
 R1T33    1      A RES_0603-0,5.0%,1/10W,EMPTY,G2A   I240 @BASEBOARD_FAB2_LIB.BASEBOARD_FAB2(SCH_1):PAGE139
C22W35    1      1 SC22U16V5MX-4-GP_SMD-BCG5-SC22A   I246 @BASEBOARD_FAB2_LIB.BASEBOARD_FAB2(SCH_1):PAGE139
  C9E6    1      1 SC22U16V5MX-4-GP_SMD-BCG5-SC22A   I248 @BASEBOARD_FAB2_LIB.BASEBOARD_FAB2(SCH_1):PAGE139

P1V5_LAN_I210 @BASEBOARD_FAB2_LIB.BASEBOARD_FAB2(SCH_1):P1V5_LAN_I210
 EU9E1   56 VDD1P5<0> SPRINGVILLE_SM1-IC,G47144-004    I72 @BASEBOARD_FAB2_LIB.BASEBOARD_FAB2(SCH_1):PAGE139
 R1T32    2      B RES_0603-0,5.0%,1/10W,CHIP,G22A   I238 @BASEBOARD_FAB2_LIB.BASEBOARD_FAB2(SCH_1):PAGE139

P1V8_M2 @BASEBOARD_FAB2_LIB.BASEBOARD_FAB2(SCH_1):P1V8_M2
 C32W1    1      A CAP_A_0402V-0.1UF,16V,10%,X7R,A   I188 @BASEBOARD_FAB2_LIB.BASEBOARD_FAB2(SCH_1):PAGE185
 C32W3    1      A CAP_A_0402V-0.1UF,16V,10%,X7R,A   I190 @BASEBOARD_FAB2_LIB.BASEBOARD_FAB2(SCH_1):PAGE185
 U32W1    1   VCCA TCA9517DGKR-GP_DISCRET-G8-TCA9A   I191 @BASEBOARD_FAB2_LIB.BASEBOARD_FAB2(SCH_1):PAGE185
 U32W2    1   VCCA TCA9517DGKR-GP_DISCRET-G8-TCA9A   I204 @BASEBOARD_FAB2_LIB.BASEBOARD_FAB2(SCH_1):PAGE185
 R32W2    1      A RES_0402-1.5K,1%,1/16W,CHIP,G2A   I207 @BASEBOARD_FAB2_LIB.BASEBOARD_FAB2(SCH_1):PAGE185
 R32W1    2      B RES_0402-4.02K,1%,1/16W,CHIP,GA   I208 @BASEBOARD_FAB2_LIB.BASEBOARD_FAB2(SCH_1):PAGE185
 R32W4    1      A RES_0402-49.9K,1%,1/16W,CHIP,GA   I211 @BASEBOARD_FAB2_LIB.BASEBOARD_FAB2(SCH_1):PAGE185
VR32W1    2 CATHODE LMV431AIMFX-GP_DISCRET-G5-LMV4A   I213 @BASEBOARD_FAB2_LIB.BASEBOARD_FAB2(SCH_1):PAGE185
 R32W6    1      A RES_0402-2.0K,1%,1/16W,CHIP,G2A   I214 @BASEBOARD_FAB2_LIB.BASEBOARD_FAB2(SCH_1):PAGE185
 R32W7    1      A RES_0402-2.0K,1%,1/16W,CHIP,G2A   I215 @BASEBOARD_FAB2_LIB.BASEBOARD_FAB2(SCH_1):PAGE185
 R32W5    1      A RES_0402-2.0K,1%,1/16W,CHIP,G2A   I216 @BASEBOARD_FAB2_LIB.BASEBOARD_FAB2(SCH_1):PAGE185
 C32W5    1      A CAP_0402-1.0UF,16V,10%,X6S,D97A   I217 @BASEBOARD_FAB2_LIB.BASEBOARD_FAB2(SCH_1):PAGE185

P1V8_MCP_CPU0 @BASEBOARD_FAB2_LIB.BASEBOARD_FAB2(SCH_1):P1V8_MCP_CPU0
  U5D1  B17 RSVD<294> SKX_EXT_B_BGA1-IC,TBD   I204 @BASEBOARD_FAB2_LIB.BASEBOARD_FAB2(SCH_1):PAGE22
  U5D1  B15 RSVD<295> SKX_EXT_B_BGA1-IC,TBD   I204 @BASEBOARD_FAB2_LIB.BASEBOARD_FAB2(SCH_1):PAGE22
  U5D1  B13 RSVD<296> SKX_EXT_B_BGA1-IC,TBD   I204 @BASEBOARD_FAB2_LIB.BASEBOARD_FAB2(SCH_1):PAGE22
  U5D1  A16 RSVD<301> SKX_EXT_B_BGA1-IC,TBD   I204 @BASEBOARD_FAB2_LIB.BASEBOARD_FAB2(SCH_1):PAGE22
  U5D1  A14 RSVD<302> SKX_EXT_B_BGA1-IC,TBD   I204 @BASEBOARD_FAB2_LIB.BASEBOARD_FAB2(SCH_1):PAGE22
  C6D1    1      A CAP_0603LF-10UF,4V,20%,X6S,E15A    I19 @BASEBOARD_FAB2_LIB.BASEBOARD_FAB2(SCH_1):PAGE38
  U5D1 BT27 CD_VCCIN<0> SKX_EXT_B_BGA1-IC,TBD    I34 @BASEBOARD_FAB2_LIB.BASEBOARD_FAB2(SCH_1):PAGE38
  U5D1 BU26 CD_VCCIN<1> SKX_EXT_B_BGA1-IC,TBD    I34 @BASEBOARD_FAB2_LIB.BASEBOARD_FAB2(SCH_1):PAGE38
  U5D1 BV27 CD_VCCIN<2> SKX_EXT_B_BGA1-IC,TBD    I34 @BASEBOARD_FAB2_LIB.BASEBOARD_FAB2(SCH_1):PAGE38
  U5D1 BY27 CD_VCCIN<3> SKX_EXT_B_BGA1-IC,TBD    I34 @BASEBOARD_FAB2_LIB.BASEBOARD_FAB2(SCH_1):PAGE38
 C1M29    1      A CAP_A_0402V-0.1UF,16V,10%,X7R,A   I147 @BASEBOARD_FAB2_LIB.BASEBOARD_FAB2(SCH_1):PAGE113
  J9B4    4    IO4 SCONN10_C12536004_SMLF-CONN,C1A   I175 @BASEBOARD_FAB2_LIB.BASEBOARD_FAB2(SCH_1):PAGE113
  U1M5    2      A 74CBTLV1G125_SMLF-IC,C88177-00A   I196 @BASEBOARD_FAB2_LIB.BASEBOARD_FAB2(SCH_1):PAGE113
 R1M19    1      A RES_0402-1.00K,1%,1/16W,CHIP,GA   I202 @BASEBOARD_FAB2_LIB.BASEBOARD_FAB2(SCH_1):PAGE113
 R9B12    1      A RES_0402-1.00K,1%,1/16W,CHIP,GA   I203 @BASEBOARD_FAB2_LIB.BASEBOARD_FAB2(SCH_1):PAGE113
 R1M20    1      A RES_0402-1.00K,1%,1/16W,CHIP,GA   I204 @BASEBOARD_FAB2_LIB.BASEBOARD_FAB2(SCH_1):PAGE113
 R1M21    1      A RES_0402-1.00K,1%,1/16W,CHIP,GA   I205 @BASEBOARD_FAB2_LIB.BASEBOARD_FAB2(SCH_1):PAGE113
  U4R1    2      A 74CBTLV1G125_SMLF-IC,C88177-00A   I206 @BASEBOARD_FAB2_LIB.BASEBOARD_FAB2(SCH_1):PAGE113
  C4T2    1      A CAP_A_0402V-1.0UF,6.3V,10%,X6SA     I9 @BASEBOARD_FAB2_LIB.BASEBOARD_FAB2(SCH_1):PAGE194
  C4T1    1      A CAP_A_0402V-1.0UF,6.3V,10%,X6SA    I16 @BASEBOARD_FAB2_LIB.BASEBOARD_FAB2(SCH_1):PAGE194
  J6E1   D3   IOD3 SCONN120_H61426002_SM-CONN,H61A    I55 @BASEBOARD_FAB2_LIB.BASEBOARD_FAB2(SCH_1):PAGE194
  J6E1   E1   IOE1 SCONN120_H61426002_SM-CONN,H61A    I55 @BASEBOARD_FAB2_LIB.BASEBOARD_FAB2(SCH_1):PAGE194
  J6E1   E2   IOE2 SCONN120_H61426002_SM-CONN,H61A    I55 @BASEBOARD_FAB2_LIB.BASEBOARD_FAB2(SCH_1):PAGE194
  J6E1   E3   IOE3 SCONN120_H61426002_SM-CONN,H61A    I55 @BASEBOARD_FAB2_LIB.BASEBOARD_FAB2(SCH_1):PAGE194
  J6E1   F1   IOF1 SCONN120_H61426002_SM-CONN,H61A    I55 @BASEBOARD_FAB2_LIB.BASEBOARD_FAB2(SCH_1):PAGE194
  J6E1   F2   IOF2 SCONN120_H61426002_SM-CONN,H61A    I55 @BASEBOARD_FAB2_LIB.BASEBOARD_FAB2(SCH_1):PAGE194
  J6E1   F3   IOF3 SCONN120_H61426002_SM-CONN,H61A    I55 @BASEBOARD_FAB2_LIB.BASEBOARD_FAB2(SCH_1):PAGE194
  C3T1    1      A CAP_A_0603V-47UF,4V,20%,X5R,60A   I149 @BASEBOARD_FAB2_LIB.BASEBOARD_FAB2(SCH_1):PAGE194
  C3T2    1      A CAP_A_0603V-47UF,4V,20%,X5R,60A   I150 @BASEBOARD_FAB2_LIB.BASEBOARD_FAB2(SCH_1):PAGE194
  R5W1    1      A RES_0402-0.0,5%,1/16W,CHIP,G21A   I272 @BASEBOARD_FAB2_LIB.BASEBOARD_FAB2(SCH_1):PAGE113

P1V8_MCP_CPU1 @BASEBOARD_FAB2_LIB.BASEBOARD_FAB2(SCH_1):P1V8_MCP_CPU1
  U2D1  B17 RSVD<294> SKX_EXT_B_BGA1-IC,TBD   I169 @BASEBOARD_FAB2_LIB.BASEBOARD_FAB2(SCH_1):PAGE56
  U2D1  B15 RSVD<295> SKX_EXT_B_BGA1-IC,TBD   I169 @BASEBOARD_FAB2_LIB.BASEBOARD_FAB2(SCH_1):PAGE56
  U2D1  B13 RSVD<296> SKX_EXT_B_BGA1-IC,TBD   I169 @BASEBOARD_FAB2_LIB.BASEBOARD_FAB2(SCH_1):PAGE56
  U2D1  A16 RSVD<301> SKX_EXT_B_BGA1-IC,TBD   I169 @BASEBOARD_FAB2_LIB.BASEBOARD_FAB2(SCH_1):PAGE56
  U2D1  A14 RSVD<302> SKX_EXT_B_BGA1-IC,TBD   I169 @BASEBOARD_FAB2_LIB.BASEBOARD_FAB2(SCH_1):PAGE56
  C3D3    1      A CAP_0603LF-10UF,4V,20%,X6S,E15A    I25 @BASEBOARD_FAB2_LIB.BASEBOARD_FAB2(SCH_1):PAGE72
  U2D1 BT27 CD_VCCIN<0> SKX_EXT_B_BGA1-IC,TBD    I33 @BASEBOARD_FAB2_LIB.BASEBOARD_FAB2(SCH_1):PAGE72
  U2D1 BU26 CD_VCCIN<1> SKX_EXT_B_BGA1-IC,TBD    I33 @BASEBOARD_FAB2_LIB.BASEBOARD_FAB2(SCH_1):PAGE72
  U2D1 BV27 CD_VCCIN<2> SKX_EXT_B_BGA1-IC,TBD    I33 @BASEBOARD_FAB2_LIB.BASEBOARD_FAB2(SCH_1):PAGE72
  U2D1 BY27 CD_VCCIN<3> SKX_EXT_B_BGA1-IC,TBD    I33 @BASEBOARD_FAB2_LIB.BASEBOARD_FAB2(SCH_1):PAGE72
  U6M1    2      A 74CBTLV1G125_SMLF-IC,C88177-00A   I190 @BASEBOARD_FAB2_LIB.BASEBOARD_FAB2(SCH_1):PAGE113
  J4E1   D3   IOD3 SCONN120_H61426002_SM-CONN,H61A    I45 @BASEBOARD_FAB2_LIB.BASEBOARD_FAB2(SCH_1):PAGE193
  J4E1   E1   IOE1 SCONN120_H61426002_SM-CONN,H61A    I45 @BASEBOARD_FAB2_LIB.BASEBOARD_FAB2(SCH_1):PAGE193
  J4E1   E2   IOE2 SCONN120_H61426002_SM-CONN,H61A    I45 @BASEBOARD_FAB2_LIB.BASEBOARD_FAB2(SCH_1):PAGE193
  J4E1   E3   IOE3 SCONN120_H61426002_SM-CONN,H61A    I45 @BASEBOARD_FAB2_LIB.BASEBOARD_FAB2(SCH_1):PAGE193
  J4E1   F1   IOF1 SCONN120_H61426002_SM-CONN,H61A    I45 @BASEBOARD_FAB2_LIB.BASEBOARD_FAB2(SCH_1):PAGE193
  J4E1   F2   IOF2 SCONN120_H61426002_SM-CONN,H61A    I45 @BASEBOARD_FAB2_LIB.BASEBOARD_FAB2(SCH_1):PAGE193
  J4E1   F3   IOF3 SCONN120_H61426002_SM-CONN,H61A    I45 @BASEBOARD_FAB2_LIB.BASEBOARD_FAB2(SCH_1):PAGE193
  C4F1    1      A CAP_A_0402V-1.0UF,6.3V,10%,X6SA    I68 @BASEBOARD_FAB2_LIB.BASEBOARD_FAB2(SCH_1):PAGE193
  C4F3    1      A CAP_A_0402V-1.0UF,6.3V,10%,X6SA    I70 @BASEBOARD_FAB2_LIB.BASEBOARD_FAB2(SCH_1):PAGE193
  C3F1    1      A CAP_A_0603V-47UF,4V,20%,X5R,60A   I140 @BASEBOARD_FAB2_LIB.BASEBOARD_FAB2(SCH_1):PAGE193
  C4F2    1      A CAP_A_0603V-47UF,4V,20%,X5R,60A   I141 @BASEBOARD_FAB2_LIB.BASEBOARD_FAB2(SCH_1):PAGE193
  R5W2    1      A RES_0402-0.0,5%,1/16W,CHIP,G21A   I273 @BASEBOARD_FAB2_LIB.BASEBOARD_FAB2(SCH_1):PAGE113

P1V8_PCH_STBY @BASEBOARD_FAB2_LIB.BASEBOARD_FAB2(SCH_1):P1V8_PCH_STBY
  U7C1 BA29 VCCP10GBE_HV_1P8<0> LBG_CORE_QAT_EXT_D_BGA1-IC,H91A    I63 @BASEBOARD_FAB2_LIB.BASEBOARD_FAB2(SCH_1):PAGE122
  U7C1 BA27 VCCP10GBE_HV_1P8<1> LBG_CORE_QAT_EXT_D_BGA1-IC,H91A    I63 @BASEBOARD_FAB2_LIB.BASEBOARD_FAB2(SCH_1):PAGE122
  U7C1 BD46 VCCP_1P8<0> LBG_CORE_QAT_EXT_D_BGA1-IC,H91A    I63 @BASEBOARD_FAB2_LIB.BASEBOARD_FAB2(SCH_1):PAGE122
  U7C1 AE26 VCCP_1P8<1> LBG_CORE_QAT_EXT_D_BGA1-IC,H91A    I63 @BASEBOARD_FAB2_LIB.BASEBOARD_FAB2(SCH_1):PAGE122
  U7C1 AU29 VCCPGPP_1P8<0> LBG_CORE_QAT_EXT_D_BGA1-IC,H91A    I63 @BASEBOARD_FAB2_LIB.BASEBOARD_FAB2(SCH_1):PAGE122
  U7C1 AW29 VCCPGPP_1P8<1> LBG_CORE_QAT_EXT_D_BGA1-IC,H91A    I63 @BASEBOARD_FAB2_LIB.BASEBOARD_FAB2(SCH_1):PAGE122
  U7C1 AT29 VCCPGPP_1P8<2> LBG_CORE_QAT_EXT_D_BGA1-IC,H91A    I63 @BASEBOARD_FAB2_LIB.BASEBOARD_FAB2(SCH_1):PAGE122
  U7C1 AM29 VCCPGPP_1P8<3> LBG_CORE_QAT_EXT_D_BGA1-IC,H91A    I63 @BASEBOARD_FAB2_LIB.BASEBOARD_FAB2(SCH_1):PAGE122
  U7C1 AP29 VCCPGPP_1P8<4> LBG_CORE_QAT_EXT_D_BGA1-IC,H91A    I63 @BASEBOARD_FAB2_LIB.BASEBOARD_FAB2(SCH_1):PAGE122
  U7C1 AW27 VCCPGPP_1P8<5> LBG_CORE_QAT_EXT_D_BGA1-IC,H91A    I63 @BASEBOARD_FAB2_LIB.BASEBOARD_FAB2(SCH_1):PAGE122
  U7C1 AK24 VCCPGPP_1P8<6> LBG_CORE_QAT_EXT_D_BGA1-IC,H91A    I63 @BASEBOARD_FAB2_LIB.BASEBOARD_FAB2(SCH_1):PAGE122
  U7C1 AG27 VCCPHDA_1P8 LBG_CORE_QAT_EXT_D_BGA1-IC,H91A    I63 @BASEBOARD_FAB2_LIB.BASEBOARD_FAB2(SCH_1):PAGE122
  U7C1 AK29 VCCPSPI_1P8 LBG_CORE_QAT_EXT_D_BGA1-IC,H91A    I63 @BASEBOARD_FAB2_LIB.BASEBOARD_FAB2(SCH_1):PAGE122
  C8B2    1      A CAP_A_0603V-22.0UF,4V,20%,X6S,A    I30 @BASEBOARD_FAB2_LIB.BASEBOARD_FAB2(SCH_1):PAGE130
  C8B3    1      A CAP_A_0603V-22.0UF,4V,20%,X6S,A    I32 @BASEBOARD_FAB2_LIB.BASEBOARD_FAB2(SCH_1):PAGE130
  C7D3    1      A CAP_A_0603V-22.0UF,4V,20%,X6S,A    I38 @BASEBOARD_FAB2_LIB.BASEBOARD_FAB2(SCH_1):PAGE130
  C8B4    1      A CAP_A_0603V-22.0UF,4V,20%,X6S,A    I39 @BASEBOARD_FAB2_LIB.BASEBOARD_FAB2(SCH_1):PAGE130
  C8B1    1      A CAP_A_0603V-22.0UF,4V,20%,X6S,A    I41 @BASEBOARD_FAB2_LIB.BASEBOARD_FAB2(SCH_1):PAGE130
  C2M1    1      A CAP_A_0603V-22.0UF,4V,20%,X6S,A    I43 @BASEBOARD_FAB2_LIB.BASEBOARD_FAB2(SCH_1):PAGE130
  C2M2    1      A CAP_A_0603V-22.0UF,4V,20%,X6S,A    I45 @BASEBOARD_FAB2_LIB.BASEBOARD_FAB2(SCH_1):PAGE130
 C2N15    1      A CAP_A_0402V-1.0UF,6.3V,10%,X6SA    I47 @BASEBOARD_FAB2_LIB.BASEBOARD_FAB2(SCH_1):PAGE130
 C3N21    1      A CAP_A_0402V-1.0UF,6.3V,10%,X6SA    I49 @BASEBOARD_FAB2_LIB.BASEBOARD_FAB2(SCH_1):PAGE130
 C3N25    1      A CAP_A_0402V-1.0UF,6.3V,10%,X6SA    I50 @BASEBOARD_FAB2_LIB.BASEBOARD_FAB2(SCH_1):PAGE130
 C2N16    1      A CAP_A_0402V-1.0UF,6.3V,10%,X6SA    I52 @BASEBOARD_FAB2_LIB.BASEBOARD_FAB2(SCH_1):PAGE130
 C3N22    1      A CAP_A_0402V-1.0UF,6.3V,10%,X6SA    I53 @BASEBOARD_FAB2_LIB.BASEBOARD_FAB2(SCH_1):PAGE130
 C2L45    1      A CAP_0805-22UF,6.3V,20%,X6S,C95A    I12 @BASEBOARD_FAB2_LIB.BASEBOARD_FAB2(SCH_1):PAGE237
 C8A14    1      A CAP_0805-22UF,6.3V,20%,X6S,C95A    I13 @BASEBOARD_FAB2_LIB.BASEBOARD_FAB2(SCH_1):PAGE237
 R8A12    1      A RES_0603-475.0,1%,1/10W,CHIP,GA    I15 @BASEBOARD_FAB2_LIB.BASEBOARD_FAB2(SCH_1):PAGE237
 C8A12    1      A CAP_0805-47UF,4V,20%,X6S,C9533A    I77 @BASEBOARD_FAB2_LIB.BASEBOARD_FAB2(SCH_1):PAGE237
 C2L32    1      A CAP_0805-47UF,4V,20%,X6S,C9533A    I79 @BASEBOARD_FAB2_LIB.BASEBOARD_FAB2(SCH_1):PAGE237
 R2L20    1      A RES_0402-63.4K,1.0%,1/16W,CHIPA    I81 @BASEBOARD_FAB2_LIB.BASEBOARD_FAB2(SCH_1):PAGE237
 EU8A2    1 VOUT<0> RT9059_DFN-IC,H65765-001    I86 @BASEBOARD_FAB2_LIB.BASEBOARD_FAB2(SCH_1):PAGE237
 EU8A2    2 VOUT<1> RT9059_DFN-IC,H65765-001    I86 @BASEBOARD_FAB2_LIB.BASEBOARD_FAB2(SCH_1):PAGE237
 EU8A2    3 VOUT<2> RT9059_DFN-IC,H65765-001    I86 @BASEBOARD_FAB2_LIB.BASEBOARD_FAB2(SCH_1):PAGE237

P2E_SSB_BMC_RX_C_DN @BASEBOARD_FAB2_LIB.BASEBOARD_FAB2(SCH_1):P2E_SSB_BMC_RX_C_DN
  U7C1 AN70 PCIE4_GBE_RXN LBG_CORE_QAT_EXT_D_BGA1-IC,H91A   I220 @BASEBOARD_FAB2_LIB.BASEBOARD_FAB2(SCH_1):PAGE116
  R3M9    1      A RES_0402-100.0K,1%,1/16W,CHIP,A   I234 @BASEBOARD_FAB2_LIB.BASEBOARD_FAB2(SCH_1):PAGE116
C25W21    2      B CAP_A_0402V-0.1UF,16V,10%,X7R,A   I159 @BASEBOARD_FAB2_LIB.BASEBOARD_FAB2(SCH_1):PAGE145

P2E_SSB_BMC_RX_C_DP @BASEBOARD_FAB2_LIB.BASEBOARD_FAB2(SCH_1):P2E_SSB_BMC_RX_C_DP
  U7C1 AN72 PCIE4_GBE_RXP LBG_CORE_QAT_EXT_D_BGA1-IC,H91A   I220 @BASEBOARD_FAB2_LIB.BASEBOARD_FAB2(SCH_1):PAGE116
  R3M8    1      A RES_0402-100.0K,1%,1/16W,CHIP,A   I235 @BASEBOARD_FAB2_LIB.BASEBOARD_FAB2(SCH_1):PAGE116
C25W20    2      B CAP_A_0402V-0.1UF,16V,10%,X7R,A   I158 @BASEBOARD_FAB2_LIB.BASEBOARD_FAB2(SCH_1):PAGE145

P2E_SSB_BMC_RX_DN @BASEBOARD_FAB2_LIB.BASEBOARD_FAB2(SCH_1):P2E_SSB_BMC_RX_DN
 U25W4  L22  PETXN AST2520A1-GP-GP_ASIC2-GB1-AST2A   I117 @BASEBOARD_FAB2_LIB.BASEBOARD_FAB2(SCH_1):PAGE145
C25W21    1      A CAP_A_0402V-0.1UF,16V,10%,X7R,A   I159 @BASEBOARD_FAB2_LIB.BASEBOARD_FAB2(SCH_1):PAGE145

P2E_SSB_BMC_RX_DP @BASEBOARD_FAB2_LIB.BASEBOARD_FAB2(SCH_1):P2E_SSB_BMC_RX_DP
 U25W4  L21  PETXP AST2520A1-GP-GP_ASIC2-GB1-AST2A   I117 @BASEBOARD_FAB2_LIB.BASEBOARD_FAB2(SCH_1):PAGE145
C25W20    1      A CAP_A_0402V-0.1UF,16V,10%,X7R,A   I158 @BASEBOARD_FAB2_LIB.BASEBOARD_FAB2(SCH_1):PAGE145

P2E_SSB_BMC_TX_C_DN @BASEBOARD_FAB2_LIB.BASEBOARD_FAB2(SCH_1):P2E_SSB_BMC_TX_C_DN
R25W65    1      A RES_0402-100.0K,1%,1/16W,CHIP,A    I38 @BASEBOARD_FAB2_LIB.BASEBOARD_FAB2(SCH_1):PAGE145
 U25W4  M22  PERXN AST2520A1-GP-GP_ASIC2-GB1-AST2A   I117 @BASEBOARD_FAB2_LIB.BASEBOARD_FAB2(SCH_1):PAGE145
  C2M3    2      B CAP_A_0402V-0.1UF,16V,10%,X7R,A   I239 @BASEBOARD_FAB2_LIB.BASEBOARD_FAB2(SCH_1):PAGE116

P2E_SSB_BMC_TX_C_DP @BASEBOARD_FAB2_LIB.BASEBOARD_FAB2(SCH_1):P2E_SSB_BMC_TX_C_DP
R25W64    1      A RES_0402-100.0K,1%,1/16W,CHIP,A    I36 @BASEBOARD_FAB2_LIB.BASEBOARD_FAB2(SCH_1):PAGE145
 U25W4  M21  PERXP AST2520A1-GP-GP_ASIC2-GB1-AST2A   I117 @BASEBOARD_FAB2_LIB.BASEBOARD_FAB2(SCH_1):PAGE145
  C2M4    2      B CAP_A_0402V-0.1UF,16V,10%,X7R,A   I238 @BASEBOARD_FAB2_LIB.BASEBOARD_FAB2(SCH_1):PAGE116

P2E_SSB_BMC_TX_DN @BASEBOARD_FAB2_LIB.BASEBOARD_FAB2(SCH_1):P2E_SSB_BMC_TX_DN
  U7C1 BG66 PCIE4_GBE_TXN LBG_CORE_QAT_EXT_D_BGA1-IC,H91A   I220 @BASEBOARD_FAB2_LIB.BASEBOARD_FAB2(SCH_1):PAGE116
  C2M3    1      A CAP_A_0402V-0.1UF,16V,10%,X7R,A   I239 @BASEBOARD_FAB2_LIB.BASEBOARD_FAB2(SCH_1):PAGE116

P2E_SSB_BMC_TX_DP @BASEBOARD_FAB2_LIB.BASEBOARD_FAB2(SCH_1):P2E_SSB_BMC_TX_DP
  U7C1 BJ66 PCIE4_GBE_TXP LBG_CORE_QAT_EXT_D_BGA1-IC,H91A   I220 @BASEBOARD_FAB2_LIB.BASEBOARD_FAB2(SCH_1):PAGE116
  C2M4    1      A CAP_A_0402V-0.1UF,16V,10%,X7R,A   I238 @BASEBOARD_FAB2_LIB.BASEBOARD_FAB2(SCH_1):PAGE116

P2V5_AUX_BMC @BASEBOARD_FAB2_LIB.BASEBOARD_FAB2(SCH_1):P2V5_AUX_BMC
EU25F2    1 VOUT<0> RT9059_DFN-IC,H65765-001    I73 @BASEBOARD_FAB2_LIB.BASEBOARD_FAB2(SCH_1):PAGE239
EU25F2    2 VOUT<1> RT9059_DFN-IC,H65765-001    I73 @BASEBOARD_FAB2_LIB.BASEBOARD_FAB2(SCH_1):PAGE239
EU25F2    3 VOUT<2> RT9059_DFN-IC,H65765-001    I73 @BASEBOARD_FAB2_LIB.BASEBOARD_FAB2(SCH_1):PAGE239
 C9W13    1      A CAP_0805LF-22UF,4V,20%,X6S,C95A    I81 @BASEBOARD_FAB2_LIB.BASEBOARD_FAB2(SCH_1):PAGE239
 C1W15    1      A CAP_0603-10UF,6.3V,20%,X6S,E15A    I83 @BASEBOARD_FAB2_LIB.BASEBOARD_FAB2(SCH_1):PAGE239
 U25W5   B1 VPP<0> H5AN4G6NAFR-TFC-GP_MEMORY-G2-HA    I49 @BASEBOARD_FAB2_LIB.BASEBOARD_FAB2(SCH_1):PAGE151
 U25W5   R9 VPP<1> H5AN4G6NAFR-TFC-GP_MEMORY-G2-HA    I49 @BASEBOARD_FAB2_LIB.BASEBOARD_FAB2(SCH_1):PAGE151
C25W14    1      A CAP_A_0402V-0.1UF,16V,10%,X7R,A   I215 @BASEBOARD_FAB2_LIB.BASEBOARD_FAB2(SCH_1):PAGE151
C25W15    1      A CAP_A_0402V-0.1UF,16V,10%,X7R,A   I216 @BASEBOARD_FAB2_LIB.BASEBOARD_FAB2(SCH_1):PAGE151
 R9W31    1      1 21K5R2F-GP_RCL_GP-21K5R2F-GP,6A   I102 @BASEBOARD_FAB2_LIB.BASEBOARD_FAB2(SCH_1):PAGE239

P3E_CPU0_PE1_PCH_CON_RXN<10> @BASEBOARD_FAB2_LIB.BASEBOARD_FAB2(SCH_1):P3E_CPU0_PE1_PCH_CON_RXN(10)
  J8G1   88   IO88 SCONN200_H68296001_SM-CONN,H68A   I258 @BASEBOARD_FAB2_LIB.BASEBOARD_FAB2(SCH_1):PAGE108
  R780    2      B RES_0402-0.0,5%,1/16W,CHIP,G21A    I97 @BASEBOARD_FAB2_LIB.BASEBOARD_FAB2(SCH_1):PAGE244

P3E_CPU0_PE1_PCH_CON_RXN<11> @BASEBOARD_FAB2_LIB.BASEBOARD_FAB2(SCH_1):P3E_CPU0_PE1_PCH_CON_RXN(11)
  J8G1   82   IO82 SCONN200_H68296001_SM-CONN,H68A   I258 @BASEBOARD_FAB2_LIB.BASEBOARD_FAB2(SCH_1):PAGE108
  R778    2      B RES_0402-0.0,5%,1/16W,CHIP,G21A    I94 @BASEBOARD_FAB2_LIB.BASEBOARD_FAB2(SCH_1):PAGE244

P3E_CPU0_PE1_PCH_CON_RXN<12> @BASEBOARD_FAB2_LIB.BASEBOARD_FAB2(SCH_1):P3E_CPU0_PE1_PCH_CON_RXN(12)
  J8G1   76   IO76 SCONN200_H68296001_SM-CONN,H68A   I258 @BASEBOARD_FAB2_LIB.BASEBOARD_FAB2(SCH_1):PAGE108
  R775    2      B RES_0402-0.0,5%,1/16W,CHIP,G21A    I93 @BASEBOARD_FAB2_LIB.BASEBOARD_FAB2(SCH_1):PAGE244

P3E_CPU0_PE1_PCH_CON_RXN<13> @BASEBOARD_FAB2_LIB.BASEBOARD_FAB2(SCH_1):P3E_CPU0_PE1_PCH_CON_RXN(13)
  J8G1   70   IO70 SCONN200_H68296001_SM-CONN,H68A   I258 @BASEBOARD_FAB2_LIB.BASEBOARD_FAB2(SCH_1):PAGE108
  R771    2      B RES_0402-0.0,5%,1/16W,CHIP,G21A    I65 @BASEBOARD_FAB2_LIB.BASEBOARD_FAB2(SCH_1):PAGE244

P3E_CPU0_PE1_PCH_CON_RXN<14> @BASEBOARD_FAB2_LIB.BASEBOARD_FAB2(SCH_1):P3E_CPU0_PE1_PCH_CON_RXN(14)
  J8G1   60   IO60 SCONN200_H68296001_SM-CONN,H68A   I258 @BASEBOARD_FAB2_LIB.BASEBOARD_FAB2(SCH_1):PAGE108
  R768    2      B RES_0402-0.0,5%,1/16W,CHIP,G21A    I66 @BASEBOARD_FAB2_LIB.BASEBOARD_FAB2(SCH_1):PAGE244

P3E_CPU0_PE1_PCH_CON_RXN<15> @BASEBOARD_FAB2_LIB.BASEBOARD_FAB2(SCH_1):P3E_CPU0_PE1_PCH_CON_RXN(15)
  J8G1   54   IO54 SCONN200_H68296001_SM-CONN,H68A   I258 @BASEBOARD_FAB2_LIB.BASEBOARD_FAB2(SCH_1):PAGE108
  R760    2      B RES_0402-0.0,5%,1/16W,CHIP,G21A    I64 @BASEBOARD_FAB2_LIB.BASEBOARD_FAB2(SCH_1):PAGE244

P3E_CPU0_PE1_PCH_CON_RXN<8> @BASEBOARD_FAB2_LIB.BASEBOARD_FAB2(SCH_1):P3E_CPU0_PE1_PCH_CON_RXN(8)
  J8G1  100  IO100 SCONN200_H68296001_SM-CONN,H68A   I258 @BASEBOARD_FAB2_LIB.BASEBOARD_FAB2(SCH_1):PAGE108
  R784    2      B RES_0402-0.0,5%,1/16W,CHIP,G21A    I99 @BASEBOARD_FAB2_LIB.BASEBOARD_FAB2(SCH_1):PAGE244

P3E_CPU0_PE1_PCH_CON_RXN<9> @BASEBOARD_FAB2_LIB.BASEBOARD_FAB2(SCH_1):P3E_CPU0_PE1_PCH_CON_RXN(9)
  J8G1   94   IO94 SCONN200_H68296001_SM-CONN,H68A   I258 @BASEBOARD_FAB2_LIB.BASEBOARD_FAB2(SCH_1):PAGE108
  R782    2      B RES_0402-0.0,5%,1/16W,CHIP,G21A    I98 @BASEBOARD_FAB2_LIB.BASEBOARD_FAB2(SCH_1):PAGE244

P3E_CPU0_PE1_PCH_CON_RXP<10> @BASEBOARD_FAB2_LIB.BASEBOARD_FAB2(SCH_1):P3E_CPU0_PE1_PCH_CON_RXP(10)
  J8G1   90   IO90 SCONN200_H68296001_SM-CONN,H68A   I258 @BASEBOARD_FAB2_LIB.BASEBOARD_FAB2(SCH_1):PAGE108
  R781    2      B RES_0402-0.0,5%,1/16W,CHIP,G21A    I86 @BASEBOARD_FAB2_LIB.BASEBOARD_FAB2(SCH_1):PAGE244

P3E_CPU0_PE1_PCH_CON_RXP<11> @BASEBOARD_FAB2_LIB.BASEBOARD_FAB2(SCH_1):P3E_CPU0_PE1_PCH_CON_RXP(11)
  J8G1   84   IO84 SCONN200_H68296001_SM-CONN,H68A   I258 @BASEBOARD_FAB2_LIB.BASEBOARD_FAB2(SCH_1):PAGE108
  R779    2      B RES_0402-0.0,5%,1/16W,CHIP,G21A    I74 @BASEBOARD_FAB2_LIB.BASEBOARD_FAB2(SCH_1):PAGE244

P3E_CPU0_PE1_PCH_CON_RXP<12> @BASEBOARD_FAB2_LIB.BASEBOARD_FAB2(SCH_1):P3E_CPU0_PE1_PCH_CON_RXP(12)
  J8G1   78   IO78 SCONN200_H68296001_SM-CONN,H68A   I258 @BASEBOARD_FAB2_LIB.BASEBOARD_FAB2(SCH_1):PAGE108
  R777    2      B RES_0402-0.0,5%,1/16W,CHIP,G21A    I80 @BASEBOARD_FAB2_LIB.BASEBOARD_FAB2(SCH_1):PAGE244

P3E_CPU0_PE1_PCH_CON_RXP<13> @BASEBOARD_FAB2_LIB.BASEBOARD_FAB2(SCH_1):P3E_CPU0_PE1_PCH_CON_RXP(13)
  J8G1   72   IO72 SCONN200_H68296001_SM-CONN,H68A   I258 @BASEBOARD_FAB2_LIB.BASEBOARD_FAB2(SCH_1):PAGE108
  R774    2      B RES_0402-0.0,5%,1/16W,CHIP,G21A    I72 @BASEBOARD_FAB2_LIB.BASEBOARD_FAB2(SCH_1):PAGE244

P3E_CPU0_PE1_PCH_CON_RXP<14> @BASEBOARD_FAB2_LIB.BASEBOARD_FAB2(SCH_1):P3E_CPU0_PE1_PCH_CON_RXP(14)
  J8G1   62   IO62 SCONN200_H68296001_SM-CONN,H68A   I258 @BASEBOARD_FAB2_LIB.BASEBOARD_FAB2(SCH_1):PAGE108
  R769    2      B RES_0402-0.0,5%,1/16W,CHIP,G21A    I58 @BASEBOARD_FAB2_LIB.BASEBOARD_FAB2(SCH_1):PAGE244

P3E_CPU0_PE1_PCH_CON_RXP<15> @BASEBOARD_FAB2_LIB.BASEBOARD_FAB2(SCH_1):P3E_CPU0_PE1_PCH_CON_RXP(15)
  J8G1   56   IO56 SCONN200_H68296001_SM-CONN,H68A   I258 @BASEBOARD_FAB2_LIB.BASEBOARD_FAB2(SCH_1):PAGE108
  R767    2      B RES_0402-0.0,5%,1/16W,CHIP,G21A    I39 @BASEBOARD_FAB2_LIB.BASEBOARD_FAB2(SCH_1):PAGE244

P3E_CPU0_PE1_PCH_CON_RXP<8> @BASEBOARD_FAB2_LIB.BASEBOARD_FAB2(SCH_1):P3E_CPU0_PE1_PCH_CON_RXP(8)
  R785    2      B RES_0402-0.0,5%,1/16W,CHIP,G21A   I103 @BASEBOARD_FAB2_LIB.BASEBOARD_FAB2(SCH_1):PAGE244
  J8G1  102  IO102 SCONN200_H68296001_SM-CONN,H68A    I78 @BASEBOARD_FAB2_LIB.BASEBOARD_FAB2(SCH_1):PAGE109

P3E_CPU0_PE1_PCH_CON_RXP<9> @BASEBOARD_FAB2_LIB.BASEBOARD_FAB2(SCH_1):P3E_CPU0_PE1_PCH_CON_RXP(9)
  J8G1   96   IO96 SCONN200_H68296001_SM-CONN,H68A   I258 @BASEBOARD_FAB2_LIB.BASEBOARD_FAB2(SCH_1):PAGE108
  R783    2      B RES_0402-0.0,5%,1/16W,CHIP,G21A    I77 @BASEBOARD_FAB2_LIB.BASEBOARD_FAB2(SCH_1):PAGE244

P3E_CPU0_PE1_PCH_CON_TXN<10> @BASEBOARD_FAB2_LIB.BASEBOARD_FAB2(SCH_1):P3E_CPU0_PE1_PCH_CON_TXN(10)
  J8G1   85   IO85 SCONN200_H68296001_SM-CONN,H68A   I258 @BASEBOARD_FAB2_LIB.BASEBOARD_FAB2(SCH_1):PAGE108
  C834    2      B CAP_0402-0.22UF,16V,10%,X7R,A3A    I50 @BASEBOARD_FAB2_LIB.BASEBOARD_FAB2(SCH_1):PAGE244

P3E_CPU0_PE1_PCH_CON_TXN<11> @BASEBOARD_FAB2_LIB.BASEBOARD_FAB2(SCH_1):P3E_CPU0_PE1_PCH_CON_TXN(11)
  J8G1   79   IO79 SCONN200_H68296001_SM-CONN,H68A   I258 @BASEBOARD_FAB2_LIB.BASEBOARD_FAB2(SCH_1):PAGE108
  C832    2      B CAP_0402-0.22UF,16V,10%,X7R,A3A    I30 @BASEBOARD_FAB2_LIB.BASEBOARD_FAB2(SCH_1):PAGE244

P3E_CPU0_PE1_PCH_CON_TXN<12> @BASEBOARD_FAB2_LIB.BASEBOARD_FAB2(SCH_1):P3E_CPU0_PE1_PCH_CON_TXN(12)
  J8G1   73   IO73 SCONN200_H68296001_SM-CONN,H68A   I258 @BASEBOARD_FAB2_LIB.BASEBOARD_FAB2(SCH_1):PAGE108
  C840    2      B CAP_0402-0.22UF,16V,10%,X7R,A3A    I29 @BASEBOARD_FAB2_LIB.BASEBOARD_FAB2(SCH_1):PAGE244

P3E_CPU0_PE1_PCH_CON_TXN<13> @BASEBOARD_FAB2_LIB.BASEBOARD_FAB2(SCH_1):P3E_CPU0_PE1_PCH_CON_TXN(13)
  J8G1   67   IO67 SCONN200_H68296001_SM-CONN,H68A   I258 @BASEBOARD_FAB2_LIB.BASEBOARD_FAB2(SCH_1):PAGE108
  C828    2      B CAP_0402-0.22UF,16V,10%,X7R,A3A    I28 @BASEBOARD_FAB2_LIB.BASEBOARD_FAB2(SCH_1):PAGE244

P3E_CPU0_PE1_PCH_CON_TXN<14> @BASEBOARD_FAB2_LIB.BASEBOARD_FAB2(SCH_1):P3E_CPU0_PE1_PCH_CON_TXN(14)
  J8G1   59   IO59 SCONN200_H68296001_SM-CONN,H68A   I258 @BASEBOARD_FAB2_LIB.BASEBOARD_FAB2(SCH_1):PAGE108
  C826    2      B CAP_0402-0.22UF,16V,10%,X7R,A3A    I24 @BASEBOARD_FAB2_LIB.BASEBOARD_FAB2(SCH_1):PAGE244

P3E_CPU0_PE1_PCH_CON_TXN<15> @BASEBOARD_FAB2_LIB.BASEBOARD_FAB2(SCH_1):P3E_CPU0_PE1_PCH_CON_TXN(15)
  J8G1   51   IO51 SCONN200_H68296001_SM-CONN,H68A   I258 @BASEBOARD_FAB2_LIB.BASEBOARD_FAB2(SCH_1):PAGE108
  C830    2      B CAP_0402-0.22UF,16V,10%,X7R,A3A    I23 @BASEBOARD_FAB2_LIB.BASEBOARD_FAB2(SCH_1):PAGE244

P3E_CPU0_PE1_PCH_CON_TXN<8> @BASEBOARD_FAB2_LIB.BASEBOARD_FAB2(SCH_1):P3E_CPU0_PE1_PCH_CON_TXN(8)
  J8G1   97   IO97 SCONN200_H68296001_SM-CONN,H68A   I258 @BASEBOARD_FAB2_LIB.BASEBOARD_FAB2(SCH_1):PAGE108
  C842    2      B CAP_0402-0.22UF,16V,10%,X7R,A3A    I52 @BASEBOARD_FAB2_LIB.BASEBOARD_FAB2(SCH_1):PAGE244

P3E_CPU0_PE1_PCH_CON_TXN<9> @BASEBOARD_FAB2_LIB.BASEBOARD_FAB2(SCH_1):P3E_CPU0_PE1_PCH_CON_TXN(9)
  J8G1   91   IO91 SCONN200_H68296001_SM-CONN,H68A   I258 @BASEBOARD_FAB2_LIB.BASEBOARD_FAB2(SCH_1):PAGE108
  C844    2      B CAP_0402-0.22UF,16V,10%,X7R,A3A    I51 @BASEBOARD_FAB2_LIB.BASEBOARD_FAB2(SCH_1):PAGE244

P3E_CPU0_PE1_PCH_CON_TXP<10> @BASEBOARD_FAB2_LIB.BASEBOARD_FAB2(SCH_1):P3E_CPU0_PE1_PCH_CON_TXP(10)
  J8G1   87   IO87 SCONN200_H68296001_SM-CONN,H68A   I258 @BASEBOARD_FAB2_LIB.BASEBOARD_FAB2(SCH_1):PAGE108
  C835    2      B CAP_0402-0.22UF,16V,10%,X7R,A3A    I41 @BASEBOARD_FAB2_LIB.BASEBOARD_FAB2(SCH_1):PAGE244

P3E_CPU0_PE1_PCH_CON_TXP<11> @BASEBOARD_FAB2_LIB.BASEBOARD_FAB2(SCH_1):P3E_CPU0_PE1_PCH_CON_TXP(11)
  J8G1   81   IO81 SCONN200_H68296001_SM-CONN,H68A   I258 @BASEBOARD_FAB2_LIB.BASEBOARD_FAB2(SCH_1):PAGE108
  C833    2      B CAP_0402-0.22UF,16V,10%,X7R,A3A     I8 @BASEBOARD_FAB2_LIB.BASEBOARD_FAB2(SCH_1):PAGE244

P3E_CPU0_PE1_PCH_CON_TXP<12> @BASEBOARD_FAB2_LIB.BASEBOARD_FAB2(SCH_1):P3E_CPU0_PE1_PCH_CON_TXP(12)
  J8G1   75   IO75 SCONN200_H68296001_SM-CONN,H68A   I258 @BASEBOARD_FAB2_LIB.BASEBOARD_FAB2(SCH_1):PAGE108
  C841    2      B CAP_0402-0.22UF,16V,10%,X7R,A3A    I17 @BASEBOARD_FAB2_LIB.BASEBOARD_FAB2(SCH_1):PAGE244

P3E_CPU0_PE1_PCH_CON_TXP<13> @BASEBOARD_FAB2_LIB.BASEBOARD_FAB2(SCH_1):P3E_CPU0_PE1_PCH_CON_TXP(13)
  J8G1   69   IO69 SCONN200_H68296001_SM-CONN,H68A   I258 @BASEBOARD_FAB2_LIB.BASEBOARD_FAB2(SCH_1):PAGE108
  C829    2      B CAP_0402-0.22UF,16V,10%,X7R,A3A     I5 @BASEBOARD_FAB2_LIB.BASEBOARD_FAB2(SCH_1):PAGE244

P3E_CPU0_PE1_PCH_CON_TXP<14> @BASEBOARD_FAB2_LIB.BASEBOARD_FAB2(SCH_1):P3E_CPU0_PE1_PCH_CON_TXP(14)
  J8G1   57   IO57 SCONN200_H68296001_SM-CONN,H68A   I258 @BASEBOARD_FAB2_LIB.BASEBOARD_FAB2(SCH_1):PAGE108
  C827    2      B CAP_0402-0.22UF,16V,10%,X7R,A3A    I12 @BASEBOARD_FAB2_LIB.BASEBOARD_FAB2(SCH_1):PAGE244

P3E_CPU0_PE1_PCH_CON_TXP<15> @BASEBOARD_FAB2_LIB.BASEBOARD_FAB2(SCH_1):P3E_CPU0_PE1_PCH_CON_TXP(15)
  J8G1   53   IO53 SCONN200_H68296001_SM-CONN,H68A   I258 @BASEBOARD_FAB2_LIB.BASEBOARD_FAB2(SCH_1):PAGE108
  C831    2      B CAP_0402-0.22UF,16V,10%,X7R,A3A     I2 @BASEBOARD_FAB2_LIB.BASEBOARD_FAB2(SCH_1):PAGE244

P3E_CPU0_PE1_PCH_CON_TXP<8> @BASEBOARD_FAB2_LIB.BASEBOARD_FAB2(SCH_1):P3E_CPU0_PE1_PCH_CON_TXP(8)
  J8G1   99   IO99 SCONN200_H68296001_SM-CONN,H68A   I258 @BASEBOARD_FAB2_LIB.BASEBOARD_FAB2(SCH_1):PAGE108
  C843    2      B CAP_0402-0.22UF,16V,10%,X7R,A3A    I47 @BASEBOARD_FAB2_LIB.BASEBOARD_FAB2(SCH_1):PAGE244

P3E_CPU0_PE1_PCH_CON_TXP<9> @BASEBOARD_FAB2_LIB.BASEBOARD_FAB2(SCH_1):P3E_CPU0_PE1_PCH_CON_TXP(9)
  J8G1   93   IO93 SCONN200_H68296001_SM-CONN,H68A   I258 @BASEBOARD_FAB2_LIB.BASEBOARD_FAB2(SCH_1):PAGE108
  C845    2      B CAP_0402-0.22UF,16V,10%,X7R,A3A    I35 @BASEBOARD_FAB2_LIB.BASEBOARD_FAB2(SCH_1):PAGE244

P3E_CPU0_PE1_PCH_C_TXN<10> @BASEBOARD_FAB2_LIB.BASEBOARD_FAB2(SCH_1):P3E_CPU0_PE1_PCH_C_TXN(10)
 C6B15    2      B CAP_0402-0.22UF,16V,10%,X7R,A3A   I163 @BASEBOARD_FAB2_LIB.BASEBOARD_FAB2(SCH_1):PAGE105
  U7C1  A59 PCIEUP_10_RXP LBG_CORE_QAT_EXT_D_BGA1-IC,H91A     I9 @BASEBOARD_FAB2_LIB.BASEBOARD_FAB2(SCH_1):PAGE117

P3E_CPU0_PE1_PCH_C_TXN<11> @BASEBOARD_FAB2_LIB.BASEBOARD_FAB2(SCH_1):P3E_CPU0_PE1_PCH_C_TXN(11)
 C6B14    2      B CAP_0402-0.22UF,16V,10%,X7R,A3A   I181 @BASEBOARD_FAB2_LIB.BASEBOARD_FAB2(SCH_1):PAGE105
  U7C1  D60 PCIEUP_11_RXN LBG_CORE_QAT_EXT_D_BGA1-IC,H91A     I9 @BASEBOARD_FAB2_LIB.BASEBOARD_FAB2(SCH_1):PAGE117

P3E_CPU0_PE1_PCH_C_TXN<12> @BASEBOARD_FAB2_LIB.BASEBOARD_FAB2(SCH_1):P3E_CPU0_PE1_PCH_C_TXN(12)
 C6B11    2      B CAP_0402-0.22UF,16V,10%,X7R,A3A   I166 @BASEBOARD_FAB2_LIB.BASEBOARD_FAB2(SCH_1):PAGE105
  U7C1  A61 PCIEUP_12_RXP LBG_CORE_QAT_EXT_D_BGA1-IC,H91A     I9 @BASEBOARD_FAB2_LIB.BASEBOARD_FAB2(SCH_1):PAGE117

P3E_CPU0_PE1_PCH_C_TXN<13> @BASEBOARD_FAB2_LIB.BASEBOARD_FAB2(SCH_1):P3E_CPU0_PE1_PCH_C_TXN(13)
  C6B9    2      B CAP_0402-0.22UF,16V,10%,X7R,A3A   I185 @BASEBOARD_FAB2_LIB.BASEBOARD_FAB2(SCH_1):PAGE105
  U7C1  B62 PCIEUP_13_RXP LBG_CORE_QAT_EXT_D_BGA1-IC,H91A     I9 @BASEBOARD_FAB2_LIB.BASEBOARD_FAB2(SCH_1):PAGE117

P3E_CPU0_PE1_PCH_C_TXN<14> @BASEBOARD_FAB2_LIB.BASEBOARD_FAB2(SCH_1):P3E_CPU0_PE1_PCH_C_TXN(14)
  C6B6    2      B CAP_0402-0.22UF,16V,10%,X7R,A3A   I169 @BASEBOARD_FAB2_LIB.BASEBOARD_FAB2(SCH_1):PAGE105
  U7C1  A63 PCIEUP_14_RXP LBG_CORE_QAT_EXT_D_BGA1-IC,H91A     I9 @BASEBOARD_FAB2_LIB.BASEBOARD_FAB2(SCH_1):PAGE117

P3E_CPU0_PE1_PCH_C_TXN<15> @BASEBOARD_FAB2_LIB.BASEBOARD_FAB2(SCH_1):P3E_CPU0_PE1_PCH_C_TXN(15)
  C6B4    2      B CAP_0402-0.22UF,16V,10%,X7R,A3A   I196 @BASEBOARD_FAB2_LIB.BASEBOARD_FAB2(SCH_1):PAGE105
  U7C1  B64 PCIEUP_15_RXP LBG_CORE_QAT_EXT_D_BGA1-IC,H91A     I9 @BASEBOARD_FAB2_LIB.BASEBOARD_FAB2(SCH_1):PAGE117

P3E_CPU0_PE1_PCH_C_TXN<8> @BASEBOARD_FAB2_LIB.BASEBOARD_FAB2(SCH_1):P3E_CPU0_PE1_PCH_C_TXN(8)
 C6B19    2      B CAP_0402-0.22UF,16V,10%,X7R,A3A   I160 @BASEBOARD_FAB2_LIB.BASEBOARD_FAB2(SCH_1):PAGE105
  U7C1  A57 PCIEUP_8_RXP LBG_CORE_QAT_EXT_D_BGA1-IC,H91A     I9 @BASEBOARD_FAB2_LIB.BASEBOARD_FAB2(SCH_1):PAGE117

P3E_CPU0_PE1_PCH_C_TXN<9> @BASEBOARD_FAB2_LIB.BASEBOARD_FAB2(SCH_1):P3E_CPU0_PE1_PCH_C_TXN(9)
 C6B17    2      B CAP_0402-0.22UF,16V,10%,X7R,A3A   I175 @BASEBOARD_FAB2_LIB.BASEBOARD_FAB2(SCH_1):PAGE105
  U7C1  B58 PCIEUP_9_RXP LBG_CORE_QAT_EXT_D_BGA1-IC,H91A     I9 @BASEBOARD_FAB2_LIB.BASEBOARD_FAB2(SCH_1):PAGE117

P3E_CPU0_PE1_PCH_C_TXP<10> @BASEBOARD_FAB2_LIB.BASEBOARD_FAB2(SCH_1):P3E_CPU0_PE1_PCH_C_TXP(10)
 C6B16    2      B CAP_0402-0.22UF,16V,10%,X7R,A3A   I180 @BASEBOARD_FAB2_LIB.BASEBOARD_FAB2(SCH_1):PAGE105
  U7C1  C59 PCIEUP_10_RXN LBG_CORE_QAT_EXT_D_BGA1-IC,H91A     I9 @BASEBOARD_FAB2_LIB.BASEBOARD_FAB2(SCH_1):PAGE117

P3E_CPU0_PE1_PCH_C_TXP<11> @BASEBOARD_FAB2_LIB.BASEBOARD_FAB2(SCH_1):P3E_CPU0_PE1_PCH_C_TXP(11)
 C6B13    2      B CAP_0402-0.22UF,16V,10%,X7R,A3A   I189 @BASEBOARD_FAB2_LIB.BASEBOARD_FAB2(SCH_1):PAGE105
  U7C1  B60 PCIEUP_11_RXP LBG_CORE_QAT_EXT_D_BGA1-IC,H91A     I9 @BASEBOARD_FAB2_LIB.BASEBOARD_FAB2(SCH_1):PAGE117

P3E_CPU0_PE1_PCH_C_TXP<12> @BASEBOARD_FAB2_LIB.BASEBOARD_FAB2(SCH_1):P3E_CPU0_PE1_PCH_C_TXP(12)
 C6B12    2      B CAP_0402-0.22UF,16V,10%,X7R,A3A   I187 @BASEBOARD_FAB2_LIB.BASEBOARD_FAB2(SCH_1):PAGE105
  U7C1  C61 PCIEUP_12_RXN LBG_CORE_QAT_EXT_D_BGA1-IC,H91A     I9 @BASEBOARD_FAB2_LIB.BASEBOARD_FAB2(SCH_1):PAGE117

P3E_CPU0_PE1_PCH_C_TXP<13> @BASEBOARD_FAB2_LIB.BASEBOARD_FAB2(SCH_1):P3E_CPU0_PE1_PCH_C_TXP(13)
 C6B10    2      B CAP_0402-0.22UF,16V,10%,X7R,A3A   I193 @BASEBOARD_FAB2_LIB.BASEBOARD_FAB2(SCH_1):PAGE105
  U7C1  D62 PCIEUP_13_RXN LBG_CORE_QAT_EXT_D_BGA1-IC,H91A     I9 @BASEBOARD_FAB2_LIB.BASEBOARD_FAB2(SCH_1):PAGE117

P3E_CPU0_PE1_PCH_C_TXP<14> @BASEBOARD_FAB2_LIB.BASEBOARD_FAB2(SCH_1):P3E_CPU0_PE1_PCH_C_TXP(14)
  C6B8    2      B CAP_0402-0.22UF,16V,10%,X7R,A3A   I198 @BASEBOARD_FAB2_LIB.BASEBOARD_FAB2(SCH_1):PAGE105
  U7C1  C63 PCIEUP_14_RXN LBG_CORE_QAT_EXT_D_BGA1-IC,H91A     I9 @BASEBOARD_FAB2_LIB.BASEBOARD_FAB2(SCH_1):PAGE117

P3E_CPU0_PE1_PCH_C_TXP<15> @BASEBOARD_FAB2_LIB.BASEBOARD_FAB2(SCH_1):P3E_CPU0_PE1_PCH_C_TXP(15)
  C6B5    2      B CAP_0402-0.22UF,16V,10%,X7R,A3A   I201 @BASEBOARD_FAB2_LIB.BASEBOARD_FAB2(SCH_1):PAGE105
  U7C1  D64 PCIEUP_15_RXN LBG_CORE_QAT_EXT_D_BGA1-IC,H91A     I9 @BASEBOARD_FAB2_LIB.BASEBOARD_FAB2(SCH_1):PAGE117

P3E_CPU0_PE1_PCH_C_TXP<8> @BASEBOARD_FAB2_LIB.BASEBOARD_FAB2(SCH_1):P3E_CPU0_PE1_PCH_C_TXP(8)
 C6B20    2      B CAP_0402-0.22UF,16V,10%,X7R,A3A   I173 @BASEBOARD_FAB2_LIB.BASEBOARD_FAB2(SCH_1):PAGE105
  U7C1  C57 PCIEUP_8_RXN LBG_CORE_QAT_EXT_D_BGA1-IC,H91A     I9 @BASEBOARD_FAB2_LIB.BASEBOARD_FAB2(SCH_1):PAGE117

P3E_CPU0_PE1_PCH_C_TXP<9> @BASEBOARD_FAB2_LIB.BASEBOARD_FAB2(SCH_1):P3E_CPU0_PE1_PCH_C_TXP(9)
 C6B18    2      B CAP_0402-0.22UF,16V,10%,X7R,A3A   I153 @BASEBOARD_FAB2_LIB.BASEBOARD_FAB2(SCH_1):PAGE105
  U7C1  D58 PCIEUP_9_RXN LBG_CORE_QAT_EXT_D_BGA1-IC,H91A     I9 @BASEBOARD_FAB2_LIB.BASEBOARD_FAB2(SCH_1):PAGE117

P3E_CPU0_PE1_PCH_RXN<0> @BASEBOARD_FAB2_LIB.BASEBOARD_FAB2(SCH_1):P3E_CPU0_PE1_PCH_RXN(0)
  C2U4    1      A CAP_0402-0.22UF,16V,10%,X7R,A3A   I257 @BASEBOARD_FAB2_LIB.BASEBOARD_FAB2(SCH_1):PAGE107
  U7C1  J52 PCIEUP_0_TXN LBG_CORE_QAT_EXT_D_BGA1-IC,H91A     I9 @BASEBOARD_FAB2_LIB.BASEBOARD_FAB2(SCH_1):PAGE117

P3E_CPU0_PE1_PCH_RXN<10> @BASEBOARD_FAB2_LIB.BASEBOARD_FAB2(SCH_1):P3E_CPU0_PE1_PCH_RXN(10)
  U5D1 DT11 PE1_RX_DN<10> SKX_EXT_B_BGA1-IC,TBD    I84 @BASEBOARD_FAB2_LIB.BASEBOARD_FAB2(SCH_1):PAGE30
 C3M32    2      B CAP_0402-0.22UF,16V,10%,X7R,A3A   I223 @BASEBOARD_FAB2_LIB.BASEBOARD_FAB2(SCH_1):PAGE105
  R780    1      A RES_0402-0.0,5%,1/16W,CHIP,G21A    I97 @BASEBOARD_FAB2_LIB.BASEBOARD_FAB2(SCH_1):PAGE244

P3E_CPU0_PE1_PCH_RXN<11> @BASEBOARD_FAB2_LIB.BASEBOARD_FAB2(SCH_1):P3E_CPU0_PE1_PCH_RXN(11)
  U5D1 DT13 PE1_RX_DN<11> SKX_EXT_B_BGA1-IC,TBD    I84 @BASEBOARD_FAB2_LIB.BASEBOARD_FAB2(SCH_1):PAGE30
 C3M26    2      B CAP_0402-0.22UF,16V,10%,X7R,A3A   I229 @BASEBOARD_FAB2_LIB.BASEBOARD_FAB2(SCH_1):PAGE105
  R778    1      A RES_0402-0.0,5%,1/16W,CHIP,G21A    I94 @BASEBOARD_FAB2_LIB.BASEBOARD_FAB2(SCH_1):PAGE244

P3E_CPU0_PE1_PCH_RXN<12> @BASEBOARD_FAB2_LIB.BASEBOARD_FAB2(SCH_1):P3E_CPU0_PE1_PCH_RXN(12)
  U5D1 DV13 PE1_RX_DN<12> SKX_EXT_B_BGA1-IC,TBD    I84 @BASEBOARD_FAB2_LIB.BASEBOARD_FAB2(SCH_1):PAGE30
  C3M4    2      B CAP_0402-0.22UF,16V,10%,X7R,A3A   I244 @BASEBOARD_FAB2_LIB.BASEBOARD_FAB2(SCH_1):PAGE105
  R775    1      A RES_0402-0.0,5%,1/16W,CHIP,G21A    I93 @BASEBOARD_FAB2_LIB.BASEBOARD_FAB2(SCH_1):PAGE244

P3E_CPU0_PE1_PCH_RXN<13> @BASEBOARD_FAB2_LIB.BASEBOARD_FAB2(SCH_1):P3E_CPU0_PE1_PCH_RXN(13)
  U5D1 DW14 PE1_RX_DN<13> SKX_EXT_B_BGA1-IC,TBD    I84 @BASEBOARD_FAB2_LIB.BASEBOARD_FAB2(SCH_1):PAGE30
 C3M14    2      B CAP_0402-0.22UF,16V,10%,X7R,A3A   I253 @BASEBOARD_FAB2_LIB.BASEBOARD_FAB2(SCH_1):PAGE105
  R771    1      A RES_0402-0.0,5%,1/16W,CHIP,G21A    I65 @BASEBOARD_FAB2_LIB.BASEBOARD_FAB2(SCH_1):PAGE244

P3E_CPU0_PE1_PCH_RXN<14> @BASEBOARD_FAB2_LIB.BASEBOARD_FAB2(SCH_1):P3E_CPU0_PE1_PCH_RXN(14)
  U5D1 DY15 PE1_RX_DN<14> SKX_EXT_B_BGA1-IC,TBD    I84 @BASEBOARD_FAB2_LIB.BASEBOARD_FAB2(SCH_1):PAGE30
 C3M12    2      B CAP_0402-0.22UF,16V,10%,X7R,A3A   I246 @BASEBOARD_FAB2_LIB.BASEBOARD_FAB2(SCH_1):PAGE105
  R768    1      A RES_0402-0.0,5%,1/16W,CHIP,G21A    I66 @BASEBOARD_FAB2_LIB.BASEBOARD_FAB2(SCH_1):PAGE244

P3E_CPU0_PE1_PCH_RXN<15> @BASEBOARD_FAB2_LIB.BASEBOARD_FAB2(SCH_1):P3E_CPU0_PE1_PCH_RXN(15)
  U5D1 DU16 PE1_RX_DN<15> SKX_EXT_B_BGA1-IC,TBD    I84 @BASEBOARD_FAB2_LIB.BASEBOARD_FAB2(SCH_1):PAGE30
  C3M1    2      B CAP_0402-0.22UF,16V,10%,X7R,A3A   I255 @BASEBOARD_FAB2_LIB.BASEBOARD_FAB2(SCH_1):PAGE105
  R760    1      A RES_0402-0.0,5%,1/16W,CHIP,G21A    I64 @BASEBOARD_FAB2_LIB.BASEBOARD_FAB2(SCH_1):PAGE244

P3E_CPU0_PE1_PCH_RXN<1> @BASEBOARD_FAB2_LIB.BASEBOARD_FAB2(SCH_1):P3E_CPU0_PE1_PCH_RXN(1)
  C2U6    1      A CAP_0402-0.22UF,16V,10%,X7R,A3A   I260 @BASEBOARD_FAB2_LIB.BASEBOARD_FAB2(SCH_1):PAGE107
  U7C1  P56 PCIEUP_1_TXN LBG_CORE_QAT_EXT_D_BGA1-IC,H91A     I9 @BASEBOARD_FAB2_LIB.BASEBOARD_FAB2(SCH_1):PAGE117

P3E_CPU0_PE1_PCH_RXN<2> @BASEBOARD_FAB2_LIB.BASEBOARD_FAB2(SCH_1):P3E_CPU0_PE1_PCH_RXN(2)
  C2U8    1      A CAP_0402-0.22UF,16V,10%,X7R,A3A   I264 @BASEBOARD_FAB2_LIB.BASEBOARD_FAB2(SCH_1):PAGE107
  U7C1  H54 PCIEUP_2_TXN LBG_CORE_QAT_EXT_D_BGA1-IC,H91A     I9 @BASEBOARD_FAB2_LIB.BASEBOARD_FAB2(SCH_1):PAGE117

P3E_CPU0_PE1_PCH_RXN<3> @BASEBOARD_FAB2_LIB.BASEBOARD_FAB2(SCH_1):P3E_CPU0_PE1_PCH_RXN(3)
 C2U10    1      A CAP_0402-0.22UF,16V,10%,X7R,A3A   I267 @BASEBOARD_FAB2_LIB.BASEBOARD_FAB2(SCH_1):PAGE107
  U7C1  J56 PCIEUP_3_TXN LBG_CORE_QAT_EXT_D_BGA1-IC,H91A     I9 @BASEBOARD_FAB2_LIB.BASEBOARD_FAB2(SCH_1):PAGE117

P3E_CPU0_PE1_PCH_RXN<4> @BASEBOARD_FAB2_LIB.BASEBOARD_FAB2(SCH_1):P3E_CPU0_PE1_PCH_RXN(4)
 C2U12    1      A CAP_0402-0.22UF,16V,10%,X7R,A3A   I265 @BASEBOARD_FAB2_LIB.BASEBOARD_FAB2(SCH_1):PAGE107
  U7C1  N58 PCIEUP_4_TXN LBG_CORE_QAT_EXT_D_BGA1-IC,H91A     I9 @BASEBOARD_FAB2_LIB.BASEBOARD_FAB2(SCH_1):PAGE117

P3E_CPU0_PE1_PCH_RXN<5> @BASEBOARD_FAB2_LIB.BASEBOARD_FAB2(SCH_1):P3E_CPU0_PE1_PCH_RXN(5)
 C2U14    1      A CAP_0402-0.22UF,16V,10%,X7R,A3A   I287 @BASEBOARD_FAB2_LIB.BASEBOARD_FAB2(SCH_1):PAGE107
  U7C1  N61 PCIEUP_5_TXN LBG_CORE_QAT_EXT_D_BGA1-IC,H91A     I9 @BASEBOARD_FAB2_LIB.BASEBOARD_FAB2(SCH_1):PAGE117

P3E_CPU0_PE1_PCH_RXN<6> @BASEBOARD_FAB2_LIB.BASEBOARD_FAB2(SCH_1):P3E_CPU0_PE1_PCH_RXN(6)
 C2U16    1      A CAP_0402-0.22UF,16V,10%,X7R,A3A   I286 @BASEBOARD_FAB2_LIB.BASEBOARD_FAB2(SCH_1):PAGE107
  U7C1  H61 PCIEUP_6_TXN LBG_CORE_QAT_EXT_D_BGA1-IC,H91A     I9 @BASEBOARD_FAB2_LIB.BASEBOARD_FAB2(SCH_1):PAGE117

P3E_CPU0_PE1_PCH_RXN<7> @BASEBOARD_FAB2_LIB.BASEBOARD_FAB2(SCH_1):P3E_CPU0_PE1_PCH_RXN(7)
 C2U18    1      A CAP_0402-0.22UF,16V,10%,X7R,A3A   I294 @BASEBOARD_FAB2_LIB.BASEBOARD_FAB2(SCH_1):PAGE107
  U7C1  P59 PCIEUP_7_TXN LBG_CORE_QAT_EXT_D_BGA1-IC,H91A     I9 @BASEBOARD_FAB2_LIB.BASEBOARD_FAB2(SCH_1):PAGE117

P3E_CPU0_PE1_PCH_RXN<8> @BASEBOARD_FAB2_LIB.BASEBOARD_FAB2(SCH_1):P3E_CPU0_PE1_PCH_RXN(8)
  U5D1 DM11 PE1_RX_DN<8> SKX_EXT_B_BGA1-IC,TBD    I84 @BASEBOARD_FAB2_LIB.BASEBOARD_FAB2(SCH_1):PAGE30
 C3M33    2      B CAP_0402-0.22UF,16V,10%,X7R,A3A   I217 @BASEBOARD_FAB2_LIB.BASEBOARD_FAB2(SCH_1):PAGE105
  R784    1      A RES_0402-0.0,5%,1/16W,CHIP,G21A    I99 @BASEBOARD_FAB2_LIB.BASEBOARD_FAB2(SCH_1):PAGE244

P3E_CPU0_PE1_PCH_RXN<9> @BASEBOARD_FAB2_LIB.BASEBOARD_FAB2(SCH_1):P3E_CPU0_PE1_PCH_RXN(9)
  U5D1 DP11 PE1_RX_DN<9> SKX_EXT_B_BGA1-IC,TBD    I84 @BASEBOARD_FAB2_LIB.BASEBOARD_FAB2(SCH_1):PAGE30
 C3M35    2      B CAP_0402-0.22UF,16V,10%,X7R,A3A   I225 @BASEBOARD_FAB2_LIB.BASEBOARD_FAB2(SCH_1):PAGE105
  R782    1      A RES_0402-0.0,5%,1/16W,CHIP,G21A    I98 @BASEBOARD_FAB2_LIB.BASEBOARD_FAB2(SCH_1):PAGE244

P3E_CPU0_PE1_PCH_RXP<0> @BASEBOARD_FAB2_LIB.BASEBOARD_FAB2(SCH_1):P3E_CPU0_PE1_PCH_RXP(0)
  C2U3    1      A CAP_0402-0.22UF,16V,10%,X7R,A3A   I272 @BASEBOARD_FAB2_LIB.BASEBOARD_FAB2(SCH_1):PAGE107
  U7C1  G52 PCIEUP_0_TXP LBG_CORE_QAT_EXT_D_BGA1-IC,H91A     I9 @BASEBOARD_FAB2_LIB.BASEBOARD_FAB2(SCH_1):PAGE117

P3E_CPU0_PE1_PCH_RXP<10> @BASEBOARD_FAB2_LIB.BASEBOARD_FAB2(SCH_1):P3E_CPU0_PE1_PCH_RXP(10)
  U5D1 DR12 PE1_RX_DP<10> SKX_EXT_B_BGA1-IC,TBD    I84 @BASEBOARD_FAB2_LIB.BASEBOARD_FAB2(SCH_1):PAGE30
 C3M28    2      B CAP_0402-0.22UF,16V,10%,X7R,A3A   I212 @BASEBOARD_FAB2_LIB.BASEBOARD_FAB2(SCH_1):PAGE105
  R781    1      A RES_0402-0.0,5%,1/16W,CHIP,G21A    I86 @BASEBOARD_FAB2_LIB.BASEBOARD_FAB2(SCH_1):PAGE244

P3E_CPU0_PE1_PCH_RXP<11> @BASEBOARD_FAB2_LIB.BASEBOARD_FAB2(SCH_1):P3E_CPU0_PE1_PCH_RXP(11)
  U5D1 DP13 PE1_RX_DP<11> SKX_EXT_B_BGA1-IC,TBD    I84 @BASEBOARD_FAB2_LIB.BASEBOARD_FAB2(SCH_1):PAGE30
 C3M25    2      B CAP_0402-0.22UF,16V,10%,X7R,A3A   I205 @BASEBOARD_FAB2_LIB.BASEBOARD_FAB2(SCH_1):PAGE105
  R779    1      A RES_0402-0.0,5%,1/16W,CHIP,G21A    I74 @BASEBOARD_FAB2_LIB.BASEBOARD_FAB2(SCH_1):PAGE244

P3E_CPU0_PE1_PCH_RXP<12> @BASEBOARD_FAB2_LIB.BASEBOARD_FAB2(SCH_1):P3E_CPU0_PE1_PCH_RXP(12)
  U5D1 DU12 PE1_RX_DP<12> SKX_EXT_B_BGA1-IC,TBD    I84 @BASEBOARD_FAB2_LIB.BASEBOARD_FAB2(SCH_1):PAGE30
  C3M3    2      B CAP_0402-0.22UF,16V,10%,X7R,A3A   I232 @BASEBOARD_FAB2_LIB.BASEBOARD_FAB2(SCH_1):PAGE105
  R777    1      A RES_0402-0.0,5%,1/16W,CHIP,G21A    I80 @BASEBOARD_FAB2_LIB.BASEBOARD_FAB2(SCH_1):PAGE244

P3E_CPU0_PE1_PCH_RXP<13> @BASEBOARD_FAB2_LIB.BASEBOARD_FAB2(SCH_1):P3E_CPU0_PE1_PCH_RXP(13)
  U5D1 DY13 PE1_RX_DP<13> SKX_EXT_B_BGA1-IC,TBD    I84 @BASEBOARD_FAB2_LIB.BASEBOARD_FAB2(SCH_1):PAGE30
 C3M13    2      B CAP_0402-0.22UF,16V,10%,X7R,A3A   I239 @BASEBOARD_FAB2_LIB.BASEBOARD_FAB2(SCH_1):PAGE105
  R774    1      A RES_0402-0.0,5%,1/16W,CHIP,G21A    I72 @BASEBOARD_FAB2_LIB.BASEBOARD_FAB2(SCH_1):PAGE244

P3E_CPU0_PE1_PCH_RXP<14> @BASEBOARD_FAB2_LIB.BASEBOARD_FAB2(SCH_1):P3E_CPU0_PE1_PCH_RXP(14)
  U5D1 DV15 PE1_RX_DP<14> SKX_EXT_B_BGA1-IC,TBD    I84 @BASEBOARD_FAB2_LIB.BASEBOARD_FAB2(SCH_1):PAGE30
 C3M11    2      B CAP_0402-0.22UF,16V,10%,X7R,A3A   I234 @BASEBOARD_FAB2_LIB.BASEBOARD_FAB2(SCH_1):PAGE105
  R769    1      A RES_0402-0.0,5%,1/16W,CHIP,G21A    I58 @BASEBOARD_FAB2_LIB.BASEBOARD_FAB2(SCH_1):PAGE244

P3E_CPU0_PE1_PCH_RXP<15> @BASEBOARD_FAB2_LIB.BASEBOARD_FAB2(SCH_1):P3E_CPU0_PE1_PCH_RXP(15)
  U5D1 DT15 PE1_RX_DP<15> SKX_EXT_B_BGA1-IC,TBD    I84 @BASEBOARD_FAB2_LIB.BASEBOARD_FAB2(SCH_1):PAGE30
  C3M2    2      B CAP_0402-0.22UF,16V,10%,X7R,A3A   I247 @BASEBOARD_FAB2_LIB.BASEBOARD_FAB2(SCH_1):PAGE105
  R767    1      A RES_0402-0.0,5%,1/16W,CHIP,G21A    I39 @BASEBOARD_FAB2_LIB.BASEBOARD_FAB2(SCH_1):PAGE244

P3E_CPU0_PE1_PCH_RXP<1> @BASEBOARD_FAB2_LIB.BASEBOARD_FAB2(SCH_1):P3E_CPU0_PE1_PCH_RXP(1)
  C2U5    1      A CAP_0402-0.22UF,16V,10%,X7R,A3A   I274 @BASEBOARD_FAB2_LIB.BASEBOARD_FAB2(SCH_1):PAGE107
  U7C1  M56 PCIEUP_1_TXP LBG_CORE_QAT_EXT_D_BGA1-IC,H91A     I9 @BASEBOARD_FAB2_LIB.BASEBOARD_FAB2(SCH_1):PAGE117

P3E_CPU0_PE1_PCH_RXP<2> @BASEBOARD_FAB2_LIB.BASEBOARD_FAB2(SCH_1):P3E_CPU0_PE1_PCH_RXP(2)
  C2U7    1      A CAP_0402-0.22UF,16V,10%,X7R,A3A   I277 @BASEBOARD_FAB2_LIB.BASEBOARD_FAB2(SCH_1):PAGE107
  U7C1  G56 PCIEUP_2_TXP LBG_CORE_QAT_EXT_D_BGA1-IC,H91A     I9 @BASEBOARD_FAB2_LIB.BASEBOARD_FAB2(SCH_1):PAGE117

P3E_CPU0_PE1_PCH_RXP<3> @BASEBOARD_FAB2_LIB.BASEBOARD_FAB2(SCH_1):P3E_CPU0_PE1_PCH_RXP(3)
  C2U9    1      A CAP_0402-0.22UF,16V,10%,X7R,A3A   I279 @BASEBOARD_FAB2_LIB.BASEBOARD_FAB2(SCH_1):PAGE107
  U7C1  K58 PCIEUP_3_TXP LBG_CORE_QAT_EXT_D_BGA1-IC,H91A     I9 @BASEBOARD_FAB2_LIB.BASEBOARD_FAB2(SCH_1):PAGE117

P3E_CPU0_PE1_PCH_RXP<4> @BASEBOARD_FAB2_LIB.BASEBOARD_FAB2(SCH_1):P3E_CPU0_PE1_PCH_RXP(4)
 C2U11    1      A CAP_0402-0.22UF,16V,10%,X7R,A3A   I278 @BASEBOARD_FAB2_LIB.BASEBOARD_FAB2(SCH_1):PAGE107
  U7C1  M59 PCIEUP_4_TXP LBG_CORE_QAT_EXT_D_BGA1-IC,H91A     I9 @BASEBOARD_FAB2_LIB.BASEBOARD_FAB2(SCH_1):PAGE117

P3E_CPU0_PE1_PCH_RXP<5> @BASEBOARD_FAB2_LIB.BASEBOARD_FAB2(SCH_1):P3E_CPU0_PE1_PCH_RXP(5)
 C2U13    1      A CAP_0402-0.22UF,16V,10%,X7R,A3A   I297 @BASEBOARD_FAB2_LIB.BASEBOARD_FAB2(SCH_1):PAGE107
  U7C1  K61 PCIEUP_5_TXP LBG_CORE_QAT_EXT_D_BGA1-IC,H91A     I9 @BASEBOARD_FAB2_LIB.BASEBOARD_FAB2(SCH_1):PAGE117

P3E_CPU0_PE1_PCH_RXP<6> @BASEBOARD_FAB2_LIB.BASEBOARD_FAB2(SCH_1):P3E_CPU0_PE1_PCH_RXP(6)
 C2U15    1      A CAP_0402-0.22UF,16V,10%,X7R,A3A   I296 @BASEBOARD_FAB2_LIB.BASEBOARD_FAB2(SCH_1):PAGE107
  U7C1  J63 PCIEUP_6_TXP LBG_CORE_QAT_EXT_D_BGA1-IC,H91A     I9 @BASEBOARD_FAB2_LIB.BASEBOARD_FAB2(SCH_1):PAGE117

P3E_CPU0_PE1_PCH_RXP<7> @BASEBOARD_FAB2_LIB.BASEBOARD_FAB2(SCH_1):P3E_CPU0_PE1_PCH_RXP(7)
 C2U17    1      A CAP_0402-0.22UF,16V,10%,X7R,A3A   I300 @BASEBOARD_FAB2_LIB.BASEBOARD_FAB2(SCH_1):PAGE107
  U7C1  R61 PCIEUP_7_TXP LBG_CORE_QAT_EXT_D_BGA1-IC,H91A     I9 @BASEBOARD_FAB2_LIB.BASEBOARD_FAB2(SCH_1):PAGE117

P3E_CPU0_PE1_PCH_RXP<8> @BASEBOARD_FAB2_LIB.BASEBOARD_FAB2(SCH_1):P3E_CPU0_PE1_PCH_RXP(8)
  U5D1 DK11 PE1_RX_DP<8> SKX_EXT_B_BGA1-IC,TBD    I84 @BASEBOARD_FAB2_LIB.BASEBOARD_FAB2(SCH_1):PAGE30
 C3M34    2      B CAP_0402-0.22UF,16V,10%,X7R,A3A   I206 @BASEBOARD_FAB2_LIB.BASEBOARD_FAB2(SCH_1):PAGE105
  R785    1      A RES_0402-0.0,5%,1/16W,CHIP,G21A   I103 @BASEBOARD_FAB2_LIB.BASEBOARD_FAB2(SCH_1):PAGE244

P3E_CPU0_PE1_PCH_RXP<9> @BASEBOARD_FAB2_LIB.BASEBOARD_FAB2(SCH_1):P3E_CPU0_PE1_PCH_RXP(9)
  U5D1 DN10 PE1_RX_DP<9> SKX_EXT_B_BGA1-IC,TBD    I84 @BASEBOARD_FAB2_LIB.BASEBOARD_FAB2(SCH_1):PAGE30
 C3M36    2      B CAP_0402-0.22UF,16V,10%,X7R,A3A   I218 @BASEBOARD_FAB2_LIB.BASEBOARD_FAB2(SCH_1):PAGE105
  R783    1      A RES_0402-0.0,5%,1/16W,CHIP,G21A    I77 @BASEBOARD_FAB2_LIB.BASEBOARD_FAB2(SCH_1):PAGE244

P3E_CPU0_PE1_PCH_R_RXN<10> @BASEBOARD_FAB2_LIB.BASEBOARD_FAB2(SCH_1):P3E_CPU0_PE1_PCH_R_RXN(10)
 C3M32    1      A CAP_0402-0.22UF,16V,10%,X7R,A3A   I223 @BASEBOARD_FAB2_LIB.BASEBOARD_FAB2(SCH_1):PAGE105
  U7C1  N65 PCIEUP_10_TXN LBG_CORE_QAT_EXT_D_BGA1-IC,H91A     I9 @BASEBOARD_FAB2_LIB.BASEBOARD_FAB2(SCH_1):PAGE117

P3E_CPU0_PE1_PCH_R_RXN<11> @BASEBOARD_FAB2_LIB.BASEBOARD_FAB2(SCH_1):P3E_CPU0_PE1_PCH_R_RXN(11)
 C3M26    1      A CAP_0402-0.22UF,16V,10%,X7R,A3A   I229 @BASEBOARD_FAB2_LIB.BASEBOARD_FAB2(SCH_1):PAGE105
  U7C1  T59 PCIEUP_11_TXN LBG_CORE_QAT_EXT_D_BGA1-IC,H91A     I9 @BASEBOARD_FAB2_LIB.BASEBOARD_FAB2(SCH_1):PAGE117

P3E_CPU0_PE1_PCH_R_RXN<12> @BASEBOARD_FAB2_LIB.BASEBOARD_FAB2(SCH_1):P3E_CPU0_PE1_PCH_R_RXN(12)
  C3M4    1      A CAP_0402-0.22UF,16V,10%,X7R,A3A   I244 @BASEBOARD_FAB2_LIB.BASEBOARD_FAB2(SCH_1):PAGE105
  U7C1  R65 PCIEUP_12_TXN LBG_CORE_QAT_EXT_D_BGA1-IC,H91A     I9 @BASEBOARD_FAB2_LIB.BASEBOARD_FAB2(SCH_1):PAGE117

P3E_CPU0_PE1_PCH_R_RXN<13> @BASEBOARD_FAB2_LIB.BASEBOARD_FAB2(SCH_1):P3E_CPU0_PE1_PCH_R_RXN(13)
 C3M14    1      A CAP_0402-0.22UF,16V,10%,X7R,A3A   I253 @BASEBOARD_FAB2_LIB.BASEBOARD_FAB2(SCH_1):PAGE105
  U7C1  T63 PCIEUP_13_TXN LBG_CORE_QAT_EXT_D_BGA1-IC,H91A     I9 @BASEBOARD_FAB2_LIB.BASEBOARD_FAB2(SCH_1):PAGE117

P3E_CPU0_PE1_PCH_R_RXN<14> @BASEBOARD_FAB2_LIB.BASEBOARD_FAB2(SCH_1):P3E_CPU0_PE1_PCH_R_RXN(14)
 C3M12    1      A CAP_0402-0.22UF,16V,10%,X7R,A3A   I246 @BASEBOARD_FAB2_LIB.BASEBOARD_FAB2(SCH_1):PAGE105
  U7C1  W65 PCIEUP_14_TXN LBG_CORE_QAT_EXT_D_BGA1-IC,H91A     I9 @BASEBOARD_FAB2_LIB.BASEBOARD_FAB2(SCH_1):PAGE117

P3E_CPU0_PE1_PCH_R_RXN<15> @BASEBOARD_FAB2_LIB.BASEBOARD_FAB2(SCH_1):P3E_CPU0_PE1_PCH_R_RXN(15)
  C3M1    1      A CAP_0402-0.22UF,16V,10%,X7R,A3A   I255 @BASEBOARD_FAB2_LIB.BASEBOARD_FAB2(SCH_1):PAGE105
  U7C1  Y66 PCIEUP_15_TXN LBG_CORE_QAT_EXT_D_BGA1-IC,H91A     I9 @BASEBOARD_FAB2_LIB.BASEBOARD_FAB2(SCH_1):PAGE117

P3E_CPU0_PE1_PCH_R_RXN<8> @BASEBOARD_FAB2_LIB.BASEBOARD_FAB2(SCH_1):P3E_CPU0_PE1_PCH_R_RXN(8)
 C3M33    1      A CAP_0402-0.22UF,16V,10%,X7R,A3A   I217 @BASEBOARD_FAB2_LIB.BASEBOARD_FAB2(SCH_1):PAGE105
  U7C1  K65 PCIEUP_8_TXN LBG_CORE_QAT_EXT_D_BGA1-IC,H91A     I9 @BASEBOARD_FAB2_LIB.BASEBOARD_FAB2(SCH_1):PAGE117

P3E_CPU0_PE1_PCH_R_RXN<9> @BASEBOARD_FAB2_LIB.BASEBOARD_FAB2(SCH_1):P3E_CPU0_PE1_PCH_R_RXN(9)
 C3M35    1      A CAP_0402-0.22UF,16V,10%,X7R,A3A   I225 @BASEBOARD_FAB2_LIB.BASEBOARD_FAB2(SCH_1):PAGE105
  U7C1  J66 PCIEUP_9_TXN LBG_CORE_QAT_EXT_D_BGA1-IC,H91A     I9 @BASEBOARD_FAB2_LIB.BASEBOARD_FAB2(SCH_1):PAGE117

P3E_CPU0_PE1_PCH_R_RXP<10> @BASEBOARD_FAB2_LIB.BASEBOARD_FAB2(SCH_1):P3E_CPU0_PE1_PCH_R_RXP(10)
 C3M28    1      A CAP_0402-0.22UF,16V,10%,X7R,A3A   I212 @BASEBOARD_FAB2_LIB.BASEBOARD_FAB2(SCH_1):PAGE105
  U7C1  P66 PCIEUP_10_TXP LBG_CORE_QAT_EXT_D_BGA1-IC,H91A     I9 @BASEBOARD_FAB2_LIB.BASEBOARD_FAB2(SCH_1):PAGE117

P3E_CPU0_PE1_PCH_R_RXP<11> @BASEBOARD_FAB2_LIB.BASEBOARD_FAB2(SCH_1):P3E_CPU0_PE1_PCH_R_RXP(11)
 C3M25    1      A CAP_0402-0.22UF,16V,10%,X7R,A3A   I205 @BASEBOARD_FAB2_LIB.BASEBOARD_FAB2(SCH_1):PAGE105
  U7C1  V59 PCIEUP_11_TXP LBG_CORE_QAT_EXT_D_BGA1-IC,H91A     I9 @BASEBOARD_FAB2_LIB.BASEBOARD_FAB2(SCH_1):PAGE117

P3E_CPU0_PE1_PCH_R_RXP<12> @BASEBOARD_FAB2_LIB.BASEBOARD_FAB2(SCH_1):P3E_CPU0_PE1_PCH_R_RXP(12)
  C3M3    1      A CAP_0402-0.22UF,16V,10%,X7R,A3A   I232 @BASEBOARD_FAB2_LIB.BASEBOARD_FAB2(SCH_1):PAGE105
  U7C1  U65 PCIEUP_12_TXP LBG_CORE_QAT_EXT_D_BGA1-IC,H91A     I9 @BASEBOARD_FAB2_LIB.BASEBOARD_FAB2(SCH_1):PAGE117

P3E_CPU0_PE1_PCH_R_RXP<13> @BASEBOARD_FAB2_LIB.BASEBOARD_FAB2(SCH_1):P3E_CPU0_PE1_PCH_R_RXP(13)
 C3M13    1      A CAP_0402-0.22UF,16V,10%,X7R,A3A   I239 @BASEBOARD_FAB2_LIB.BASEBOARD_FAB2(SCH_1):PAGE105
  U7C1  U61 PCIEUP_13_TXP LBG_CORE_QAT_EXT_D_BGA1-IC,H91A     I9 @BASEBOARD_FAB2_LIB.BASEBOARD_FAB2(SCH_1):PAGE117

P3E_CPU0_PE1_PCH_R_RXP<14> @BASEBOARD_FAB2_LIB.BASEBOARD_FAB2(SCH_1):P3E_CPU0_PE1_PCH_R_RXP(14)
 C3M11    1      A CAP_0402-0.22UF,16V,10%,X7R,A3A   I234 @BASEBOARD_FAB2_LIB.BASEBOARD_FAB2(SCH_1):PAGE105
  U7C1  V63 PCIEUP_14_TXP LBG_CORE_QAT_EXT_D_BGA1-IC,H91A     I9 @BASEBOARD_FAB2_LIB.BASEBOARD_FAB2(SCH_1):PAGE117

P3E_CPU0_PE1_PCH_R_RXP<15> @BASEBOARD_FAB2_LIB.BASEBOARD_FAB2(SCH_1):P3E_CPU0_PE1_PCH_R_RXP(15)
  C3M2    1      A CAP_0402-0.22UF,16V,10%,X7R,A3A   I247 @BASEBOARD_FAB2_LIB.BASEBOARD_FAB2(SCH_1):PAGE105
  U7C1 AA65 PCIEUP_15_TXP LBG_CORE_QAT_EXT_D_BGA1-IC,H91A     I9 @BASEBOARD_FAB2_LIB.BASEBOARD_FAB2(SCH_1):PAGE117

P3E_CPU0_PE1_PCH_R_RXP<8> @BASEBOARD_FAB2_LIB.BASEBOARD_FAB2(SCH_1):P3E_CPU0_PE1_PCH_R_RXP(8)
 C3M34    1      A CAP_0402-0.22UF,16V,10%,X7R,A3A   I206 @BASEBOARD_FAB2_LIB.BASEBOARD_FAB2(SCH_1):PAGE105
  U7C1  M63 PCIEUP_8_TXP LBG_CORE_QAT_EXT_D_BGA1-IC,H91A     I9 @BASEBOARD_FAB2_LIB.BASEBOARD_FAB2(SCH_1):PAGE117

P3E_CPU0_PE1_PCH_R_RXP<9> @BASEBOARD_FAB2_LIB.BASEBOARD_FAB2(SCH_1):P3E_CPU0_PE1_PCH_R_RXP(9)
 C3M36    1      A CAP_0402-0.22UF,16V,10%,X7R,A3A   I218 @BASEBOARD_FAB2_LIB.BASEBOARD_FAB2(SCH_1):PAGE105
  U7C1  M66 PCIEUP_9_TXP LBG_CORE_QAT_EXT_D_BGA1-IC,H91A     I9 @BASEBOARD_FAB2_LIB.BASEBOARD_FAB2(SCH_1):PAGE117

P3E_CPU0_PE1_PCH_TXN<0> @BASEBOARD_FAB2_LIB.BASEBOARD_FAB2(SCH_1):P3E_CPU0_PE1_PCH_TXN(0)
 C3P13    2      B CAP_0402-0.22UF,16V,10%,X7R,A3A   I207 @BASEBOARD_FAB2_LIB.BASEBOARD_FAB2(SCH_1):PAGE107
  U7C1  C48 PCIEUP_0_RXN LBG_CORE_QAT_EXT_D_BGA1-IC,H91A     I9 @BASEBOARD_FAB2_LIB.BASEBOARD_FAB2(SCH_1):PAGE117

P3E_CPU0_PE1_PCH_TXN<10> @BASEBOARD_FAB2_LIB.BASEBOARD_FAB2(SCH_1):P3E_CPU0_PE1_PCH_TXN(10)
  U5D1  DW4 PE1_TX_DN<10> SKX_EXT_B_BGA1-IC,TBD    I84 @BASEBOARD_FAB2_LIB.BASEBOARD_FAB2(SCH_1):PAGE30
 C6B15    1      A CAP_0402-0.22UF,16V,10%,X7R,A3A   I163 @BASEBOARD_FAB2_LIB.BASEBOARD_FAB2(SCH_1):PAGE105
  C834    1      A CAP_0402-0.22UF,16V,10%,X7R,A3A    I50 @BASEBOARD_FAB2_LIB.BASEBOARD_FAB2(SCH_1):PAGE244

P3E_CPU0_PE1_PCH_TXN<11> @BASEBOARD_FAB2_LIB.BASEBOARD_FAB2(SCH_1):P3E_CPU0_PE1_PCH_TXN(11)
  U5D1  DU6 PE1_TX_DN<11> SKX_EXT_B_BGA1-IC,TBD    I84 @BASEBOARD_FAB2_LIB.BASEBOARD_FAB2(SCH_1):PAGE30
 C6B14    1      A CAP_0402-0.22UF,16V,10%,X7R,A3A   I181 @BASEBOARD_FAB2_LIB.BASEBOARD_FAB2(SCH_1):PAGE105
  C832    1      A CAP_0402-0.22UF,16V,10%,X7R,A3A    I30 @BASEBOARD_FAB2_LIB.BASEBOARD_FAB2(SCH_1):PAGE244

P3E_CPU0_PE1_PCH_TXN<12> @BASEBOARD_FAB2_LIB.BASEBOARD_FAB2(SCH_1):P3E_CPU0_PE1_PCH_TXN(12)
  U5D1  DV7 PE1_TX_DN<12> SKX_EXT_B_BGA1-IC,TBD    I84 @BASEBOARD_FAB2_LIB.BASEBOARD_FAB2(SCH_1):PAGE30
 C6B11    1      A CAP_0402-0.22UF,16V,10%,X7R,A3A   I166 @BASEBOARD_FAB2_LIB.BASEBOARD_FAB2(SCH_1):PAGE105
  C840    1      A CAP_0402-0.22UF,16V,10%,X7R,A3A    I29 @BASEBOARD_FAB2_LIB.BASEBOARD_FAB2(SCH_1):PAGE244

P3E_CPU0_PE1_PCH_TXN<13> @BASEBOARD_FAB2_LIB.BASEBOARD_FAB2(SCH_1):P3E_CPU0_PE1_PCH_TXN(13)
  U5D1  DY7 PE1_TX_DN<13> SKX_EXT_B_BGA1-IC,TBD    I84 @BASEBOARD_FAB2_LIB.BASEBOARD_FAB2(SCH_1):PAGE30
  C6B9    1      A CAP_0402-0.22UF,16V,10%,X7R,A3A   I185 @BASEBOARD_FAB2_LIB.BASEBOARD_FAB2(SCH_1):PAGE105
  C828    1      A CAP_0402-0.22UF,16V,10%,X7R,A3A    I28 @BASEBOARD_FAB2_LIB.BASEBOARD_FAB2(SCH_1):PAGE244

P3E_CPU0_PE1_PCH_TXN<14> @BASEBOARD_FAB2_LIB.BASEBOARD_FAB2(SCH_1):P3E_CPU0_PE1_PCH_TXN(14)
  U5D1  EA8 PE1_TX_DN<14> SKX_EXT_B_BGA1-IC,TBD    I84 @BASEBOARD_FAB2_LIB.BASEBOARD_FAB2(SCH_1):PAGE30
  C6B6    1      A CAP_0402-0.22UF,16V,10%,X7R,A3A   I169 @BASEBOARD_FAB2_LIB.BASEBOARD_FAB2(SCH_1):PAGE105
  C826    1      A CAP_0402-0.22UF,16V,10%,X7R,A3A    I24 @BASEBOARD_FAB2_LIB.BASEBOARD_FAB2(SCH_1):PAGE244

P3E_CPU0_PE1_PCH_TXN<15> @BASEBOARD_FAB2_LIB.BASEBOARD_FAB2(SCH_1):P3E_CPU0_PE1_PCH_TXN(15)
  U5D1  ED9 PE1_TX_DN<15> SKX_EXT_B_BGA1-IC,TBD    I84 @BASEBOARD_FAB2_LIB.BASEBOARD_FAB2(SCH_1):PAGE30
  C6B4    1      A CAP_0402-0.22UF,16V,10%,X7R,A3A   I196 @BASEBOARD_FAB2_LIB.BASEBOARD_FAB2(SCH_1):PAGE105
  C830    1      A CAP_0402-0.22UF,16V,10%,X7R,A3A    I23 @BASEBOARD_FAB2_LIB.BASEBOARD_FAB2(SCH_1):PAGE244

P3E_CPU0_PE1_PCH_TXN<1> @BASEBOARD_FAB2_LIB.BASEBOARD_FAB2(SCH_1):P3E_CPU0_PE1_PCH_TXN(1)
 C3P17    2      B CAP_0402-0.22UF,16V,10%,X7R,A3A   I208 @BASEBOARD_FAB2_LIB.BASEBOARD_FAB2(SCH_1):PAGE107
  U7C1  D49 PCIEUP_1_RXN LBG_CORE_QAT_EXT_D_BGA1-IC,H91A     I9 @BASEBOARD_FAB2_LIB.BASEBOARD_FAB2(SCH_1):PAGE117

P3E_CPU0_PE1_PCH_TXN<2> @BASEBOARD_FAB2_LIB.BASEBOARD_FAB2(SCH_1):P3E_CPU0_PE1_PCH_TXN(2)
 C3P20    2      B CAP_0402-0.22UF,16V,10%,X7R,A3A   I215 @BASEBOARD_FAB2_LIB.BASEBOARD_FAB2(SCH_1):PAGE107
  U7C1  C50 PCIEUP_2_RXN LBG_CORE_QAT_EXT_D_BGA1-IC,H91A     I9 @BASEBOARD_FAB2_LIB.BASEBOARD_FAB2(SCH_1):PAGE117

P3E_CPU0_PE1_PCH_TXN<3> @BASEBOARD_FAB2_LIB.BASEBOARD_FAB2(SCH_1):P3E_CPU0_PE1_PCH_TXN(3)
 C3P25    2      B CAP_0402-0.22UF,16V,10%,X7R,A3A   I216 @BASEBOARD_FAB2_LIB.BASEBOARD_FAB2(SCH_1):PAGE107
  U7C1  D51 PCIEUP_3_RXN LBG_CORE_QAT_EXT_D_BGA1-IC,H91A     I9 @BASEBOARD_FAB2_LIB.BASEBOARD_FAB2(SCH_1):PAGE117

P3E_CPU0_PE1_PCH_TXN<4> @BASEBOARD_FAB2_LIB.BASEBOARD_FAB2(SCH_1):P3E_CPU0_PE1_PCH_TXN(4)
 C3P28    2      B CAP_0402-0.22UF,16V,10%,X7R,A3A   I232 @BASEBOARD_FAB2_LIB.BASEBOARD_FAB2(SCH_1):PAGE107
  U7C1  C52 PCIEUP_4_RXN LBG_CORE_QAT_EXT_D_BGA1-IC,H91A     I9 @BASEBOARD_FAB2_LIB.BASEBOARD_FAB2(SCH_1):PAGE117

P3E_CPU0_PE1_PCH_TXN<5> @BASEBOARD_FAB2_LIB.BASEBOARD_FAB2(SCH_1):P3E_CPU0_PE1_PCH_TXN(5)
 C3P32    2      B CAP_0402-0.22UF,16V,10%,X7R,A3A   I234 @BASEBOARD_FAB2_LIB.BASEBOARD_FAB2(SCH_1):PAGE107
  U7C1  D53 PCIEUP_5_RXN LBG_CORE_QAT_EXT_D_BGA1-IC,H91A     I9 @BASEBOARD_FAB2_LIB.BASEBOARD_FAB2(SCH_1):PAGE117

P3E_CPU0_PE1_PCH_TXN<6> @BASEBOARD_FAB2_LIB.BASEBOARD_FAB2(SCH_1):P3E_CPU0_PE1_PCH_TXN(6)
 C3P37    2      B CAP_0402-0.22UF,16V,10%,X7R,A3A   I235 @BASEBOARD_FAB2_LIB.BASEBOARD_FAB2(SCH_1):PAGE107
  U7C1  C54 PCIEUP_6_RXN LBG_CORE_QAT_EXT_D_BGA1-IC,H91A     I9 @BASEBOARD_FAB2_LIB.BASEBOARD_FAB2(SCH_1):PAGE117

P3E_CPU0_PE1_PCH_TXN<7> @BASEBOARD_FAB2_LIB.BASEBOARD_FAB2(SCH_1):P3E_CPU0_PE1_PCH_TXN(7)
 C3P40    2      B CAP_0402-0.22UF,16V,10%,X7R,A3A   I241 @BASEBOARD_FAB2_LIB.BASEBOARD_FAB2(SCH_1):PAGE107
  U7C1  D55 PCIEUP_7_RXN LBG_CORE_QAT_EXT_D_BGA1-IC,H91A     I9 @BASEBOARD_FAB2_LIB.BASEBOARD_FAB2(SCH_1):PAGE117

P3E_CPU0_PE1_PCH_TXN<8> @BASEBOARD_FAB2_LIB.BASEBOARD_FAB2(SCH_1):P3E_CPU0_PE1_PCH_TXN(8)
  U5D1  DT5 PE1_TX_DN<8> SKX_EXT_B_BGA1-IC,TBD    I84 @BASEBOARD_FAB2_LIB.BASEBOARD_FAB2(SCH_1):PAGE30
 C6B19    1      A CAP_0402-0.22UF,16V,10%,X7R,A3A   I160 @BASEBOARD_FAB2_LIB.BASEBOARD_FAB2(SCH_1):PAGE105
  C842    1      A CAP_0402-0.22UF,16V,10%,X7R,A3A    I52 @BASEBOARD_FAB2_LIB.BASEBOARD_FAB2(SCH_1):PAGE244

P3E_CPU0_PE1_PCH_TXN<9> @BASEBOARD_FAB2_LIB.BASEBOARD_FAB2(SCH_1):P3E_CPU0_PE1_PCH_TXN(9)
  U5D1  DV3 PE1_TX_DN<9> SKX_EXT_B_BGA1-IC,TBD    I84 @BASEBOARD_FAB2_LIB.BASEBOARD_FAB2(SCH_1):PAGE30
 C6B17    1      A CAP_0402-0.22UF,16V,10%,X7R,A3A   I175 @BASEBOARD_FAB2_LIB.BASEBOARD_FAB2(SCH_1):PAGE105
  C844    1      A CAP_0402-0.22UF,16V,10%,X7R,A3A    I51 @BASEBOARD_FAB2_LIB.BASEBOARD_FAB2(SCH_1):PAGE244

P3E_CPU0_PE1_PCH_TXP<0> @BASEBOARD_FAB2_LIB.BASEBOARD_FAB2(SCH_1):P3E_CPU0_PE1_PCH_TXP(0)
 C3P11    2      B CAP_0402-0.22UF,16V,10%,X7R,A3A   I212 @BASEBOARD_FAB2_LIB.BASEBOARD_FAB2(SCH_1):PAGE107
  U7C1  A48 PCIEUP_0_RXP LBG_CORE_QAT_EXT_D_BGA1-IC,H91A     I9 @BASEBOARD_FAB2_LIB.BASEBOARD_FAB2(SCH_1):PAGE117

P3E_CPU0_PE1_PCH_TXP<10> @BASEBOARD_FAB2_LIB.BASEBOARD_FAB2(SCH_1):P3E_CPU0_PE1_PCH_TXP(10)
  U5D1  DU4 PE1_TX_DP<10> SKX_EXT_B_BGA1-IC,TBD    I84 @BASEBOARD_FAB2_LIB.BASEBOARD_FAB2(SCH_1):PAGE30
 C6B16    1      A CAP_0402-0.22UF,16V,10%,X7R,A3A   I180 @BASEBOARD_FAB2_LIB.BASEBOARD_FAB2(SCH_1):PAGE105
  C835    1      A CAP_0402-0.22UF,16V,10%,X7R,A3A    I41 @BASEBOARD_FAB2_LIB.BASEBOARD_FAB2(SCH_1):PAGE244

P3E_CPU0_PE1_PCH_TXP<11> @BASEBOARD_FAB2_LIB.BASEBOARD_FAB2(SCH_1):P3E_CPU0_PE1_PCH_TXP(11)
  U5D1  DV5 PE1_TX_DP<11> SKX_EXT_B_BGA1-IC,TBD    I84 @BASEBOARD_FAB2_LIB.BASEBOARD_FAB2(SCH_1):PAGE30
 C6B13    1      A CAP_0402-0.22UF,16V,10%,X7R,A3A   I189 @BASEBOARD_FAB2_LIB.BASEBOARD_FAB2(SCH_1):PAGE105
  C833    1      A CAP_0402-0.22UF,16V,10%,X7R,A3A     I8 @BASEBOARD_FAB2_LIB.BASEBOARD_FAB2(SCH_1):PAGE244

P3E_CPU0_PE1_PCH_TXP<12> @BASEBOARD_FAB2_LIB.BASEBOARD_FAB2(SCH_1):P3E_CPU0_PE1_PCH_TXP(12)
  U5D1  DT7 PE1_TX_DP<12> SKX_EXT_B_BGA1-IC,TBD    I84 @BASEBOARD_FAB2_LIB.BASEBOARD_FAB2(SCH_1):PAGE30
 C6B12    1      A CAP_0402-0.22UF,16V,10%,X7R,A3A   I187 @BASEBOARD_FAB2_LIB.BASEBOARD_FAB2(SCH_1):PAGE105
  C841    1      A CAP_0402-0.22UF,16V,10%,X7R,A3A    I17 @BASEBOARD_FAB2_LIB.BASEBOARD_FAB2(SCH_1):PAGE244

P3E_CPU0_PE1_PCH_TXP<13> @BASEBOARD_FAB2_LIB.BASEBOARD_FAB2(SCH_1):P3E_CPU0_PE1_PCH_TXP(13)
  U5D1  DW6 PE1_TX_DP<13> SKX_EXT_B_BGA1-IC,TBD    I84 @BASEBOARD_FAB2_LIB.BASEBOARD_FAB2(SCH_1):PAGE30
 C6B10    1      A CAP_0402-0.22UF,16V,10%,X7R,A3A   I193 @BASEBOARD_FAB2_LIB.BASEBOARD_FAB2(SCH_1):PAGE105
  C829    1      A CAP_0402-0.22UF,16V,10%,X7R,A3A     I5 @BASEBOARD_FAB2_LIB.BASEBOARD_FAB2(SCH_1):PAGE244

P3E_CPU0_PE1_PCH_TXP<14> @BASEBOARD_FAB2_LIB.BASEBOARD_FAB2(SCH_1):P3E_CPU0_PE1_PCH_TXP(14)
  U5D1  EB7 PE1_TX_DP<14> SKX_EXT_B_BGA1-IC,TBD    I84 @BASEBOARD_FAB2_LIB.BASEBOARD_FAB2(SCH_1):PAGE30
  C6B8    1      A CAP_0402-0.22UF,16V,10%,X7R,A3A   I198 @BASEBOARD_FAB2_LIB.BASEBOARD_FAB2(SCH_1):PAGE105
  C827    1      A CAP_0402-0.22UF,16V,10%,X7R,A3A    I12 @BASEBOARD_FAB2_LIB.BASEBOARD_FAB2(SCH_1):PAGE244

P3E_CPU0_PE1_PCH_TXP<15> @BASEBOARD_FAB2_LIB.BASEBOARD_FAB2(SCH_1):P3E_CPU0_PE1_PCH_TXP(15)
  U5D1  EC8 PE1_TX_DP<15> SKX_EXT_B_BGA1-IC,TBD    I84 @BASEBOARD_FAB2_LIB.BASEBOARD_FAB2(SCH_1):PAGE30
  C6B5    1      A CAP_0402-0.22UF,16V,10%,X7R,A3A   I201 @BASEBOARD_FAB2_LIB.BASEBOARD_FAB2(SCH_1):PAGE105
  C831    1      A CAP_0402-0.22UF,16V,10%,X7R,A3A     I2 @BASEBOARD_FAB2_LIB.BASEBOARD_FAB2(SCH_1):PAGE244

P3E_CPU0_PE1_PCH_TXP<1> @BASEBOARD_FAB2_LIB.BASEBOARD_FAB2(SCH_1):P3E_CPU0_PE1_PCH_TXP(1)
 C3P15    2      B CAP_0402-0.22UF,16V,10%,X7R,A3A   I226 @BASEBOARD_FAB2_LIB.BASEBOARD_FAB2(SCH_1):PAGE107
  U7C1  B49 PCIEUP_1_RXP LBG_CORE_QAT_EXT_D_BGA1-IC,H91A     I9 @BASEBOARD_FAB2_LIB.BASEBOARD_FAB2(SCH_1):PAGE117

P3E_CPU0_PE1_PCH_TXP<2> @BASEBOARD_FAB2_LIB.BASEBOARD_FAB2(SCH_1):P3E_CPU0_PE1_PCH_TXP(2)
 C3P18    2      B CAP_0402-0.22UF,16V,10%,X7R,A3A   I219 @BASEBOARD_FAB2_LIB.BASEBOARD_FAB2(SCH_1):PAGE107
  U7C1  A50 PCIEUP_2_RXP LBG_CORE_QAT_EXT_D_BGA1-IC,H91A     I9 @BASEBOARD_FAB2_LIB.BASEBOARD_FAB2(SCH_1):PAGE117

P3E_CPU0_PE1_PCH_TXP<3> @BASEBOARD_FAB2_LIB.BASEBOARD_FAB2(SCH_1):P3E_CPU0_PE1_PCH_TXP(3)
 C3P23    2      B CAP_0402-0.22UF,16V,10%,X7R,A3A   I229 @BASEBOARD_FAB2_LIB.BASEBOARD_FAB2(SCH_1):PAGE107
  U7C1  B51 PCIEUP_3_RXP LBG_CORE_QAT_EXT_D_BGA1-IC,H91A     I9 @BASEBOARD_FAB2_LIB.BASEBOARD_FAB2(SCH_1):PAGE117

P3E_CPU0_PE1_PCH_TXP<4> @BASEBOARD_FAB2_LIB.BASEBOARD_FAB2(SCH_1):P3E_CPU0_PE1_PCH_TXP(4)
 C3P27    2      B CAP_0402-0.22UF,16V,10%,X7R,A3A   I223 @BASEBOARD_FAB2_LIB.BASEBOARD_FAB2(SCH_1):PAGE107
  U7C1  A52 PCIEUP_4_RXP LBG_CORE_QAT_EXT_D_BGA1-IC,H91A     I9 @BASEBOARD_FAB2_LIB.BASEBOARD_FAB2(SCH_1):PAGE117

P3E_CPU0_PE1_PCH_TXP<5> @BASEBOARD_FAB2_LIB.BASEBOARD_FAB2(SCH_1):P3E_CPU0_PE1_PCH_TXP(5)
 C3P30    2      B CAP_0402-0.22UF,16V,10%,X7R,A3A   I245 @BASEBOARD_FAB2_LIB.BASEBOARD_FAB2(SCH_1):PAGE107
  U7C1  B53 PCIEUP_5_RXP LBG_CORE_QAT_EXT_D_BGA1-IC,H91A     I9 @BASEBOARD_FAB2_LIB.BASEBOARD_FAB2(SCH_1):PAGE117

P3E_CPU0_PE1_PCH_TXP<6> @BASEBOARD_FAB2_LIB.BASEBOARD_FAB2(SCH_1):P3E_CPU0_PE1_PCH_TXP(6)
 C3P35    2      B CAP_0402-0.22UF,16V,10%,X7R,A3A   I240 @BASEBOARD_FAB2_LIB.BASEBOARD_FAB2(SCH_1):PAGE107
  U7C1  A54 PCIEUP_6_RXP LBG_CORE_QAT_EXT_D_BGA1-IC,H91A     I9 @BASEBOARD_FAB2_LIB.BASEBOARD_FAB2(SCH_1):PAGE117

P3E_CPU0_PE1_PCH_TXP<7> @BASEBOARD_FAB2_LIB.BASEBOARD_FAB2(SCH_1):P3E_CPU0_PE1_PCH_TXP(7)
 C3P39    2      B CAP_0402-0.22UF,16V,10%,X7R,A3A   I248 @BASEBOARD_FAB2_LIB.BASEBOARD_FAB2(SCH_1):PAGE107
  U7C1  B55 PCIEUP_7_RXP LBG_CORE_QAT_EXT_D_BGA1-IC,H91A     I9 @BASEBOARD_FAB2_LIB.BASEBOARD_FAB2(SCH_1):PAGE117

P3E_CPU0_PE1_PCH_TXP<8> @BASEBOARD_FAB2_LIB.BASEBOARD_FAB2(SCH_1):P3E_CPU0_PE1_PCH_TXP(8)
  U5D1  DR4 PE1_TX_DP<8> SKX_EXT_B_BGA1-IC,TBD    I84 @BASEBOARD_FAB2_LIB.BASEBOARD_FAB2(SCH_1):PAGE30
 C6B20    1      A CAP_0402-0.22UF,16V,10%,X7R,A3A   I173 @BASEBOARD_FAB2_LIB.BASEBOARD_FAB2(SCH_1):PAGE105
  C843    1      A CAP_0402-0.22UF,16V,10%,X7R,A3A    I47 @BASEBOARD_FAB2_LIB.BASEBOARD_FAB2(SCH_1):PAGE244

P3E_CPU0_PE1_PCH_TXP<9> @BASEBOARD_FAB2_LIB.BASEBOARD_FAB2(SCH_1):P3E_CPU0_PE1_PCH_TXP(9)
  U5D1  DU2 PE1_TX_DP<9> SKX_EXT_B_BGA1-IC,TBD    I84 @BASEBOARD_FAB2_LIB.BASEBOARD_FAB2(SCH_1):PAGE30
 C6B18    1      A CAP_0402-0.22UF,16V,10%,X7R,A3A   I153 @BASEBOARD_FAB2_LIB.BASEBOARD_FAB2(SCH_1):PAGE105
  C845    1      A CAP_0402-0.22UF,16V,10%,X7R,A3A    I35 @BASEBOARD_FAB2_LIB.BASEBOARD_FAB2(SCH_1):PAGE244

P3E_CPU0_PE1_SS_C_TXN<0> @BASEBOARD_FAB2_LIB.BASEBOARD_FAB2(SCH_1):P3E_CPU0_PE1_SS_C_TXN(0)
  J8G1  145  IO145 SCONN200_H68296001_SM-CONN,H68A    I78 @BASEBOARD_FAB2_LIB.BASEBOARD_FAB2(SCH_1):PAGE109
 C3P12    2      B CAP_0402-0.22UF,16V,10%,X7R,A3A   I481 @BASEBOARD_FAB2_LIB.BASEBOARD_FAB2(SCH_1):PAGE107

P3E_CPU0_PE1_SS_C_TXN<1> @BASEBOARD_FAB2_LIB.BASEBOARD_FAB2(SCH_1):P3E_CPU0_PE1_SS_C_TXN(1)
  J8G1  139  IO139 SCONN200_H68296001_SM-CONN,H68A    I78 @BASEBOARD_FAB2_LIB.BASEBOARD_FAB2(SCH_1):PAGE109
 C3P16    2      B CAP_0402-0.22UF,16V,10%,X7R,A3A   I476 @BASEBOARD_FAB2_LIB.BASEBOARD_FAB2(SCH_1):PAGE107

P3E_CPU0_PE1_SS_C_TXN<2> @BASEBOARD_FAB2_LIB.BASEBOARD_FAB2(SCH_1):P3E_CPU0_PE1_SS_C_TXN(2)
  J8G1  133  IO133 SCONN200_H68296001_SM-CONN,H68A    I78 @BASEBOARD_FAB2_LIB.BASEBOARD_FAB2(SCH_1):PAGE109
 C3P21    2      B CAP_0402-0.22UF,16V,10%,X7R,A3A   I480 @BASEBOARD_FAB2_LIB.BASEBOARD_FAB2(SCH_1):PAGE107

P3E_CPU0_PE1_SS_C_TXN<3> @BASEBOARD_FAB2_LIB.BASEBOARD_FAB2(SCH_1):P3E_CPU0_PE1_SS_C_TXN(3)
  J8G1  127  IO127 SCONN200_H68296001_SM-CONN,H68A    I78 @BASEBOARD_FAB2_LIB.BASEBOARD_FAB2(SCH_1):PAGE109
 C3P24    2      B CAP_0402-0.22UF,16V,10%,X7R,A3A   I479 @BASEBOARD_FAB2_LIB.BASEBOARD_FAB2(SCH_1):PAGE107

P3E_CPU0_PE1_SS_C_TXN<4> @BASEBOARD_FAB2_LIB.BASEBOARD_FAB2(SCH_1):P3E_CPU0_PE1_SS_C_TXN(4)
  J8G1  121  IO121 SCONN200_H68296001_SM-CONN,H68A    I78 @BASEBOARD_FAB2_LIB.BASEBOARD_FAB2(SCH_1):PAGE109
 C3P29    2      B CAP_0402-0.22UF,16V,10%,X7R,A3A   I478 @BASEBOARD_FAB2_LIB.BASEBOARD_FAB2(SCH_1):PAGE107

P3E_CPU0_PE1_SS_C_TXN<5> @BASEBOARD_FAB2_LIB.BASEBOARD_FAB2(SCH_1):P3E_CPU0_PE1_SS_C_TXN(5)
  J8G1  115  IO115 SCONN200_H68296001_SM-CONN,H68A    I78 @BASEBOARD_FAB2_LIB.BASEBOARD_FAB2(SCH_1):PAGE109
 C3P33    2      B CAP_0402-0.22UF,16V,10%,X7R,A3A   I477 @BASEBOARD_FAB2_LIB.BASEBOARD_FAB2(SCH_1):PAGE107

P3E_CPU0_PE1_SS_C_TXN<6> @BASEBOARD_FAB2_LIB.BASEBOARD_FAB2(SCH_1):P3E_CPU0_PE1_SS_C_TXN(6)
  J8G1  109  IO109 SCONN200_H68296001_SM-CONN,H68A    I78 @BASEBOARD_FAB2_LIB.BASEBOARD_FAB2(SCH_1):PAGE109
 C3P36    2      B CAP_0402-0.22UF,16V,10%,X7R,A3A   I475 @BASEBOARD_FAB2_LIB.BASEBOARD_FAB2(SCH_1):PAGE107

P3E_CPU0_PE1_SS_C_TXN<7> @BASEBOARD_FAB2_LIB.BASEBOARD_FAB2(SCH_1):P3E_CPU0_PE1_SS_C_TXN(7)
  J8G1  105  IO105 SCONN200_H68296001_SM-CONN,H68A    I78 @BASEBOARD_FAB2_LIB.BASEBOARD_FAB2(SCH_1):PAGE109
 C3P41    2      B CAP_0402-0.22UF,16V,10%,X7R,A3A   I474 @BASEBOARD_FAB2_LIB.BASEBOARD_FAB2(SCH_1):PAGE107

P3E_CPU0_PE1_SS_C_TXP<0> @BASEBOARD_FAB2_LIB.BASEBOARD_FAB2(SCH_1):P3E_CPU0_PE1_SS_C_TXP(0)
  J8G1  147  IO147 SCONN200_H68296001_SM-CONN,H68A    I78 @BASEBOARD_FAB2_LIB.BASEBOARD_FAB2(SCH_1):PAGE109
 C3P10    2      B CAP_0402-0.22UF,16V,10%,X7R,A3A   I482 @BASEBOARD_FAB2_LIB.BASEBOARD_FAB2(SCH_1):PAGE107

P3E_CPU0_PE1_SS_C_TXP<1> @BASEBOARD_FAB2_LIB.BASEBOARD_FAB2(SCH_1):P3E_CPU0_PE1_SS_C_TXP(1)
  J8G1  141  IO141 SCONN200_H68296001_SM-CONN,H68A    I78 @BASEBOARD_FAB2_LIB.BASEBOARD_FAB2(SCH_1):PAGE109
 C3P14    2      B CAP_0402-0.22UF,16V,10%,X7R,A3A   I483 @BASEBOARD_FAB2_LIB.BASEBOARD_FAB2(SCH_1):PAGE107

P3E_CPU0_PE1_SS_C_TXP<2> @BASEBOARD_FAB2_LIB.BASEBOARD_FAB2(SCH_1):P3E_CPU0_PE1_SS_C_TXP(2)
  J8G1  135  IO135 SCONN200_H68296001_SM-CONN,H68A    I78 @BASEBOARD_FAB2_LIB.BASEBOARD_FAB2(SCH_1):PAGE109
 C3P19    2      B CAP_0402-0.22UF,16V,10%,X7R,A3A   I485 @BASEBOARD_FAB2_LIB.BASEBOARD_FAB2(SCH_1):PAGE107

P3E_CPU0_PE1_SS_C_TXP<3> @BASEBOARD_FAB2_LIB.BASEBOARD_FAB2(SCH_1):P3E_CPU0_PE1_SS_C_TXP(3)
  J8G1  129  IO129 SCONN200_H68296001_SM-CONN,H68A    I78 @BASEBOARD_FAB2_LIB.BASEBOARD_FAB2(SCH_1):PAGE109
 C3P22    2      B CAP_0402-0.22UF,16V,10%,X7R,A3A   I484 @BASEBOARD_FAB2_LIB.BASEBOARD_FAB2(SCH_1):PAGE107

P3E_CPU0_PE1_SS_C_TXP<4> @BASEBOARD_FAB2_LIB.BASEBOARD_FAB2(SCH_1):P3E_CPU0_PE1_SS_C_TXP(4)
  J8G1  123  IO123 SCONN200_H68296001_SM-CONN,H68A    I78 @BASEBOARD_FAB2_LIB.BASEBOARD_FAB2(SCH_1):PAGE109
 C3P26    2      B CAP_0402-0.22UF,16V,10%,X7R,A3A   I487 @BASEBOARD_FAB2_LIB.BASEBOARD_FAB2(SCH_1):PAGE107

P3E_CPU0_PE1_SS_C_TXP<5> @BASEBOARD_FAB2_LIB.BASEBOARD_FAB2(SCH_1):P3E_CPU0_PE1_SS_C_TXP(5)
  J8G1  117  IO117 SCONN200_H68296001_SM-CONN,H68A    I78 @BASEBOARD_FAB2_LIB.BASEBOARD_FAB2(SCH_1):PAGE109
 C3P31    2      B CAP_0402-0.22UF,16V,10%,X7R,A3A   I488 @BASEBOARD_FAB2_LIB.BASEBOARD_FAB2(SCH_1):PAGE107

P3E_CPU0_PE1_SS_C_TXP<6> @BASEBOARD_FAB2_LIB.BASEBOARD_FAB2(SCH_1):P3E_CPU0_PE1_SS_C_TXP(6)
  J8G1  111  IO111 SCONN200_H68296001_SM-CONN,H68A    I78 @BASEBOARD_FAB2_LIB.BASEBOARD_FAB2(SCH_1):PAGE109
 C3P34    2      B CAP_0402-0.22UF,16V,10%,X7R,A3A   I489 @BASEBOARD_FAB2_LIB.BASEBOARD_FAB2(SCH_1):PAGE107

P3E_CPU0_PE1_SS_C_TXP<7> @BASEBOARD_FAB2_LIB.BASEBOARD_FAB2(SCH_1):P3E_CPU0_PE1_SS_C_TXP(7)
  J8G1  103  IO103 SCONN200_H68296001_SM-CONN,H68A    I78 @BASEBOARD_FAB2_LIB.BASEBOARD_FAB2(SCH_1):PAGE109
 C3P38    2      B CAP_0402-0.22UF,16V,10%,X7R,A3A   I486 @BASEBOARD_FAB2_LIB.BASEBOARD_FAB2(SCH_1):PAGE107

P3E_CPU0_PE1_SS_RXN<0> @BASEBOARD_FAB2_LIB.BASEBOARD_FAB2(SCH_1):P3E_CPU0_PE1_SS_RXN(0)
  U5D1  CW8 PE1_RX_DN<0> SKX_EXT_B_BGA1-IC,TBD    I84 @BASEBOARD_FAB2_LIB.BASEBOARD_FAB2(SCH_1):PAGE30
  C2U4    2      B CAP_0402-0.22UF,16V,10%,X7R,A3A   I257 @BASEBOARD_FAB2_LIB.BASEBOARD_FAB2(SCH_1):PAGE107
 R2U15    1      A RES_0402-0.0,5%,1/16W,CHIP,G21A   I490 @BASEBOARD_FAB2_LIB.BASEBOARD_FAB2(SCH_1):PAGE107

P3E_CPU0_PE1_SS_RXN<1> @BASEBOARD_FAB2_LIB.BASEBOARD_FAB2(SCH_1):P3E_CPU0_PE1_SS_RXN(1)
  U5D1  DA8 PE1_RX_DN<1> SKX_EXT_B_BGA1-IC,TBD    I84 @BASEBOARD_FAB2_LIB.BASEBOARD_FAB2(SCH_1):PAGE30
  C2U6    2      B CAP_0402-0.22UF,16V,10%,X7R,A3A   I260 @BASEBOARD_FAB2_LIB.BASEBOARD_FAB2(SCH_1):PAGE107
 R2U17    1      A RES_0402-0.0,5%,1/16W,CHIP,G21A   I492 @BASEBOARD_FAB2_LIB.BASEBOARD_FAB2(SCH_1):PAGE107

P3E_CPU0_PE1_SS_RXN<2> @BASEBOARD_FAB2_LIB.BASEBOARD_FAB2(SCH_1):P3E_CPU0_PE1_SS_RXN(2)
  U5D1  DC8 PE1_RX_DN<2> SKX_EXT_B_BGA1-IC,TBD    I84 @BASEBOARD_FAB2_LIB.BASEBOARD_FAB2(SCH_1):PAGE30
  C2U8    2      B CAP_0402-0.22UF,16V,10%,X7R,A3A   I264 @BASEBOARD_FAB2_LIB.BASEBOARD_FAB2(SCH_1):PAGE107
 R2U19    1      A RES_0402-0.0,5%,1/16W,CHIP,G21A   I493 @BASEBOARD_FAB2_LIB.BASEBOARD_FAB2(SCH_1):PAGE107

P3E_CPU0_PE1_SS_RXN<3> @BASEBOARD_FAB2_LIB.BASEBOARD_FAB2(SCH_1):P3E_CPU0_PE1_SS_RXN(3)
  U5D1 DC10 PE1_RX_DN<3> SKX_EXT_B_BGA1-IC,TBD    I84 @BASEBOARD_FAB2_LIB.BASEBOARD_FAB2(SCH_1):PAGE30
 C2U10    2      B CAP_0402-0.22UF,16V,10%,X7R,A3A   I267 @BASEBOARD_FAB2_LIB.BASEBOARD_FAB2(SCH_1):PAGE107
 R2U21    1      A RES_0402-0.0,5%,1/16W,CHIP,G21A   I491 @BASEBOARD_FAB2_LIB.BASEBOARD_FAB2(SCH_1):PAGE107

P3E_CPU0_PE1_SS_RXN<4> @BASEBOARD_FAB2_LIB.BASEBOARD_FAB2(SCH_1):P3E_CPU0_PE1_SS_RXN(4)
  U5D1 DE10 PE1_RX_DN<4> SKX_EXT_B_BGA1-IC,TBD    I84 @BASEBOARD_FAB2_LIB.BASEBOARD_FAB2(SCH_1):PAGE30
 C2U12    2      B CAP_0402-0.22UF,16V,10%,X7R,A3A   I265 @BASEBOARD_FAB2_LIB.BASEBOARD_FAB2(SCH_1):PAGE107
 R2U23    1      A RES_0402-0.0,5%,1/16W,CHIP,G21A   I495 @BASEBOARD_FAB2_LIB.BASEBOARD_FAB2(SCH_1):PAGE107

P3E_CPU0_PE1_SS_RXN<5> @BASEBOARD_FAB2_LIB.BASEBOARD_FAB2(SCH_1):P3E_CPU0_PE1_SS_RXN(5)
  U5D1  DH9 PE1_RX_DN<5> SKX_EXT_B_BGA1-IC,TBD    I84 @BASEBOARD_FAB2_LIB.BASEBOARD_FAB2(SCH_1):PAGE30
 C2U14    2      B CAP_0402-0.22UF,16V,10%,X7R,A3A   I287 @BASEBOARD_FAB2_LIB.BASEBOARD_FAB2(SCH_1):PAGE107
 R2U25    1      A RES_0402-0.0,5%,1/16W,CHIP,G21A   I496 @BASEBOARD_FAB2_LIB.BASEBOARD_FAB2(SCH_1):PAGE107

P3E_CPU0_PE1_SS_RXN<6> @BASEBOARD_FAB2_LIB.BASEBOARD_FAB2(SCH_1):P3E_CPU0_PE1_SS_RXN(6)
  U5D1  DK9 PE1_RX_DN<6> SKX_EXT_B_BGA1-IC,TBD    I84 @BASEBOARD_FAB2_LIB.BASEBOARD_FAB2(SCH_1):PAGE30
 C2U16    2      B CAP_0402-0.22UF,16V,10%,X7R,A3A   I286 @BASEBOARD_FAB2_LIB.BASEBOARD_FAB2(SCH_1):PAGE107
 R2U27    1      A RES_0402-0.0,5%,1/16W,CHIP,G21A   I497 @BASEBOARD_FAB2_LIB.BASEBOARD_FAB2(SCH_1):PAGE107

P3E_CPU0_PE1_SS_RXN<7> @BASEBOARD_FAB2_LIB.BASEBOARD_FAB2(SCH_1):P3E_CPU0_PE1_SS_RXN(7)
  U5D1  DM9 PE1_RX_DN<7> SKX_EXT_B_BGA1-IC,TBD    I84 @BASEBOARD_FAB2_LIB.BASEBOARD_FAB2(SCH_1):PAGE30
 C2U18    2      B CAP_0402-0.22UF,16V,10%,X7R,A3A   I294 @BASEBOARD_FAB2_LIB.BASEBOARD_FAB2(SCH_1):PAGE107
 R2U29    1      A RES_0402-0.0,5%,1/16W,CHIP,G21A   I494 @BASEBOARD_FAB2_LIB.BASEBOARD_FAB2(SCH_1):PAGE107

P3E_CPU0_PE1_SS_RXP<0> @BASEBOARD_FAB2_LIB.BASEBOARD_FAB2(SCH_1):P3E_CPU0_PE1_SS_RXP(0)
  U5D1  CU8 PE1_RX_DP<0> SKX_EXT_B_BGA1-IC,TBD    I84 @BASEBOARD_FAB2_LIB.BASEBOARD_FAB2(SCH_1):PAGE30
  C2U3    2      B CAP_0402-0.22UF,16V,10%,X7R,A3A   I272 @BASEBOARD_FAB2_LIB.BASEBOARD_FAB2(SCH_1):PAGE107
 R2U14    1      A RES_0402-0.0,5%,1/16W,CHIP,G21A   I499 @BASEBOARD_FAB2_LIB.BASEBOARD_FAB2(SCH_1):PAGE107

P3E_CPU0_PE1_SS_RXP<1> @BASEBOARD_FAB2_LIB.BASEBOARD_FAB2(SCH_1):P3E_CPU0_PE1_SS_RXP(1)
  U5D1  CY7 PE1_RX_DP<1> SKX_EXT_B_BGA1-IC,TBD    I84 @BASEBOARD_FAB2_LIB.BASEBOARD_FAB2(SCH_1):PAGE30
  C2U5    2      B CAP_0402-0.22UF,16V,10%,X7R,A3A   I274 @BASEBOARD_FAB2_LIB.BASEBOARD_FAB2(SCH_1):PAGE107
 R2U16    1      A RES_0402-0.0,5%,1/16W,CHIP,G21A   I501 @BASEBOARD_FAB2_LIB.BASEBOARD_FAB2(SCH_1):PAGE107

P3E_CPU0_PE1_SS_RXP<2> @BASEBOARD_FAB2_LIB.BASEBOARD_FAB2(SCH_1):P3E_CPU0_PE1_SS_RXP(2)
  U5D1  DB9 PE1_RX_DP<2> SKX_EXT_B_BGA1-IC,TBD    I84 @BASEBOARD_FAB2_LIB.BASEBOARD_FAB2(SCH_1):PAGE30
  C2U7    2      B CAP_0402-0.22UF,16V,10%,X7R,A3A   I277 @BASEBOARD_FAB2_LIB.BASEBOARD_FAB2(SCH_1):PAGE107
 R2U18    1      A RES_0402-0.0,5%,1/16W,CHIP,G21A   I502 @BASEBOARD_FAB2_LIB.BASEBOARD_FAB2(SCH_1):PAGE107

P3E_CPU0_PE1_SS_RXP<3> @BASEBOARD_FAB2_LIB.BASEBOARD_FAB2(SCH_1):P3E_CPU0_PE1_SS_RXP(3)
  U5D1 DA10 PE1_RX_DP<3> SKX_EXT_B_BGA1-IC,TBD    I84 @BASEBOARD_FAB2_LIB.BASEBOARD_FAB2(SCH_1):PAGE30
  C2U9    2      B CAP_0402-0.22UF,16V,10%,X7R,A3A   I279 @BASEBOARD_FAB2_LIB.BASEBOARD_FAB2(SCH_1):PAGE107
 R2U20    1      A RES_0402-0.0,5%,1/16W,CHIP,G21A   I503 @BASEBOARD_FAB2_LIB.BASEBOARD_FAB2(SCH_1):PAGE107

P3E_CPU0_PE1_SS_RXP<4> @BASEBOARD_FAB2_LIB.BASEBOARD_FAB2(SCH_1):P3E_CPU0_PE1_SS_RXP(4)
  U5D1  DD9 PE1_RX_DP<4> SKX_EXT_B_BGA1-IC,TBD    I84 @BASEBOARD_FAB2_LIB.BASEBOARD_FAB2(SCH_1):PAGE30
 C2U11    2      B CAP_0402-0.22UF,16V,10%,X7R,A3A   I278 @BASEBOARD_FAB2_LIB.BASEBOARD_FAB2(SCH_1):PAGE107
 R2U22    1      A RES_0402-0.0,5%,1/16W,CHIP,G21A   I504 @BASEBOARD_FAB2_LIB.BASEBOARD_FAB2(SCH_1):PAGE107

P3E_CPU0_PE1_SS_RXP<5> @BASEBOARD_FAB2_LIB.BASEBOARD_FAB2(SCH_1):P3E_CPU0_PE1_SS_RXP(5)
  U5D1  DF9 PE1_RX_DP<5> SKX_EXT_B_BGA1-IC,TBD    I84 @BASEBOARD_FAB2_LIB.BASEBOARD_FAB2(SCH_1):PAGE30
 C2U13    2      B CAP_0402-0.22UF,16V,10%,X7R,A3A   I297 @BASEBOARD_FAB2_LIB.BASEBOARD_FAB2(SCH_1):PAGE107
 R2U24    1      A RES_0402-0.0,5%,1/16W,CHIP,G21A   I505 @BASEBOARD_FAB2_LIB.BASEBOARD_FAB2(SCH_1):PAGE107

P3E_CPU0_PE1_SS_RXP<6> @BASEBOARD_FAB2_LIB.BASEBOARD_FAB2(SCH_1):P3E_CPU0_PE1_SS_RXP(6)
  U5D1  DJ8 PE1_RX_DP<6> SKX_EXT_B_BGA1-IC,TBD    I84 @BASEBOARD_FAB2_LIB.BASEBOARD_FAB2(SCH_1):PAGE30
 C2U15    2      B CAP_0402-0.22UF,16V,10%,X7R,A3A   I296 @BASEBOARD_FAB2_LIB.BASEBOARD_FAB2(SCH_1):PAGE107
 R2U26    1      A RES_0402-0.0,5%,1/16W,CHIP,G21A   I498 @BASEBOARD_FAB2_LIB.BASEBOARD_FAB2(SCH_1):PAGE107

P3E_CPU0_PE1_SS_RXP<7> @BASEBOARD_FAB2_LIB.BASEBOARD_FAB2(SCH_1):P3E_CPU0_PE1_SS_RXP(7)
  U5D1 DL10 PE1_RX_DP<7> SKX_EXT_B_BGA1-IC,TBD    I84 @BASEBOARD_FAB2_LIB.BASEBOARD_FAB2(SCH_1):PAGE30
 C2U17    2      B CAP_0402-0.22UF,16V,10%,X7R,A3A   I300 @BASEBOARD_FAB2_LIB.BASEBOARD_FAB2(SCH_1):PAGE107
 R2U28    1      A RES_0402-0.0,5%,1/16W,CHIP,G21A   I500 @BASEBOARD_FAB2_LIB.BASEBOARD_FAB2(SCH_1):PAGE107

P3E_CPU0_PE1_SS_R_RXN<0> @BASEBOARD_FAB2_LIB.BASEBOARD_FAB2(SCH_1):P3E_CPU0_PE1_SS_R_RXN(0)
  J8G1  148  IO148 SCONN200_H68296001_SM-CONN,H68A    I78 @BASEBOARD_FAB2_LIB.BASEBOARD_FAB2(SCH_1):PAGE109
 R2U15    2      B RES_0402-0.0,5%,1/16W,CHIP,G21A   I490 @BASEBOARD_FAB2_LIB.BASEBOARD_FAB2(SCH_1):PAGE107

P3E_CPU0_PE1_SS_R_RXN<1> @BASEBOARD_FAB2_LIB.BASEBOARD_FAB2(SCH_1):P3E_CPU0_PE1_SS_R_RXN(1)
  J8G1  142  IO142 SCONN200_H68296001_SM-CONN,H68A    I78 @BASEBOARD_FAB2_LIB.BASEBOARD_FAB2(SCH_1):PAGE109
 R2U17    2      B RES_0402-0.0,5%,1/16W,CHIP,G21A   I492 @BASEBOARD_FAB2_LIB.BASEBOARD_FAB2(SCH_1):PAGE107

P3E_CPU0_PE1_SS_R_RXN<2> @BASEBOARD_FAB2_LIB.BASEBOARD_FAB2(SCH_1):P3E_CPU0_PE1_SS_R_RXN(2)
  J8G1  136  IO136 SCONN200_H68296001_SM-CONN,H68A    I78 @BASEBOARD_FAB2_LIB.BASEBOARD_FAB2(SCH_1):PAGE109
 R2U19    2      B RES_0402-0.0,5%,1/16W,CHIP,G21A   I493 @BASEBOARD_FAB2_LIB.BASEBOARD_FAB2(SCH_1):PAGE107

P3E_CPU0_PE1_SS_R_RXN<3> @BASEBOARD_FAB2_LIB.BASEBOARD_FAB2(SCH_1):P3E_CPU0_PE1_SS_R_RXN(3)
  J8G1  130  IO130 SCONN200_H68296001_SM-CONN,H68A    I78 @BASEBOARD_FAB2_LIB.BASEBOARD_FAB2(SCH_1):PAGE109
 R2U21    2      B RES_0402-0.0,5%,1/16W,CHIP,G21A   I491 @BASEBOARD_FAB2_LIB.BASEBOARD_FAB2(SCH_1):PAGE107

P3E_CPU0_PE1_SS_R_RXN<4> @BASEBOARD_FAB2_LIB.BASEBOARD_FAB2(SCH_1):P3E_CPU0_PE1_SS_R_RXN(4)
  J8G1  124  IO124 SCONN200_H68296001_SM-CONN,H68A    I78 @BASEBOARD_FAB2_LIB.BASEBOARD_FAB2(SCH_1):PAGE109
 R2U23    2      B RES_0402-0.0,5%,1/16W,CHIP,G21A   I495 @BASEBOARD_FAB2_LIB.BASEBOARD_FAB2(SCH_1):PAGE107

P3E_CPU0_PE1_SS_R_RXN<5> @BASEBOARD_FAB2_LIB.BASEBOARD_FAB2(SCH_1):P3E_CPU0_PE1_SS_R_RXN(5)
  J8G1  118  IO118 SCONN200_H68296001_SM-CONN,H68A    I78 @BASEBOARD_FAB2_LIB.BASEBOARD_FAB2(SCH_1):PAGE109
 R2U25    2      B RES_0402-0.0,5%,1/16W,CHIP,G21A   I496 @BASEBOARD_FAB2_LIB.BASEBOARD_FAB2(SCH_1):PAGE107

P3E_CPU0_PE1_SS_R_RXN<6> @BASEBOARD_FAB2_LIB.BASEBOARD_FAB2(SCH_1):P3E_CPU0_PE1_SS_R_RXN(6)
  J8G1  112  IO112 SCONN200_H68296001_SM-CONN,H68A    I78 @BASEBOARD_FAB2_LIB.BASEBOARD_FAB2(SCH_1):PAGE109
 R2U27    2      B RES_0402-0.0,5%,1/16W,CHIP,G21A   I497 @BASEBOARD_FAB2_LIB.BASEBOARD_FAB2(SCH_1):PAGE107

P3E_CPU0_PE1_SS_R_RXN<7> @BASEBOARD_FAB2_LIB.BASEBOARD_FAB2(SCH_1):P3E_CPU0_PE1_SS_R_RXN(7)
  J8G1  106  IO106 SCONN200_H68296001_SM-CONN,H68A    I78 @BASEBOARD_FAB2_LIB.BASEBOARD_FAB2(SCH_1):PAGE109
 R2U29    2      B RES_0402-0.0,5%,1/16W,CHIP,G21A   I494 @BASEBOARD_FAB2_LIB.BASEBOARD_FAB2(SCH_1):PAGE107

P3E_CPU0_PE1_SS_R_RXP<0> @BASEBOARD_FAB2_LIB.BASEBOARD_FAB2(SCH_1):P3E_CPU0_PE1_SS_R_RXP(0)
  J8G1  150  IO150 SCONN200_H68296001_SM-CONN,H68A    I78 @BASEBOARD_FAB2_LIB.BASEBOARD_FAB2(SCH_1):PAGE109
 R2U14    2      B RES_0402-0.0,5%,1/16W,CHIP,G21A   I499 @BASEBOARD_FAB2_LIB.BASEBOARD_FAB2(SCH_1):PAGE107

P3E_CPU0_PE1_SS_R_RXP<1> @BASEBOARD_FAB2_LIB.BASEBOARD_FAB2(SCH_1):P3E_CPU0_PE1_SS_R_RXP(1)
  J8G1  144  IO144 SCONN200_H68296001_SM-CONN,H68A    I78 @BASEBOARD_FAB2_LIB.BASEBOARD_FAB2(SCH_1):PAGE109
 R2U16    2      B RES_0402-0.0,5%,1/16W,CHIP,G21A   I501 @BASEBOARD_FAB2_LIB.BASEBOARD_FAB2(SCH_1):PAGE107

P3E_CPU0_PE1_SS_R_RXP<2> @BASEBOARD_FAB2_LIB.BASEBOARD_FAB2(SCH_1):P3E_CPU0_PE1_SS_R_RXP(2)
  J8G1  138  IO138 SCONN200_H68296001_SM-CONN,H68A    I78 @BASEBOARD_FAB2_LIB.BASEBOARD_FAB2(SCH_1):PAGE109
 R2U18    2      B RES_0402-0.0,5%,1/16W,CHIP,G21A   I502 @BASEBOARD_FAB2_LIB.BASEBOARD_FAB2(SCH_1):PAGE107

P3E_CPU0_PE1_SS_R_RXP<3> @BASEBOARD_FAB2_LIB.BASEBOARD_FAB2(SCH_1):P3E_CPU0_PE1_SS_R_RXP(3)
  J8G1  132  IO132 SCONN200_H68296001_SM-CONN,H68A    I78 @BASEBOARD_FAB2_LIB.BASEBOARD_FAB2(SCH_1):PAGE109
 R2U20    2      B RES_0402-0.0,5%,1/16W,CHIP,G21A   I503 @BASEBOARD_FAB2_LIB.BASEBOARD_FAB2(SCH_1):PAGE107

P3E_CPU0_PE1_SS_R_RXP<4> @BASEBOARD_FAB2_LIB.BASEBOARD_FAB2(SCH_1):P3E_CPU0_PE1_SS_R_RXP(4)
  J8G1  126  IO126 SCONN200_H68296001_SM-CONN,H68A    I78 @BASEBOARD_FAB2_LIB.BASEBOARD_FAB2(SCH_1):PAGE109
 R2U22    2      B RES_0402-0.0,5%,1/16W,CHIP,G21A   I504 @BASEBOARD_FAB2_LIB.BASEBOARD_FAB2(SCH_1):PAGE107

P3E_CPU0_PE1_SS_R_RXP<5> @BASEBOARD_FAB2_LIB.BASEBOARD_FAB2(SCH_1):P3E_CPU0_PE1_SS_R_RXP(5)
  J8G1  120  IO120 SCONN200_H68296001_SM-CONN,H68A    I78 @BASEBOARD_FAB2_LIB.BASEBOARD_FAB2(SCH_1):PAGE109
 R2U24    2      B RES_0402-0.0,5%,1/16W,CHIP,G21A   I505 @BASEBOARD_FAB2_LIB.BASEBOARD_FAB2(SCH_1):PAGE107

P3E_CPU0_PE1_SS_R_RXP<6> @BASEBOARD_FAB2_LIB.BASEBOARD_FAB2(SCH_1):P3E_CPU0_PE1_SS_R_RXP(6)
  J8G1  114  IO114 SCONN200_H68296001_SM-CONN,H68A    I78 @BASEBOARD_FAB2_LIB.BASEBOARD_FAB2(SCH_1):PAGE109
 R2U26    2      B RES_0402-0.0,5%,1/16W,CHIP,G21A   I498 @BASEBOARD_FAB2_LIB.BASEBOARD_FAB2(SCH_1):PAGE107

P3E_CPU0_PE1_SS_R_RXP<7> @BASEBOARD_FAB2_LIB.BASEBOARD_FAB2(SCH_1):P3E_CPU0_PE1_SS_R_RXP(7)
  J8G1  108  IO108 SCONN200_H68296001_SM-CONN,H68A    I78 @BASEBOARD_FAB2_LIB.BASEBOARD_FAB2(SCH_1):PAGE109
 R2U28    2      B RES_0402-0.0,5%,1/16W,CHIP,G21A   I500 @BASEBOARD_FAB2_LIB.BASEBOARD_FAB2(SCH_1):PAGE107

P3E_CPU0_PE1_SS_TXN<0> @BASEBOARD_FAB2_LIB.BASEBOARD_FAB2(SCH_1):P3E_CPU0_PE1_SS_TXN(0)
  U5D1  DA2 PE1_TX_DN<0> SKX_EXT_B_BGA1-IC,TBD    I84 @BASEBOARD_FAB2_LIB.BASEBOARD_FAB2(SCH_1):PAGE30
 C3P13    1      A CAP_0402-0.22UF,16V,10%,X7R,A3A   I207 @BASEBOARD_FAB2_LIB.BASEBOARD_FAB2(SCH_1):PAGE107
 C3P12    1      A CAP_0402-0.22UF,16V,10%,X7R,A3A   I481 @BASEBOARD_FAB2_LIB.BASEBOARD_FAB2(SCH_1):PAGE107

P3E_CPU0_PE1_SS_TXN<1> @BASEBOARD_FAB2_LIB.BASEBOARD_FAB2(SCH_1):P3E_CPU0_PE1_SS_TXN(1)
  U5D1  DC2 PE1_TX_DN<1> SKX_EXT_B_BGA1-IC,TBD    I84 @BASEBOARD_FAB2_LIB.BASEBOARD_FAB2(SCH_1):PAGE30
 C3P17    1      A CAP_0402-0.22UF,16V,10%,X7R,A3A   I208 @BASEBOARD_FAB2_LIB.BASEBOARD_FAB2(SCH_1):PAGE107
 C3P16    1      A CAP_0402-0.22UF,16V,10%,X7R,A3A   I476 @BASEBOARD_FAB2_LIB.BASEBOARD_FAB2(SCH_1):PAGE107

P3E_CPU0_PE1_SS_TXN<2> @BASEBOARD_FAB2_LIB.BASEBOARD_FAB2(SCH_1):P3E_CPU0_PE1_SS_TXN(2)
  U5D1  DE2 PE1_TX_DN<2> SKX_EXT_B_BGA1-IC,TBD    I84 @BASEBOARD_FAB2_LIB.BASEBOARD_FAB2(SCH_1):PAGE30
 C3P20    1      A CAP_0402-0.22UF,16V,10%,X7R,A3A   I215 @BASEBOARD_FAB2_LIB.BASEBOARD_FAB2(SCH_1):PAGE107
 C3P21    1      A CAP_0402-0.22UF,16V,10%,X7R,A3A   I480 @BASEBOARD_FAB2_LIB.BASEBOARD_FAB2(SCH_1):PAGE107

P3E_CPU0_PE1_SS_TXN<3> @BASEBOARD_FAB2_LIB.BASEBOARD_FAB2(SCH_1):P3E_CPU0_PE1_SS_TXN(3)
  U5D1  DE4 PE1_TX_DN<3> SKX_EXT_B_BGA1-IC,TBD    I84 @BASEBOARD_FAB2_LIB.BASEBOARD_FAB2(SCH_1):PAGE30
 C3P25    1      A CAP_0402-0.22UF,16V,10%,X7R,A3A   I216 @BASEBOARD_FAB2_LIB.BASEBOARD_FAB2(SCH_1):PAGE107
 C3P24    1      A CAP_0402-0.22UF,16V,10%,X7R,A3A   I479 @BASEBOARD_FAB2_LIB.BASEBOARD_FAB2(SCH_1):PAGE107

P3E_CPU0_PE1_SS_TXN<4> @BASEBOARD_FAB2_LIB.BASEBOARD_FAB2(SCH_1):P3E_CPU0_PE1_SS_TXN(4)
  U5D1  DG4 PE1_TX_DN<4> SKX_EXT_B_BGA1-IC,TBD    I84 @BASEBOARD_FAB2_LIB.BASEBOARD_FAB2(SCH_1):PAGE30
 C3P28    1      A CAP_0402-0.22UF,16V,10%,X7R,A3A   I232 @BASEBOARD_FAB2_LIB.BASEBOARD_FAB2(SCH_1):PAGE107
 C3P29    1      A CAP_0402-0.22UF,16V,10%,X7R,A3A   I478 @BASEBOARD_FAB2_LIB.BASEBOARD_FAB2(SCH_1):PAGE107

P3E_CPU0_PE1_SS_TXN<5> @BASEBOARD_FAB2_LIB.BASEBOARD_FAB2(SCH_1):P3E_CPU0_PE1_SS_TXN(5)
  U5D1  DK3 PE1_TX_DN<5> SKX_EXT_B_BGA1-IC,TBD    I84 @BASEBOARD_FAB2_LIB.BASEBOARD_FAB2(SCH_1):PAGE30
 C3P32    1      A CAP_0402-0.22UF,16V,10%,X7R,A3A   I234 @BASEBOARD_FAB2_LIB.BASEBOARD_FAB2(SCH_1):PAGE107
 C3P33    1      A CAP_0402-0.22UF,16V,10%,X7R,A3A   I477 @BASEBOARD_FAB2_LIB.BASEBOARD_FAB2(SCH_1):PAGE107

P3E_CPU0_PE1_SS_TXN<6> @BASEBOARD_FAB2_LIB.BASEBOARD_FAB2(SCH_1):P3E_CPU0_PE1_SS_TXN(6)
  U5D1  DM3 PE1_TX_DN<6> SKX_EXT_B_BGA1-IC,TBD    I84 @BASEBOARD_FAB2_LIB.BASEBOARD_FAB2(SCH_1):PAGE30
 C3P37    1      A CAP_0402-0.22UF,16V,10%,X7R,A3A   I235 @BASEBOARD_FAB2_LIB.BASEBOARD_FAB2(SCH_1):PAGE107
 C3P36    1      A CAP_0402-0.22UF,16V,10%,X7R,A3A   I475 @BASEBOARD_FAB2_LIB.BASEBOARD_FAB2(SCH_1):PAGE107

P3E_CPU0_PE1_SS_TXN<7> @BASEBOARD_FAB2_LIB.BASEBOARD_FAB2(SCH_1):P3E_CPU0_PE1_SS_TXN(7)
  U5D1  DN4 PE1_TX_DN<7> SKX_EXT_B_BGA1-IC,TBD    I84 @BASEBOARD_FAB2_LIB.BASEBOARD_FAB2(SCH_1):PAGE30
 C3P40    1      A CAP_0402-0.22UF,16V,10%,X7R,A3A   I241 @BASEBOARD_FAB2_LIB.BASEBOARD_FAB2(SCH_1):PAGE107
 C3P41    1      A CAP_0402-0.22UF,16V,10%,X7R,A3A   I474 @BASEBOARD_FAB2_LIB.BASEBOARD_FAB2(SCH_1):PAGE107

P3E_CPU0_PE1_SS_TXP<0> @BASEBOARD_FAB2_LIB.BASEBOARD_FAB2(SCH_1):P3E_CPU0_PE1_SS_TXP(0)
  U5D1  CW2 PE1_TX_DP<0> SKX_EXT_B_BGA1-IC,TBD    I84 @BASEBOARD_FAB2_LIB.BASEBOARD_FAB2(SCH_1):PAGE30
 C3P11    1      A CAP_0402-0.22UF,16V,10%,X7R,A3A   I212 @BASEBOARD_FAB2_LIB.BASEBOARD_FAB2(SCH_1):PAGE107
 C3P10    1      A CAP_0402-0.22UF,16V,10%,X7R,A3A   I482 @BASEBOARD_FAB2_LIB.BASEBOARD_FAB2(SCH_1):PAGE107

P3E_CPU0_PE1_SS_TXP<1> @BASEBOARD_FAB2_LIB.BASEBOARD_FAB2(SCH_1):P3E_CPU0_PE1_SS_TXP(1)
  U5D1  DB1 PE1_TX_DP<1> SKX_EXT_B_BGA1-IC,TBD    I84 @BASEBOARD_FAB2_LIB.BASEBOARD_FAB2(SCH_1):PAGE30
 C3P15    1      A CAP_0402-0.22UF,16V,10%,X7R,A3A   I226 @BASEBOARD_FAB2_LIB.BASEBOARD_FAB2(SCH_1):PAGE107
 C3P14    1      A CAP_0402-0.22UF,16V,10%,X7R,A3A   I483 @BASEBOARD_FAB2_LIB.BASEBOARD_FAB2(SCH_1):PAGE107

P3E_CPU0_PE1_SS_TXP<2> @BASEBOARD_FAB2_LIB.BASEBOARD_FAB2(SCH_1):P3E_CPU0_PE1_SS_TXP(2)
  U5D1  DD3 PE1_TX_DP<2> SKX_EXT_B_BGA1-IC,TBD    I84 @BASEBOARD_FAB2_LIB.BASEBOARD_FAB2(SCH_1):PAGE30
 C3P18    1      A CAP_0402-0.22UF,16V,10%,X7R,A3A   I219 @BASEBOARD_FAB2_LIB.BASEBOARD_FAB2(SCH_1):PAGE107
 C3P19    1      A CAP_0402-0.22UF,16V,10%,X7R,A3A   I485 @BASEBOARD_FAB2_LIB.BASEBOARD_FAB2(SCH_1):PAGE107

P3E_CPU0_PE1_SS_TXP<3> @BASEBOARD_FAB2_LIB.BASEBOARD_FAB2(SCH_1):P3E_CPU0_PE1_SS_TXP(3)
  U5D1  DC4 PE1_TX_DP<3> SKX_EXT_B_BGA1-IC,TBD    I84 @BASEBOARD_FAB2_LIB.BASEBOARD_FAB2(SCH_1):PAGE30
 C3P23    1      A CAP_0402-0.22UF,16V,10%,X7R,A3A   I229 @BASEBOARD_FAB2_LIB.BASEBOARD_FAB2(SCH_1):PAGE107
 C3P22    1      A CAP_0402-0.22UF,16V,10%,X7R,A3A   I484 @BASEBOARD_FAB2_LIB.BASEBOARD_FAB2(SCH_1):PAGE107

P3E_CPU0_PE1_SS_TXP<4> @BASEBOARD_FAB2_LIB.BASEBOARD_FAB2(SCH_1):P3E_CPU0_PE1_SS_TXP(4)
  U5D1  DF3 PE1_TX_DP<4> SKX_EXT_B_BGA1-IC,TBD    I84 @BASEBOARD_FAB2_LIB.BASEBOARD_FAB2(SCH_1):PAGE30
 C3P27    1      A CAP_0402-0.22UF,16V,10%,X7R,A3A   I223 @BASEBOARD_FAB2_LIB.BASEBOARD_FAB2(SCH_1):PAGE107
 C3P26    1      A CAP_0402-0.22UF,16V,10%,X7R,A3A   I487 @BASEBOARD_FAB2_LIB.BASEBOARD_FAB2(SCH_1):PAGE107

P3E_CPU0_PE1_SS_TXP<5> @BASEBOARD_FAB2_LIB.BASEBOARD_FAB2(SCH_1):P3E_CPU0_PE1_SS_TXP(5)
  U5D1  DH3 PE1_TX_DP<5> SKX_EXT_B_BGA1-IC,TBD    I84 @BASEBOARD_FAB2_LIB.BASEBOARD_FAB2(SCH_1):PAGE30
 C3P30    1      A CAP_0402-0.22UF,16V,10%,X7R,A3A   I245 @BASEBOARD_FAB2_LIB.BASEBOARD_FAB2(SCH_1):PAGE107
 C3P31    1      A CAP_0402-0.22UF,16V,10%,X7R,A3A   I488 @BASEBOARD_FAB2_LIB.BASEBOARD_FAB2(SCH_1):PAGE107

P3E_CPU0_PE1_SS_TXP<6> @BASEBOARD_FAB2_LIB.BASEBOARD_FAB2(SCH_1):P3E_CPU0_PE1_SS_TXP(6)
  U5D1  DL2 PE1_TX_DP<6> SKX_EXT_B_BGA1-IC,TBD    I84 @BASEBOARD_FAB2_LIB.BASEBOARD_FAB2(SCH_1):PAGE30
 C3P35    1      A CAP_0402-0.22UF,16V,10%,X7R,A3A   I240 @BASEBOARD_FAB2_LIB.BASEBOARD_FAB2(SCH_1):PAGE107
 C3P34    1      A CAP_0402-0.22UF,16V,10%,X7R,A3A   I489 @BASEBOARD_FAB2_LIB.BASEBOARD_FAB2(SCH_1):PAGE107

P3E_CPU0_PE1_SS_TXP<7> @BASEBOARD_FAB2_LIB.BASEBOARD_FAB2(SCH_1):P3E_CPU0_PE1_SS_TXP(7)
  U5D1  DP3 PE1_TX_DP<7> SKX_EXT_B_BGA1-IC,TBD    I84 @BASEBOARD_FAB2_LIB.BASEBOARD_FAB2(SCH_1):PAGE30
 C3P39    1      A CAP_0402-0.22UF,16V,10%,X7R,A3A   I248 @BASEBOARD_FAB2_LIB.BASEBOARD_FAB2(SCH_1):PAGE107
 C3P38    1      A CAP_0402-0.22UF,16V,10%,X7R,A3A   I486 @BASEBOARD_FAB2_LIB.BASEBOARD_FAB2(SCH_1):PAGE107

P3E_CPU0_PE2_SS_C_TXN<0> @BASEBOARD_FAB2_LIB.BASEBOARD_FAB2(SCH_1):P3E_CPU0_PE2_SS_C_TXN(0)
 C8G10    2      B CAP_0402-0.22UF,16V,10%,X7R,A3A    I96 @BASEBOARD_FAB2_LIB.BASEBOARD_FAB2(SCH_1):PAGE105
  J8G1  151  IO151 SCONN200_H68296001_SM-CONN,H68A    I78 @BASEBOARD_FAB2_LIB.BASEBOARD_FAB2(SCH_1):PAGE109

P3E_CPU0_PE2_SS_C_TXN<10> @BASEBOARD_FAB2_LIB.BASEBOARD_FAB2(SCH_1):P3E_CPU0_PE2_SS_C_TXN(10)
 C7G16    2      B CAP_0402-0.22UF,16V,10%,X7R,A3A    I31 @BASEBOARD_FAB2_LIB.BASEBOARD_FAB2(SCH_1):PAGE105
 CONX8   15     15 SMC-CONN60A-22-GP_CONN-G7-SMC-A    I48 @BASEBOARD_FAB2_LIB.BASEBOARD_FAB2(SCH_1):PAGE245

P3E_CPU0_PE2_SS_C_TXN<11> @BASEBOARD_FAB2_LIB.BASEBOARD_FAB2(SCH_1):P3E_CPU0_PE2_SS_C_TXN(11)
 C7G13    2      B CAP_0402-0.22UF,16V,10%,X7R,A3A    I13 @BASEBOARD_FAB2_LIB.BASEBOARD_FAB2(SCH_1):PAGE105
 CONX8   23     23 SMC-CONN60A-22-GP_CONN-G7-SMC-A    I48 @BASEBOARD_FAB2_LIB.BASEBOARD_FAB2(SCH_1):PAGE245

P3E_CPU0_PE2_SS_C_TXN<12> @BASEBOARD_FAB2_LIB.BASEBOARD_FAB2(SCH_1):P3E_CPU0_PE2_SS_C_TXN(12)
 C7G12    2      B CAP_0402-0.22UF,16V,10%,X7R,A3A    I12 @BASEBOARD_FAB2_LIB.BASEBOARD_FAB2(SCH_1):PAGE105
 CONX8   27     27 SMC-CONN60A-22-GP_CONN-G7-SMC-A    I48 @BASEBOARD_FAB2_LIB.BASEBOARD_FAB2(SCH_1):PAGE245

P3E_CPU0_PE2_SS_C_TXN<13> @BASEBOARD_FAB2_LIB.BASEBOARD_FAB2(SCH_1):P3E_CPU0_PE2_SS_C_TXN(13)
 C7G10    2      B CAP_0402-0.22UF,16V,10%,X7R,A3A     I8 @BASEBOARD_FAB2_LIB.BASEBOARD_FAB2(SCH_1):PAGE105
 CONX8   33     33 SMC-CONN60A-22-GP_CONN-G7-SMC-A    I48 @BASEBOARD_FAB2_LIB.BASEBOARD_FAB2(SCH_1):PAGE245

P3E_CPU0_PE2_SS_C_TXN<14> @BASEBOARD_FAB2_LIB.BASEBOARD_FAB2(SCH_1):P3E_CPU0_PE2_SS_C_TXN(14)
  C7G7    2      B CAP_0402-0.22UF,16V,10%,X7R,A3A     I7 @BASEBOARD_FAB2_LIB.BASEBOARD_FAB2(SCH_1):PAGE105
 CONX8   41     41 SMC-CONN60A-22-GP_CONN-G7-SMC-A    I48 @BASEBOARD_FAB2_LIB.BASEBOARD_FAB2(SCH_1):PAGE245

P3E_CPU0_PE2_SS_C_TXN<15> @BASEBOARD_FAB2_LIB.BASEBOARD_FAB2(SCH_1):P3E_CPU0_PE2_SS_C_TXN(15)
  C7G6    2      B CAP_0402-0.22UF,16V,10%,X7R,A3A     I6 @BASEBOARD_FAB2_LIB.BASEBOARD_FAB2(SCH_1):PAGE105
 CONX8   45     45 SMC-CONN60A-22-GP_CONN-G7-SMC-A    I48 @BASEBOARD_FAB2_LIB.BASEBOARD_FAB2(SCH_1):PAGE245

P3E_CPU0_PE2_SS_C_TXN<1> @BASEBOARD_FAB2_LIB.BASEBOARD_FAB2(SCH_1):P3E_CPU0_PE2_SS_C_TXN(1)
  C8G7    2      B CAP_0402-0.22UF,16V,10%,X7R,A3A    I62 @BASEBOARD_FAB2_LIB.BASEBOARD_FAB2(SCH_1):PAGE105
  J8G1  159  IO159 SCONN200_H68296001_SM-CONN,H68A    I78 @BASEBOARD_FAB2_LIB.BASEBOARD_FAB2(SCH_1):PAGE109

P3E_CPU0_PE2_SS_C_TXN<2> @BASEBOARD_FAB2_LIB.BASEBOARD_FAB2(SCH_1):P3E_CPU0_PE2_SS_C_TXN(2)
  C8G6    2      B CAP_0402-0.22UF,16V,10%,X7R,A3A    I61 @BASEBOARD_FAB2_LIB.BASEBOARD_FAB2(SCH_1):PAGE105
  J8G1  163  IO163 SCONN200_H68296001_SM-CONN,H68A    I78 @BASEBOARD_FAB2_LIB.BASEBOARD_FAB2(SCH_1):PAGE109

P3E_CPU0_PE2_SS_C_TXN<3> @BASEBOARD_FAB2_LIB.BASEBOARD_FAB2(SCH_1):P3E_CPU0_PE2_SS_C_TXN(3)
  C8G4    2      B CAP_0402-0.22UF,16V,10%,X7R,A3A    I56 @BASEBOARD_FAB2_LIB.BASEBOARD_FAB2(SCH_1):PAGE105
  J8G1  169  IO169 SCONN200_H68296001_SM-CONN,H68A    I78 @BASEBOARD_FAB2_LIB.BASEBOARD_FAB2(SCH_1):PAGE109

P3E_CPU0_PE2_SS_C_TXN<4> @BASEBOARD_FAB2_LIB.BASEBOARD_FAB2(SCH_1):P3E_CPU0_PE2_SS_C_TXN(4)
  C8G2    2      B CAP_0402-0.22UF,16V,10%,X7R,A3A    I58 @BASEBOARD_FAB2_LIB.BASEBOARD_FAB2(SCH_1):PAGE105
  J8G1  175  IO175 SCONN200_H68296001_SM-CONN,H68A    I78 @BASEBOARD_FAB2_LIB.BASEBOARD_FAB2(SCH_1):PAGE109

P3E_CPU0_PE2_SS_C_TXN<5> @BASEBOARD_FAB2_LIB.BASEBOARD_FAB2(SCH_1):P3E_CPU0_PE2_SS_C_TXN(5)
 C7G26    2      B CAP_0402-0.22UF,16V,10%,X7R,A3A    I55 @BASEBOARD_FAB2_LIB.BASEBOARD_FAB2(SCH_1):PAGE105
  J8G1  181  IO181 SCONN200_H68296001_SM-CONN,H68A    I78 @BASEBOARD_FAB2_LIB.BASEBOARD_FAB2(SCH_1):PAGE109

P3E_CPU0_PE2_SS_C_TXN<6> @BASEBOARD_FAB2_LIB.BASEBOARD_FAB2(SCH_1):P3E_CPU0_PE2_SS_C_TXN(6)
 C7G24    2      B CAP_0402-0.22UF,16V,10%,X7R,A3A     I1 @BASEBOARD_FAB2_LIB.BASEBOARD_FAB2(SCH_1):PAGE105
  J8G1  187  IO187 SCONN200_H68296001_SM-CONN,H68A    I78 @BASEBOARD_FAB2_LIB.BASEBOARD_FAB2(SCH_1):PAGE109

P3E_CPU0_PE2_SS_C_TXN<7> @BASEBOARD_FAB2_LIB.BASEBOARD_FAB2(SCH_1):P3E_CPU0_PE2_SS_C_TXN(7)
 C7G22    2      B CAP_0402-0.22UF,16V,10%,X7R,A3A    I37 @BASEBOARD_FAB2_LIB.BASEBOARD_FAB2(SCH_1):PAGE105
  J8G1  193  IO193 SCONN200_H68296001_SM-CONN,H68A    I78 @BASEBOARD_FAB2_LIB.BASEBOARD_FAB2(SCH_1):PAGE109

P3E_CPU0_PE2_SS_C_TXN<8> @BASEBOARD_FAB2_LIB.BASEBOARD_FAB2(SCH_1):P3E_CPU0_PE2_SS_C_TXN(8)
 CONX8    3      3 SMC-CONN60A-22-GP_CONN-G7-SMC-A    I48 @BASEBOARD_FAB2_LIB.BASEBOARD_FAB2(SCH_1):PAGE245
 C7G19    2      B CAP_0402-0.22UF,16V,10%,X7R,A3A   I257 @BASEBOARD_FAB2_LIB.BASEBOARD_FAB2(SCH_1):PAGE105

P3E_CPU0_PE2_SS_C_TXN<9> @BASEBOARD_FAB2_LIB.BASEBOARD_FAB2(SCH_1):P3E_CPU0_PE2_SS_C_TXN(9)
 C7G18    2      B CAP_0402-0.22UF,16V,10%,X7R,A3A    I32 @BASEBOARD_FAB2_LIB.BASEBOARD_FAB2(SCH_1):PAGE105
 CONX8    9      9 SMC-CONN60A-22-GP_CONN-G7-SMC-A    I48 @BASEBOARD_FAB2_LIB.BASEBOARD_FAB2(SCH_1):PAGE245

P3E_CPU0_PE2_SS_C_TXP<0> @BASEBOARD_FAB2_LIB.BASEBOARD_FAB2(SCH_1):P3E_CPU0_PE2_SS_C_TXP(0)
  C8G9    2      B CAP_0402-0.22UF,16V,10%,X7R,A3A    I93 @BASEBOARD_FAB2_LIB.BASEBOARD_FAB2(SCH_1):PAGE105
  J8G1  153  IO153 SCONN200_H68296001_SM-CONN,H68A    I78 @BASEBOARD_FAB2_LIB.BASEBOARD_FAB2(SCH_1):PAGE109

P3E_CPU0_PE2_SS_C_TXP<10> @BASEBOARD_FAB2_LIB.BASEBOARD_FAB2(SCH_1):P3E_CPU0_PE2_SS_C_TXP(10)
 C7G15    2      B CAP_0402-0.22UF,16V,10%,X7R,A3A    I45 @BASEBOARD_FAB2_LIB.BASEBOARD_FAB2(SCH_1):PAGE105
 CONX8   17     17 SMC-CONN60A-22-GP_CONN-G7-SMC-A    I48 @BASEBOARD_FAB2_LIB.BASEBOARD_FAB2(SCH_1):PAGE245

P3E_CPU0_PE2_SS_C_TXP<11> @BASEBOARD_FAB2_LIB.BASEBOARD_FAB2(SCH_1):P3E_CPU0_PE2_SS_C_TXP(11)
 C7G14    2      B CAP_0402-0.22UF,16V,10%,X7R,A3A    I28 @BASEBOARD_FAB2_LIB.BASEBOARD_FAB2(SCH_1):PAGE105
 CONX8   21     21 SMC-CONN60A-22-GP_CONN-G7-SMC-A    I48 @BASEBOARD_FAB2_LIB.BASEBOARD_FAB2(SCH_1):PAGE245

P3E_CPU0_PE2_SS_C_TXP<12> @BASEBOARD_FAB2_LIB.BASEBOARD_FAB2(SCH_1):P3E_CPU0_PE2_SS_C_TXP(12)
 C7G11    2      B CAP_0402-0.22UF,16V,10%,X7R,A3A    I27 @BASEBOARD_FAB2_LIB.BASEBOARD_FAB2(SCH_1):PAGE105
 CONX8   29     29 SMC-CONN60A-22-GP_CONN-G7-SMC-A    I48 @BASEBOARD_FAB2_LIB.BASEBOARD_FAB2(SCH_1):PAGE245

P3E_CPU0_PE2_SS_C_TXP<13> @BASEBOARD_FAB2_LIB.BASEBOARD_FAB2(SCH_1):P3E_CPU0_PE2_SS_C_TXP(13)
  C7G9    2      B CAP_0402-0.22UF,16V,10%,X7R,A3A    I21 @BASEBOARD_FAB2_LIB.BASEBOARD_FAB2(SCH_1):PAGE105
 CONX8   35     35 SMC-CONN60A-22-GP_CONN-G7-SMC-A    I48 @BASEBOARD_FAB2_LIB.BASEBOARD_FAB2(SCH_1):PAGE245

P3E_CPU0_PE2_SS_C_TXP<14> @BASEBOARD_FAB2_LIB.BASEBOARD_FAB2(SCH_1):P3E_CPU0_PE2_SS_C_TXP(14)
  C7G8    2      B CAP_0402-0.22UF,16V,10%,X7R,A3A    I22 @BASEBOARD_FAB2_LIB.BASEBOARD_FAB2(SCH_1):PAGE105
 CONX8   39     39 SMC-CONN60A-22-GP_CONN-G7-SMC-A    I48 @BASEBOARD_FAB2_LIB.BASEBOARD_FAB2(SCH_1):PAGE245

P3E_CPU0_PE2_SS_C_TXP<15> @BASEBOARD_FAB2_LIB.BASEBOARD_FAB2(SCH_1):P3E_CPU0_PE2_SS_C_TXP(15)
  C7G5    2      B CAP_0402-0.22UF,16V,10%,X7R,A3A    I20 @BASEBOARD_FAB2_LIB.BASEBOARD_FAB2(SCH_1):PAGE105
 CONX8   47     47 SMC-CONN60A-22-GP_CONN-G7-SMC-A    I48 @BASEBOARD_FAB2_LIB.BASEBOARD_FAB2(SCH_1):PAGE245

P3E_CPU0_PE2_SS_C_TXP<1> @BASEBOARD_FAB2_LIB.BASEBOARD_FAB2(SCH_1):P3E_CPU0_PE2_SS_C_TXP(1)
  C8G8    2      B CAP_0402-0.22UF,16V,10%,X7R,A3A    I76 @BASEBOARD_FAB2_LIB.BASEBOARD_FAB2(SCH_1):PAGE105
  J8G1  157  IO157 SCONN200_H68296001_SM-CONN,H68A    I78 @BASEBOARD_FAB2_LIB.BASEBOARD_FAB2(SCH_1):PAGE109

P3E_CPU0_PE2_SS_C_TXP<2> @BASEBOARD_FAB2_LIB.BASEBOARD_FAB2(SCH_1):P3E_CPU0_PE2_SS_C_TXP(2)
  C8G5    2      B CAP_0402-0.22UF,16V,10%,X7R,A3A    I75 @BASEBOARD_FAB2_LIB.BASEBOARD_FAB2(SCH_1):PAGE105
  J8G1  165  IO165 SCONN200_H68296001_SM-CONN,H68A    I78 @BASEBOARD_FAB2_LIB.BASEBOARD_FAB2(SCH_1):PAGE109

P3E_CPU0_PE2_SS_C_TXP<3> @BASEBOARD_FAB2_LIB.BASEBOARD_FAB2(SCH_1):P3E_CPU0_PE2_SS_C_TXP(3)
  C8G3    2      B CAP_0402-0.22UF,16V,10%,X7R,A3A    I71 @BASEBOARD_FAB2_LIB.BASEBOARD_FAB2(SCH_1):PAGE105
  J8G1  171  IO171 SCONN200_H68296001_SM-CONN,H68A    I78 @BASEBOARD_FAB2_LIB.BASEBOARD_FAB2(SCH_1):PAGE109

P3E_CPU0_PE2_SS_C_TXP<4> @BASEBOARD_FAB2_LIB.BASEBOARD_FAB2(SCH_1):P3E_CPU0_PE2_SS_C_TXP(4)
  C8G1    2      B CAP_0402-0.22UF,16V,10%,X7R,A3A    I70 @BASEBOARD_FAB2_LIB.BASEBOARD_FAB2(SCH_1):PAGE105
  J8G1  177  IO177 SCONN200_H68296001_SM-CONN,H68A    I78 @BASEBOARD_FAB2_LIB.BASEBOARD_FAB2(SCH_1):PAGE109

P3E_CPU0_PE2_SS_C_TXP<5> @BASEBOARD_FAB2_LIB.BASEBOARD_FAB2(SCH_1):P3E_CPU0_PE2_SS_C_TXP(5)
 C7G25    2      B CAP_0402-0.22UF,16V,10%,X7R,A3A    I69 @BASEBOARD_FAB2_LIB.BASEBOARD_FAB2(SCH_1):PAGE105
  J8G1  183  IO183 SCONN200_H68296001_SM-CONN,H68A    I78 @BASEBOARD_FAB2_LIB.BASEBOARD_FAB2(SCH_1):PAGE109

P3E_CPU0_PE2_SS_C_TXP<6> @BASEBOARD_FAB2_LIB.BASEBOARD_FAB2(SCH_1):P3E_CPU0_PE2_SS_C_TXP(6)
 C7G23    2      B CAP_0402-0.22UF,16V,10%,X7R,A3A    I52 @BASEBOARD_FAB2_LIB.BASEBOARD_FAB2(SCH_1):PAGE105
  J8G1  189  IO189 SCONN200_H68296001_SM-CONN,H68A    I78 @BASEBOARD_FAB2_LIB.BASEBOARD_FAB2(SCH_1):PAGE109

P3E_CPU0_PE2_SS_C_TXP<7> @BASEBOARD_FAB2_LIB.BASEBOARD_FAB2(SCH_1):P3E_CPU0_PE2_SS_C_TXP(7)
 C7G21    2      B CAP_0402-0.22UF,16V,10%,X7R,A3A    I51 @BASEBOARD_FAB2_LIB.BASEBOARD_FAB2(SCH_1):PAGE105
  J8G1  195  IO195 SCONN200_H68296001_SM-CONN,H68A    I78 @BASEBOARD_FAB2_LIB.BASEBOARD_FAB2(SCH_1):PAGE109

P3E_CPU0_PE2_SS_C_TXP<8> @BASEBOARD_FAB2_LIB.BASEBOARD_FAB2(SCH_1):P3E_CPU0_PE2_SS_C_TXP(8)
 CONX8    5      5 SMC-CONN60A-22-GP_CONN-G7-SMC-A    I48 @BASEBOARD_FAB2_LIB.BASEBOARD_FAB2(SCH_1):PAGE245
 C7G20    2      B CAP_0402-0.22UF,16V,10%,X7R,A3A   I258 @BASEBOARD_FAB2_LIB.BASEBOARD_FAB2(SCH_1):PAGE105

P3E_CPU0_PE2_SS_C_TXP<9> @BASEBOARD_FAB2_LIB.BASEBOARD_FAB2(SCH_1):P3E_CPU0_PE2_SS_C_TXP(9)
 C7G17    2      B CAP_0402-0.22UF,16V,10%,X7R,A3A    I44 @BASEBOARD_FAB2_LIB.BASEBOARD_FAB2(SCH_1):PAGE105
 CONX8   11     11 SMC-CONN60A-22-GP_CONN-G7-SMC-A    I48 @BASEBOARD_FAB2_LIB.BASEBOARD_FAB2(SCH_1):PAGE245

P3E_CPU0_PE2_SS_RXN<0> @BASEBOARD_FAB2_LIB.BASEBOARD_FAB2(SCH_1):P3E_CPU0_PE2_SS_RXN(0)
  U5D1  CT9 PE2_RX_DN<0> SKX_EXT_B_BGA1-IC,TBD   I106 @BASEBOARD_FAB2_LIB.BASEBOARD_FAB2(SCH_1):PAGE31
  J8G1  154  IO154 SCONN200_H68296001_SM-CONN,H68A    I78 @BASEBOARD_FAB2_LIB.BASEBOARD_FAB2(SCH_1):PAGE109

P3E_CPU0_PE2_SS_RXN<10> @BASEBOARD_FAB2_LIB.BASEBOARD_FAB2(SCH_1):P3E_CPU0_PE2_SS_RXN(10)
  U5D1  BV7 PE2_RX_DN<10> SKX_EXT_B_BGA1-IC,TBD   I106 @BASEBOARD_FAB2_LIB.BASEBOARD_FAB2(SCH_1):PAGE31
 CONX8   18     18 SMC-CONN60A-22-GP_CONN-G7-SMC-A    I48 @BASEBOARD_FAB2_LIB.BASEBOARD_FAB2(SCH_1):PAGE245

P3E_CPU0_PE2_SS_RXN<11> @BASEBOARD_FAB2_LIB.BASEBOARD_FAB2(SCH_1):P3E_CPU0_PE2_SS_RXN(11)
  U5D1  BT7 PE2_RX_DN<11> SKX_EXT_B_BGA1-IC,TBD   I106 @BASEBOARD_FAB2_LIB.BASEBOARD_FAB2(SCH_1):PAGE31
 CONX8   24     24 SMC-CONN60A-22-GP_CONN-G7-SMC-A    I48 @BASEBOARD_FAB2_LIB.BASEBOARD_FAB2(SCH_1):PAGE245

P3E_CPU0_PE2_SS_RXN<12> @BASEBOARD_FAB2_LIB.BASEBOARD_FAB2(SCH_1):P3E_CPU0_PE2_SS_RXN(12)
  U5D1  BR8 PE2_RX_DN<12> SKX_EXT_B_BGA1-IC,TBD   I106 @BASEBOARD_FAB2_LIB.BASEBOARD_FAB2(SCH_1):PAGE31
 CONX8   30     30 SMC-CONN60A-22-GP_CONN-G7-SMC-A    I48 @BASEBOARD_FAB2_LIB.BASEBOARD_FAB2(SCH_1):PAGE245

P3E_CPU0_PE2_SS_RXN<13> @BASEBOARD_FAB2_LIB.BASEBOARD_FAB2(SCH_1):P3E_CPU0_PE2_SS_RXN(13)
  U5D1  BN8 PE2_RX_DN<13> SKX_EXT_B_BGA1-IC,TBD   I106 @BASEBOARD_FAB2_LIB.BASEBOARD_FAB2(SCH_1):PAGE31
 CONX8   38     38 SMC-CONN60A-22-GP_CONN-G7-SMC-A    I48 @BASEBOARD_FAB2_LIB.BASEBOARD_FAB2(SCH_1):PAGE245

P3E_CPU0_PE2_SS_RXN<14> @BASEBOARD_FAB2_LIB.BASEBOARD_FAB2(SCH_1):P3E_CPU0_PE2_SS_RXN(14)
  U5D1  BL8 PE2_RX_DN<14> SKX_EXT_B_BGA1-IC,TBD   I106 @BASEBOARD_FAB2_LIB.BASEBOARD_FAB2(SCH_1):PAGE31
 CONX8   42     42 SMC-CONN60A-22-GP_CONN-G7-SMC-A    I48 @BASEBOARD_FAB2_LIB.BASEBOARD_FAB2(SCH_1):PAGE245

P3E_CPU0_PE2_SS_RXN<15> @BASEBOARD_FAB2_LIB.BASEBOARD_FAB2(SCH_1):P3E_CPU0_PE2_SS_RXN(15)
  U5D1  BK9 PE2_RX_DN<15> SKX_EXT_B_BGA1-IC,TBD   I106 @BASEBOARD_FAB2_LIB.BASEBOARD_FAB2(SCH_1):PAGE31
 CONX8   48     48 SMC-CONN60A-22-GP_CONN-G7-SMC-A    I48 @BASEBOARD_FAB2_LIB.BASEBOARD_FAB2(SCH_1):PAGE245

P3E_CPU0_PE2_SS_RXN<1> @BASEBOARD_FAB2_LIB.BASEBOARD_FAB2(SCH_1):P3E_CPU0_PE2_SS_RXN(1)
  U5D1  CP9 PE2_RX_DN<1> SKX_EXT_B_BGA1-IC,TBD   I106 @BASEBOARD_FAB2_LIB.BASEBOARD_FAB2(SCH_1):PAGE31
  J8G1  160  IO160 SCONN200_H68296001_SM-CONN,H68A    I78 @BASEBOARD_FAB2_LIB.BASEBOARD_FAB2(SCH_1):PAGE109

P3E_CPU0_PE2_SS_RXN<2> @BASEBOARD_FAB2_LIB.BASEBOARD_FAB2(SCH_1):P3E_CPU0_PE2_SS_RXN(2)
  U5D1  CP7 PE2_RX_DN<2> SKX_EXT_B_BGA1-IC,TBD   I106 @BASEBOARD_FAB2_LIB.BASEBOARD_FAB2(SCH_1):PAGE31
  J8G1  166  IO166 SCONN200_H68296001_SM-CONN,H68A    I78 @BASEBOARD_FAB2_LIB.BASEBOARD_FAB2(SCH_1):PAGE109

P3E_CPU0_PE2_SS_RXN<3> @BASEBOARD_FAB2_LIB.BASEBOARD_FAB2(SCH_1):P3E_CPU0_PE2_SS_RXN(3)
  U5D1  CM7 PE2_RX_DN<3> SKX_EXT_B_BGA1-IC,TBD   I106 @BASEBOARD_FAB2_LIB.BASEBOARD_FAB2(SCH_1):PAGE31
  J8G1  172  IO172 SCONN200_H68296001_SM-CONN,H68A    I78 @BASEBOARD_FAB2_LIB.BASEBOARD_FAB2(SCH_1):PAGE109

P3E_CPU0_PE2_SS_RXN<4> @BASEBOARD_FAB2_LIB.BASEBOARD_FAB2(SCH_1):P3E_CPU0_PE2_SS_RXN(4)
  U5D1  CK7 PE2_RX_DN<4> SKX_EXT_B_BGA1-IC,TBD   I106 @BASEBOARD_FAB2_LIB.BASEBOARD_FAB2(SCH_1):PAGE31
  J8G1  178  IO178 SCONN200_H68296001_SM-CONN,H68A    I78 @BASEBOARD_FAB2_LIB.BASEBOARD_FAB2(SCH_1):PAGE109

P3E_CPU0_PE2_SS_RXN<5> @BASEBOARD_FAB2_LIB.BASEBOARD_FAB2(SCH_1):P3E_CPU0_PE2_SS_RXN(5)
  U5D1  CG8 PE2_RX_DN<5> SKX_EXT_B_BGA1-IC,TBD   I106 @BASEBOARD_FAB2_LIB.BASEBOARD_FAB2(SCH_1):PAGE31
  J8G1  184  IO184 SCONN200_H68296001_SM-CONN,H68A    I78 @BASEBOARD_FAB2_LIB.BASEBOARD_FAB2(SCH_1):PAGE109

P3E_CPU0_PE2_SS_RXN<6> @BASEBOARD_FAB2_LIB.BASEBOARD_FAB2(SCH_1):P3E_CPU0_PE2_SS_RXN(6)
  U5D1  CE6 PE2_RX_DN<6> SKX_EXT_B_BGA1-IC,TBD   I106 @BASEBOARD_FAB2_LIB.BASEBOARD_FAB2(SCH_1):PAGE31
  J8G1  192  IO192 SCONN200_H68296001_SM-CONN,H68A    I78 @BASEBOARD_FAB2_LIB.BASEBOARD_FAB2(SCH_1):PAGE109

P3E_CPU0_PE2_SS_RXN<7> @BASEBOARD_FAB2_LIB.BASEBOARD_FAB2(SCH_1):P3E_CPU0_PE2_SS_RXN(7)
  U5D1  CE8 PE2_RX_DN<7> SKX_EXT_B_BGA1-IC,TBD   I106 @BASEBOARD_FAB2_LIB.BASEBOARD_FAB2(SCH_1):PAGE31
  J8G1  196  IO196 SCONN200_H68296001_SM-CONN,H68A    I78 @BASEBOARD_FAB2_LIB.BASEBOARD_FAB2(SCH_1):PAGE109

P3E_CPU0_PE2_SS_RXN<8> @BASEBOARD_FAB2_LIB.BASEBOARD_FAB2(SCH_1):P3E_CPU0_PE2_SS_RXN(8)
  U5D1  BY9 PE2_RX_DN<8> SKX_EXT_B_BGA1-IC,TBD   I106 @BASEBOARD_FAB2_LIB.BASEBOARD_FAB2(SCH_1):PAGE31
 CONX8    6      6 SMC-CONN60A-22-GP_CONN-G7-SMC-A    I48 @BASEBOARD_FAB2_LIB.BASEBOARD_FAB2(SCH_1):PAGE245

P3E_CPU0_PE2_SS_RXN<9> @BASEBOARD_FAB2_LIB.BASEBOARD_FAB2(SCH_1):P3E_CPU0_PE2_SS_RXN(9)
  U5D1  BY7 PE2_RX_DN<9> SKX_EXT_B_BGA1-IC,TBD   I106 @BASEBOARD_FAB2_LIB.BASEBOARD_FAB2(SCH_1):PAGE31
 CONX8   12     12 SMC-CONN60A-22-GP_CONN-G7-SMC-A    I48 @BASEBOARD_FAB2_LIB.BASEBOARD_FAB2(SCH_1):PAGE245

P3E_CPU0_PE2_SS_RXP<0> @BASEBOARD_FAB2_LIB.BASEBOARD_FAB2(SCH_1):P3E_CPU0_PE2_SS_RXP(0)
  U5D1  CR8 PE2_RX_DP<0> SKX_EXT_B_BGA1-IC,TBD   I106 @BASEBOARD_FAB2_LIB.BASEBOARD_FAB2(SCH_1):PAGE31
  J8G1  156  IO156 SCONN200_H68296001_SM-CONN,H68A    I78 @BASEBOARD_FAB2_LIB.BASEBOARD_FAB2(SCH_1):PAGE109

P3E_CPU0_PE2_SS_RXP<10> @BASEBOARD_FAB2_LIB.BASEBOARD_FAB2(SCH_1):P3E_CPU0_PE2_SS_RXP(10)
  U5D1  BU6 PE2_RX_DP<10> SKX_EXT_B_BGA1-IC,TBD   I106 @BASEBOARD_FAB2_LIB.BASEBOARD_FAB2(SCH_1):PAGE31
 CONX8   20     20 SMC-CONN60A-22-GP_CONN-G7-SMC-A    I48 @BASEBOARD_FAB2_LIB.BASEBOARD_FAB2(SCH_1):PAGE245

P3E_CPU0_PE2_SS_RXP<11> @BASEBOARD_FAB2_LIB.BASEBOARD_FAB2(SCH_1):P3E_CPU0_PE2_SS_RXP(11)
  U5D1  BP7 PE2_RX_DP<11> SKX_EXT_B_BGA1-IC,TBD   I106 @BASEBOARD_FAB2_LIB.BASEBOARD_FAB2(SCH_1):PAGE31
 CONX8   26     26 SMC-CONN60A-22-GP_CONN-G7-SMC-A    I48 @BASEBOARD_FAB2_LIB.BASEBOARD_FAB2(SCH_1):PAGE245

P3E_CPU0_PE2_SS_RXP<12> @BASEBOARD_FAB2_LIB.BASEBOARD_FAB2(SCH_1):P3E_CPU0_PE2_SS_RXP(12)
  U5D1  BP9 PE2_RX_DP<12> SKX_EXT_B_BGA1-IC,TBD   I106 @BASEBOARD_FAB2_LIB.BASEBOARD_FAB2(SCH_1):PAGE31
 CONX8   32     32 SMC-CONN60A-22-GP_CONN-G7-SMC-A    I48 @BASEBOARD_FAB2_LIB.BASEBOARD_FAB2(SCH_1):PAGE245

P3E_CPU0_PE2_SS_RXP<13> @BASEBOARD_FAB2_LIB.BASEBOARD_FAB2(SCH_1):P3E_CPU0_PE2_SS_RXP(13)
  U5D1  BM7 PE2_RX_DP<13> SKX_EXT_B_BGA1-IC,TBD   I106 @BASEBOARD_FAB2_LIB.BASEBOARD_FAB2(SCH_1):PAGE31
 CONX8   36     36 SMC-CONN60A-22-GP_CONN-G7-SMC-A    I48 @BASEBOARD_FAB2_LIB.BASEBOARD_FAB2(SCH_1):PAGE245

P3E_CPU0_PE2_SS_RXP<14> @BASEBOARD_FAB2_LIB.BASEBOARD_FAB2(SCH_1):P3E_CPU0_PE2_SS_RXP(14)
  U5D1  BJ8 PE2_RX_DP<14> SKX_EXT_B_BGA1-IC,TBD   I106 @BASEBOARD_FAB2_LIB.BASEBOARD_FAB2(SCH_1):PAGE31
 CONX8   44     44 SMC-CONN60A-22-GP_CONN-G7-SMC-A    I48 @BASEBOARD_FAB2_LIB.BASEBOARD_FAB2(SCH_1):PAGE245

P3E_CPU0_PE2_SS_RXP<15> @BASEBOARD_FAB2_LIB.BASEBOARD_FAB2(SCH_1):P3E_CPU0_PE2_SS_RXP(15)
  U5D1 BJ10 PE2_RX_DP<15> SKX_EXT_B_BGA1-IC,TBD   I106 @BASEBOARD_FAB2_LIB.BASEBOARD_FAB2(SCH_1):PAGE31
 CONX8   50     50 SMC-CONN60A-22-GP_CONN-G7-SMC-A    I48 @BASEBOARD_FAB2_LIB.BASEBOARD_FAB2(SCH_1):PAGE245

P3E_CPU0_PE2_SS_RXP<1> @BASEBOARD_FAB2_LIB.BASEBOARD_FAB2(SCH_1):P3E_CPU0_PE2_SS_RXP(1)
  U5D1  CM9 PE2_RX_DP<1> SKX_EXT_B_BGA1-IC,TBD   I106 @BASEBOARD_FAB2_LIB.BASEBOARD_FAB2(SCH_1):PAGE31
  J8G1  162  IO162 SCONN200_H68296001_SM-CONN,H68A    I78 @BASEBOARD_FAB2_LIB.BASEBOARD_FAB2(SCH_1):PAGE109

P3E_CPU0_PE2_SS_RXP<2> @BASEBOARD_FAB2_LIB.BASEBOARD_FAB2(SCH_1):P3E_CPU0_PE2_SS_RXP(2)
  U5D1  CN8 PE2_RX_DP<2> SKX_EXT_B_BGA1-IC,TBD   I106 @BASEBOARD_FAB2_LIB.BASEBOARD_FAB2(SCH_1):PAGE31
  J8G1  168  IO168 SCONN200_H68296001_SM-CONN,H68A    I78 @BASEBOARD_FAB2_LIB.BASEBOARD_FAB2(SCH_1):PAGE109

P3E_CPU0_PE2_SS_RXP<3> @BASEBOARD_FAB2_LIB.BASEBOARD_FAB2(SCH_1):P3E_CPU0_PE2_SS_RXP(3)
  U5D1  CL6 PE2_RX_DP<3> SKX_EXT_B_BGA1-IC,TBD   I106 @BASEBOARD_FAB2_LIB.BASEBOARD_FAB2(SCH_1):PAGE31
  J8G1  174  IO174 SCONN200_H68296001_SM-CONN,H68A    I78 @BASEBOARD_FAB2_LIB.BASEBOARD_FAB2(SCH_1):PAGE109

P3E_CPU0_PE2_SS_RXP<4> @BASEBOARD_FAB2_LIB.BASEBOARD_FAB2(SCH_1):P3E_CPU0_PE2_SS_RXP(4)
  U5D1  CH7 PE2_RX_DP<4> SKX_EXT_B_BGA1-IC,TBD   I106 @BASEBOARD_FAB2_LIB.BASEBOARD_FAB2(SCH_1):PAGE31
  J8G1  180  IO180 SCONN200_H68296001_SM-CONN,H68A    I78 @BASEBOARD_FAB2_LIB.BASEBOARD_FAB2(SCH_1):PAGE109

P3E_CPU0_PE2_SS_RXP<5> @BASEBOARD_FAB2_LIB.BASEBOARD_FAB2(SCH_1):P3E_CPU0_PE2_SS_RXP(5)
  U5D1  CF7 PE2_RX_DP<5> SKX_EXT_B_BGA1-IC,TBD   I106 @BASEBOARD_FAB2_LIB.BASEBOARD_FAB2(SCH_1):PAGE31
  J8G1  186  IO186 SCONN200_H68296001_SM-CONN,H68A    I78 @BASEBOARD_FAB2_LIB.BASEBOARD_FAB2(SCH_1):PAGE109

P3E_CPU0_PE2_SS_RXP<6> @BASEBOARD_FAB2_LIB.BASEBOARD_FAB2(SCH_1):P3E_CPU0_PE2_SS_RXP(6)
  U5D1  CD7 PE2_RX_DP<6> SKX_EXT_B_BGA1-IC,TBD   I106 @BASEBOARD_FAB2_LIB.BASEBOARD_FAB2(SCH_1):PAGE31
  J8G1  190  IO190 SCONN200_H68296001_SM-CONN,H68A    I78 @BASEBOARD_FAB2_LIB.BASEBOARD_FAB2(SCH_1):PAGE109

P3E_CPU0_PE2_SS_RXP<7> @BASEBOARD_FAB2_LIB.BASEBOARD_FAB2(SCH_1):P3E_CPU0_PE2_SS_RXP(7)
  U5D1  CC8 PE2_RX_DP<7> SKX_EXT_B_BGA1-IC,TBD   I106 @BASEBOARD_FAB2_LIB.BASEBOARD_FAB2(SCH_1):PAGE31
  J8G1  198  IO198 SCONN200_H68296001_SM-CONN,H68A    I78 @BASEBOARD_FAB2_LIB.BASEBOARD_FAB2(SCH_1):PAGE109

P3E_CPU0_PE2_SS_RXP<8> @BASEBOARD_FAB2_LIB.BASEBOARD_FAB2(SCH_1):P3E_CPU0_PE2_SS_RXP(8)
  U5D1  BV9 PE2_RX_DP<8> SKX_EXT_B_BGA1-IC,TBD   I106 @BASEBOARD_FAB2_LIB.BASEBOARD_FAB2(SCH_1):PAGE31
 CONX8    8      8 SMC-CONN60A-22-GP_CONN-G7-SMC-A    I48 @BASEBOARD_FAB2_LIB.BASEBOARD_FAB2(SCH_1):PAGE245

P3E_CPU0_PE2_SS_RXP<9> @BASEBOARD_FAB2_LIB.BASEBOARD_FAB2(SCH_1):P3E_CPU0_PE2_SS_RXP(9)
  U5D1  BW8 PE2_RX_DP<9> SKX_EXT_B_BGA1-IC,TBD   I106 @BASEBOARD_FAB2_LIB.BASEBOARD_FAB2(SCH_1):PAGE31
 CONX8   14     14 SMC-CONN60A-22-GP_CONN-G7-SMC-A    I48 @BASEBOARD_FAB2_LIB.BASEBOARD_FAB2(SCH_1):PAGE245

P3E_CPU0_PE2_SS_TXN<0> @BASEBOARD_FAB2_LIB.BASEBOARD_FAB2(SCH_1):P3E_CPU0_PE2_SS_TXN(0)
  U5D1  CY3 PE2_TX_DN<0> SKX_EXT_B_BGA1-IC,TBD   I106 @BASEBOARD_FAB2_LIB.BASEBOARD_FAB2(SCH_1):PAGE31
 C8G10    1      A CAP_0402-0.22UF,16V,10%,X7R,A3A    I96 @BASEBOARD_FAB2_LIB.BASEBOARD_FAB2(SCH_1):PAGE105

P3E_CPU0_PE2_SS_TXN<10> @BASEBOARD_FAB2_LIB.BASEBOARD_FAB2(SCH_1):P3E_CPU0_PE2_SS_TXN(10)
  U5D1  CA4 PE2_TX_DN<10> SKX_EXT_B_BGA1-IC,TBD   I106 @BASEBOARD_FAB2_LIB.BASEBOARD_FAB2(SCH_1):PAGE31
 C7G16    1      A CAP_0402-0.22UF,16V,10%,X7R,A3A    I31 @BASEBOARD_FAB2_LIB.BASEBOARD_FAB2(SCH_1):PAGE105

P3E_CPU0_PE2_SS_TXN<11> @BASEBOARD_FAB2_LIB.BASEBOARD_FAB2(SCH_1):P3E_CPU0_PE2_SS_TXN(11)
  U5D1  BW4 PE2_TX_DN<11> SKX_EXT_B_BGA1-IC,TBD   I106 @BASEBOARD_FAB2_LIB.BASEBOARD_FAB2(SCH_1):PAGE31
 C7G13    1      A CAP_0402-0.22UF,16V,10%,X7R,A3A    I13 @BASEBOARD_FAB2_LIB.BASEBOARD_FAB2(SCH_1):PAGE105

P3E_CPU0_PE2_SS_TXN<12> @BASEBOARD_FAB2_LIB.BASEBOARD_FAB2(SCH_1):P3E_CPU0_PE2_SS_TXN(12)
  U5D1  BU4 PE2_TX_DN<12> SKX_EXT_B_BGA1-IC,TBD   I106 @BASEBOARD_FAB2_LIB.BASEBOARD_FAB2(SCH_1):PAGE31
 C7G12    1      A CAP_0402-0.22UF,16V,10%,X7R,A3A    I12 @BASEBOARD_FAB2_LIB.BASEBOARD_FAB2(SCH_1):PAGE105

P3E_CPU0_PE2_SS_TXN<13> @BASEBOARD_FAB2_LIB.BASEBOARD_FAB2(SCH_1):P3E_CPU0_PE2_SS_TXN(13)
  U5D1  BP5 PE2_TX_DN<13> SKX_EXT_B_BGA1-IC,TBD   I106 @BASEBOARD_FAB2_LIB.BASEBOARD_FAB2(SCH_1):PAGE31
 C7G10    1      A CAP_0402-0.22UF,16V,10%,X7R,A3A     I8 @BASEBOARD_FAB2_LIB.BASEBOARD_FAB2(SCH_1):PAGE105

P3E_CPU0_PE2_SS_TXN<14> @BASEBOARD_FAB2_LIB.BASEBOARD_FAB2(SCH_1):P3E_CPU0_PE2_SS_TXN(14)
  U5D1  BL4 PE2_TX_DN<14> SKX_EXT_B_BGA1-IC,TBD   I106 @BASEBOARD_FAB2_LIB.BASEBOARD_FAB2(SCH_1):PAGE31
  C7G7    1      A CAP_0402-0.22UF,16V,10%,X7R,A3A     I7 @BASEBOARD_FAB2_LIB.BASEBOARD_FAB2(SCH_1):PAGE105

P3E_CPU0_PE2_SS_TXN<15> @BASEBOARD_FAB2_LIB.BASEBOARD_FAB2(SCH_1):P3E_CPU0_PE2_SS_TXN(15)
  U5D1  BM5 PE2_TX_DN<15> SKX_EXT_B_BGA1-IC,TBD   I106 @BASEBOARD_FAB2_LIB.BASEBOARD_FAB2(SCH_1):PAGE31
  C7G6    1      A CAP_0402-0.22UF,16V,10%,X7R,A3A     I6 @BASEBOARD_FAB2_LIB.BASEBOARD_FAB2(SCH_1):PAGE105

P3E_CPU0_PE2_SS_TXN<1> @BASEBOARD_FAB2_LIB.BASEBOARD_FAB2(SCH_1):P3E_CPU0_PE2_SS_TXN(1)
  U5D1  CV3 PE2_TX_DN<1> SKX_EXT_B_BGA1-IC,TBD   I106 @BASEBOARD_FAB2_LIB.BASEBOARD_FAB2(SCH_1):PAGE31
  C8G7    1      A CAP_0402-0.22UF,16V,10%,X7R,A3A    I62 @BASEBOARD_FAB2_LIB.BASEBOARD_FAB2(SCH_1):PAGE105

P3E_CPU0_PE2_SS_TXN<2> @BASEBOARD_FAB2_LIB.BASEBOARD_FAB2(SCH_1):P3E_CPU0_PE2_SS_TXN(2)
  U5D1  CT1 PE2_TX_DN<2> SKX_EXT_B_BGA1-IC,TBD   I106 @BASEBOARD_FAB2_LIB.BASEBOARD_FAB2(SCH_1):PAGE31
  C8G6    1      A CAP_0402-0.22UF,16V,10%,X7R,A3A    I61 @BASEBOARD_FAB2_LIB.BASEBOARD_FAB2(SCH_1):PAGE105

P3E_CPU0_PE2_SS_TXN<3> @BASEBOARD_FAB2_LIB.BASEBOARD_FAB2(SCH_1):P3E_CPU0_PE2_SS_TXN(3)
  U5D1  CT3 PE2_TX_DN<3> SKX_EXT_B_BGA1-IC,TBD   I106 @BASEBOARD_FAB2_LIB.BASEBOARD_FAB2(SCH_1):PAGE31
  C8G4    1      A CAP_0402-0.22UF,16V,10%,X7R,A3A    I56 @BASEBOARD_FAB2_LIB.BASEBOARD_FAB2(SCH_1):PAGE105

P3E_CPU0_PE2_SS_TXN<4> @BASEBOARD_FAB2_LIB.BASEBOARD_FAB2(SCH_1):P3E_CPU0_PE2_SS_TXN(4)
  U5D1  CM1 PE2_TX_DN<4> SKX_EXT_B_BGA1-IC,TBD   I106 @BASEBOARD_FAB2_LIB.BASEBOARD_FAB2(SCH_1):PAGE31
  C8G2    1      A CAP_0402-0.22UF,16V,10%,X7R,A3A    I58 @BASEBOARD_FAB2_LIB.BASEBOARD_FAB2(SCH_1):PAGE105

P3E_CPU0_PE2_SS_TXN<5> @BASEBOARD_FAB2_LIB.BASEBOARD_FAB2(SCH_1):P3E_CPU0_PE2_SS_TXN(5)
  U5D1  CL2 PE2_TX_DN<5> SKX_EXT_B_BGA1-IC,TBD   I106 @BASEBOARD_FAB2_LIB.BASEBOARD_FAB2(SCH_1):PAGE31
 C7G26    1      A CAP_0402-0.22UF,16V,10%,X7R,A3A    I55 @BASEBOARD_FAB2_LIB.BASEBOARD_FAB2(SCH_1):PAGE105

P3E_CPU0_PE2_SS_TXN<6> @BASEBOARD_FAB2_LIB.BASEBOARD_FAB2(SCH_1):P3E_CPU0_PE2_SS_TXN(6)
  U5D1  CG2 PE2_TX_DN<6> SKX_EXT_B_BGA1-IC,TBD   I106 @BASEBOARD_FAB2_LIB.BASEBOARD_FAB2(SCH_1):PAGE31
 C7G24    1      A CAP_0402-0.22UF,16V,10%,X7R,A3A     I1 @BASEBOARD_FAB2_LIB.BASEBOARD_FAB2(SCH_1):PAGE105

P3E_CPU0_PE2_SS_TXN<7> @BASEBOARD_FAB2_LIB.BASEBOARD_FAB2(SCH_1):P3E_CPU0_PE2_SS_TXN(7)
  U5D1  CF3 PE2_TX_DN<7> SKX_EXT_B_BGA1-IC,TBD   I106 @BASEBOARD_FAB2_LIB.BASEBOARD_FAB2(SCH_1):PAGE31
 C7G22    1      A CAP_0402-0.22UF,16V,10%,X7R,A3A    I37 @BASEBOARD_FAB2_LIB.BASEBOARD_FAB2(SCH_1):PAGE105

P3E_CPU0_PE2_SS_TXN<8> @BASEBOARD_FAB2_LIB.BASEBOARD_FAB2(SCH_1):P3E_CPU0_PE2_SS_TXN(8)
  U5D1  CC2 PE2_TX_DN<8> SKX_EXT_B_BGA1-IC,TBD   I106 @BASEBOARD_FAB2_LIB.BASEBOARD_FAB2(SCH_1):PAGE31
 C7G19    1      A CAP_0402-0.22UF,16V,10%,X7R,A3A   I257 @BASEBOARD_FAB2_LIB.BASEBOARD_FAB2(SCH_1):PAGE105

P3E_CPU0_PE2_SS_TXN<9> @BASEBOARD_FAB2_LIB.BASEBOARD_FAB2(SCH_1):P3E_CPU0_PE2_SS_TXN(9)
  U5D1  CB3 PE2_TX_DN<9> SKX_EXT_B_BGA1-IC,TBD   I106 @BASEBOARD_FAB2_LIB.BASEBOARD_FAB2(SCH_1):PAGE31
 C7G18    1      A CAP_0402-0.22UF,16V,10%,X7R,A3A    I32 @BASEBOARD_FAB2_LIB.BASEBOARD_FAB2(SCH_1):PAGE105

P3E_CPU0_PE2_SS_TXP<0> @BASEBOARD_FAB2_LIB.BASEBOARD_FAB2(SCH_1):P3E_CPU0_PE2_SS_TXP(0)
  U5D1  CW4 PE2_TX_DP<0> SKX_EXT_B_BGA1-IC,TBD   I106 @BASEBOARD_FAB2_LIB.BASEBOARD_FAB2(SCH_1):PAGE31
  C8G9    1      A CAP_0402-0.22UF,16V,10%,X7R,A3A    I93 @BASEBOARD_FAB2_LIB.BASEBOARD_FAB2(SCH_1):PAGE105

P3E_CPU0_PE2_SS_TXP<10> @BASEBOARD_FAB2_LIB.BASEBOARD_FAB2(SCH_1):P3E_CPU0_PE2_SS_TXP(10)
  U5D1  BY5 PE2_TX_DP<10> SKX_EXT_B_BGA1-IC,TBD   I106 @BASEBOARD_FAB2_LIB.BASEBOARD_FAB2(SCH_1):PAGE31
 C7G15    1      A CAP_0402-0.22UF,16V,10%,X7R,A3A    I45 @BASEBOARD_FAB2_LIB.BASEBOARD_FAB2(SCH_1):PAGE105

P3E_CPU0_PE2_SS_TXP<11> @BASEBOARD_FAB2_LIB.BASEBOARD_FAB2(SCH_1):P3E_CPU0_PE2_SS_TXP(11)
  U5D1  BV3 PE2_TX_DP<11> SKX_EXT_B_BGA1-IC,TBD   I106 @BASEBOARD_FAB2_LIB.BASEBOARD_FAB2(SCH_1):PAGE31
 C7G14    1      A CAP_0402-0.22UF,16V,10%,X7R,A3A    I28 @BASEBOARD_FAB2_LIB.BASEBOARD_FAB2(SCH_1):PAGE105

P3E_CPU0_PE2_SS_TXP<12> @BASEBOARD_FAB2_LIB.BASEBOARD_FAB2(SCH_1):P3E_CPU0_PE2_SS_TXP(12)
  U5D1  BR4 PE2_TX_DP<12> SKX_EXT_B_BGA1-IC,TBD   I106 @BASEBOARD_FAB2_LIB.BASEBOARD_FAB2(SCH_1):PAGE31
 C7G11    1      A CAP_0402-0.22UF,16V,10%,X7R,A3A    I27 @BASEBOARD_FAB2_LIB.BASEBOARD_FAB2(SCH_1):PAGE105

P3E_CPU0_PE2_SS_TXP<13> @BASEBOARD_FAB2_LIB.BASEBOARD_FAB2(SCH_1):P3E_CPU0_PE2_SS_TXP(13)
  U5D1  BN4 PE2_TX_DP<13> SKX_EXT_B_BGA1-IC,TBD   I106 @BASEBOARD_FAB2_LIB.BASEBOARD_FAB2(SCH_1):PAGE31
  C7G9    1      A CAP_0402-0.22UF,16V,10%,X7R,A3A    I21 @BASEBOARD_FAB2_LIB.BASEBOARD_FAB2(SCH_1):PAGE105

P3E_CPU0_PE2_SS_TXP<14> @BASEBOARD_FAB2_LIB.BASEBOARD_FAB2(SCH_1):P3E_CPU0_PE2_SS_TXP(14)
  U5D1  BM3 PE2_TX_DP<14> SKX_EXT_B_BGA1-IC,TBD   I106 @BASEBOARD_FAB2_LIB.BASEBOARD_FAB2(SCH_1):PAGE31
  C7G8    1      A CAP_0402-0.22UF,16V,10%,X7R,A3A    I22 @BASEBOARD_FAB2_LIB.BASEBOARD_FAB2(SCH_1):PAGE105

P3E_CPU0_PE2_SS_TXP<15> @BASEBOARD_FAB2_LIB.BASEBOARD_FAB2(SCH_1):P3E_CPU0_PE2_SS_TXP(15)
  U5D1  BK5 PE2_TX_DP<15> SKX_EXT_B_BGA1-IC,TBD   I106 @BASEBOARD_FAB2_LIB.BASEBOARD_FAB2(SCH_1):PAGE31
  C7G5    1      A CAP_0402-0.22UF,16V,10%,X7R,A3A    I20 @BASEBOARD_FAB2_LIB.BASEBOARD_FAB2(SCH_1):PAGE105

P3E_CPU0_PE2_SS_TXP<1> @BASEBOARD_FAB2_LIB.BASEBOARD_FAB2(SCH_1):P3E_CPU0_PE2_SS_TXP(1)
  U5D1  CU2 PE2_TX_DP<1> SKX_EXT_B_BGA1-IC,TBD   I106 @BASEBOARD_FAB2_LIB.BASEBOARD_FAB2(SCH_1):PAGE31
  C8G8    1      A CAP_0402-0.22UF,16V,10%,X7R,A3A    I76 @BASEBOARD_FAB2_LIB.BASEBOARD_FAB2(SCH_1):PAGE105

P3E_CPU0_PE2_SS_TXP<2> @BASEBOARD_FAB2_LIB.BASEBOARD_FAB2(SCH_1):P3E_CPU0_PE2_SS_TXP(2)
  U5D1  CR2 PE2_TX_DP<2> SKX_EXT_B_BGA1-IC,TBD   I106 @BASEBOARD_FAB2_LIB.BASEBOARD_FAB2(SCH_1):PAGE31
  C8G5    1      A CAP_0402-0.22UF,16V,10%,X7R,A3A    I75 @BASEBOARD_FAB2_LIB.BASEBOARD_FAB2(SCH_1):PAGE105

P3E_CPU0_PE2_SS_TXP<3> @BASEBOARD_FAB2_LIB.BASEBOARD_FAB2(SCH_1):P3E_CPU0_PE2_SS_TXP(3)
  U5D1  CP3 PE2_TX_DP<3> SKX_EXT_B_BGA1-IC,TBD   I106 @BASEBOARD_FAB2_LIB.BASEBOARD_FAB2(SCH_1):PAGE31
  C8G3    1      A CAP_0402-0.22UF,16V,10%,X7R,A3A    I71 @BASEBOARD_FAB2_LIB.BASEBOARD_FAB2(SCH_1):PAGE105

P3E_CPU0_PE2_SS_TXP<4> @BASEBOARD_FAB2_LIB.BASEBOARD_FAB2(SCH_1):P3E_CPU0_PE2_SS_TXP(4)
  U5D1  CK1 PE2_TX_DP<4> SKX_EXT_B_BGA1-IC,TBD   I106 @BASEBOARD_FAB2_LIB.BASEBOARD_FAB2(SCH_1):PAGE31
  C8G1    1      A CAP_0402-0.22UF,16V,10%,X7R,A3A    I70 @BASEBOARD_FAB2_LIB.BASEBOARD_FAB2(SCH_1):PAGE105

P3E_CPU0_PE2_SS_TXP<5> @BASEBOARD_FAB2_LIB.BASEBOARD_FAB2(SCH_1):P3E_CPU0_PE2_SS_TXP(5)
  U5D1  CK3 PE2_TX_DP<5> SKX_EXT_B_BGA1-IC,TBD   I106 @BASEBOARD_FAB2_LIB.BASEBOARD_FAB2(SCH_1):PAGE31
 C7G25    1      A CAP_0402-0.22UF,16V,10%,X7R,A3A    I69 @BASEBOARD_FAB2_LIB.BASEBOARD_FAB2(SCH_1):PAGE105

P3E_CPU0_PE2_SS_TXP<6> @BASEBOARD_FAB2_LIB.BASEBOARD_FAB2(SCH_1):P3E_CPU0_PE2_SS_TXP(6)
  U5D1  CE2 PE2_TX_DP<6> SKX_EXT_B_BGA1-IC,TBD   I106 @BASEBOARD_FAB2_LIB.BASEBOARD_FAB2(SCH_1):PAGE31
 C7G23    1      A CAP_0402-0.22UF,16V,10%,X7R,A3A    I52 @BASEBOARD_FAB2_LIB.BASEBOARD_FAB2(SCH_1):PAGE105

P3E_CPU0_PE2_SS_TXP<7> @BASEBOARD_FAB2_LIB.BASEBOARD_FAB2(SCH_1):P3E_CPU0_PE2_SS_TXP(7)
  U5D1  CE4 PE2_TX_DP<7> SKX_EXT_B_BGA1-IC,TBD   I106 @BASEBOARD_FAB2_LIB.BASEBOARD_FAB2(SCH_1):PAGE31
 C7G21    1      A CAP_0402-0.22UF,16V,10%,X7R,A3A    I51 @BASEBOARD_FAB2_LIB.BASEBOARD_FAB2(SCH_1):PAGE105

P3E_CPU0_PE2_SS_TXP<8> @BASEBOARD_FAB2_LIB.BASEBOARD_FAB2(SCH_1):P3E_CPU0_PE2_SS_TXP(8)
  U5D1  CD3 PE2_TX_DP<8> SKX_EXT_B_BGA1-IC,TBD   I106 @BASEBOARD_FAB2_LIB.BASEBOARD_FAB2(SCH_1):PAGE31
 C7G20    1      A CAP_0402-0.22UF,16V,10%,X7R,A3A   I258 @BASEBOARD_FAB2_LIB.BASEBOARD_FAB2(SCH_1):PAGE105

P3E_CPU0_PE2_SS_TXP<9> @BASEBOARD_FAB2_LIB.BASEBOARD_FAB2(SCH_1):P3E_CPU0_PE2_SS_TXP(9)
  U5D1  BY3 PE2_TX_DP<9> SKX_EXT_B_BGA1-IC,TBD   I106 @BASEBOARD_FAB2_LIB.BASEBOARD_FAB2(SCH_1):PAGE31
 C7G17    1      A CAP_0402-0.22UF,16V,10%,X7R,A3A    I44 @BASEBOARD_FAB2_LIB.BASEBOARD_FAB2(SCH_1):PAGE105

P3E_CPU0_PE3_OCP_RXN<0> @BASEBOARD_FAB2_LIB.BASEBOARD_FAB2(SCH_1):P3E_CPU0_PE3_OCP_RXN(0)
  U5D1 EA18 PE3_RX_DN<0> SKX_EXT_B_BGA1-IC,TBD    I89 @BASEBOARD_FAB2_LIB.BASEBOARD_FAB2(SCH_1):PAGE32
  J8E3   63   IO63 SCONN80_E67482007_SM-CONN,E674A   I119 @BASEBOARD_FAB2_LIB.BASEBOARD_FAB2(SCH_1):PAGE187

P3E_CPU0_PE3_OCP_RXN<10> @BASEBOARD_FAB2_LIB.BASEBOARD_FAB2(SCH_1):P3E_CPU0_PE3_OCP_RXN(10)
  U5D1 DG12 PE3_RX_DN<10> SKX_EXT_B_BGA1-IC,TBD    I89 @BASEBOARD_FAB2_LIB.BASEBOARD_FAB2(SCH_1):PAGE32
  J9B3  101  IO101 SCONN120_A28699018_SM-SCONN,A2A   I336 @BASEBOARD_FAB2_LIB.BASEBOARD_FAB2(SCH_1):PAGE186

P3E_CPU0_PE3_OCP_RXN<11> @BASEBOARD_FAB2_LIB.BASEBOARD_FAB2(SCH_1):P3E_CPU0_PE3_OCP_RXN(11)
  U5D1 DG10 PE3_RX_DN<11> SKX_EXT_B_BGA1-IC,TBD    I89 @BASEBOARD_FAB2_LIB.BASEBOARD_FAB2(SCH_1):PAGE32
  J9B3   93   IO93 SCONN120_A28699018_SM-SCONN,A2A   I336 @BASEBOARD_FAB2_LIB.BASEBOARD_FAB2(SCH_1):PAGE186

P3E_CPU0_PE3_OCP_RXN<12> @BASEBOARD_FAB2_LIB.BASEBOARD_FAB2(SCH_1):P3E_CPU0_PE3_OCP_RXN(12)
  U5D1 DD13 PE3_RX_DN<12> SKX_EXT_B_BGA1-IC,TBD    I89 @BASEBOARD_FAB2_LIB.BASEBOARD_FAB2(SCH_1):PAGE32
  J9B3   85   IO85 SCONN120_A28699018_SM-SCONN,A2A   I336 @BASEBOARD_FAB2_LIB.BASEBOARD_FAB2(SCH_1):PAGE186

P3E_CPU0_PE3_OCP_RXN<13> @BASEBOARD_FAB2_LIB.BASEBOARD_FAB2(SCH_1):P3E_CPU0_PE3_OCP_RXN(13)
  U5D1 DB11 PE3_RX_DN<13> SKX_EXT_B_BGA1-IC,TBD    I89 @BASEBOARD_FAB2_LIB.BASEBOARD_FAB2(SCH_1):PAGE32
  J9B3   77   IO77 SCONN120_A28699018_SM-SCONN,A2A   I336 @BASEBOARD_FAB2_LIB.BASEBOARD_FAB2(SCH_1):PAGE186

P3E_CPU0_PE3_OCP_RXN<14> @BASEBOARD_FAB2_LIB.BASEBOARD_FAB2(SCH_1):P3E_CPU0_PE3_OCP_RXN(14)
  U5D1 CY11 PE3_RX_DN<14> SKX_EXT_B_BGA1-IC,TBD    I89 @BASEBOARD_FAB2_LIB.BASEBOARD_FAB2(SCH_1):PAGE32
  J9B3   69   IO69 SCONN120_A28699018_SM-SCONN,A2A   I336 @BASEBOARD_FAB2_LIB.BASEBOARD_FAB2(SCH_1):PAGE186

P3E_CPU0_PE3_OCP_RXN<15> @BASEBOARD_FAB2_LIB.BASEBOARD_FAB2(SCH_1):P3E_CPU0_PE3_OCP_RXN(15)
  U5D1  CV9 PE3_RX_DN<15> SKX_EXT_B_BGA1-IC,TBD    I89 @BASEBOARD_FAB2_LIB.BASEBOARD_FAB2(SCH_1):PAGE32
  J9B3   61   IO61 SCONN120_A28699018_SM-SCONN,A2A   I336 @BASEBOARD_FAB2_LIB.BASEBOARD_FAB2(SCH_1):PAGE186

P3E_CPU0_PE3_OCP_RXN<1> @BASEBOARD_FAB2_LIB.BASEBOARD_FAB2(SCH_1):P3E_CPU0_PE3_OCP_RXN(1)
  U5D1 DW18 PE3_RX_DN<1> SKX_EXT_B_BGA1-IC,TBD    I89 @BASEBOARD_FAB2_LIB.BASEBOARD_FAB2(SCH_1):PAGE32
  J8E3   55   IO55 SCONN80_E67482007_SM-CONN,E674A   I119 @BASEBOARD_FAB2_LIB.BASEBOARD_FAB2(SCH_1):PAGE187

P3E_CPU0_PE3_OCP_RXN<2> @BASEBOARD_FAB2_LIB.BASEBOARD_FAB2(SCH_1):P3E_CPU0_PE3_OCP_RXN(2)
  U5D1 DW16 PE3_RX_DN<2> SKX_EXT_B_BGA1-IC,TBD    I89 @BASEBOARD_FAB2_LIB.BASEBOARD_FAB2(SCH_1):PAGE32
  J8E3   47   IO47 SCONN80_E67482007_SM-CONN,E674A   I119 @BASEBOARD_FAB2_LIB.BASEBOARD_FAB2(SCH_1):PAGE187

P3E_CPU0_PE3_OCP_RXN<3> @BASEBOARD_FAB2_LIB.BASEBOARD_FAB2(SCH_1):P3E_CPU0_PE3_OCP_RXN(3)
  U5D1 DT19 PE3_RX_DN<3> SKX_EXT_B_BGA1-IC,TBD    I89 @BASEBOARD_FAB2_LIB.BASEBOARD_FAB2(SCH_1):PAGE32
  J8E3   39   IO39 SCONN80_E67482007_SM-CONN,E674A   I119 @BASEBOARD_FAB2_LIB.BASEBOARD_FAB2(SCH_1):PAGE187

P3E_CPU0_PE3_OCP_RXN<4> @BASEBOARD_FAB2_LIB.BASEBOARD_FAB2(SCH_1):P3E_CPU0_PE3_OCP_RXN(4)
  U5D1 DR16 PE3_RX_DN<4> SKX_EXT_B_BGA1-IC,TBD    I89 @BASEBOARD_FAB2_LIB.BASEBOARD_FAB2(SCH_1):PAGE32
  J8E3   29   IO29 SCONN80_E67482007_SM-CONN,E674A   I119 @BASEBOARD_FAB2_LIB.BASEBOARD_FAB2(SCH_1):PAGE187

P3E_CPU0_PE3_OCP_RXN<5> @BASEBOARD_FAB2_LIB.BASEBOARD_FAB2(SCH_1):P3E_CPU0_PE3_OCP_RXN(5)
  U5D1 DR14 PE3_RX_DN<5> SKX_EXT_B_BGA1-IC,TBD    I89 @BASEBOARD_FAB2_LIB.BASEBOARD_FAB2(SCH_1):PAGE32
  J8E3   21   IO21 SCONN80_E67482007_SM-CONN,E674A   I119 @BASEBOARD_FAB2_LIB.BASEBOARD_FAB2(SCH_1):PAGE187

P3E_CPU0_PE3_OCP_RXN<6> @BASEBOARD_FAB2_LIB.BASEBOARD_FAB2(SCH_1):P3E_CPU0_PE3_OCP_RXN(6)
  U5D1 DN14 PE3_RX_DN<6> SKX_EXT_B_BGA1-IC,TBD    I89 @BASEBOARD_FAB2_LIB.BASEBOARD_FAB2(SCH_1):PAGE32
  J8E3   13   IO13 SCONN80_E67482007_SM-CONN,E674A   I119 @BASEBOARD_FAB2_LIB.BASEBOARD_FAB2(SCH_1):PAGE187

P3E_CPU0_PE3_OCP_RXN<7> @BASEBOARD_FAB2_LIB.BASEBOARD_FAB2(SCH_1):P3E_CPU0_PE3_OCP_RXN(7)
  U5D1 DL14 PE3_RX_DN<7> SKX_EXT_B_BGA1-IC,TBD    I89 @BASEBOARD_FAB2_LIB.BASEBOARD_FAB2(SCH_1):PAGE32
  J8E3    7    IO7 SCONN80_E67482007_SM-CONN,E674A   I119 @BASEBOARD_FAB2_LIB.BASEBOARD_FAB2(SCH_1):PAGE187

P3E_CPU0_PE3_OCP_RXN<8> @BASEBOARD_FAB2_LIB.BASEBOARD_FAB2(SCH_1):P3E_CPU0_PE3_OCP_RXN(8)
  U5D1 DL12 PE3_RX_DN<8> SKX_EXT_B_BGA1-IC,TBD    I89 @BASEBOARD_FAB2_LIB.BASEBOARD_FAB2(SCH_1):PAGE32
  J9B3  117  IO117 SCONN120_A28699018_SM-SCONN,A2A   I336 @BASEBOARD_FAB2_LIB.BASEBOARD_FAB2(SCH_1):PAGE186

P3E_CPU0_PE3_OCP_RXN<9> @BASEBOARD_FAB2_LIB.BASEBOARD_FAB2(SCH_1):P3E_CPU0_PE3_OCP_RXN(9)
  U5D1 DJ12 PE3_RX_DN<9> SKX_EXT_B_BGA1-IC,TBD    I89 @BASEBOARD_FAB2_LIB.BASEBOARD_FAB2(SCH_1):PAGE32
  J9B3  109  IO109 SCONN120_A28699018_SM-SCONN,A2A   I336 @BASEBOARD_FAB2_LIB.BASEBOARD_FAB2(SCH_1):PAGE186

P3E_CPU0_PE3_OCP_RXP<0> @BASEBOARD_FAB2_LIB.BASEBOARD_FAB2(SCH_1):P3E_CPU0_PE3_OCP_RXP(0)
  U5D1 DY17 PE3_RX_DP<0> SKX_EXT_B_BGA1-IC,TBD    I89 @BASEBOARD_FAB2_LIB.BASEBOARD_FAB2(SCH_1):PAGE32
  J8E3   61   IO61 SCONN80_E67482007_SM-CONN,E674A   I119 @BASEBOARD_FAB2_LIB.BASEBOARD_FAB2(SCH_1):PAGE187

P3E_CPU0_PE3_OCP_RXP<10> @BASEBOARD_FAB2_LIB.BASEBOARD_FAB2(SCH_1):P3E_CPU0_PE3_OCP_RXP(10)
  U5D1 DE12 PE3_RX_DP<10> SKX_EXT_B_BGA1-IC,TBD    I89 @BASEBOARD_FAB2_LIB.BASEBOARD_FAB2(SCH_1):PAGE32
  J9B3   99   IO99 SCONN120_A28699018_SM-SCONN,A2A   I336 @BASEBOARD_FAB2_LIB.BASEBOARD_FAB2(SCH_1):PAGE186

P3E_CPU0_PE3_OCP_RXP<11> @BASEBOARD_FAB2_LIB.BASEBOARD_FAB2(SCH_1):P3E_CPU0_PE3_OCP_RXP(11)
  U5D1 DF11 PE3_RX_DP<11> SKX_EXT_B_BGA1-IC,TBD    I89 @BASEBOARD_FAB2_LIB.BASEBOARD_FAB2(SCH_1):PAGE32
  J9B3   91   IO91 SCONN120_A28699018_SM-SCONN,A2A   I336 @BASEBOARD_FAB2_LIB.BASEBOARD_FAB2(SCH_1):PAGE186

P3E_CPU0_PE3_OCP_RXP<12> @BASEBOARD_FAB2_LIB.BASEBOARD_FAB2(SCH_1):P3E_CPU0_PE3_OCP_RXP(12)
  U5D1 DC12 PE3_RX_DP<12> SKX_EXT_B_BGA1-IC,TBD    I89 @BASEBOARD_FAB2_LIB.BASEBOARD_FAB2(SCH_1):PAGE32
  J9B3   83   IO83 SCONN120_A28699018_SM-SCONN,A2A   I336 @BASEBOARD_FAB2_LIB.BASEBOARD_FAB2(SCH_1):PAGE186

P3E_CPU0_PE3_OCP_RXP<13> @BASEBOARD_FAB2_LIB.BASEBOARD_FAB2(SCH_1):P3E_CPU0_PE3_OCP_RXP(13)
  U5D1 DA12 PE3_RX_DP<13> SKX_EXT_B_BGA1-IC,TBD    I89 @BASEBOARD_FAB2_LIB.BASEBOARD_FAB2(SCH_1):PAGE32
  J9B3   75   IO75 SCONN120_A28699018_SM-SCONN,A2A   I336 @BASEBOARD_FAB2_LIB.BASEBOARD_FAB2(SCH_1):PAGE186

P3E_CPU0_PE3_OCP_RXP<14> @BASEBOARD_FAB2_LIB.BASEBOARD_FAB2(SCH_1):P3E_CPU0_PE3_OCP_RXP(14)
  U5D1 CW10 PE3_RX_DP<14> SKX_EXT_B_BGA1-IC,TBD    I89 @BASEBOARD_FAB2_LIB.BASEBOARD_FAB2(SCH_1):PAGE32
  J9B3   67   IO67 SCONN120_A28699018_SM-SCONN,A2A   I336 @BASEBOARD_FAB2_LIB.BASEBOARD_FAB2(SCH_1):PAGE186

P3E_CPU0_PE3_OCP_RXP<15> @BASEBOARD_FAB2_LIB.BASEBOARD_FAB2(SCH_1):P3E_CPU0_PE3_OCP_RXP(15)
  U5D1 CU10 PE3_RX_DP<15> SKX_EXT_B_BGA1-IC,TBD    I89 @BASEBOARD_FAB2_LIB.BASEBOARD_FAB2(SCH_1):PAGE32
  J9B3   59   IO59 SCONN120_A28699018_SM-SCONN,A2A   I336 @BASEBOARD_FAB2_LIB.BASEBOARD_FAB2(SCH_1):PAGE186

P3E_CPU0_PE3_OCP_RXP<1> @BASEBOARD_FAB2_LIB.BASEBOARD_FAB2(SCH_1):P3E_CPU0_PE3_OCP_RXP(1)
  U5D1 DU18 PE3_RX_DP<1> SKX_EXT_B_BGA1-IC,TBD    I89 @BASEBOARD_FAB2_LIB.BASEBOARD_FAB2(SCH_1):PAGE32
  J8E3   53   IO53 SCONN80_E67482007_SM-CONN,E674A   I119 @BASEBOARD_FAB2_LIB.BASEBOARD_FAB2(SCH_1):PAGE187

P3E_CPU0_PE3_OCP_RXP<2> @BASEBOARD_FAB2_LIB.BASEBOARD_FAB2(SCH_1):P3E_CPU0_PE3_OCP_RXP(2)
  U5D1 DV17 PE3_RX_DP<2> SKX_EXT_B_BGA1-IC,TBD    I89 @BASEBOARD_FAB2_LIB.BASEBOARD_FAB2(SCH_1):PAGE32
  J8E3   45   IO45 SCONN80_E67482007_SM-CONN,E674A   I119 @BASEBOARD_FAB2_LIB.BASEBOARD_FAB2(SCH_1):PAGE187

P3E_CPU0_PE3_OCP_RXP<3> @BASEBOARD_FAB2_LIB.BASEBOARD_FAB2(SCH_1):P3E_CPU0_PE3_OCP_RXP(3)
  U5D1 DR18 PE3_RX_DP<3> SKX_EXT_B_BGA1-IC,TBD    I89 @BASEBOARD_FAB2_LIB.BASEBOARD_FAB2(SCH_1):PAGE32
  J8E3   37   IO37 SCONN80_E67482007_SM-CONN,E674A   I119 @BASEBOARD_FAB2_LIB.BASEBOARD_FAB2(SCH_1):PAGE187

P3E_CPU0_PE3_OCP_RXP<4> @BASEBOARD_FAB2_LIB.BASEBOARD_FAB2(SCH_1):P3E_CPU0_PE3_OCP_RXP(4)
  U5D1 DN16 PE3_RX_DP<4> SKX_EXT_B_BGA1-IC,TBD    I89 @BASEBOARD_FAB2_LIB.BASEBOARD_FAB2(SCH_1):PAGE32
  J8E3   31   IO31 SCONN80_E67482007_SM-CONN,E674A   I119 @BASEBOARD_FAB2_LIB.BASEBOARD_FAB2(SCH_1):PAGE187

P3E_CPU0_PE3_OCP_RXP<5> @BASEBOARD_FAB2_LIB.BASEBOARD_FAB2(SCH_1):P3E_CPU0_PE3_OCP_RXP(5)
  U5D1 DP15 PE3_RX_DP<5> SKX_EXT_B_BGA1-IC,TBD    I89 @BASEBOARD_FAB2_LIB.BASEBOARD_FAB2(SCH_1):PAGE32
  J8E3   23   IO23 SCONN80_E67482007_SM-CONN,E674A   I119 @BASEBOARD_FAB2_LIB.BASEBOARD_FAB2(SCH_1):PAGE187

P3E_CPU0_PE3_OCP_RXP<6> @BASEBOARD_FAB2_LIB.BASEBOARD_FAB2(SCH_1):P3E_CPU0_PE3_OCP_RXP(6)
  U5D1 DM13 PE3_RX_DP<6> SKX_EXT_B_BGA1-IC,TBD    I89 @BASEBOARD_FAB2_LIB.BASEBOARD_FAB2(SCH_1):PAGE32
  J8E3   15   IO15 SCONN80_E67482007_SM-CONN,E674A   I119 @BASEBOARD_FAB2_LIB.BASEBOARD_FAB2(SCH_1):PAGE187

P3E_CPU0_PE3_OCP_RXP<7> @BASEBOARD_FAB2_LIB.BASEBOARD_FAB2(SCH_1):P3E_CPU0_PE3_OCP_RXP(7)
  U5D1 DJ14 PE3_RX_DP<7> SKX_EXT_B_BGA1-IC,TBD    I89 @BASEBOARD_FAB2_LIB.BASEBOARD_FAB2(SCH_1):PAGE32
  J8E3    5    IO5 SCONN80_E67482007_SM-CONN,E674A   I119 @BASEBOARD_FAB2_LIB.BASEBOARD_FAB2(SCH_1):PAGE187

P3E_CPU0_PE3_OCP_RXP<8> @BASEBOARD_FAB2_LIB.BASEBOARD_FAB2(SCH_1):P3E_CPU0_PE3_OCP_RXP(8)
  U5D1 DK13 PE3_RX_DP<8> SKX_EXT_B_BGA1-IC,TBD    I89 @BASEBOARD_FAB2_LIB.BASEBOARD_FAB2(SCH_1):PAGE32
  J9B3  115  IO115 SCONN120_A28699018_SM-SCONN,A2A   I336 @BASEBOARD_FAB2_LIB.BASEBOARD_FAB2(SCH_1):PAGE186

P3E_CPU0_PE3_OCP_RXP<9> @BASEBOARD_FAB2_LIB.BASEBOARD_FAB2(SCH_1):P3E_CPU0_PE3_OCP_RXP(9)
  U5D1 DH11 PE3_RX_DP<9> SKX_EXT_B_BGA1-IC,TBD    I89 @BASEBOARD_FAB2_LIB.BASEBOARD_FAB2(SCH_1):PAGE32
  J9B3  107  IO107 SCONN120_A28699018_SM-SCONN,A2A   I336 @BASEBOARD_FAB2_LIB.BASEBOARD_FAB2(SCH_1):PAGE186

P3E_CPU0_PE3_OCP_TXN<0> @BASEBOARD_FAB2_LIB.BASEBOARD_FAB2(SCH_1):P3E_CPU0_PE3_OCP_TXN(0)
  U5D1 EE14 PE3_TX_DN<0> SKX_EXT_B_BGA1-IC,TBD    I89 @BASEBOARD_FAB2_LIB.BASEBOARD_FAB2(SCH_1):PAGE32
  C1R1    1      A CAP_0402-0.22UF,16V,10%,X7R,A3A    I29 @BASEBOARD_FAB2_LIB.BASEBOARD_FAB2(SCH_1):PAGE106

P3E_CPU0_PE3_OCP_TXN<10> @BASEBOARD_FAB2_LIB.BASEBOARD_FAB2(SCH_1):P3E_CPU0_PE3_OCP_TXN(10)
  U5D1  DL6 PE3_TX_DN<10> SKX_EXT_B_BGA1-IC,TBD    I89 @BASEBOARD_FAB2_LIB.BASEBOARD_FAB2(SCH_1):PAGE32
 C1M17    1      A CAP_0402-0.22UF,16V,10%,X7R,A3A    I92 @BASEBOARD_FAB2_LIB.BASEBOARD_FAB2(SCH_1):PAGE106

P3E_CPU0_PE3_OCP_TXN<11> @BASEBOARD_FAB2_LIB.BASEBOARD_FAB2(SCH_1):P3E_CPU0_PE3_OCP_TXN(11)
  U5D1  DJ4 PE3_TX_DN<11> SKX_EXT_B_BGA1-IC,TBD    I89 @BASEBOARD_FAB2_LIB.BASEBOARD_FAB2(SCH_1):PAGE32
 C1M15    1      A CAP_0402-0.22UF,16V,10%,X7R,A3A    I95 @BASEBOARD_FAB2_LIB.BASEBOARD_FAB2(SCH_1):PAGE106

P3E_CPU0_PE3_OCP_TXN<12> @BASEBOARD_FAB2_LIB.BASEBOARD_FAB2(SCH_1):P3E_CPU0_PE3_OCP_TXN(12)
  U5D1  DJ6 PE3_TX_DN<12> SKX_EXT_B_BGA1-IC,TBD    I89 @BASEBOARD_FAB2_LIB.BASEBOARD_FAB2(SCH_1):PAGE32
 C1M13    1      A CAP_0402-0.22UF,16V,10%,X7R,A3A   I111 @BASEBOARD_FAB2_LIB.BASEBOARD_FAB2(SCH_1):PAGE106

P3E_CPU0_PE3_OCP_TXN<13> @BASEBOARD_FAB2_LIB.BASEBOARD_FAB2(SCH_1):P3E_CPU0_PE3_OCP_TXN(13)
  U5D1  DD5 PE3_TX_DN<13> SKX_EXT_B_BGA1-IC,TBD    I89 @BASEBOARD_FAB2_LIB.BASEBOARD_FAB2(SCH_1):PAGE32
 C1M11    1      A CAP_0402-0.22UF,16V,10%,X7R,A3A   I117 @BASEBOARD_FAB2_LIB.BASEBOARD_FAB2(SCH_1):PAGE106

P3E_CPU0_PE3_OCP_TXN<14> @BASEBOARD_FAB2_LIB.BASEBOARD_FAB2(SCH_1):P3E_CPU0_PE3_OCP_TXN(14)
  U5D1  DB5 PE3_TX_DN<14> SKX_EXT_B_BGA1-IC,TBD    I89 @BASEBOARD_FAB2_LIB.BASEBOARD_FAB2(SCH_1):PAGE32
  C1M9    1      A CAP_0402-0.22UF,16V,10%,X7R,A3A   I114 @BASEBOARD_FAB2_LIB.BASEBOARD_FAB2(SCH_1):PAGE106

P3E_CPU0_PE3_OCP_TXN<15> @BASEBOARD_FAB2_LIB.BASEBOARD_FAB2(SCH_1):P3E_CPU0_PE3_OCP_TXN(15)
  U5D1  CY5 PE3_TX_DN<15> SKX_EXT_B_BGA1-IC,TBD    I89 @BASEBOARD_FAB2_LIB.BASEBOARD_FAB2(SCH_1):PAGE32
  C1M7    1      A CAP_0402-0.22UF,16V,10%,X7R,A3A   I122 @BASEBOARD_FAB2_LIB.BASEBOARD_FAB2(SCH_1):PAGE106

P3E_CPU0_PE3_OCP_TXN<1> @BASEBOARD_FAB2_LIB.BASEBOARD_FAB2(SCH_1):P3E_CPU0_PE3_OCP_TXN(1)
  U5D1 EE12 PE3_TX_DN<1> SKX_EXT_B_BGA1-IC,TBD    I89 @BASEBOARD_FAB2_LIB.BASEBOARD_FAB2(SCH_1):PAGE32
  C1R3    1      A CAP_0402-0.22UF,16V,10%,X7R,A3A    I37 @BASEBOARD_FAB2_LIB.BASEBOARD_FAB2(SCH_1):PAGE106

P3E_CPU0_PE3_OCP_TXN<2> @BASEBOARD_FAB2_LIB.BASEBOARD_FAB2(SCH_1):P3E_CPU0_PE3_OCP_TXN(2)
  U5D1 EC12 PE3_TX_DN<2> SKX_EXT_B_BGA1-IC,TBD    I89 @BASEBOARD_FAB2_LIB.BASEBOARD_FAB2(SCH_1):PAGE32
  C1R5    1      A CAP_0402-0.22UF,16V,10%,X7R,A3A    I59 @BASEBOARD_FAB2_LIB.BASEBOARD_FAB2(SCH_1):PAGE106

P3E_CPU0_PE3_OCP_TXN<3> @BASEBOARD_FAB2_LIB.BASEBOARD_FAB2(SCH_1):P3E_CPU0_PE3_OCP_TXN(3)
  U5D1 DY11 PE3_TX_DN<3> SKX_EXT_B_BGA1-IC,TBD    I89 @BASEBOARD_FAB2_LIB.BASEBOARD_FAB2(SCH_1):PAGE32
  C1R7    1      A CAP_0402-0.22UF,16V,10%,X7R,A3A    I70 @BASEBOARD_FAB2_LIB.BASEBOARD_FAB2(SCH_1):PAGE106

P3E_CPU0_PE3_OCP_TXN<4> @BASEBOARD_FAB2_LIB.BASEBOARD_FAB2(SCH_1):P3E_CPU0_PE3_OCP_TXN(4)
  U5D1  EB9 PE3_TX_DN<4> SKX_EXT_B_BGA1-IC,TBD    I89 @BASEBOARD_FAB2_LIB.BASEBOARD_FAB2(SCH_1):PAGE32
  C1R9    1      A CAP_0402-0.22UF,16V,10%,X7R,A3A   I134 @BASEBOARD_FAB2_LIB.BASEBOARD_FAB2(SCH_1):PAGE106

P3E_CPU0_PE3_OCP_TXN<5> @BASEBOARD_FAB2_LIB.BASEBOARD_FAB2(SCH_1):P3E_CPU0_PE3_OCP_TXN(5)
  U5D1 DW10 PE3_TX_DN<5> SKX_EXT_B_BGA1-IC,TBD    I89 @BASEBOARD_FAB2_LIB.BASEBOARD_FAB2(SCH_1):PAGE32
 C2R13    1      A CAP_0402-0.22UF,16V,10%,X7R,A3A   I137 @BASEBOARD_FAB2_LIB.BASEBOARD_FAB2(SCH_1):PAGE106

P3E_CPU0_PE3_OCP_TXN<6> @BASEBOARD_FAB2_LIB.BASEBOARD_FAB2(SCH_1):P3E_CPU0_PE3_OCP_TXN(6)
  U5D1  DU8 PE3_TX_DN<6> SKX_EXT_B_BGA1-IC,TBD    I89 @BASEBOARD_FAB2_LIB.BASEBOARD_FAB2(SCH_1):PAGE32
  C2R7    1      A CAP_0402-0.22UF,16V,10%,X7R,A3A   I123 @BASEBOARD_FAB2_LIB.BASEBOARD_FAB2(SCH_1):PAGE106

P3E_CPU0_PE3_OCP_TXN<7> @BASEBOARD_FAB2_LIB.BASEBOARD_FAB2(SCH_1):P3E_CPU0_PE3_OCP_TXN(7)
  U5D1  DR8 PE3_TX_DN<7> SKX_EXT_B_BGA1-IC,TBD    I89 @BASEBOARD_FAB2_LIB.BASEBOARD_FAB2(SCH_1):PAGE32
  C2R9    1      A CAP_0402-0.22UF,16V,10%,X7R,A3A   I147 @BASEBOARD_FAB2_LIB.BASEBOARD_FAB2(SCH_1):PAGE106

P3E_CPU0_PE3_OCP_TXN<8> @BASEBOARD_FAB2_LIB.BASEBOARD_FAB2(SCH_1):P3E_CPU0_PE3_OCP_TXN(8)
  U5D1  DM7 PE3_TX_DN<8> SKX_EXT_B_BGA1-IC,TBD    I89 @BASEBOARD_FAB2_LIB.BASEBOARD_FAB2(SCH_1):PAGE32
 C2M15    1      A CAP_0402-0.22UF,16V,10%,X7R,A3A    I86 @BASEBOARD_FAB2_LIB.BASEBOARD_FAB2(SCH_1):PAGE106

P3E_CPU0_PE3_OCP_TXN<9> @BASEBOARD_FAB2_LIB.BASEBOARD_FAB2(SCH_1):P3E_CPU0_PE3_OCP_TXN(9)
  U5D1  DP5 PE3_TX_DN<9> SKX_EXT_B_BGA1-IC,TBD    I89 @BASEBOARD_FAB2_LIB.BASEBOARD_FAB2(SCH_1):PAGE32
 C1M19    1      A CAP_0402-0.22UF,16V,10%,X7R,A3A    I90 @BASEBOARD_FAB2_LIB.BASEBOARD_FAB2(SCH_1):PAGE106

P3E_CPU0_PE3_OCP_TXP<0> @BASEBOARD_FAB2_LIB.BASEBOARD_FAB2(SCH_1):P3E_CPU0_PE3_OCP_TXP(0)
  U5D1 EC14 PE3_TX_DP<0> SKX_EXT_B_BGA1-IC,TBD    I89 @BASEBOARD_FAB2_LIB.BASEBOARD_FAB2(SCH_1):PAGE32
  C1R2    1      A CAP_0402-0.22UF,16V,10%,X7R,A3A    I10 @BASEBOARD_FAB2_LIB.BASEBOARD_FAB2(SCH_1):PAGE106

P3E_CPU0_PE3_OCP_TXP<10> @BASEBOARD_FAB2_LIB.BASEBOARD_FAB2(SCH_1):P3E_CPU0_PE3_OCP_TXP(10)
  U5D1  DK5 PE3_TX_DP<10> SKX_EXT_B_BGA1-IC,TBD    I89 @BASEBOARD_FAB2_LIB.BASEBOARD_FAB2(SCH_1):PAGE32
 C1M16    1      A CAP_0402-0.22UF,16V,10%,X7R,A3A    I82 @BASEBOARD_FAB2_LIB.BASEBOARD_FAB2(SCH_1):PAGE106

P3E_CPU0_PE3_OCP_TXP<11> @BASEBOARD_FAB2_LIB.BASEBOARD_FAB2(SCH_1):P3E_CPU0_PE3_OCP_TXP(11)
  U5D1  DH5 PE3_TX_DP<11> SKX_EXT_B_BGA1-IC,TBD    I89 @BASEBOARD_FAB2_LIB.BASEBOARD_FAB2(SCH_1):PAGE32
 C1M14    1      A CAP_0402-0.22UF,16V,10%,X7R,A3A    I85 @BASEBOARD_FAB2_LIB.BASEBOARD_FAB2(SCH_1):PAGE106

P3E_CPU0_PE3_OCP_TXP<12> @BASEBOARD_FAB2_LIB.BASEBOARD_FAB2(SCH_1):P3E_CPU0_PE3_OCP_TXP(12)
  U5D1  DG6 PE3_TX_DP<12> SKX_EXT_B_BGA1-IC,TBD    I89 @BASEBOARD_FAB2_LIB.BASEBOARD_FAB2(SCH_1):PAGE32
 C1M12    1      A CAP_0402-0.22UF,16V,10%,X7R,A3A   I100 @BASEBOARD_FAB2_LIB.BASEBOARD_FAB2(SCH_1):PAGE106

P3E_CPU0_PE3_OCP_TXP<13> @BASEBOARD_FAB2_LIB.BASEBOARD_FAB2(SCH_1):P3E_CPU0_PE3_OCP_TXP(13)
  U5D1  DC6 PE3_TX_DP<13> SKX_EXT_B_BGA1-IC,TBD    I89 @BASEBOARD_FAB2_LIB.BASEBOARD_FAB2(SCH_1):PAGE32
 C1M10    1      A CAP_0402-0.22UF,16V,10%,X7R,A3A   I102 @BASEBOARD_FAB2_LIB.BASEBOARD_FAB2(SCH_1):PAGE106

P3E_CPU0_PE3_OCP_TXP<14> @BASEBOARD_FAB2_LIB.BASEBOARD_FAB2(SCH_1):P3E_CPU0_PE3_OCP_TXP(14)
  U5D1  DA4 PE3_TX_DP<14> SKX_EXT_B_BGA1-IC,TBD    I89 @BASEBOARD_FAB2_LIB.BASEBOARD_FAB2(SCH_1):PAGE32
  C1M8    1      A CAP_0402-0.22UF,16V,10%,X7R,A3A   I105 @BASEBOARD_FAB2_LIB.BASEBOARD_FAB2(SCH_1):PAGE106

P3E_CPU0_PE3_OCP_TXP<15> @BASEBOARD_FAB2_LIB.BASEBOARD_FAB2(SCH_1):P3E_CPU0_PE3_OCP_TXP(15)
  U5D1  CV5 PE3_TX_DP<15> SKX_EXT_B_BGA1-IC,TBD    I89 @BASEBOARD_FAB2_LIB.BASEBOARD_FAB2(SCH_1):PAGE32
  C1M6    1      A CAP_0402-0.22UF,16V,10%,X7R,A3A   I109 @BASEBOARD_FAB2_LIB.BASEBOARD_FAB2(SCH_1):PAGE106

P3E_CPU0_PE3_OCP_TXP<1> @BASEBOARD_FAB2_LIB.BASEBOARD_FAB2(SCH_1):P3E_CPU0_PE3_OCP_TXP(1)
  U5D1 ED13 PE3_TX_DP<1> SKX_EXT_B_BGA1-IC,TBD    I89 @BASEBOARD_FAB2_LIB.BASEBOARD_FAB2(SCH_1):PAGE32
  C1R4    1      A CAP_0402-0.22UF,16V,10%,X7R,A3A    I26 @BASEBOARD_FAB2_LIB.BASEBOARD_FAB2(SCH_1):PAGE106

P3E_CPU0_PE3_OCP_TXP<2> @BASEBOARD_FAB2_LIB.BASEBOARD_FAB2(SCH_1):P3E_CPU0_PE3_OCP_TXP(2)
  U5D1 EB11 PE3_TX_DP<2> SKX_EXT_B_BGA1-IC,TBD    I89 @BASEBOARD_FAB2_LIB.BASEBOARD_FAB2(SCH_1):PAGE32
  C1R6    1      A CAP_0402-0.22UF,16V,10%,X7R,A3A    I40 @BASEBOARD_FAB2_LIB.BASEBOARD_FAB2(SCH_1):PAGE106

P3E_CPU0_PE3_OCP_TXP<3> @BASEBOARD_FAB2_LIB.BASEBOARD_FAB2(SCH_1):P3E_CPU0_PE3_OCP_TXP(3)
  U5D1 EA10 PE3_TX_DP<3> SKX_EXT_B_BGA1-IC,TBD    I89 @BASEBOARD_FAB2_LIB.BASEBOARD_FAB2(SCH_1):PAGE32
  C1R8    1      A CAP_0402-0.22UF,16V,10%,X7R,A3A    I55 @BASEBOARD_FAB2_LIB.BASEBOARD_FAB2(SCH_1):PAGE106

P3E_CPU0_PE3_OCP_TXP<4> @BASEBOARD_FAB2_LIB.BASEBOARD_FAB2(SCH_1):P3E_CPU0_PE3_OCP_TXP(4)
  U5D1  DY9 PE3_TX_DP<4> SKX_EXT_B_BGA1-IC,TBD    I89 @BASEBOARD_FAB2_LIB.BASEBOARD_FAB2(SCH_1):PAGE32
 C1R10    1      A CAP_0402-0.22UF,16V,10%,X7R,A3A   I128 @BASEBOARD_FAB2_LIB.BASEBOARD_FAB2(SCH_1):PAGE106

P3E_CPU0_PE3_OCP_TXP<5> @BASEBOARD_FAB2_LIB.BASEBOARD_FAB2(SCH_1):P3E_CPU0_PE3_OCP_TXP(5)
  U5D1  DV9 PE3_TX_DP<5> SKX_EXT_B_BGA1-IC,TBD    I89 @BASEBOARD_FAB2_LIB.BASEBOARD_FAB2(SCH_1):PAGE32
 C2R14    1      A CAP_0402-0.22UF,16V,10%,X7R,A3A   I130 @BASEBOARD_FAB2_LIB.BASEBOARD_FAB2(SCH_1):PAGE106

P3E_CPU0_PE3_OCP_TXP<6> @BASEBOARD_FAB2_LIB.BASEBOARD_FAB2(SCH_1):P3E_CPU0_PE3_OCP_TXP(6)
  U5D1  DT9 PE3_TX_DP<6> SKX_EXT_B_BGA1-IC,TBD    I89 @BASEBOARD_FAB2_LIB.BASEBOARD_FAB2(SCH_1):PAGE32
  C2R8    1      A CAP_0402-0.22UF,16V,10%,X7R,A3A   I141 @BASEBOARD_FAB2_LIB.BASEBOARD_FAB2(SCH_1):PAGE106

P3E_CPU0_PE3_OCP_TXP<7> @BASEBOARD_FAB2_LIB.BASEBOARD_FAB2(SCH_1):P3E_CPU0_PE3_OCP_TXP(7)
  U5D1  DP7 PE3_TX_DP<7> SKX_EXT_B_BGA1-IC,TBD    I89 @BASEBOARD_FAB2_LIB.BASEBOARD_FAB2(SCH_1):PAGE32
 C2R10    1      A CAP_0402-0.22UF,16V,10%,X7R,A3A   I142 @BASEBOARD_FAB2_LIB.BASEBOARD_FAB2(SCH_1):PAGE106

P3E_CPU0_PE3_OCP_TXP<8> @BASEBOARD_FAB2_LIB.BASEBOARD_FAB2(SCH_1):P3E_CPU0_PE3_OCP_TXP(8)
  U5D1  DN6 PE3_TX_DP<8> SKX_EXT_B_BGA1-IC,TBD    I89 @BASEBOARD_FAB2_LIB.BASEBOARD_FAB2(SCH_1):PAGE32
 C2M14    1      A CAP_0402-0.22UF,16V,10%,X7R,A3A    I76 @BASEBOARD_FAB2_LIB.BASEBOARD_FAB2(SCH_1):PAGE106

P3E_CPU0_PE3_OCP_TXP<9> @BASEBOARD_FAB2_LIB.BASEBOARD_FAB2(SCH_1):P3E_CPU0_PE3_OCP_TXP(9)
  U5D1  DM5 PE3_TX_DP<9> SKX_EXT_B_BGA1-IC,TBD    I89 @BASEBOARD_FAB2_LIB.BASEBOARD_FAB2(SCH_1):PAGE32
 C1M18    1      A CAP_0402-0.22UF,16V,10%,X7R,A3A    I78 @BASEBOARD_FAB2_LIB.BASEBOARD_FAB2(SCH_1):PAGE106

P3E_CPU1_PE3_MP_C_TXN<0> @BASEBOARD_FAB2_LIB.BASEBOARD_FAB2(SCH_1):P3E_CPU1_PE3_MP_C_TXN(0)
 C1F20    1      A CAP_0402-0.22UF,16V,10%,X7R,A3A    I86 @BASEBOARD_FAB2_LIB.BASEBOARD_FAB2(SCH_1):PAGE181
  J1F1   B8 PCIE_TX_DP0 DM-FCI-CONN76-8R-GP-U-01_CONN-A   I134 @BASEBOARD_FAB2_LIB.BASEBOARD_FAB2(SCH_1):PAGE181

P3E_CPU1_PE3_MP_C_TXN<10> @BASEBOARD_FAB2_LIB.BASEBOARD_FAB2(SCH_1):P3E_CPU1_PE3_MP_C_TXN(10)
  C9N2    1      A CAP_0402-0.22UF,16V,10%,X7R,A3A    I36 @BASEBOARD_FAB2_LIB.BASEBOARD_FAB2(SCH_1):PAGE182
  J1C1   I8 PCIE_TX_DN2 DM-FCI-CONN76-8R-GP-U-01_CONN-A    I79 @BASEBOARD_FAB2_LIB.BASEBOARD_FAB2(SCH_1):PAGE182

P3E_CPU1_PE3_MP_C_TXN<11> @BASEBOARD_FAB2_LIB.BASEBOARD_FAB2(SCH_1):P3E_CPU1_PE3_MP_C_TXN(11)
  C9N3    1      A CAP_0402-0.22UF,16V,10%,X7R,A3A    I47 @BASEBOARD_FAB2_LIB.BASEBOARD_FAB2(SCH_1):PAGE182
  J1C1   A7 PCIE_TX_DP3 DM-FCI-CONN76-8R-GP-U-01_CONN-A    I79 @BASEBOARD_FAB2_LIB.BASEBOARD_FAB2(SCH_1):PAGE182

P3E_CPU1_PE3_MP_C_TXN<12> @BASEBOARD_FAB2_LIB.BASEBOARD_FAB2(SCH_1):P3E_CPU1_PE3_MP_C_TXN(12)
 C9N16    1      A CAP_0402-0.22UF,16V,10%,X7R,A3A    I46 @BASEBOARD_FAB2_LIB.BASEBOARD_FAB2(SCH_1):PAGE182
  J1C1   D7 PCIE_TX_DP4 DM-FCI-CONN76-8R-GP-U-01_CONN-A    I79 @BASEBOARD_FAB2_LIB.BASEBOARD_FAB2(SCH_1):PAGE182

P3E_CPU1_PE3_MP_C_TXN<13> @BASEBOARD_FAB2_LIB.BASEBOARD_FAB2(SCH_1):P3E_CPU1_PE3_MP_C_TXN(13)
  C9N6    1      A CAP_0402-0.22UF,16V,10%,X7R,A3A    I42 @BASEBOARD_FAB2_LIB.BASEBOARD_FAB2(SCH_1):PAGE182
  J1C1   G7 PCIE_TX_DP5 DM-FCI-CONN76-8R-GP-U-01_CONN-A    I79 @BASEBOARD_FAB2_LIB.BASEBOARD_FAB2(SCH_1):PAGE182

P3E_CPU1_PE3_MP_C_TXN<14> @BASEBOARD_FAB2_LIB.BASEBOARD_FAB2(SCH_1):P3E_CPU1_PE3_MP_C_TXN(14)
  C9N8    1      A CAP_0402-0.22UF,16V,10%,X7R,A3A    I53 @BASEBOARD_FAB2_LIB.BASEBOARD_FAB2(SCH_1):PAGE182
  J1C1   E6 PCIE_TX_DP6 DM-FCI-CONN76-8R-GP-U-01_CONN-A    I79 @BASEBOARD_FAB2_LIB.BASEBOARD_FAB2(SCH_1):PAGE182

P3E_CPU1_PE3_MP_C_TXN<15> @BASEBOARD_FAB2_LIB.BASEBOARD_FAB2(SCH_1):P3E_CPU1_PE3_MP_C_TXN(15)
  C9N9    1      A CAP_0402-0.22UF,16V,10%,X7R,A3A    I52 @BASEBOARD_FAB2_LIB.BASEBOARD_FAB2(SCH_1):PAGE182
  J1C1   H6 PCIE_TX_DP7 DM-FCI-CONN76-8R-GP-U-01_CONN-A    I79 @BASEBOARD_FAB2_LIB.BASEBOARD_FAB2(SCH_1):PAGE182

P3E_CPU1_PE3_MP_C_TXN<1> @BASEBOARD_FAB2_LIB.BASEBOARD_FAB2(SCH_1):P3E_CPU1_PE3_MP_C_TXN(1)
 C1F16    1      A CAP_0402-0.22UF,16V,10%,X7R,A3A    I79 @BASEBOARD_FAB2_LIB.BASEBOARD_FAB2(SCH_1):PAGE181
  J1F1   E8 PCIE_TX_DP1 DM-FCI-CONN76-8R-GP-U-01_CONN-A   I134 @BASEBOARD_FAB2_LIB.BASEBOARD_FAB2(SCH_1):PAGE181

P3E_CPU1_PE3_MP_C_TXN<2> @BASEBOARD_FAB2_LIB.BASEBOARD_FAB2(SCH_1):P3E_CPU1_PE3_MP_C_TXN(2)
 C1F15    1      A CAP_0402-0.22UF,16V,10%,X7R,A3A    I78 @BASEBOARD_FAB2_LIB.BASEBOARD_FAB2(SCH_1):PAGE181
  J1F1   H8 PCIE_TX_DP2 DM-FCI-CONN76-8R-GP-U-01_CONN-A   I134 @BASEBOARD_FAB2_LIB.BASEBOARD_FAB2(SCH_1):PAGE181

P3E_CPU1_PE3_MP_C_TXN<3> @BASEBOARD_FAB2_LIB.BASEBOARD_FAB2(SCH_1):P3E_CPU1_PE3_MP_C_TXN(3)
 C1F13    1      A CAP_0402-0.22UF,16V,10%,X7R,A3A    I89 @BASEBOARD_FAB2_LIB.BASEBOARD_FAB2(SCH_1):PAGE181
  J1F1   A7 PCIE_TX_DP3 DM-FCI-CONN76-8R-GP-U-01_CONN-A   I134 @BASEBOARD_FAB2_LIB.BASEBOARD_FAB2(SCH_1):PAGE181

P3E_CPU1_PE3_MP_C_TXN<4> @BASEBOARD_FAB2_LIB.BASEBOARD_FAB2(SCH_1):P3E_CPU1_PE3_MP_C_TXN(4)
 C1F10    1      A CAP_0402-0.22UF,16V,10%,X7R,A3A    I87 @BASEBOARD_FAB2_LIB.BASEBOARD_FAB2(SCH_1):PAGE181
  J1F1   D7 PCIE_TX_DP4 DM-FCI-CONN76-8R-GP-U-01_CONN-A   I134 @BASEBOARD_FAB2_LIB.BASEBOARD_FAB2(SCH_1):PAGE181

P3E_CPU1_PE3_MP_C_TXN<5> @BASEBOARD_FAB2_LIB.BASEBOARD_FAB2(SCH_1):P3E_CPU1_PE3_MP_C_TXN(5)
  C1F8    1      A CAP_0402-0.22UF,16V,10%,X7R,A3A    I73 @BASEBOARD_FAB2_LIB.BASEBOARD_FAB2(SCH_1):PAGE181
  J1F1   H7 PCIE_TX_DN5 DM-FCI-CONN76-8R-GP-U-01_CONN-A   I134 @BASEBOARD_FAB2_LIB.BASEBOARD_FAB2(SCH_1):PAGE181

P3E_CPU1_PE3_MP_C_TXN<6> @BASEBOARD_FAB2_LIB.BASEBOARD_FAB2(SCH_1):P3E_CPU1_PE3_MP_C_TXN(6)
  C1F4    1      A CAP_0402-0.22UF,16V,10%,X7R,A3A    I91 @BASEBOARD_FAB2_LIB.BASEBOARD_FAB2(SCH_1):PAGE181
  J1F1   E6 PCIE_TX_DP6 DM-FCI-CONN76-8R-GP-U-01_CONN-A   I134 @BASEBOARD_FAB2_LIB.BASEBOARD_FAB2(SCH_1):PAGE181

P3E_CPU1_PE3_MP_C_TXN<7> @BASEBOARD_FAB2_LIB.BASEBOARD_FAB2(SCH_1):P3E_CPU1_PE3_MP_C_TXN(7)
  C1F3    1      A CAP_0402-0.22UF,16V,10%,X7R,A3A    I76 @BASEBOARD_FAB2_LIB.BASEBOARD_FAB2(SCH_1):PAGE181
  J1F1   I6 PCIE_TX_DN7 DM-FCI-CONN76-8R-GP-U-01_CONN-A   I134 @BASEBOARD_FAB2_LIB.BASEBOARD_FAB2(SCH_1):PAGE181

P3E_CPU1_PE3_MP_C_TXN<8> @BASEBOARD_FAB2_LIB.BASEBOARD_FAB2(SCH_1):P3E_CPU1_PE3_MP_C_TXN(8)
 C9N18    1      A CAP_0402-0.22UF,16V,10%,X7R,A3A    I39 @BASEBOARD_FAB2_LIB.BASEBOARD_FAB2(SCH_1):PAGE182
  J1C1   B8 PCIE_TX_DP0 DM-FCI-CONN76-8R-GP-U-01_CONN-A    I79 @BASEBOARD_FAB2_LIB.BASEBOARD_FAB2(SCH_1):PAGE182

P3E_CPU1_PE3_MP_C_TXN<9> @BASEBOARD_FAB2_LIB.BASEBOARD_FAB2(SCH_1):P3E_CPU1_PE3_MP_C_TXN(9)
 C9N15    1      A CAP_0402-0.22UF,16V,10%,X7R,A3A    I41 @BASEBOARD_FAB2_LIB.BASEBOARD_FAB2(SCH_1):PAGE182
  J1C1   E8 PCIE_TX_DP1 DM-FCI-CONN76-8R-GP-U-01_CONN-A    I79 @BASEBOARD_FAB2_LIB.BASEBOARD_FAB2(SCH_1):PAGE182

P3E_CPU1_PE3_MP_C_TXP<0> @BASEBOARD_FAB2_LIB.BASEBOARD_FAB2(SCH_1):P3E_CPU1_PE3_MP_C_TXP(0)
 C1F18    1      A CAP_0402-0.22UF,16V,10%,X7R,A3A    I72 @BASEBOARD_FAB2_LIB.BASEBOARD_FAB2(SCH_1):PAGE181
  J1F1   C8 PCIE_TX_DN0 DM-FCI-CONN76-8R-GP-U-01_CONN-A   I134 @BASEBOARD_FAB2_LIB.BASEBOARD_FAB2(SCH_1):PAGE181

P3E_CPU1_PE3_MP_C_TXP<10> @BASEBOARD_FAB2_LIB.BASEBOARD_FAB2(SCH_1):P3E_CPU1_PE3_MP_C_TXP(10)
  C9N1    1      A CAP_0402-0.22UF,16V,10%,X7R,A3A    I40 @BASEBOARD_FAB2_LIB.BASEBOARD_FAB2(SCH_1):PAGE182
  J1C1   H8 PCIE_TX_DP2 DM-FCI-CONN76-8R-GP-U-01_CONN-A    I79 @BASEBOARD_FAB2_LIB.BASEBOARD_FAB2(SCH_1):PAGE182

P3E_CPU1_PE3_MP_C_TXP<11> @BASEBOARD_FAB2_LIB.BASEBOARD_FAB2(SCH_1):P3E_CPU1_PE3_MP_C_TXP(11)
  C9N4    1      A CAP_0402-0.22UF,16V,10%,X7R,A3A    I44 @BASEBOARD_FAB2_LIB.BASEBOARD_FAB2(SCH_1):PAGE182
  J1C1   B7 PCIE_TX_DN3 DM-FCI-CONN76-8R-GP-U-01_CONN-A    I79 @BASEBOARD_FAB2_LIB.BASEBOARD_FAB2(SCH_1):PAGE182

P3E_CPU1_PE3_MP_C_TXP<12> @BASEBOARD_FAB2_LIB.BASEBOARD_FAB2(SCH_1):P3E_CPU1_PE3_MP_C_TXP(12)
 C9N14    1      A CAP_0402-0.22UF,16V,10%,X7R,A3A    I43 @BASEBOARD_FAB2_LIB.BASEBOARD_FAB2(SCH_1):PAGE182
  J1C1   E7 PCIE_TX_DN4 DM-FCI-CONN76-8R-GP-U-01_CONN-A    I79 @BASEBOARD_FAB2_LIB.BASEBOARD_FAB2(SCH_1):PAGE182

P3E_CPU1_PE3_MP_C_TXP<13> @BASEBOARD_FAB2_LIB.BASEBOARD_FAB2(SCH_1):P3E_CPU1_PE3_MP_C_TXP(13)
  C9N5    1      A CAP_0402-0.22UF,16V,10%,X7R,A3A    I45 @BASEBOARD_FAB2_LIB.BASEBOARD_FAB2(SCH_1):PAGE182
  J1C1   H7 PCIE_TX_DN5 DM-FCI-CONN76-8R-GP-U-01_CONN-A    I79 @BASEBOARD_FAB2_LIB.BASEBOARD_FAB2(SCH_1):PAGE182

P3E_CPU1_PE3_MP_C_TXP<14> @BASEBOARD_FAB2_LIB.BASEBOARD_FAB2(SCH_1):P3E_CPU1_PE3_MP_C_TXP(14)
 C9N10    1      A CAP_0402-0.22UF,16V,10%,X7R,A3A    I49 @BASEBOARD_FAB2_LIB.BASEBOARD_FAB2(SCH_1):PAGE182
  J1C1   F6 PCIE_TX_DN6 DM-FCI-CONN76-8R-GP-U-01_CONN-A    I79 @BASEBOARD_FAB2_LIB.BASEBOARD_FAB2(SCH_1):PAGE182

P3E_CPU1_PE3_MP_C_TXP<15> @BASEBOARD_FAB2_LIB.BASEBOARD_FAB2(SCH_1):P3E_CPU1_PE3_MP_C_TXP(15)
  C9N7    1      A CAP_0402-0.22UF,16V,10%,X7R,A3A    I48 @BASEBOARD_FAB2_LIB.BASEBOARD_FAB2(SCH_1):PAGE182
  J1C1   I6 PCIE_TX_DN7 DM-FCI-CONN76-8R-GP-U-01_CONN-A    I79 @BASEBOARD_FAB2_LIB.BASEBOARD_FAB2(SCH_1):PAGE182

P3E_CPU1_PE3_MP_C_TXP<1> @BASEBOARD_FAB2_LIB.BASEBOARD_FAB2(SCH_1):P3E_CPU1_PE3_MP_C_TXP(1)
 C1F17    1      A CAP_0402-0.22UF,16V,10%,X7R,A3A    I71 @BASEBOARD_FAB2_LIB.BASEBOARD_FAB2(SCH_1):PAGE181
  J1F1   F8 PCIE_TX_DN1 DM-FCI-CONN76-8R-GP-U-01_CONN-A   I134 @BASEBOARD_FAB2_LIB.BASEBOARD_FAB2(SCH_1):PAGE181

P3E_CPU1_PE3_MP_C_TXP<2> @BASEBOARD_FAB2_LIB.BASEBOARD_FAB2(SCH_1):P3E_CPU1_PE3_MP_C_TXP(2)
 C1F14    1      A CAP_0402-0.22UF,16V,10%,X7R,A3A    I70 @BASEBOARD_FAB2_LIB.BASEBOARD_FAB2(SCH_1):PAGE181
  J1F1   I8 PCIE_TX_DN2 DM-FCI-CONN76-8R-GP-U-01_CONN-A   I134 @BASEBOARD_FAB2_LIB.BASEBOARD_FAB2(SCH_1):PAGE181

P3E_CPU1_PE3_MP_C_TXP<3> @BASEBOARD_FAB2_LIB.BASEBOARD_FAB2(SCH_1):P3E_CPU1_PE3_MP_C_TXP(3)
 C1F12    1      A CAP_0402-0.22UF,16V,10%,X7R,A3A    I75 @BASEBOARD_FAB2_LIB.BASEBOARD_FAB2(SCH_1):PAGE181
  J1F1   B7 PCIE_TX_DN3 DM-FCI-CONN76-8R-GP-U-01_CONN-A   I134 @BASEBOARD_FAB2_LIB.BASEBOARD_FAB2(SCH_1):PAGE181

P3E_CPU1_PE3_MP_C_TXP<4> @BASEBOARD_FAB2_LIB.BASEBOARD_FAB2(SCH_1):P3E_CPU1_PE3_MP_C_TXP(4)
 C1F11    1      A CAP_0402-0.22UF,16V,10%,X7R,A3A    I74 @BASEBOARD_FAB2_LIB.BASEBOARD_FAB2(SCH_1):PAGE181
  J1F1   E7 PCIE_TX_DN4 DM-FCI-CONN76-8R-GP-U-01_CONN-A   I134 @BASEBOARD_FAB2_LIB.BASEBOARD_FAB2(SCH_1):PAGE181

P3E_CPU1_PE3_MP_C_TXP<5> @BASEBOARD_FAB2_LIB.BASEBOARD_FAB2(SCH_1):P3E_CPU1_PE3_MP_C_TXP(5)
  C1F6    1      A CAP_0402-0.22UF,16V,10%,X7R,A3A    I88 @BASEBOARD_FAB2_LIB.BASEBOARD_FAB2(SCH_1):PAGE181
  J1F1   G7 PCIE_TX_DP5 DM-FCI-CONN76-8R-GP-U-01_CONN-A   I134 @BASEBOARD_FAB2_LIB.BASEBOARD_FAB2(SCH_1):PAGE181

P3E_CPU1_PE3_MP_C_TXP<6> @BASEBOARD_FAB2_LIB.BASEBOARD_FAB2(SCH_1):P3E_CPU1_PE3_MP_C_TXP(6)
  C1F5    1      A CAP_0402-0.22UF,16V,10%,X7R,A3A    I77 @BASEBOARD_FAB2_LIB.BASEBOARD_FAB2(SCH_1):PAGE181
  J1F1   F6 PCIE_TX_DN6 DM-FCI-CONN76-8R-GP-U-01_CONN-A   I134 @BASEBOARD_FAB2_LIB.BASEBOARD_FAB2(SCH_1):PAGE181

P3E_CPU1_PE3_MP_C_TXP<7> @BASEBOARD_FAB2_LIB.BASEBOARD_FAB2(SCH_1):P3E_CPU1_PE3_MP_C_TXP(7)
  C1F2    1      A CAP_0402-0.22UF,16V,10%,X7R,A3A    I90 @BASEBOARD_FAB2_LIB.BASEBOARD_FAB2(SCH_1):PAGE181
  J1F1   H6 PCIE_TX_DP7 DM-FCI-CONN76-8R-GP-U-01_CONN-A   I134 @BASEBOARD_FAB2_LIB.BASEBOARD_FAB2(SCH_1):PAGE181

P3E_CPU1_PE3_MP_C_TXP<8> @BASEBOARD_FAB2_LIB.BASEBOARD_FAB2(SCH_1):P3E_CPU1_PE3_MP_C_TXP(8)
 C9N17    1      A CAP_0402-0.22UF,16V,10%,X7R,A3A    I38 @BASEBOARD_FAB2_LIB.BASEBOARD_FAB2(SCH_1):PAGE182
  J1C1   C8 PCIE_TX_DN0 DM-FCI-CONN76-8R-GP-U-01_CONN-A    I79 @BASEBOARD_FAB2_LIB.BASEBOARD_FAB2(SCH_1):PAGE182

P3E_CPU1_PE3_MP_C_TXP<9> @BASEBOARD_FAB2_LIB.BASEBOARD_FAB2(SCH_1):P3E_CPU1_PE3_MP_C_TXP(9)
 C9N12    1      A CAP_0402-0.22UF,16V,10%,X7R,A3A    I37 @BASEBOARD_FAB2_LIB.BASEBOARD_FAB2(SCH_1):PAGE182
  J1C1   F8 PCIE_TX_DN1 DM-FCI-CONN76-8R-GP-U-01_CONN-A    I79 @BASEBOARD_FAB2_LIB.BASEBOARD_FAB2(SCH_1):PAGE182

P3E_CPU1_PE3_MP_RXN<0> @BASEBOARD_FAB2_LIB.BASEBOARD_FAB2(SCH_1):P3E_CPU1_PE3_MP_RXN(0)
  U2D1 EA18 PE3_RX_DN<0> SKX_EXT_B_BGA1-IC,TBD    I84 @BASEBOARD_FAB2_LIB.BASEBOARD_FAB2(SCH_1):PAGE66
  J1F1   A1 PCIE_RX_DP0 DM-FCI-CONN76-8R-GP-U-01_CONN-A   I134 @BASEBOARD_FAB2_LIB.BASEBOARD_FAB2(SCH_1):PAGE181

P3E_CPU1_PE3_MP_RXN<10> @BASEBOARD_FAB2_LIB.BASEBOARD_FAB2(SCH_1):P3E_CPU1_PE3_MP_RXN(10)
  U2D1 DG12 PE3_RX_DN<10> SKX_EXT_B_BGA1-IC,TBD    I84 @BASEBOARD_FAB2_LIB.BASEBOARD_FAB2(SCH_1):PAGE66
  J1C1   H1 PCIE_RX_DN2 DM-FCI-CONN76-8R-GP-U-01_CONN-A    I79 @BASEBOARD_FAB2_LIB.BASEBOARD_FAB2(SCH_1):PAGE182

P3E_CPU1_PE3_MP_RXN<11> @BASEBOARD_FAB2_LIB.BASEBOARD_FAB2(SCH_1):P3E_CPU1_PE3_MP_RXN(11)
  U2D1 DG10 PE3_RX_DN<11> SKX_EXT_B_BGA1-IC,TBD    I84 @BASEBOARD_FAB2_LIB.BASEBOARD_FAB2(SCH_1):PAGE66
  J1C1   B2 PCIE_RX_DP3 DM-FCI-CONN76-8R-GP-U-01_CONN-A    I79 @BASEBOARD_FAB2_LIB.BASEBOARD_FAB2(SCH_1):PAGE182

P3E_CPU1_PE3_MP_RXN<12> @BASEBOARD_FAB2_LIB.BASEBOARD_FAB2(SCH_1):P3E_CPU1_PE3_MP_RXN(12)
  U2D1 DC12 PE3_RX_DP<12> SKX_EXT_B_BGA1-IC,TBD    I84 @BASEBOARD_FAB2_LIB.BASEBOARD_FAB2(SCH_1):PAGE66
  J1C1   E2 PCIE_RX_DP4 DM-FCI-CONN76-8R-GP-U-01_CONN-A    I79 @BASEBOARD_FAB2_LIB.BASEBOARD_FAB2(SCH_1):PAGE182

P3E_CPU1_PE3_MP_RXN<13> @BASEBOARD_FAB2_LIB.BASEBOARD_FAB2(SCH_1):P3E_CPU1_PE3_MP_RXN(13)
  U2D1 DB11 PE3_RX_DN<13> SKX_EXT_B_BGA1-IC,TBD    I84 @BASEBOARD_FAB2_LIB.BASEBOARD_FAB2(SCH_1):PAGE66
  J1C1   I2 PCIE_RX_DN5 DM-FCI-CONN76-8R-GP-U-01_CONN-A    I79 @BASEBOARD_FAB2_LIB.BASEBOARD_FAB2(SCH_1):PAGE182

P3E_CPU1_PE3_MP_RXN<14> @BASEBOARD_FAB2_LIB.BASEBOARD_FAB2(SCH_1):P3E_CPU1_PE3_MP_RXN(14)
  U2D1 CY11 PE3_RX_DN<14> SKX_EXT_B_BGA1-IC,TBD    I84 @BASEBOARD_FAB2_LIB.BASEBOARD_FAB2(SCH_1):PAGE66
  J1C1   B3 PCIE_RX_DN6 DM-FCI-CONN76-8R-GP-U-01_CONN-A    I79 @BASEBOARD_FAB2_LIB.BASEBOARD_FAB2(SCH_1):PAGE182

P3E_CPU1_PE3_MP_RXN<15> @BASEBOARD_FAB2_LIB.BASEBOARD_FAB2(SCH_1):P3E_CPU1_PE3_MP_RXN(15)
  U2D1  CV9 PE3_RX_DN<15> SKX_EXT_B_BGA1-IC,TBD    I84 @BASEBOARD_FAB2_LIB.BASEBOARD_FAB2(SCH_1):PAGE66
  J1C1   D3 PCIE_RX_DP7 DM-FCI-CONN76-8R-GP-U-01_CONN-A    I79 @BASEBOARD_FAB2_LIB.BASEBOARD_FAB2(SCH_1):PAGE182

P3E_CPU1_PE3_MP_RXN<1> @BASEBOARD_FAB2_LIB.BASEBOARD_FAB2(SCH_1):P3E_CPU1_PE3_MP_RXN(1)
  U2D1 DW18 PE3_RX_DN<1> SKX_EXT_B_BGA1-IC,TBD    I84 @BASEBOARD_FAB2_LIB.BASEBOARD_FAB2(SCH_1):PAGE66
  J1F1   D1 PCIE_RX_DP1 DM-FCI-CONN76-8R-GP-U-01_CONN-A   I134 @BASEBOARD_FAB2_LIB.BASEBOARD_FAB2(SCH_1):PAGE181

P3E_CPU1_PE3_MP_RXN<2> @BASEBOARD_FAB2_LIB.BASEBOARD_FAB2(SCH_1):P3E_CPU1_PE3_MP_RXN(2)
  U2D1 DW16 PE3_RX_DN<2> SKX_EXT_B_BGA1-IC,TBD    I84 @BASEBOARD_FAB2_LIB.BASEBOARD_FAB2(SCH_1):PAGE66
  J1F1   H1 PCIE_RX_DN2 DM-FCI-CONN76-8R-GP-U-01_CONN-A   I134 @BASEBOARD_FAB2_LIB.BASEBOARD_FAB2(SCH_1):PAGE181

P3E_CPU1_PE3_MP_RXN<3> @BASEBOARD_FAB2_LIB.BASEBOARD_FAB2(SCH_1):P3E_CPU1_PE3_MP_RXN(3)
  U2D1 DT19 PE3_RX_DN<3> SKX_EXT_B_BGA1-IC,TBD    I84 @BASEBOARD_FAB2_LIB.BASEBOARD_FAB2(SCH_1):PAGE66
  J1F1   B2 PCIE_RX_DP3 DM-FCI-CONN76-8R-GP-U-01_CONN-A   I134 @BASEBOARD_FAB2_LIB.BASEBOARD_FAB2(SCH_1):PAGE181

P3E_CPU1_PE3_MP_RXN<4> @BASEBOARD_FAB2_LIB.BASEBOARD_FAB2(SCH_1):P3E_CPU1_PE3_MP_RXN(4)
  U2D1 DR16 PE3_RX_DN<4> SKX_EXT_B_BGA1-IC,TBD    I84 @BASEBOARD_FAB2_LIB.BASEBOARD_FAB2(SCH_1):PAGE66
  J1F1   E2 PCIE_RX_DP4 DM-FCI-CONN76-8R-GP-U-01_CONN-A   I134 @BASEBOARD_FAB2_LIB.BASEBOARD_FAB2(SCH_1):PAGE181

P3E_CPU1_PE3_MP_RXN<5> @BASEBOARD_FAB2_LIB.BASEBOARD_FAB2(SCH_1):P3E_CPU1_PE3_MP_RXN(5)
  U2D1 DR14 PE3_RX_DN<5> SKX_EXT_B_BGA1-IC,TBD    I84 @BASEBOARD_FAB2_LIB.BASEBOARD_FAB2(SCH_1):PAGE66
  J1F1   I2 PCIE_RX_DN5 DM-FCI-CONN76-8R-GP-U-01_CONN-A   I134 @BASEBOARD_FAB2_LIB.BASEBOARD_FAB2(SCH_1):PAGE181

P3E_CPU1_PE3_MP_RXN<6> @BASEBOARD_FAB2_LIB.BASEBOARD_FAB2(SCH_1):P3E_CPU1_PE3_MP_RXN(6)
  U2D1 DN14 PE3_RX_DN<6> SKX_EXT_B_BGA1-IC,TBD    I84 @BASEBOARD_FAB2_LIB.BASEBOARD_FAB2(SCH_1):PAGE66
  J1F1   B3 PCIE_RX_DN6 DM-FCI-CONN76-8R-GP-U-01_CONN-A   I134 @BASEBOARD_FAB2_LIB.BASEBOARD_FAB2(SCH_1):PAGE181

P3E_CPU1_PE3_MP_RXN<7> @BASEBOARD_FAB2_LIB.BASEBOARD_FAB2(SCH_1):P3E_CPU1_PE3_MP_RXN(7)
  U2D1 DL14 PE3_RX_DN<7> SKX_EXT_B_BGA1-IC,TBD    I84 @BASEBOARD_FAB2_LIB.BASEBOARD_FAB2(SCH_1):PAGE66
  J1F1   D3 PCIE_RX_DP7 DM-FCI-CONN76-8R-GP-U-01_CONN-A   I134 @BASEBOARD_FAB2_LIB.BASEBOARD_FAB2(SCH_1):PAGE181

P3E_CPU1_PE3_MP_RXN<8> @BASEBOARD_FAB2_LIB.BASEBOARD_FAB2(SCH_1):P3E_CPU1_PE3_MP_RXN(8)
  U2D1 DL12 PE3_RX_DN<8> SKX_EXT_B_BGA1-IC,TBD    I84 @BASEBOARD_FAB2_LIB.BASEBOARD_FAB2(SCH_1):PAGE66
  J1C1   A1 PCIE_RX_DP0 DM-FCI-CONN76-8R-GP-U-01_CONN-A    I79 @BASEBOARD_FAB2_LIB.BASEBOARD_FAB2(SCH_1):PAGE182

P3E_CPU1_PE3_MP_RXN<9> @BASEBOARD_FAB2_LIB.BASEBOARD_FAB2(SCH_1):P3E_CPU1_PE3_MP_RXN(9)
  U2D1 DJ12 PE3_RX_DN<9> SKX_EXT_B_BGA1-IC,TBD    I84 @BASEBOARD_FAB2_LIB.BASEBOARD_FAB2(SCH_1):PAGE66
  J1C1   D1 PCIE_RX_DP1 DM-FCI-CONN76-8R-GP-U-01_CONN-A    I79 @BASEBOARD_FAB2_LIB.BASEBOARD_FAB2(SCH_1):PAGE182

P3E_CPU1_PE3_MP_RXP<0> @BASEBOARD_FAB2_LIB.BASEBOARD_FAB2(SCH_1):P3E_CPU1_PE3_MP_RXP(0)
  U2D1 DY17 PE3_RX_DP<0> SKX_EXT_B_BGA1-IC,TBD    I84 @BASEBOARD_FAB2_LIB.BASEBOARD_FAB2(SCH_1):PAGE66
  J1F1   B1 PCIE_RX_DN0 DM-FCI-CONN76-8R-GP-U-01_CONN-A   I134 @BASEBOARD_FAB2_LIB.BASEBOARD_FAB2(SCH_1):PAGE181

P3E_CPU1_PE3_MP_RXP<10> @BASEBOARD_FAB2_LIB.BASEBOARD_FAB2(SCH_1):P3E_CPU1_PE3_MP_RXP(10)
  U2D1 DE12 PE3_RX_DP<10> SKX_EXT_B_BGA1-IC,TBD    I84 @BASEBOARD_FAB2_LIB.BASEBOARD_FAB2(SCH_1):PAGE66
  J1C1   G1 PCIE_RX_DP2 DM-FCI-CONN76-8R-GP-U-01_CONN-A    I79 @BASEBOARD_FAB2_LIB.BASEBOARD_FAB2(SCH_1):PAGE182

P3E_CPU1_PE3_MP_RXP<11> @BASEBOARD_FAB2_LIB.BASEBOARD_FAB2(SCH_1):P3E_CPU1_PE3_MP_RXP(11)
  U2D1 DF11 PE3_RX_DP<11> SKX_EXT_B_BGA1-IC,TBD    I84 @BASEBOARD_FAB2_LIB.BASEBOARD_FAB2(SCH_1):PAGE66
  J1C1   C2 PCIE_RX_DN3 DM-FCI-CONN76-8R-GP-U-01_CONN-A    I79 @BASEBOARD_FAB2_LIB.BASEBOARD_FAB2(SCH_1):PAGE182

P3E_CPU1_PE3_MP_RXP<12> @BASEBOARD_FAB2_LIB.BASEBOARD_FAB2(SCH_1):P3E_CPU1_PE3_MP_RXP(12)
  U2D1 DD13 PE3_RX_DN<12> SKX_EXT_B_BGA1-IC,TBD    I84 @BASEBOARD_FAB2_LIB.BASEBOARD_FAB2(SCH_1):PAGE66
  J1C1   F2 PCIE_RX_DN4 DM-FCI-CONN76-8R-GP-U-01_CONN-A    I79 @BASEBOARD_FAB2_LIB.BASEBOARD_FAB2(SCH_1):PAGE182

P3E_CPU1_PE3_MP_RXP<13> @BASEBOARD_FAB2_LIB.BASEBOARD_FAB2(SCH_1):P3E_CPU1_PE3_MP_RXP(13)
  U2D1 DA12 PE3_RX_DP<13> SKX_EXT_B_BGA1-IC,TBD    I84 @BASEBOARD_FAB2_LIB.BASEBOARD_FAB2(SCH_1):PAGE66
  J1C1   H2 PCIE_RX_DP5 DM-FCI-CONN76-8R-GP-U-01_CONN-A    I79 @BASEBOARD_FAB2_LIB.BASEBOARD_FAB2(SCH_1):PAGE182

P3E_CPU1_PE3_MP_RXP<14> @BASEBOARD_FAB2_LIB.BASEBOARD_FAB2(SCH_1):P3E_CPU1_PE3_MP_RXP(14)
  U2D1 CW10 PE3_RX_DP<14> SKX_EXT_B_BGA1-IC,TBD    I84 @BASEBOARD_FAB2_LIB.BASEBOARD_FAB2(SCH_1):PAGE66
  J1C1   A3 PCIE_RX_DP6 DM-FCI-CONN76-8R-GP-U-01_CONN-A    I79 @BASEBOARD_FAB2_LIB.BASEBOARD_FAB2(SCH_1):PAGE182

P3E_CPU1_PE3_MP_RXP<15> @BASEBOARD_FAB2_LIB.BASEBOARD_FAB2(SCH_1):P3E_CPU1_PE3_MP_RXP(15)
  U2D1 CU10 PE3_RX_DP<15> SKX_EXT_B_BGA1-IC,TBD    I84 @BASEBOARD_FAB2_LIB.BASEBOARD_FAB2(SCH_1):PAGE66
  J1C1   E3 PCIE_RX_DN7 DM-FCI-CONN76-8R-GP-U-01_CONN-A    I79 @BASEBOARD_FAB2_LIB.BASEBOARD_FAB2(SCH_1):PAGE182

P3E_CPU1_PE3_MP_RXP<1> @BASEBOARD_FAB2_LIB.BASEBOARD_FAB2(SCH_1):P3E_CPU1_PE3_MP_RXP(1)
  U2D1 DU18 PE3_RX_DP<1> SKX_EXT_B_BGA1-IC,TBD    I84 @BASEBOARD_FAB2_LIB.BASEBOARD_FAB2(SCH_1):PAGE66
  J1F1   E1 PCIE_RX_DN1 DM-FCI-CONN76-8R-GP-U-01_CONN-A   I134 @BASEBOARD_FAB2_LIB.BASEBOARD_FAB2(SCH_1):PAGE181

P3E_CPU1_PE3_MP_RXP<2> @BASEBOARD_FAB2_LIB.BASEBOARD_FAB2(SCH_1):P3E_CPU1_PE3_MP_RXP(2)
  U2D1 DV17 PE3_RX_DP<2> SKX_EXT_B_BGA1-IC,TBD    I84 @BASEBOARD_FAB2_LIB.BASEBOARD_FAB2(SCH_1):PAGE66
  J1F1   G1 PCIE_RX_DP2 DM-FCI-CONN76-8R-GP-U-01_CONN-A   I134 @BASEBOARD_FAB2_LIB.BASEBOARD_FAB2(SCH_1):PAGE181

P3E_CPU1_PE3_MP_RXP<3> @BASEBOARD_FAB2_LIB.BASEBOARD_FAB2(SCH_1):P3E_CPU1_PE3_MP_RXP(3)
  U2D1 DR18 PE3_RX_DP<3> SKX_EXT_B_BGA1-IC,TBD    I84 @BASEBOARD_FAB2_LIB.BASEBOARD_FAB2(SCH_1):PAGE66
  J1F1   C2 PCIE_RX_DN3 DM-FCI-CONN76-8R-GP-U-01_CONN-A   I134 @BASEBOARD_FAB2_LIB.BASEBOARD_FAB2(SCH_1):PAGE181

P3E_CPU1_PE3_MP_RXP<4> @BASEBOARD_FAB2_LIB.BASEBOARD_FAB2(SCH_1):P3E_CPU1_PE3_MP_RXP(4)
  U2D1 DN16 PE3_RX_DP<4> SKX_EXT_B_BGA1-IC,TBD    I84 @BASEBOARD_FAB2_LIB.BASEBOARD_FAB2(SCH_1):PAGE66
  J1F1   F2 PCIE_RX_DN4 DM-FCI-CONN76-8R-GP-U-01_CONN-A   I134 @BASEBOARD_FAB2_LIB.BASEBOARD_FAB2(SCH_1):PAGE181

P3E_CPU1_PE3_MP_RXP<5> @BASEBOARD_FAB2_LIB.BASEBOARD_FAB2(SCH_1):P3E_CPU1_PE3_MP_RXP(5)
  U2D1 DP15 PE3_RX_DP<5> SKX_EXT_B_BGA1-IC,TBD    I84 @BASEBOARD_FAB2_LIB.BASEBOARD_FAB2(SCH_1):PAGE66
  J1F1   H2 PCIE_RX_DP5 DM-FCI-CONN76-8R-GP-U-01_CONN-A   I134 @BASEBOARD_FAB2_LIB.BASEBOARD_FAB2(SCH_1):PAGE181

P3E_CPU1_PE3_MP_RXP<6> @BASEBOARD_FAB2_LIB.BASEBOARD_FAB2(SCH_1):P3E_CPU1_PE3_MP_RXP(6)
  U2D1 DM13 PE3_RX_DP<6> SKX_EXT_B_BGA1-IC,TBD    I84 @BASEBOARD_FAB2_LIB.BASEBOARD_FAB2(SCH_1):PAGE66
  J1F1   A3 PCIE_RX_DP6 DM-FCI-CONN76-8R-GP-U-01_CONN-A   I134 @BASEBOARD_FAB2_LIB.BASEBOARD_FAB2(SCH_1):PAGE181

P3E_CPU1_PE3_MP_RXP<7> @BASEBOARD_FAB2_LIB.BASEBOARD_FAB2(SCH_1):P3E_CPU1_PE3_MP_RXP(7)
  U2D1 DJ14 PE3_RX_DP<7> SKX_EXT_B_BGA1-IC,TBD    I84 @BASEBOARD_FAB2_LIB.BASEBOARD_FAB2(SCH_1):PAGE66
  J1F1   E3 PCIE_RX_DN7 DM-FCI-CONN76-8R-GP-U-01_CONN-A   I134 @BASEBOARD_FAB2_LIB.BASEBOARD_FAB2(SCH_1):PAGE181

P3E_CPU1_PE3_MP_RXP<8> @BASEBOARD_FAB2_LIB.BASEBOARD_FAB2(SCH_1):P3E_CPU1_PE3_MP_RXP(8)
  U2D1 DK13 PE3_RX_DP<8> SKX_EXT_B_BGA1-IC,TBD    I84 @BASEBOARD_FAB2_LIB.BASEBOARD_FAB2(SCH_1):PAGE66
  J1C1   B1 PCIE_RX_DN0 DM-FCI-CONN76-8R-GP-U-01_CONN-A    I79 @BASEBOARD_FAB2_LIB.BASEBOARD_FAB2(SCH_1):PAGE182

P3E_CPU1_PE3_MP_RXP<9> @BASEBOARD_FAB2_LIB.BASEBOARD_FAB2(SCH_1):P3E_CPU1_PE3_MP_RXP(9)
  U2D1 DH11 PE3_RX_DP<9> SKX_EXT_B_BGA1-IC,TBD    I84 @BASEBOARD_FAB2_LIB.BASEBOARD_FAB2(SCH_1):PAGE66
  J1C1   E1 PCIE_RX_DN1 DM-FCI-CONN76-8R-GP-U-01_CONN-A    I79 @BASEBOARD_FAB2_LIB.BASEBOARD_FAB2(SCH_1):PAGE182

P3E_CPU1_PE3_MP_TXN<0> @BASEBOARD_FAB2_LIB.BASEBOARD_FAB2(SCH_1):P3E_CPU1_PE3_MP_TXN(0)
  U2D1 EE14 PE3_TX_DN<0> SKX_EXT_B_BGA1-IC,TBD    I84 @BASEBOARD_FAB2_LIB.BASEBOARD_FAB2(SCH_1):PAGE66
 C1F20    2      B CAP_0402-0.22UF,16V,10%,X7R,A3A    I86 @BASEBOARD_FAB2_LIB.BASEBOARD_FAB2(SCH_1):PAGE181

P3E_CPU1_PE3_MP_TXN<10> @BASEBOARD_FAB2_LIB.BASEBOARD_FAB2(SCH_1):P3E_CPU1_PE3_MP_TXN(10)
  U2D1  DL6 PE3_TX_DN<10> SKX_EXT_B_BGA1-IC,TBD    I84 @BASEBOARD_FAB2_LIB.BASEBOARD_FAB2(SCH_1):PAGE66
  C9N2    2      B CAP_0402-0.22UF,16V,10%,X7R,A3A    I36 @BASEBOARD_FAB2_LIB.BASEBOARD_FAB2(SCH_1):PAGE182

P3E_CPU1_PE3_MP_TXN<11> @BASEBOARD_FAB2_LIB.BASEBOARD_FAB2(SCH_1):P3E_CPU1_PE3_MP_TXN(11)
  U2D1  DJ4 PE3_TX_DN<11> SKX_EXT_B_BGA1-IC,TBD    I84 @BASEBOARD_FAB2_LIB.BASEBOARD_FAB2(SCH_1):PAGE66
  C9N3    2      B CAP_0402-0.22UF,16V,10%,X7R,A3A    I47 @BASEBOARD_FAB2_LIB.BASEBOARD_FAB2(SCH_1):PAGE182

P3E_CPU1_PE3_MP_TXN<12> @BASEBOARD_FAB2_LIB.BASEBOARD_FAB2(SCH_1):P3E_CPU1_PE3_MP_TXN(12)
  U2D1  DJ6 PE3_TX_DN<12> SKX_EXT_B_BGA1-IC,TBD    I84 @BASEBOARD_FAB2_LIB.BASEBOARD_FAB2(SCH_1):PAGE66
 C9N16    2      B CAP_0402-0.22UF,16V,10%,X7R,A3A    I46 @BASEBOARD_FAB2_LIB.BASEBOARD_FAB2(SCH_1):PAGE182

P3E_CPU1_PE3_MP_TXN<13> @BASEBOARD_FAB2_LIB.BASEBOARD_FAB2(SCH_1):P3E_CPU1_PE3_MP_TXN(13)
  U2D1  DD5 PE3_TX_DN<13> SKX_EXT_B_BGA1-IC,TBD    I84 @BASEBOARD_FAB2_LIB.BASEBOARD_FAB2(SCH_1):PAGE66
  C9N6    2      B CAP_0402-0.22UF,16V,10%,X7R,A3A    I42 @BASEBOARD_FAB2_LIB.BASEBOARD_FAB2(SCH_1):PAGE182

P3E_CPU1_PE3_MP_TXN<14> @BASEBOARD_FAB2_LIB.BASEBOARD_FAB2(SCH_1):P3E_CPU1_PE3_MP_TXN(14)
  U2D1  DB5 PE3_TX_DN<14> SKX_EXT_B_BGA1-IC,TBD    I84 @BASEBOARD_FAB2_LIB.BASEBOARD_FAB2(SCH_1):PAGE66
  C9N8    2      B CAP_0402-0.22UF,16V,10%,X7R,A3A    I53 @BASEBOARD_FAB2_LIB.BASEBOARD_FAB2(SCH_1):PAGE182

P3E_CPU1_PE3_MP_TXN<15> @BASEBOARD_FAB2_LIB.BASEBOARD_FAB2(SCH_1):P3E_CPU1_PE3_MP_TXN(15)
  U2D1  CY5 PE3_TX_DN<15> SKX_EXT_B_BGA1-IC,TBD    I84 @BASEBOARD_FAB2_LIB.BASEBOARD_FAB2(SCH_1):PAGE66
  C9N9    2      B CAP_0402-0.22UF,16V,10%,X7R,A3A    I52 @BASEBOARD_FAB2_LIB.BASEBOARD_FAB2(SCH_1):PAGE182

P3E_CPU1_PE3_MP_TXN<1> @BASEBOARD_FAB2_LIB.BASEBOARD_FAB2(SCH_1):P3E_CPU1_PE3_MP_TXN(1)
  U2D1 EE12 PE3_TX_DN<1> SKX_EXT_B_BGA1-IC,TBD    I84 @BASEBOARD_FAB2_LIB.BASEBOARD_FAB2(SCH_1):PAGE66
 C1F16    2      B CAP_0402-0.22UF,16V,10%,X7R,A3A    I79 @BASEBOARD_FAB2_LIB.BASEBOARD_FAB2(SCH_1):PAGE181

P3E_CPU1_PE3_MP_TXN<2> @BASEBOARD_FAB2_LIB.BASEBOARD_FAB2(SCH_1):P3E_CPU1_PE3_MP_TXN(2)
  U2D1 EC12 PE3_TX_DN<2> SKX_EXT_B_BGA1-IC,TBD    I84 @BASEBOARD_FAB2_LIB.BASEBOARD_FAB2(SCH_1):PAGE66
 C1F15    2      B CAP_0402-0.22UF,16V,10%,X7R,A3A    I78 @BASEBOARD_FAB2_LIB.BASEBOARD_FAB2(SCH_1):PAGE181

P3E_CPU1_PE3_MP_TXN<3> @BASEBOARD_FAB2_LIB.BASEBOARD_FAB2(SCH_1):P3E_CPU1_PE3_MP_TXN(3)
  U2D1 DY11 PE3_TX_DN<3> SKX_EXT_B_BGA1-IC,TBD    I84 @BASEBOARD_FAB2_LIB.BASEBOARD_FAB2(SCH_1):PAGE66
 C1F13    2      B CAP_0402-0.22UF,16V,10%,X7R,A3A    I89 @BASEBOARD_FAB2_LIB.BASEBOARD_FAB2(SCH_1):PAGE181

P3E_CPU1_PE3_MP_TXN<4> @BASEBOARD_FAB2_LIB.BASEBOARD_FAB2(SCH_1):P3E_CPU1_PE3_MP_TXN(4)
  U2D1  EB9 PE3_TX_DN<4> SKX_EXT_B_BGA1-IC,TBD    I84 @BASEBOARD_FAB2_LIB.BASEBOARD_FAB2(SCH_1):PAGE66
 C1F10    2      B CAP_0402-0.22UF,16V,10%,X7R,A3A    I87 @BASEBOARD_FAB2_LIB.BASEBOARD_FAB2(SCH_1):PAGE181

P3E_CPU1_PE3_MP_TXN<5> @BASEBOARD_FAB2_LIB.BASEBOARD_FAB2(SCH_1):P3E_CPU1_PE3_MP_TXN(5)
  U2D1 DW10 PE3_TX_DN<5> SKX_EXT_B_BGA1-IC,TBD    I84 @BASEBOARD_FAB2_LIB.BASEBOARD_FAB2(SCH_1):PAGE66
  C1F8    2      B CAP_0402-0.22UF,16V,10%,X7R,A3A    I73 @BASEBOARD_FAB2_LIB.BASEBOARD_FAB2(SCH_1):PAGE181

P3E_CPU1_PE3_MP_TXN<6> @BASEBOARD_FAB2_LIB.BASEBOARD_FAB2(SCH_1):P3E_CPU1_PE3_MP_TXN(6)
  U2D1  DU8 PE3_TX_DN<6> SKX_EXT_B_BGA1-IC,TBD    I84 @BASEBOARD_FAB2_LIB.BASEBOARD_FAB2(SCH_1):PAGE66
  C1F4    2      B CAP_0402-0.22UF,16V,10%,X7R,A3A    I91 @BASEBOARD_FAB2_LIB.BASEBOARD_FAB2(SCH_1):PAGE181

P3E_CPU1_PE3_MP_TXN<7> @BASEBOARD_FAB2_LIB.BASEBOARD_FAB2(SCH_1):P3E_CPU1_PE3_MP_TXN(7)
  U2D1  DR8 PE3_TX_DN<7> SKX_EXT_B_BGA1-IC,TBD    I84 @BASEBOARD_FAB2_LIB.BASEBOARD_FAB2(SCH_1):PAGE66
  C1F3    2      B CAP_0402-0.22UF,16V,10%,X7R,A3A    I76 @BASEBOARD_FAB2_LIB.BASEBOARD_FAB2(SCH_1):PAGE181

P3E_CPU1_PE3_MP_TXN<8> @BASEBOARD_FAB2_LIB.BASEBOARD_FAB2(SCH_1):P3E_CPU1_PE3_MP_TXN(8)
  U2D1  DM7 PE3_TX_DN<8> SKX_EXT_B_BGA1-IC,TBD    I84 @BASEBOARD_FAB2_LIB.BASEBOARD_FAB2(SCH_1):PAGE66
 C9N18    2      B CAP_0402-0.22UF,16V,10%,X7R,A3A    I39 @BASEBOARD_FAB2_LIB.BASEBOARD_FAB2(SCH_1):PAGE182

P3E_CPU1_PE3_MP_TXN<9> @BASEBOARD_FAB2_LIB.BASEBOARD_FAB2(SCH_1):P3E_CPU1_PE3_MP_TXN(9)
  U2D1  DP5 PE3_TX_DN<9> SKX_EXT_B_BGA1-IC,TBD    I84 @BASEBOARD_FAB2_LIB.BASEBOARD_FAB2(SCH_1):PAGE66
 C9N15    2      B CAP_0402-0.22UF,16V,10%,X7R,A3A    I41 @BASEBOARD_FAB2_LIB.BASEBOARD_FAB2(SCH_1):PAGE182

P3E_CPU1_PE3_MP_TXP<0> @BASEBOARD_FAB2_LIB.BASEBOARD_FAB2(SCH_1):P3E_CPU1_PE3_MP_TXP(0)
  U2D1 EC14 PE3_TX_DP<0> SKX_EXT_B_BGA1-IC,TBD    I84 @BASEBOARD_FAB2_LIB.BASEBOARD_FAB2(SCH_1):PAGE66
 C1F18    2      B CAP_0402-0.22UF,16V,10%,X7R,A3A    I72 @BASEBOARD_FAB2_LIB.BASEBOARD_FAB2(SCH_1):PAGE181

P3E_CPU1_PE3_MP_TXP<10> @BASEBOARD_FAB2_LIB.BASEBOARD_FAB2(SCH_1):P3E_CPU1_PE3_MP_TXP(10)
  U2D1  DK5 PE3_TX_DP<10> SKX_EXT_B_BGA1-IC,TBD    I84 @BASEBOARD_FAB2_LIB.BASEBOARD_FAB2(SCH_1):PAGE66
  C9N1    2      B CAP_0402-0.22UF,16V,10%,X7R,A3A    I40 @BASEBOARD_FAB2_LIB.BASEBOARD_FAB2(SCH_1):PAGE182

P3E_CPU1_PE3_MP_TXP<11> @BASEBOARD_FAB2_LIB.BASEBOARD_FAB2(SCH_1):P3E_CPU1_PE3_MP_TXP(11)
  U2D1  DH5 PE3_TX_DP<11> SKX_EXT_B_BGA1-IC,TBD    I84 @BASEBOARD_FAB2_LIB.BASEBOARD_FAB2(SCH_1):PAGE66
  C9N4    2      B CAP_0402-0.22UF,16V,10%,X7R,A3A    I44 @BASEBOARD_FAB2_LIB.BASEBOARD_FAB2(SCH_1):PAGE182

P3E_CPU1_PE3_MP_TXP<12> @BASEBOARD_FAB2_LIB.BASEBOARD_FAB2(SCH_1):P3E_CPU1_PE3_MP_TXP(12)
  U2D1  DG6 PE3_TX_DP<12> SKX_EXT_B_BGA1-IC,TBD    I84 @BASEBOARD_FAB2_LIB.BASEBOARD_FAB2(SCH_1):PAGE66
 C9N14    2      B CAP_0402-0.22UF,16V,10%,X7R,A3A    I43 @BASEBOARD_FAB2_LIB.BASEBOARD_FAB2(SCH_1):PAGE182

P3E_CPU1_PE3_MP_TXP<13> @BASEBOARD_FAB2_LIB.BASEBOARD_FAB2(SCH_1):P3E_CPU1_PE3_MP_TXP(13)
  U2D1  DC6 PE3_TX_DP<13> SKX_EXT_B_BGA1-IC,TBD    I84 @BASEBOARD_FAB2_LIB.BASEBOARD_FAB2(SCH_1):PAGE66
  C9N5    2      B CAP_0402-0.22UF,16V,10%,X7R,A3A    I45 @BASEBOARD_FAB2_LIB.BASEBOARD_FAB2(SCH_1):PAGE182

P3E_CPU1_PE3_MP_TXP<14> @BASEBOARD_FAB2_LIB.BASEBOARD_FAB2(SCH_1):P3E_CPU1_PE3_MP_TXP(14)
  U2D1  DA4 PE3_TX_DP<14> SKX_EXT_B_BGA1-IC,TBD    I84 @BASEBOARD_FAB2_LIB.BASEBOARD_FAB2(SCH_1):PAGE66
 C9N10    2      B CAP_0402-0.22UF,16V,10%,X7R,A3A    I49 @BASEBOARD_FAB2_LIB.BASEBOARD_FAB2(SCH_1):PAGE182

P3E_CPU1_PE3_MP_TXP<15> @BASEBOARD_FAB2_LIB.BASEBOARD_FAB2(SCH_1):P3E_CPU1_PE3_MP_TXP(15)
  U2D1  CV5 PE3_TX_DP<15> SKX_EXT_B_BGA1-IC,TBD    I84 @BASEBOARD_FAB2_LIB.BASEBOARD_FAB2(SCH_1):PAGE66
  C9N7    2      B CAP_0402-0.22UF,16V,10%,X7R,A3A    I48 @BASEBOARD_FAB2_LIB.BASEBOARD_FAB2(SCH_1):PAGE182

P3E_CPU1_PE3_MP_TXP<1> @BASEBOARD_FAB2_LIB.BASEBOARD_FAB2(SCH_1):P3E_CPU1_PE3_MP_TXP(1)
  U2D1 ED13 PE3_TX_DP<1> SKX_EXT_B_BGA1-IC,TBD    I84 @BASEBOARD_FAB2_LIB.BASEBOARD_FAB2(SCH_1):PAGE66
 C1F17    2      B CAP_0402-0.22UF,16V,10%,X7R,A3A    I71 @BASEBOARD_FAB2_LIB.BASEBOARD_FAB2(SCH_1):PAGE181

P3E_CPU1_PE3_MP_TXP<2> @BASEBOARD_FAB2_LIB.BASEBOARD_FAB2(SCH_1):P3E_CPU1_PE3_MP_TXP(2)
  U2D1 EB11 PE3_TX_DP<2> SKX_EXT_B_BGA1-IC,TBD    I84 @BASEBOARD_FAB2_LIB.BASEBOARD_FAB2(SCH_1):PAGE66
 C1F14    2      B CAP_0402-0.22UF,16V,10%,X7R,A3A    I70 @BASEBOARD_FAB2_LIB.BASEBOARD_FAB2(SCH_1):PAGE181

P3E_CPU1_PE3_MP_TXP<3> @BASEBOARD_FAB2_LIB.BASEBOARD_FAB2(SCH_1):P3E_CPU1_PE3_MP_TXP(3)
  U2D1 EA10 PE3_TX_DP<3> SKX_EXT_B_BGA1-IC,TBD    I84 @BASEBOARD_FAB2_LIB.BASEBOARD_FAB2(SCH_1):PAGE66
 C1F12    2      B CAP_0402-0.22UF,16V,10%,X7R,A3A    I75 @BASEBOARD_FAB2_LIB.BASEBOARD_FAB2(SCH_1):PAGE181

P3E_CPU1_PE3_MP_TXP<4> @BASEBOARD_FAB2_LIB.BASEBOARD_FAB2(SCH_1):P3E_CPU1_PE3_MP_TXP(4)
  U2D1  DY9 PE3_TX_DP<4> SKX_EXT_B_BGA1-IC,TBD    I84 @BASEBOARD_FAB2_LIB.BASEBOARD_FAB2(SCH_1):PAGE66
 C1F11    2      B CAP_0402-0.22UF,16V,10%,X7R,A3A    I74 @BASEBOARD_FAB2_LIB.BASEBOARD_FAB2(SCH_1):PAGE181

P3E_CPU1_PE3_MP_TXP<5> @BASEBOARD_FAB2_LIB.BASEBOARD_FAB2(SCH_1):P3E_CPU1_PE3_MP_TXP(5)
  U2D1  DV9 PE3_TX_DP<5> SKX_EXT_B_BGA1-IC,TBD    I84 @BASEBOARD_FAB2_LIB.BASEBOARD_FAB2(SCH_1):PAGE66
  C1F6    2      B CAP_0402-0.22UF,16V,10%,X7R,A3A    I88 @BASEBOARD_FAB2_LIB.BASEBOARD_FAB2(SCH_1):PAGE181

P3E_CPU1_PE3_MP_TXP<6> @BASEBOARD_FAB2_LIB.BASEBOARD_FAB2(SCH_1):P3E_CPU1_PE3_MP_TXP(6)
  U2D1  DT9 PE3_TX_DP<6> SKX_EXT_B_BGA1-IC,TBD    I84 @BASEBOARD_FAB2_LIB.BASEBOARD_FAB2(SCH_1):PAGE66
  C1F5    2      B CAP_0402-0.22UF,16V,10%,X7R,A3A    I77 @BASEBOARD_FAB2_LIB.BASEBOARD_FAB2(SCH_1):PAGE181

P3E_CPU1_PE3_MP_TXP<7> @BASEBOARD_FAB2_LIB.BASEBOARD_FAB2(SCH_1):P3E_CPU1_PE3_MP_TXP(7)
  U2D1  DP7 PE3_TX_DP<7> SKX_EXT_B_BGA1-IC,TBD    I84 @BASEBOARD_FAB2_LIB.BASEBOARD_FAB2(SCH_1):PAGE66
  C1F2    2      B CAP_0402-0.22UF,16V,10%,X7R,A3A    I90 @BASEBOARD_FAB2_LIB.BASEBOARD_FAB2(SCH_1):PAGE181

P3E_CPU1_PE3_MP_TXP<8> @BASEBOARD_FAB2_LIB.BASEBOARD_FAB2(SCH_1):P3E_CPU1_PE3_MP_TXP(8)
  U2D1  DN6 PE3_TX_DP<8> SKX_EXT_B_BGA1-IC,TBD    I84 @BASEBOARD_FAB2_LIB.BASEBOARD_FAB2(SCH_1):PAGE66
 C9N17    2      B CAP_0402-0.22UF,16V,10%,X7R,A3A    I38 @BASEBOARD_FAB2_LIB.BASEBOARD_FAB2(SCH_1):PAGE182

P3E_CPU1_PE3_MP_TXP<9> @BASEBOARD_FAB2_LIB.BASEBOARD_FAB2(SCH_1):P3E_CPU1_PE3_MP_TXP(9)
  U2D1  DM5 PE3_TX_DP<9> SKX_EXT_B_BGA1-IC,TBD    I84 @BASEBOARD_FAB2_LIB.BASEBOARD_FAB2(SCH_1):PAGE66
 C9N12    2      B CAP_0402-0.22UF,16V,10%,X7R,A3A    I37 @BASEBOARD_FAB2_LIB.BASEBOARD_FAB2(SCH_1):PAGE182

P3E_OCP_CPU0_PE3_C_TXN<0> @BASEBOARD_FAB2_LIB.BASEBOARD_FAB2(SCH_1):P3E_OCP_CPU0_PE3_C_TXN(0)
  C1R1    2      B CAP_0402-0.22UF,16V,10%,X7R,A3A    I29 @BASEBOARD_FAB2_LIB.BASEBOARD_FAB2(SCH_1):PAGE106
  J8E3   68   IO68 SCONN80_E67482007_SM-CONN,E674A   I119 @BASEBOARD_FAB2_LIB.BASEBOARD_FAB2(SCH_1):PAGE187

P3E_OCP_CPU0_PE3_C_TXN<10> @BASEBOARD_FAB2_LIB.BASEBOARD_FAB2(SCH_1):P3E_OCP_CPU0_PE3_C_TXN(10)
 C1M17    2      B CAP_0402-0.22UF,16V,10%,X7R,A3A    I92 @BASEBOARD_FAB2_LIB.BASEBOARD_FAB2(SCH_1):PAGE106
  J9B3   98   IO98 SCONN120_A28699018_SM-SCONN,A2A   I336 @BASEBOARD_FAB2_LIB.BASEBOARD_FAB2(SCH_1):PAGE186

P3E_OCP_CPU0_PE3_C_TXN<11> @BASEBOARD_FAB2_LIB.BASEBOARD_FAB2(SCH_1):P3E_OCP_CPU0_PE3_C_TXN(11)
 C1M15    2      B CAP_0402-0.22UF,16V,10%,X7R,A3A    I95 @BASEBOARD_FAB2_LIB.BASEBOARD_FAB2(SCH_1):PAGE106
  J9B3   90   IO90 SCONN120_A28699018_SM-SCONN,A2A   I336 @BASEBOARD_FAB2_LIB.BASEBOARD_FAB2(SCH_1):PAGE186

P3E_OCP_CPU0_PE3_C_TXN<12> @BASEBOARD_FAB2_LIB.BASEBOARD_FAB2(SCH_1):P3E_OCP_CPU0_PE3_C_TXN(12)
 C1M13    2      B CAP_0402-0.22UF,16V,10%,X7R,A3A   I111 @BASEBOARD_FAB2_LIB.BASEBOARD_FAB2(SCH_1):PAGE106
  J9B3   82   IO82 SCONN120_A28699018_SM-SCONN,A2A   I336 @BASEBOARD_FAB2_LIB.BASEBOARD_FAB2(SCH_1):PAGE186

P3E_OCP_CPU0_PE3_C_TXN<13> @BASEBOARD_FAB2_LIB.BASEBOARD_FAB2(SCH_1):P3E_OCP_CPU0_PE3_C_TXN(13)
 C1M11    2      B CAP_0402-0.22UF,16V,10%,X7R,A3A   I117 @BASEBOARD_FAB2_LIB.BASEBOARD_FAB2(SCH_1):PAGE106
  J9B3   74   IO74 SCONN120_A28699018_SM-SCONN,A2A   I336 @BASEBOARD_FAB2_LIB.BASEBOARD_FAB2(SCH_1):PAGE186

P3E_OCP_CPU0_PE3_C_TXN<14> @BASEBOARD_FAB2_LIB.BASEBOARD_FAB2(SCH_1):P3E_OCP_CPU0_PE3_C_TXN(14)
  C1M9    2      B CAP_0402-0.22UF,16V,10%,X7R,A3A   I114 @BASEBOARD_FAB2_LIB.BASEBOARD_FAB2(SCH_1):PAGE106
  J9B3   66   IO66 SCONN120_A28699018_SM-SCONN,A2A   I336 @BASEBOARD_FAB2_LIB.BASEBOARD_FAB2(SCH_1):PAGE186

P3E_OCP_CPU0_PE3_C_TXN<15> @BASEBOARD_FAB2_LIB.BASEBOARD_FAB2(SCH_1):P3E_OCP_CPU0_PE3_C_TXN(15)
  C1M7    2      B CAP_0402-0.22UF,16V,10%,X7R,A3A   I122 @BASEBOARD_FAB2_LIB.BASEBOARD_FAB2(SCH_1):PAGE106
  J9B3   58   IO58 SCONN120_A28699018_SM-SCONN,A2A   I336 @BASEBOARD_FAB2_LIB.BASEBOARD_FAB2(SCH_1):PAGE186

P3E_OCP_CPU0_PE3_C_TXN<1> @BASEBOARD_FAB2_LIB.BASEBOARD_FAB2(SCH_1):P3E_OCP_CPU0_PE3_C_TXN(1)
  C1R3    2      B CAP_0402-0.22UF,16V,10%,X7R,A3A    I37 @BASEBOARD_FAB2_LIB.BASEBOARD_FAB2(SCH_1):PAGE106
  J8E3   60   IO60 SCONN80_E67482007_SM-CONN,E674A   I119 @BASEBOARD_FAB2_LIB.BASEBOARD_FAB2(SCH_1):PAGE187

P3E_OCP_CPU0_PE3_C_TXN<2> @BASEBOARD_FAB2_LIB.BASEBOARD_FAB2(SCH_1):P3E_OCP_CPU0_PE3_C_TXN(2)
  C1R5    2      B CAP_0402-0.22UF,16V,10%,X7R,A3A    I59 @BASEBOARD_FAB2_LIB.BASEBOARD_FAB2(SCH_1):PAGE106
  J8E3   52   IO52 SCONN80_E67482007_SM-CONN,E674A   I119 @BASEBOARD_FAB2_LIB.BASEBOARD_FAB2(SCH_1):PAGE187

P3E_OCP_CPU0_PE3_C_TXN<3> @BASEBOARD_FAB2_LIB.BASEBOARD_FAB2(SCH_1):P3E_OCP_CPU0_PE3_C_TXN(3)
  C1R7    2      B CAP_0402-0.22UF,16V,10%,X7R,A3A    I70 @BASEBOARD_FAB2_LIB.BASEBOARD_FAB2(SCH_1):PAGE106
  J8E3   44   IO44 SCONN80_E67482007_SM-CONN,E674A   I119 @BASEBOARD_FAB2_LIB.BASEBOARD_FAB2(SCH_1):PAGE187

P3E_OCP_CPU0_PE3_C_TXN<4> @BASEBOARD_FAB2_LIB.BASEBOARD_FAB2(SCH_1):P3E_OCP_CPU0_PE3_C_TXN(4)
  C1R9    2      B CAP_0402-0.22UF,16V,10%,X7R,A3A   I134 @BASEBOARD_FAB2_LIB.BASEBOARD_FAB2(SCH_1):PAGE106
  J8E3   36   IO36 SCONN80_E67482007_SM-CONN,E674A   I119 @BASEBOARD_FAB2_LIB.BASEBOARD_FAB2(SCH_1):PAGE187

P3E_OCP_CPU0_PE3_C_TXN<5> @BASEBOARD_FAB2_LIB.BASEBOARD_FAB2(SCH_1):P3E_OCP_CPU0_PE3_C_TXN(5)
 C2R13    2      B CAP_0402-0.22UF,16V,10%,X7R,A3A   I137 @BASEBOARD_FAB2_LIB.BASEBOARD_FAB2(SCH_1):PAGE106
  J8E3   28   IO28 SCONN80_E67482007_SM-CONN,E674A   I119 @BASEBOARD_FAB2_LIB.BASEBOARD_FAB2(SCH_1):PAGE187

P3E_OCP_CPU0_PE3_C_TXN<6> @BASEBOARD_FAB2_LIB.BASEBOARD_FAB2(SCH_1):P3E_OCP_CPU0_PE3_C_TXN(6)
  C2R7    2      B CAP_0402-0.22UF,16V,10%,X7R,A3A   I123 @BASEBOARD_FAB2_LIB.BASEBOARD_FAB2(SCH_1):PAGE106
  J8E3   20   IO20 SCONN80_E67482007_SM-CONN,E674A   I119 @BASEBOARD_FAB2_LIB.BASEBOARD_FAB2(SCH_1):PAGE187

P3E_OCP_CPU0_PE3_C_TXN<7> @BASEBOARD_FAB2_LIB.BASEBOARD_FAB2(SCH_1):P3E_OCP_CPU0_PE3_C_TXN(7)
  C2R9    2      B CAP_0402-0.22UF,16V,10%,X7R,A3A   I147 @BASEBOARD_FAB2_LIB.BASEBOARD_FAB2(SCH_1):PAGE106
  J8E3   12   IO12 SCONN80_E67482007_SM-CONN,E674A   I119 @BASEBOARD_FAB2_LIB.BASEBOARD_FAB2(SCH_1):PAGE187

P3E_OCP_CPU0_PE3_C_TXN<8> @BASEBOARD_FAB2_LIB.BASEBOARD_FAB2(SCH_1):P3E_OCP_CPU0_PE3_C_TXN(8)
 C2M15    2      B CAP_0402-0.22UF,16V,10%,X7R,A3A    I86 @BASEBOARD_FAB2_LIB.BASEBOARD_FAB2(SCH_1):PAGE106
  J9B3  114  IO114 SCONN120_A28699018_SM-SCONN,A2A   I336 @BASEBOARD_FAB2_LIB.BASEBOARD_FAB2(SCH_1):PAGE186

P3E_OCP_CPU0_PE3_C_TXN<9> @BASEBOARD_FAB2_LIB.BASEBOARD_FAB2(SCH_1):P3E_OCP_CPU0_PE3_C_TXN(9)
 C1M19    2      B CAP_0402-0.22UF,16V,10%,X7R,A3A    I90 @BASEBOARD_FAB2_LIB.BASEBOARD_FAB2(SCH_1):PAGE106
  J9B3  106  IO106 SCONN120_A28699018_SM-SCONN,A2A   I336 @BASEBOARD_FAB2_LIB.BASEBOARD_FAB2(SCH_1):PAGE186

P3E_OCP_CPU0_PE3_C_TXP<0> @BASEBOARD_FAB2_LIB.BASEBOARD_FAB2(SCH_1):P3E_OCP_CPU0_PE3_C_TXP(0)
  C1R2    2      B CAP_0402-0.22UF,16V,10%,X7R,A3A    I10 @BASEBOARD_FAB2_LIB.BASEBOARD_FAB2(SCH_1):PAGE106
  J8E3   66   IO66 SCONN80_E67482007_SM-CONN,E674A   I119 @BASEBOARD_FAB2_LIB.BASEBOARD_FAB2(SCH_1):PAGE187

P3E_OCP_CPU0_PE3_C_TXP<10> @BASEBOARD_FAB2_LIB.BASEBOARD_FAB2(SCH_1):P3E_OCP_CPU0_PE3_C_TXP(10)
 C1M16    2      B CAP_0402-0.22UF,16V,10%,X7R,A3A    I82 @BASEBOARD_FAB2_LIB.BASEBOARD_FAB2(SCH_1):PAGE106
  J9B3   96   IO96 SCONN120_A28699018_SM-SCONN,A2A   I336 @BASEBOARD_FAB2_LIB.BASEBOARD_FAB2(SCH_1):PAGE186

P3E_OCP_CPU0_PE3_C_TXP<11> @BASEBOARD_FAB2_LIB.BASEBOARD_FAB2(SCH_1):P3E_OCP_CPU0_PE3_C_TXP(11)
 C1M14    2      B CAP_0402-0.22UF,16V,10%,X7R,A3A    I85 @BASEBOARD_FAB2_LIB.BASEBOARD_FAB2(SCH_1):PAGE106
  J9B3   88   IO88 SCONN120_A28699018_SM-SCONN,A2A   I336 @BASEBOARD_FAB2_LIB.BASEBOARD_FAB2(SCH_1):PAGE186

P3E_OCP_CPU0_PE3_C_TXP<12> @BASEBOARD_FAB2_LIB.BASEBOARD_FAB2(SCH_1):P3E_OCP_CPU0_PE3_C_TXP(12)
 C1M12    2      B CAP_0402-0.22UF,16V,10%,X7R,A3A   I100 @BASEBOARD_FAB2_LIB.BASEBOARD_FAB2(SCH_1):PAGE106
  J9B3   80   IO80 SCONN120_A28699018_SM-SCONN,A2A   I336 @BASEBOARD_FAB2_LIB.BASEBOARD_FAB2(SCH_1):PAGE186

P3E_OCP_CPU0_PE3_C_TXP<13> @BASEBOARD_FAB2_LIB.BASEBOARD_FAB2(SCH_1):P3E_OCP_CPU0_PE3_C_TXP(13)
 C1M10    2      B CAP_0402-0.22UF,16V,10%,X7R,A3A   I102 @BASEBOARD_FAB2_LIB.BASEBOARD_FAB2(SCH_1):PAGE106
  J9B3   72   IO72 SCONN120_A28699018_SM-SCONN,A2A   I336 @BASEBOARD_FAB2_LIB.BASEBOARD_FAB2(SCH_1):PAGE186

P3E_OCP_CPU0_PE3_C_TXP<14> @BASEBOARD_FAB2_LIB.BASEBOARD_FAB2(SCH_1):P3E_OCP_CPU0_PE3_C_TXP(14)
  C1M8    2      B CAP_0402-0.22UF,16V,10%,X7R,A3A   I105 @BASEBOARD_FAB2_LIB.BASEBOARD_FAB2(SCH_1):PAGE106
  J9B3   64   IO64 SCONN120_A28699018_SM-SCONN,A2A   I336 @BASEBOARD_FAB2_LIB.BASEBOARD_FAB2(SCH_1):PAGE186

P3E_OCP_CPU0_PE3_C_TXP<15> @BASEBOARD_FAB2_LIB.BASEBOARD_FAB2(SCH_1):P3E_OCP_CPU0_PE3_C_TXP(15)
  C1M6    2      B CAP_0402-0.22UF,16V,10%,X7R,A3A   I109 @BASEBOARD_FAB2_LIB.BASEBOARD_FAB2(SCH_1):PAGE106
  J9B3   56   IO56 SCONN120_A28699018_SM-SCONN,A2A   I336 @BASEBOARD_FAB2_LIB.BASEBOARD_FAB2(SCH_1):PAGE186

P3E_OCP_CPU0_PE3_C_TXP<1> @BASEBOARD_FAB2_LIB.BASEBOARD_FAB2(SCH_1):P3E_OCP_CPU0_PE3_C_TXP(1)
  C1R4    2      B CAP_0402-0.22UF,16V,10%,X7R,A3A    I26 @BASEBOARD_FAB2_LIB.BASEBOARD_FAB2(SCH_1):PAGE106
  J8E3   58   IO58 SCONN80_E67482007_SM-CONN,E674A   I119 @BASEBOARD_FAB2_LIB.BASEBOARD_FAB2(SCH_1):PAGE187

P3E_OCP_CPU0_PE3_C_TXP<2> @BASEBOARD_FAB2_LIB.BASEBOARD_FAB2(SCH_1):P3E_OCP_CPU0_PE3_C_TXP(2)
  C1R6    2      B CAP_0402-0.22UF,16V,10%,X7R,A3A    I40 @BASEBOARD_FAB2_LIB.BASEBOARD_FAB2(SCH_1):PAGE106
  J8E3   50   IO50 SCONN80_E67482007_SM-CONN,E674A   I119 @BASEBOARD_FAB2_LIB.BASEBOARD_FAB2(SCH_1):PAGE187

P3E_OCP_CPU0_PE3_C_TXP<3> @BASEBOARD_FAB2_LIB.BASEBOARD_FAB2(SCH_1):P3E_OCP_CPU0_PE3_C_TXP(3)
  C1R8    2      B CAP_0402-0.22UF,16V,10%,X7R,A3A    I55 @BASEBOARD_FAB2_LIB.BASEBOARD_FAB2(SCH_1):PAGE106
  J8E3   42   IO42 SCONN80_E67482007_SM-CONN,E674A   I119 @BASEBOARD_FAB2_LIB.BASEBOARD_FAB2(SCH_1):PAGE187

P3E_OCP_CPU0_PE3_C_TXP<4> @BASEBOARD_FAB2_LIB.BASEBOARD_FAB2(SCH_1):P3E_OCP_CPU0_PE3_C_TXP(4)
 C1R10    2      B CAP_0402-0.22UF,16V,10%,X7R,A3A   I128 @BASEBOARD_FAB2_LIB.BASEBOARD_FAB2(SCH_1):PAGE106
  J8E3   34   IO34 SCONN80_E67482007_SM-CONN,E674A   I119 @BASEBOARD_FAB2_LIB.BASEBOARD_FAB2(SCH_1):PAGE187

P3E_OCP_CPU0_PE3_C_TXP<5> @BASEBOARD_FAB2_LIB.BASEBOARD_FAB2(SCH_1):P3E_OCP_CPU0_PE3_C_TXP(5)
 C2R14    2      B CAP_0402-0.22UF,16V,10%,X7R,A3A   I130 @BASEBOARD_FAB2_LIB.BASEBOARD_FAB2(SCH_1):PAGE106
  J8E3   26   IO26 SCONN80_E67482007_SM-CONN,E674A   I119 @BASEBOARD_FAB2_LIB.BASEBOARD_FAB2(SCH_1):PAGE187

P3E_OCP_CPU0_PE3_C_TXP<6> @BASEBOARD_FAB2_LIB.BASEBOARD_FAB2(SCH_1):P3E_OCP_CPU0_PE3_C_TXP(6)
  C2R8    2      B CAP_0402-0.22UF,16V,10%,X7R,A3A   I141 @BASEBOARD_FAB2_LIB.BASEBOARD_FAB2(SCH_1):PAGE106
  J8E3   18   IO18 SCONN80_E67482007_SM-CONN,E674A   I119 @BASEBOARD_FAB2_LIB.BASEBOARD_FAB2(SCH_1):PAGE187

P3E_OCP_CPU0_PE3_C_TXP<7> @BASEBOARD_FAB2_LIB.BASEBOARD_FAB2(SCH_1):P3E_OCP_CPU0_PE3_C_TXP(7)
 C2R10    2      B CAP_0402-0.22UF,16V,10%,X7R,A3A   I142 @BASEBOARD_FAB2_LIB.BASEBOARD_FAB2(SCH_1):PAGE106
  J8E3   10   IO10 SCONN80_E67482007_SM-CONN,E674A   I119 @BASEBOARD_FAB2_LIB.BASEBOARD_FAB2(SCH_1):PAGE187

P3E_OCP_CPU0_PE3_C_TXP<8> @BASEBOARD_FAB2_LIB.BASEBOARD_FAB2(SCH_1):P3E_OCP_CPU0_PE3_C_TXP(8)
 C2M14    2      B CAP_0402-0.22UF,16V,10%,X7R,A3A    I76 @BASEBOARD_FAB2_LIB.BASEBOARD_FAB2(SCH_1):PAGE106
  J9B3  112  IO112 SCONN120_A28699018_SM-SCONN,A2A   I336 @BASEBOARD_FAB2_LIB.BASEBOARD_FAB2(SCH_1):PAGE186

P3E_OCP_CPU0_PE3_C_TXP<9> @BASEBOARD_FAB2_LIB.BASEBOARD_FAB2(SCH_1):P3E_OCP_CPU0_PE3_C_TXP(9)
 C1M18    2      B CAP_0402-0.22UF,16V,10%,X7R,A3A    I78 @BASEBOARD_FAB2_LIB.BASEBOARD_FAB2(SCH_1):PAGE106
  J9B3  104  IO104 SCONN120_A28699018_SM-SCONN,A2A   I336 @BASEBOARD_FAB2_LIB.BASEBOARD_FAB2(SCH_1):PAGE186

P3E_PCH_M2_RX_DN<1> @BASEBOARD_FAB2_LIB.BASEBOARD_FAB2(SCH_1):P3E_PCH_M2_RX_DN(1)
  U7C1 AY72 USB3_8_PCIE1_RXN LBG_CORE_QAT_EXT_D_BGA1-IC,H91A   I220 @BASEBOARD_FAB2_LIB.BASEBOARD_FAB2(SCH_1):PAGE116
  J8F1   29     29 SKT-MINI67P-41-GP_SOCKET-G4-SKA   I143 @BASEBOARD_FAB2_LIB.BASEBOARD_FAB2(SCH_1):PAGE185

P3E_PCH_M2_RX_DN<2> @BASEBOARD_FAB2_LIB.BASEBOARD_FAB2(SCH_1):P3E_PCH_M2_RX_DN(2)
  U7C1 AW71 USB3_9_PCIE2_RXN LBG_CORE_QAT_EXT_D_BGA1-IC,H91A   I220 @BASEBOARD_FAB2_LIB.BASEBOARD_FAB2(SCH_1):PAGE116
  J8F1   17     17 SKT-MINI67P-41-GP_SOCKET-G4-SKA   I143 @BASEBOARD_FAB2_LIB.BASEBOARD_FAB2(SCH_1):PAGE185

P3E_PCH_M2_RX_DN<3> @BASEBOARD_FAB2_LIB.BASEBOARD_FAB2(SCH_1):P3E_PCH_M2_RX_DN(3)
  U7C1 AV72 USB3_10_PCIE3_GBE_RXN LBG_CORE_QAT_EXT_D_BGA1-IC,H91A   I220 @BASEBOARD_FAB2_LIB.BASEBOARD_FAB2(SCH_1):PAGE116
  J8F1    5      5 SKT-MINI67P-41-GP_SOCKET-G4-SKA   I143 @BASEBOARD_FAB2_LIB.BASEBOARD_FAB2(SCH_1):PAGE185

P3E_PCH_M2_RX_DP<1> @BASEBOARD_FAB2_LIB.BASEBOARD_FAB2(SCH_1):P3E_PCH_M2_RX_DP(1)
  U7C1 AY70 USB3_8_PCIE1_RXP LBG_CORE_QAT_EXT_D_BGA1-IC,H91A   I220 @BASEBOARD_FAB2_LIB.BASEBOARD_FAB2(SCH_1):PAGE116
  J8F1   31     31 SKT-MINI67P-41-GP_SOCKET-G4-SKA   I143 @BASEBOARD_FAB2_LIB.BASEBOARD_FAB2(SCH_1):PAGE185

P3E_PCH_M2_RX_DP<2> @BASEBOARD_FAB2_LIB.BASEBOARD_FAB2(SCH_1):P3E_PCH_M2_RX_DP(2)
  U7C1 AW69 USB3_9_PCIE2_RXP LBG_CORE_QAT_EXT_D_BGA1-IC,H91A   I220 @BASEBOARD_FAB2_LIB.BASEBOARD_FAB2(SCH_1):PAGE116
  J8F1   19     19 SKT-MINI67P-41-GP_SOCKET-G4-SKA   I143 @BASEBOARD_FAB2_LIB.BASEBOARD_FAB2(SCH_1):PAGE185

P3E_PCH_M2_RX_DP<3> @BASEBOARD_FAB2_LIB.BASEBOARD_FAB2(SCH_1):P3E_PCH_M2_RX_DP(3)
  U7C1 AV70 USB3_10_PCIE3_GBE_RXP LBG_CORE_QAT_EXT_D_BGA1-IC,H91A   I220 @BASEBOARD_FAB2_LIB.BASEBOARD_FAB2(SCH_1):PAGE116
  J8F1    7      7 SKT-MINI67P-41-GP_SOCKET-G4-SKA   I143 @BASEBOARD_FAB2_LIB.BASEBOARD_FAB2(SCH_1):PAGE185

P3E_PCH_M2_SATA6G_RX_R_DN @BASEBOARD_FAB2_LIB.BASEBOARD_FAB2(SCH_1):P3E_PCH_M2_SATA6G_RX_R_DN
 R8F21    2      B RES_0402-0.0,5%,1/16W,CHIP,G21A   I106 @BASEBOARD_FAB2_LIB.BASEBOARD_FAB2(SCH_1):PAGE185
 C8F15    2      B CAP_A_0402V-0.01UF,25V,10%,X7RA   I142 @BASEBOARD_FAB2_LIB.BASEBOARD_FAB2(SCH_1):PAGE185
  J8F1   43     43 SKT-MINI67P-41-GP_SOCKET-G4-SKA   I143 @BASEBOARD_FAB2_LIB.BASEBOARD_FAB2(SCH_1):PAGE185

P3E_PCH_M2_SATA6G_RX_R_DP @BASEBOARD_FAB2_LIB.BASEBOARD_FAB2(SCH_1):P3E_PCH_M2_SATA6G_RX_R_DP
 R8F18    2      B RES_0402-0.0,5%,1/16W,CHIP,G21A   I105 @BASEBOARD_FAB2_LIB.BASEBOARD_FAB2(SCH_1):PAGE185
 C8F13    2      B CAP_A_0402V-0.01UF,25V,10%,X7RA   I141 @BASEBOARD_FAB2_LIB.BASEBOARD_FAB2(SCH_1):PAGE185
  J8F1   41     41 SKT-MINI67P-41-GP_SOCKET-G4-SKA   I143 @BASEBOARD_FAB2_LIB.BASEBOARD_FAB2(SCH_1):PAGE185

P3E_PCH_M2_SATA6G_TX_R_DN @BASEBOARD_FAB2_LIB.BASEBOARD_FAB2(SCH_1):P3E_PCH_M2_SATA6G_TX_R_DN
 C8F11    2      B CAP_A_0402V-0.01UF,25V,10%,X7RA   I139 @BASEBOARD_FAB2_LIB.BASEBOARD_FAB2(SCH_1):PAGE185
 C8F12    2      B CAP_0402-0.22UF,16V,10%,X7R,A3A   I140 @BASEBOARD_FAB2_LIB.BASEBOARD_FAB2(SCH_1):PAGE185
  J8F1   47     47 SKT-MINI67P-41-GP_SOCKET-G4-SKA   I143 @BASEBOARD_FAB2_LIB.BASEBOARD_FAB2(SCH_1):PAGE185

P3E_PCH_M2_SATA6G_TX_R_DP @BASEBOARD_FAB2_LIB.BASEBOARD_FAB2(SCH_1):P3E_PCH_M2_SATA6G_TX_R_DP
  C8F7    2      B CAP_0402-0.22UF,16V,10%,X7R,A3A    I96 @BASEBOARD_FAB2_LIB.BASEBOARD_FAB2(SCH_1):PAGE185
  C8F6    2      B CAP_A_0402V-0.01UF,25V,10%,X7RA   I138 @BASEBOARD_FAB2_LIB.BASEBOARD_FAB2(SCH_1):PAGE185
  J8F1   49     49 SKT-MINI67P-41-GP_SOCKET-G4-SKA   I143 @BASEBOARD_FAB2_LIB.BASEBOARD_FAB2(SCH_1):PAGE185

P3E_PCH_M2_TX_C_DN<1> @BASEBOARD_FAB2_LIB.BASEBOARD_FAB2(SCH_1):P3E_PCH_M2_TX_C_DN(1)
  J8F1   35     35 SKT-MINI67P-41-GP_SOCKET-G4-SKA   I143 @BASEBOARD_FAB2_LIB.BASEBOARD_FAB2(SCH_1):PAGE185
 C2T11    1      A CAP_0402-0.22UF,16V,10%,X7R,A3A   I167 @BASEBOARD_FAB2_LIB.BASEBOARD_FAB2(SCH_1):PAGE185

P3E_PCH_M2_TX_C_DN<2> @BASEBOARD_FAB2_LIB.BASEBOARD_FAB2(SCH_1):P3E_PCH_M2_TX_C_DN(2)
  J8F1   23     23 SKT-MINI67P-41-GP_SOCKET-G4-SKA   I143 @BASEBOARD_FAB2_LIB.BASEBOARD_FAB2(SCH_1):PAGE185
 C2T14    1      A CAP_0402-0.22UF,16V,10%,X7R,A3A   I171 @BASEBOARD_FAB2_LIB.BASEBOARD_FAB2(SCH_1):PAGE185

P3E_PCH_M2_TX_C_DN<3> @BASEBOARD_FAB2_LIB.BASEBOARD_FAB2(SCH_1):P3E_PCH_M2_TX_C_DN(3)
  J8F1   11     11 SKT-MINI67P-41-GP_SOCKET-G4-SKA   I143 @BASEBOARD_FAB2_LIB.BASEBOARD_FAB2(SCH_1):PAGE185
 C2T23    1      A CAP_0402-0.22UF,16V,10%,X7R,A3A   I180 @BASEBOARD_FAB2_LIB.BASEBOARD_FAB2(SCH_1):PAGE185

P3E_PCH_M2_TX_C_DP<1> @BASEBOARD_FAB2_LIB.BASEBOARD_FAB2(SCH_1):P3E_PCH_M2_TX_C_DP(1)
  J8F1   37     37 SKT-MINI67P-41-GP_SOCKET-G4-SKA   I143 @BASEBOARD_FAB2_LIB.BASEBOARD_FAB2(SCH_1):PAGE185
 C2T10    1      A CAP_0402-0.22UF,16V,10%,X7R,A3A   I168 @BASEBOARD_FAB2_LIB.BASEBOARD_FAB2(SCH_1):PAGE185

P3E_PCH_M2_TX_C_DP<2> @BASEBOARD_FAB2_LIB.BASEBOARD_FAB2(SCH_1):P3E_PCH_M2_TX_C_DP(2)
  J8F1   25     25 SKT-MINI67P-41-GP_SOCKET-G4-SKA   I143 @BASEBOARD_FAB2_LIB.BASEBOARD_FAB2(SCH_1):PAGE185
 C2T13    1      A CAP_0402-0.22UF,16V,10%,X7R,A3A   I172 @BASEBOARD_FAB2_LIB.BASEBOARD_FAB2(SCH_1):PAGE185

P3E_PCH_M2_TX_C_DP<3> @BASEBOARD_FAB2_LIB.BASEBOARD_FAB2(SCH_1):P3E_PCH_M2_TX_C_DP(3)
  J8F1   13     13 SKT-MINI67P-41-GP_SOCKET-G4-SKA   I143 @BASEBOARD_FAB2_LIB.BASEBOARD_FAB2(SCH_1):PAGE185
 C2T20    1      A CAP_0402-0.22UF,16V,10%,X7R,A3A   I179 @BASEBOARD_FAB2_LIB.BASEBOARD_FAB2(SCH_1):PAGE185

P3E_PCH_M2_TX_DN<1> @BASEBOARD_FAB2_LIB.BASEBOARD_FAB2(SCH_1):P3E_PCH_M2_TX_DN(1)
  U7C1 BM65 USB3_8_PCIE1_TXN LBG_CORE_QAT_EXT_D_BGA1-IC,H91A   I220 @BASEBOARD_FAB2_LIB.BASEBOARD_FAB2(SCH_1):PAGE116
 C2T11    2      B CAP_0402-0.22UF,16V,10%,X7R,A3A   I167 @BASEBOARD_FAB2_LIB.BASEBOARD_FAB2(SCH_1):PAGE185

P3E_PCH_M2_TX_DN<2> @BASEBOARD_FAB2_LIB.BASEBOARD_FAB2(SCH_1):P3E_PCH_M2_TX_DN(2)
  U7C1 BK65 USB3_9_PCIE2_TXN LBG_CORE_QAT_EXT_D_BGA1-IC,H91A   I220 @BASEBOARD_FAB2_LIB.BASEBOARD_FAB2(SCH_1):PAGE116
 C2T14    2      B CAP_0402-0.22UF,16V,10%,X7R,A3A   I171 @BASEBOARD_FAB2_LIB.BASEBOARD_FAB2(SCH_1):PAGE185

P3E_PCH_M2_TX_DN<3> @BASEBOARD_FAB2_LIB.BASEBOARD_FAB2(SCH_1):P3E_PCH_M2_TX_DN(3)
  U7C1 BH61 USB3_10_PCIE3_GBE_TXN LBG_CORE_QAT_EXT_D_BGA1-IC,H91A   I220 @BASEBOARD_FAB2_LIB.BASEBOARD_FAB2(SCH_1):PAGE116
 C2T23    2      B CAP_0402-0.22UF,16V,10%,X7R,A3A   I180 @BASEBOARD_FAB2_LIB.BASEBOARD_FAB2(SCH_1):PAGE185

P3E_PCH_M2_TX_DP<1> @BASEBOARD_FAB2_LIB.BASEBOARD_FAB2(SCH_1):P3E_PCH_M2_TX_DP(1)
  U7C1 BR65 USB3_8_PCIE1_TXP LBG_CORE_QAT_EXT_D_BGA1-IC,H91A   I220 @BASEBOARD_FAB2_LIB.BASEBOARD_FAB2(SCH_1):PAGE116
 C2T10    2      B CAP_0402-0.22UF,16V,10%,X7R,A3A   I168 @BASEBOARD_FAB2_LIB.BASEBOARD_FAB2(SCH_1):PAGE185

P3E_PCH_M2_TX_DP<2> @BASEBOARD_FAB2_LIB.BASEBOARD_FAB2(SCH_1):P3E_PCH_M2_TX_DP(2)
  U7C1 BL66 USB3_9_PCIE2_TXP LBG_CORE_QAT_EXT_D_BGA1-IC,H91A   I220 @BASEBOARD_FAB2_LIB.BASEBOARD_FAB2(SCH_1):PAGE116
 C2T13    2      B CAP_0402-0.22UF,16V,10%,X7R,A3A   I172 @BASEBOARD_FAB2_LIB.BASEBOARD_FAB2(SCH_1):PAGE185

P3E_PCH_M2_TX_DP<3> @BASEBOARD_FAB2_LIB.BASEBOARD_FAB2(SCH_1):P3E_PCH_M2_TX_DP(3)
  U7C1 BK61 USB3_10_PCIE3_GBE_TXP LBG_CORE_QAT_EXT_D_BGA1-IC,H91A   I220 @BASEBOARD_FAB2_LIB.BASEBOARD_FAB2(SCH_1):PAGE116
 C2T20    2      B CAP_0402-0.22UF,16V,10%,X7R,A3A   I179 @BASEBOARD_FAB2_LIB.BASEBOARD_FAB2(SCH_1):PAGE185

P3E_PCH_RX_0_DN @BASEBOARD_FAB2_LIB.BASEBOARD_FAB2(SCH_1):P3E_PCH_RX_0_DN
  U7C1 BA71 USB3_7_PCIE0_RXN LBG_CORE_QAT_EXT_D_BGA1-IC,H91A   I220 @BASEBOARD_FAB2_LIB.BASEBOARD_FAB2(SCH_1):PAGE116
 R8F21    1      A RES_0402-0.0,5%,1/16W,CHIP,G21A   I106 @BASEBOARD_FAB2_LIB.BASEBOARD_FAB2(SCH_1):PAGE185

P3E_PCH_RX_0_DP @BASEBOARD_FAB2_LIB.BASEBOARD_FAB2(SCH_1):P3E_PCH_RX_0_DP
  U7C1 BA69 USB3_7_PCIE0_RXP LBG_CORE_QAT_EXT_D_BGA1-IC,H91A   I220 @BASEBOARD_FAB2_LIB.BASEBOARD_FAB2(SCH_1):PAGE116
 R8F18    1      A RES_0402-0.0,5%,1/16W,CHIP,G21A   I105 @BASEBOARD_FAB2_LIB.BASEBOARD_FAB2(SCH_1):PAGE185

P3E_PCH_TX_0_DN @BASEBOARD_FAB2_LIB.BASEBOARD_FAB2(SCH_1):P3E_PCH_TX_0_DN
  U7C1 BR61 USB3_7_PCIE0_TXN LBG_CORE_QAT_EXT_D_BGA1-IC,H91A   I220 @BASEBOARD_FAB2_LIB.BASEBOARD_FAB2(SCH_1):PAGE116
 C8F12    1      A CAP_0402-0.22UF,16V,10%,X7R,A3A   I140 @BASEBOARD_FAB2_LIB.BASEBOARD_FAB2(SCH_1):PAGE185

P3E_PCH_TX_0_DP @BASEBOARD_FAB2_LIB.BASEBOARD_FAB2(SCH_1):P3E_PCH_TX_0_DP
  U7C1 BN63 USB3_7_PCIE0_TXP LBG_CORE_QAT_EXT_D_BGA1-IC,H91A   I220 @BASEBOARD_FAB2_LIB.BASEBOARD_FAB2(SCH_1):PAGE116
  C8F7    1      A CAP_0402-0.22UF,16V,10%,X7R,A3A    I96 @BASEBOARD_FAB2_LIB.BASEBOARD_FAB2(SCH_1):PAGE185

P3V3 @BASEBOARD_FAB2_LIB.BASEBOARD_FAB2(SCH_1):P3V3
  J8B1   18   IO18 SCONN24_H46321001_SM-SCONN,H46A     I1 @BASEBOARD_FAB2_LIB.BASEBOARD_FAB2(SCH_1):PAGE91
  J8B1   20   IO20 SCONN24_H46321001_SM-SCONN,H46A     I1 @BASEBOARD_FAB2_LIB.BASEBOARD_FAB2(SCH_1):PAGE91
  U3P2   14    VCC GTL2014_SM-IC,D66151-001     I1 @BASEBOARD_FAB2_LIB.BASEBOARD_FAB2(SCH_1):PAGE92
  U7D2   14    VCC GTL2014_SM-IC,D66151-001    I32 @BASEBOARD_FAB2_LIB.BASEBOARD_FAB2(SCH_1):PAGE92
  C7D4    1      A CAP_0402-1.0UF,16V,10%,X6S,D97A    I79 @BASEBOARD_FAB2_LIB.BASEBOARD_FAB2(SCH_1):PAGE92
 C3P50    1      A CAP_0402-1.0UF,16V,10%,X6S,D97A    I84 @BASEBOARD_FAB2_LIB.BASEBOARD_FAB2(SCH_1):PAGE92
  U2T4   14    VCC GTL2014_SM-IC,D66151-001    I30 @BASEBOARD_FAB2_LIB.BASEBOARD_FAB2(SCH_1):PAGE93
 C2T33    1      A CAP_A_0402V-1.0UF,6.3V,10%,X6SA    I72 @BASEBOARD_FAB2_LIB.BASEBOARD_FAB2(SCH_1):PAGE93
  R7G7    1      A RES_0402-4.75K,1%,1/16W,CHIP,GA    I51 @BASEBOARD_FAB2_LIB.BASEBOARD_FAB2(SCH_1):PAGE94
  R3R4    1      A RES_0402-4.75K,1%,1/16W,CHIP,GA    I66 @BASEBOARD_FAB2_LIB.BASEBOARD_FAB2(SCH_1):PAGE94
 R3R10    1      A RES_0402-4.75K,1%,1/16W,CHIP,GA    I79 @BASEBOARD_FAB2_LIB.BASEBOARD_FAB2(SCH_1):PAGE94
  R6M4    1      A RES_0402-4.75K,1%,1/16W,CHIP,GA    I82 @BASEBOARD_FAB2_LIB.BASEBOARD_FAB2(SCH_1):PAGE94
 R7E10    1      A RES_0402-4.75K,1%,1/16W,CHIP,GA    I62 @BASEBOARD_FAB2_LIB.BASEBOARD_FAB2(SCH_1):PAGE95
 R7E11    1      A RES_0402-4.75K,1%,1/16W,CHIP,GA    I72 @BASEBOARD_FAB2_LIB.BASEBOARD_FAB2(SCH_1):PAGE95
  R7E7    1      A RES_0402-4.75K,1%,1/16W,CHIP,GA   I106 @BASEBOARD_FAB2_LIB.BASEBOARD_FAB2(SCH_1):PAGE95
 FB6P1    1      A FERRITE_SMLF-600,FB,656554-043     I8 @BASEBOARD_FAB2_LIB.BASEBOARD_FAB2(SCH_1):PAGE102
 R4D69    1      A RES_0402-4.75K,1%,1/16W,CHIP,GA    I93 @BASEBOARD_FAB2_LIB.BASEBOARD_FAB2(SCH_1):PAGE102
 R4D70    1      A RES_0402-4.75K,1%,1/16W,CHIP,GA    I94 @BASEBOARD_FAB2_LIB.BASEBOARD_FAB2(SCH_1):PAGE102
  C6F1    1      A CAP_A_0402V-0.1UF,16V,10%,X7R,A    I25 @BASEBOARD_FAB2_LIB.BASEBOARD_FAB2(SCH_1):PAGE104
  C3F2    1      A CAP_A_0402V-0.1UF,16V,10%,X7R,A    I34 @BASEBOARD_FAB2_LIB.BASEBOARD_FAB2(SCH_1):PAGE104
  Y6F1    6    VCC OSC_C_6P10-156.25MHZ,OSC,G6383A    I71 @BASEBOARD_FAB2_LIB.BASEBOARD_FAB2(SCH_1):PAGE104
  Y3F1    6    VCC OSC_C_6P10-156.25MHZ,OSC,G6383A    I72 @BASEBOARD_FAB2_LIB.BASEBOARD_FAB2(SCH_1):PAGE104
 C2U21    1      A CAP_A_0402V-0.1UF,16V,10%,X7R,A     I5 @BASEBOARD_FAB2_LIB.BASEBOARD_FAB2(SCH_1):PAGE108
 C2U25    1      A CAP_A_0402V-0.1UF,16V,10%,X7R,A     I7 @BASEBOARD_FAB2_LIB.BASEBOARD_FAB2(SCH_1):PAGE108
  J8G1   21   IO21 SCONN200_H68296001_SM-CONN,H68A   I258 @BASEBOARD_FAB2_LIB.BASEBOARD_FAB2(SCH_1):PAGE108
  J8G1   22   IO22 SCONN200_H68296001_SM-CONN,H68A   I258 @BASEBOARD_FAB2_LIB.BASEBOARD_FAB2(SCH_1):PAGE108
  J8G1   23   IO23 SCONN200_H68296001_SM-CONN,H68A   I258 @BASEBOARD_FAB2_LIB.BASEBOARD_FAB2(SCH_1):PAGE108
  J8G1   24   IO24 SCONN200_H68296001_SM-CONN,H68A   I258 @BASEBOARD_FAB2_LIB.BASEBOARD_FAB2(SCH_1):PAGE108
 R7E21    1      A RES_0402-4.75K,1%,1/16W,CHIP,GA   I343 @BASEBOARD_FAB2_LIB.BASEBOARD_FAB2(SCH_1):PAGE108
  Q9A1    3   C<0> NPN_DUAL_SSOPLF-MBT3904,EMPTY,A    I94 @BASEBOARD_FAB2_LIB.BASEBOARD_FAB2(SCH_1):PAGE111
  R9A1    1      A RES_0402-1.00K,1%,1/16W,EMPTY,A    I95 @BASEBOARD_FAB2_LIB.BASEBOARD_FAB2(SCH_1):PAGE111
  U9G1   14    VCC GTL2014_SM-IC,D66151-001     I1 @BASEBOARD_FAB2_LIB.BASEBOARD_FAB2(SCH_1):PAGE152
 C1U19    1      A CAP_0402-1.0UF,16V,10%,X6S,D97A    I18 @BASEBOARD_FAB2_LIB.BASEBOARD_FAB2(SCH_1):PAGE152
 R2N27    1      A RES_0402-4.75K,1%,1/16W,CHIP,GA    I97 @BASEBOARD_FAB2_LIB.BASEBOARD_FAB2(SCH_1):PAGE157
 R1U26    1      A RES_0402-5.11K,1%,1/16W,CHIP,GA   I148 @BASEBOARD_FAB2_LIB.BASEBOARD_FAB2(SCH_1):PAGE169
 R2L23    1      A RES_0402-2.0K,1%,1/16W,CHIP,G2A   I261 @BASEBOARD_FAB2_LIB.BASEBOARD_FAB2(SCH_1):PAGE173
 R2L21    1      A RES_0402-2.0K,1%,1/16W,CHIP,G2A   I263 @BASEBOARD_FAB2_LIB.BASEBOARD_FAB2(SCH_1):PAGE173
 R1M12    1      A RES_0402-10.0K,1%,1/16W,CHIP,GA     I8 @BASEBOARD_FAB2_LIB.BASEBOARD_FAB2(SCH_1):PAGE177
 R1M11    1      A RES_0402-10.0K,1%,1/16W,CHIP,GA     I9 @BASEBOARD_FAB2_LIB.BASEBOARD_FAB2(SCH_1):PAGE177
  C1M3    1      A CAP_A_0402V-1.0UF,6.3V,10%,X6SA    I20 @BASEBOARD_FAB2_LIB.BASEBOARD_FAB2(SCH_1):PAGE177
 R1L21    1      A RES_0402-64.9,1.0%,1/16W,CHIP,A    I43 @BASEBOARD_FAB2_LIB.BASEBOARD_FAB2(SCH_1):PAGE177
 R2P15    1      A RES_0402-10.0K,1%,1/16W,CHIP,GA   I111 @BASEBOARD_FAB2_LIB.BASEBOARD_FAB2(SCH_1):PAGE185
 C2T29    1      A CAP_A_0402V-0.1UF,16V,10%,X7R,A   I120 @BASEBOARD_FAB2_LIB.BASEBOARD_FAB2(SCH_1):PAGE185
 C2T26    1      A CAP_A_0402V-0.1UF,16V,10%,X7R,A   I123 @BASEBOARD_FAB2_LIB.BASEBOARD_FAB2(SCH_1):PAGE185
 C2T21    1      A CAP_A_0402V-0.1UF,16V,10%,X7R,A   I124 @BASEBOARD_FAB2_LIB.BASEBOARD_FAB2(SCH_1):PAGE185
 C2T16    1      A CAP_A_0402V-0.1UF,16V,10%,X7R,A   I126 @BASEBOARD_FAB2_LIB.BASEBOARD_FAB2(SCH_1):PAGE185
 C2T15    1      A CAP_A_0402V-0.1UF,16V,10%,X7R,A   I127 @BASEBOARD_FAB2_LIB.BASEBOARD_FAB2(SCH_1):PAGE185
 C2T24    1      A CAP_A_0402V-0.1UF,16V,10%,X7R,A   I129 @BASEBOARD_FAB2_LIB.BASEBOARD_FAB2(SCH_1):PAGE185
  C2T2    1      A CAP_A_0402V-0.1UF,16V,10%,X7R,A   I131 @BASEBOARD_FAB2_LIB.BASEBOARD_FAB2(SCH_1):PAGE185
  C2T4    1      A CAP_A_0402V-0.1UF,16V,10%,X7R,A   I132 @BASEBOARD_FAB2_LIB.BASEBOARD_FAB2(SCH_1):PAGE185
  C2T5    1      A CAP_A_0402V-0.1UF,16V,10%,X7R,A   I135 @BASEBOARD_FAB2_LIB.BASEBOARD_FAB2(SCH_1):PAGE185
 R8F36    1      A RES_0402-10.0K,1%,1/16W,CHIP,GA   I136 @BASEBOARD_FAB2_LIB.BASEBOARD_FAB2(SCH_1):PAGE185
 C1M24    1      A CAP_A_0402V-0.1UF,16V,10%,X7R,A    I10 @BASEBOARD_FAB2_LIB.BASEBOARD_FAB2(SCH_1):PAGE186
 C1M21    1      A CAP_A_0402V-1.0UF,6.3V,10%,X6SA   I334 @BASEBOARD_FAB2_LIB.BASEBOARD_FAB2(SCH_1):PAGE186
  J9B3   18   IO18 SCONN120_A28699018_SM-SCONN,A2A   I336 @BASEBOARD_FAB2_LIB.BASEBOARD_FAB2(SCH_1):PAGE186
  J9B3   19   IO19 SCONN120_A28699018_SM-SCONN,A2A   I336 @BASEBOARD_FAB2_LIB.BASEBOARD_FAB2(SCH_1):PAGE186
  J9B3   20   IO20 SCONN120_A28699018_SM-SCONN,A2A   I336 @BASEBOARD_FAB2_LIB.BASEBOARD_FAB2(SCH_1):PAGE186
  J9B3   21   IO21 SCONN120_A28699018_SM-SCONN,A2A   I336 @BASEBOARD_FAB2_LIB.BASEBOARD_FAB2(SCH_1):PAGE186
  J9B3   22   IO22 SCONN120_A28699018_SM-SCONN,A2A   I336 @BASEBOARD_FAB2_LIB.BASEBOARD_FAB2(SCH_1):PAGE186
  J9B3   23   IO23 SCONN120_A28699018_SM-SCONN,A2A   I336 @BASEBOARD_FAB2_LIB.BASEBOARD_FAB2(SCH_1):PAGE186
  J9B3   24   IO24 SCONN120_A28699018_SM-SCONN,A2A   I336 @BASEBOARD_FAB2_LIB.BASEBOARD_FAB2(SCH_1):PAGE186
  J9B3   25   IO25 SCONN120_A28699018_SM-SCONN,A2A   I336 @BASEBOARD_FAB2_LIB.BASEBOARD_FAB2(SCH_1):PAGE186
  J4B2   D1   IOD1 SCONN120_H61426002_SM-CONN,H61A    I46 @BASEBOARD_FAB2_LIB.BASEBOARD_FAB2(SCH_1):PAGE193
  J6B1   D1   IOD1 SCONN120_H61426002_SM-CONN,H61A    I56 @BASEBOARD_FAB2_LIB.BASEBOARD_FAB2(SCH_1):PAGE194
  U1L3    3    VCC ADM809_SMLF-IC,D23047-001-GND=A    I80 @BASEBOARD_FAB2_LIB.BASEBOARD_FAB2(SCH_1):PAGE196
 C1L16    1      A CAP_A_0402V-0.1UF,16V,10%,X7R,A    I81 @BASEBOARD_FAB2_LIB.BASEBOARD_FAB2(SCH_1):PAGE196
 EU2T1    6      S SLG55021_SM-IC,G56246-001     I1 @BASEBOARD_FAB2_LIB.BASEBOARD_FAB2(SCH_1):PAGE198
 C2U19    1      A CAP_A_0402V-0.1UF,16V,10%,X7R,A    I46 @BASEBOARD_FAB2_LIB.BASEBOARD_FAB2(SCH_1):PAGE198
  C2U2    1      A CAP_0805-10UF,16V,10%,X6S,C953A    I47 @BASEBOARD_FAB2_LIB.BASEBOARD_FAB2(SCH_1):PAGE198
  Q8G1    1    SRC MOSFET_N_LCC3-BSZ019N03LS,NFETA    I85 @BASEBOARD_FAB2_LIB.BASEBOARD_FAB2(SCH_1):PAGE198
 C14W1    1      A CAP_A_0402V-0.1UF,16V,10%,X7R,A    I13 @BASEBOARD_FAB2_LIB.BASEBOARD_FAB2(SCH_1):PAGE248
 C14W2    1      A CAP_A_0402V-0.1UF,16V,10%,X7R,A    I17 @BASEBOARD_FAB2_LIB.BASEBOARD_FAB2(SCH_1):PAGE248
R25W129    1      A RES_0402-4.75K,1%,1/16W,CHIP,GA   I152 @BASEBOARD_FAB2_LIB.BASEBOARD_FAB2(SCH_1):PAGE146
R25W130    1      A RES_0402-4.75K,1%,1/16W,CHIP,GA   I153 @BASEBOARD_FAB2_LIB.BASEBOARD_FAB2(SCH_1):PAGE146
R25W131    1      A RES_0402-4.75K,1%,1/16W,CHIP,GA    I30 @BASEBOARD_FAB2_LIB.BASEBOARD_FAB2(SCH_1):PAGE255
R25W134    1      A RES_0402-4.75K,1%,1/16W,CHIP,GA    I43 @BASEBOARD_FAB2_LIB.BASEBOARD_FAB2(SCH_1):PAGE255
  J8F1    2      2 SKT-MINI67P-41-GP_SOCKET-G4-SKA   I143 @BASEBOARD_FAB2_LIB.BASEBOARD_FAB2(SCH_1):PAGE185
  J8F1    4      4 SKT-MINI67P-41-GP_SOCKET-G4-SKA   I143 @BASEBOARD_FAB2_LIB.BASEBOARD_FAB2(SCH_1):PAGE185
  J8F1   12     12 SKT-MINI67P-41-GP_SOCKET-G4-SKA   I143 @BASEBOARD_FAB2_LIB.BASEBOARD_FAB2(SCH_1):PAGE185
  J8F1   14     14 SKT-MINI67P-41-GP_SOCKET-G4-SKA   I143 @BASEBOARD_FAB2_LIB.BASEBOARD_FAB2(SCH_1):PAGE185
  J8F1   16     16 SKT-MINI67P-41-GP_SOCKET-G4-SKA   I143 @BASEBOARD_FAB2_LIB.BASEBOARD_FAB2(SCH_1):PAGE185
  J8F1   18     18 SKT-MINI67P-41-GP_SOCKET-G4-SKA   I143 @BASEBOARD_FAB2_LIB.BASEBOARD_FAB2(SCH_1):PAGE185
  J8F1   70     70 SKT-MINI67P-41-GP_SOCKET-G4-SKA   I143 @BASEBOARD_FAB2_LIB.BASEBOARD_FAB2(SCH_1):PAGE185
  J8F1   72     72 SKT-MINI67P-41-GP_SOCKET-G4-SKA   I143 @BASEBOARD_FAB2_LIB.BASEBOARD_FAB2(SCH_1):PAGE185
  J8F1   74     74 SKT-MINI67P-41-GP_SOCKET-G4-SKA   I143 @BASEBOARD_FAB2_LIB.BASEBOARD_FAB2(SCH_1):PAGE185
 R6U15    1      A RES_0402-1.0M,1%,1/16W,EMPTY,GA     I5 @BASEBOARD_FAB2_LIB.BASEBOARD_FAB2(SCH_1):PAGE221
  R6U4    1      A RES_0402-0.0,5%,1/16W,CHIP,G21A    I14 @BASEBOARD_FAB2_LIB.BASEBOARD_FAB2(SCH_1):PAGE221
 R4G18    1      A RES_0402-10.0K,1%,1/16W,CHIP,GA    I25 @BASEBOARD_FAB2_LIB.BASEBOARD_FAB2(SCH_1):PAGE221
  R6L4    1      A RES_0402-1.0M,1%,1/16W,EMPTY,GA     I5 @BASEBOARD_FAB2_LIB.BASEBOARD_FAB2(SCH_1):PAGE222
 R6L11    1      A RES_0402-0.0,5%,1/16W,CHIP,G21A    I10 @BASEBOARD_FAB2_LIB.BASEBOARD_FAB2(SCH_1):PAGE222
  R6L9    1      A RES_0402-10.0K,1%,1/16W,CHIP,GA    I23 @BASEBOARD_FAB2_LIB.BASEBOARD_FAB2(SCH_1):PAGE222
  R6U3    1      A RES_0402-1.0M,1%,1/16W,EMPTY,GA     I5 @BASEBOARD_FAB2_LIB.BASEBOARD_FAB2(SCH_1):PAGE229
  R6U7    1      A RES_0402-0.0,5%,1/16W,CHIP,G21A     I9 @BASEBOARD_FAB2_LIB.BASEBOARD_FAB2(SCH_1):PAGE229
 R4G17    1      A RES_0402-10.0K,1%,1/16W,CHIP,GA    I24 @BASEBOARD_FAB2_LIB.BASEBOARD_FAB2(SCH_1):PAGE229
  R6L5    1      A RES_0402-1.0M,1%,1/16W,EMPTY,GA     I5 @BASEBOARD_FAB2_LIB.BASEBOARD_FAB2(SCH_1):PAGE230
  R6L8    1      A RES_0402-0.0,5%,1/16W,CHIP,G21A    I13 @BASEBOARD_FAB2_LIB.BASEBOARD_FAB2(SCH_1):PAGE230
  R4A5    1      A RES_0402-10.0K,1%,1/16W,CHIP,GA    I21 @BASEBOARD_FAB2_LIB.BASEBOARD_FAB2(SCH_1):PAGE230
 R3P45    1      1 374R2F-1-GP_SMD-RG-374R2F-1-GPA   I110 @BASEBOARD_FAB2_LIB.BASEBOARD_FAB2(SCH_1):PAGE92
 R7D33    1      1 374R2F-1-GP_SMD-RG-374R2F-1-GPA   I111 @BASEBOARD_FAB2_LIB.BASEBOARD_FAB2(SCH_1):PAGE92
 R2T36    1      1 374R2F-1-GP_SMD-RG-374R2F-1-GPA   I148 @BASEBOARD_FAB2_LIB.BASEBOARD_FAB2(SCH_1):PAGE93
 R1U43    1      1 374R2F-1-GP_SMD-RG-374R2F-1-GPA   I106 @BASEBOARD_FAB2_LIB.BASEBOARD_FAB2(SCH_1):PAGE152
 R32W1    1      A RES_0402-4.02K,1%,1/16W,CHIP,GA   I208 @BASEBOARD_FAB2_LIB.BASEBOARD_FAB2(SCH_1):PAGE185
 R6P48    1      A RES_0402-1.00K,1%,1/16W,CHIP,GA   I115 @BASEBOARD_FAB2_LIB.BASEBOARD_FAB2(SCH_1):PAGE102

P3V3_DB1200 @BASEBOARD_FAB2_LIB.BASEBOARD_FAB2(SCH_1):P3V3_DB1200
 EU4D2   24 VDD<0> NB3W1200L_LCC-IC,H13585-001     I1 @BASEBOARD_FAB2_LIB.BASEBOARD_FAB2(SCH_1):PAGE102
 EU4D2   40 VDD<1> NB3W1200L_LCC-IC,H13585-001     I1 @BASEBOARD_FAB2_LIB.BASEBOARD_FAB2(SCH_1):PAGE102
 EU4D2   57 VDD<2> NB3W1200L_LCC-IC,H13585-001     I1 @BASEBOARD_FAB2_LIB.BASEBOARD_FAB2(SCH_1):PAGE102
 EU4D2   25 VDDIO<0> NB3W1200L_LCC-IC,H13585-001     I1 @BASEBOARD_FAB2_LIB.BASEBOARD_FAB2(SCH_1):PAGE102
 EU4D2   32 VDDIO<1> NB3W1200L_LCC-IC,H13585-001     I1 @BASEBOARD_FAB2_LIB.BASEBOARD_FAB2(SCH_1):PAGE102
 EU4D2   49 VDDIO<2> NB3W1200L_LCC-IC,H13585-001     I1 @BASEBOARD_FAB2_LIB.BASEBOARD_FAB2(SCH_1):PAGE102
 EU4D2   56 VDDIO<3> NB3W1200L_LCC-IC,H13585-001     I1 @BASEBOARD_FAB2_LIB.BASEBOARD_FAB2(SCH_1):PAGE102
 FB6P1    2      B FERRITE_SMLF-600,FB,656554-043     I8 @BASEBOARD_FAB2_LIB.BASEBOARD_FAB2(SCH_1):PAGE102
 C3D22    1      A CAP_0805-10UF,16V,10%,X7R,G106A    I10 @BASEBOARD_FAB2_LIB.BASEBOARD_FAB2(SCH_1):PAGE102
  C6P4    1      A CAP_A_0402V-0.1UF,16V,10%,X7R,A    I11 @BASEBOARD_FAB2_LIB.BASEBOARD_FAB2(SCH_1):PAGE102
  C6P6    1      A CAP_A_0402V-0.1UF,16V,10%,X7R,A    I12 @BASEBOARD_FAB2_LIB.BASEBOARD_FAB2(SCH_1):PAGE102
 C6P10    1      A CAP_A_0402V-0.1UF,16V,10%,X7R,A    I13 @BASEBOARD_FAB2_LIB.BASEBOARD_FAB2(SCH_1):PAGE102
  C6P5    1      A CAP_A_0402V-0.1UF,16V,10%,X7R,A    I14 @BASEBOARD_FAB2_LIB.BASEBOARD_FAB2(SCH_1):PAGE102
 C6P12    1      A CAP_A_0402V-0.1UF,16V,10%,X7R,A    I15 @BASEBOARD_FAB2_LIB.BASEBOARD_FAB2(SCH_1):PAGE102
 C6P11    1      A CAP_A_0402V-0.1UF,16V,10%,X7R,A    I16 @BASEBOARD_FAB2_LIB.BASEBOARD_FAB2(SCH_1):PAGE102
 R3D14    1      A RES_0603-2.2,1.0%,1/10W,CHIP,GA    I21 @BASEBOARD_FAB2_LIB.BASEBOARD_FAB2(SCH_1):PAGE102
 R6P25    1      A RES_0603-2.2,1.0%,1/10W,CHIP,GA    I26 @BASEBOARD_FAB2_LIB.BASEBOARD_FAB2(SCH_1):PAGE102
 R4D38    1      A RES_0402-10.0K,1%,1/16W,EMPTY,A    I37 @BASEBOARD_FAB2_LIB.BASEBOARD_FAB2(SCH_1):PAGE102
 R4D35    1      A RES_0402-10.0K,1%,1/16W,EMPTY,A    I38 @BASEBOARD_FAB2_LIB.BASEBOARD_FAB2(SCH_1):PAGE102
 R4D40    1      A RES_0402-4.75K,1%,1/16W,CHIP,GA    I45 @BASEBOARD_FAB2_LIB.BASEBOARD_FAB2(SCH_1):PAGE102
 R4D41    1      A RES_0402-4.75K,1%,1/16W,CHIP,GA    I53 @BASEBOARD_FAB2_LIB.BASEBOARD_FAB2(SCH_1):PAGE102
  C6P9    1      A CAP_A_0402V-0.1UF,16V,10%,X7R,A    I79 @BASEBOARD_FAB2_LIB.BASEBOARD_FAB2(SCH_1):PAGE102
  R4W2    1      A RES_0402-1.00K,1%,1/16W,CHIP,GA   I103 @BASEBOARD_FAB2_LIB.BASEBOARD_FAB2(SCH_1):PAGE102
  R4W3    1      A RES_0402-3.3K,5%,1/16W,CHIP,G2A   I105 @BASEBOARD_FAB2_LIB.BASEBOARD_FAB2(SCH_1):PAGE102
  R4W4    1      A RES_0402-3.3K,5%,1/16W,CHIP,G2A   I106 @BASEBOARD_FAB2_LIB.BASEBOARD_FAB2(SCH_1):PAGE102
  R4W6    1      A RES_0402-4.75K,1%,1/16W,CHIP,GA   I109 @BASEBOARD_FAB2_LIB.BASEBOARD_FAB2(SCH_1):PAGE102

P3V3_DB1200_A @BASEBOARD_FAB2_LIB.BASEBOARD_FAB2(SCH_1):P3V3_DB1200_A
 EU4D2    1   VDDA NB3W1200L_LCC-IC,H13585-001     I1 @BASEBOARD_FAB2_LIB.BASEBOARD_FAB2(SCH_1):PAGE102
 C4D24    1      A CAP_A_0402V-0.1UF,16V,10%,X7R,A    I18 @BASEBOARD_FAB2_LIB.BASEBOARD_FAB2(SCH_1):PAGE102
 C4D23    1      A CAP_A_0402V-1.0UF,6.3V,10%,X6SA    I19 @BASEBOARD_FAB2_LIB.BASEBOARD_FAB2(SCH_1):PAGE102
 R3D14    2      B RES_0603-2.2,1.0%,1/10W,CHIP,GA    I21 @BASEBOARD_FAB2_LIB.BASEBOARD_FAB2(SCH_1):PAGE102

P3V3_DB1200_R @BASEBOARD_FAB2_LIB.BASEBOARD_FAB2(SCH_1):P3V3_DB1200_R
 EU4D2    8   VDDR NB3W1200L_LCC-IC,H13585-001     I1 @BASEBOARD_FAB2_LIB.BASEBOARD_FAB2(SCH_1):PAGE102
 R6P25    2      B RES_0603-2.2,1.0%,1/10W,CHIP,GA    I26 @BASEBOARD_FAB2_LIB.BASEBOARD_FAB2(SCH_1):PAGE102
 C4D22    1      A CAP_A_0402V-0.1UF,16V,10%,X7R,A    I28 @BASEBOARD_FAB2_LIB.BASEBOARD_FAB2(SCH_1):PAGE102
 C4D27    1      A CAP_A_0402V-1.0UF,6.3V,10%,X6SA    I30 @BASEBOARD_FAB2_LIB.BASEBOARD_FAB2(SCH_1):PAGE102

P3V3_DB1200_R1 @BASEBOARD_FAB2_LIB.BASEBOARD_FAB2(SCH_1):P3V3_DB1200_R1
  Q4W1    5 GATE<0> FET_N_DUAL_SMLF-2N7002DW,FET,DA   I101 @BASEBOARD_FAB2_LIB.BASEBOARD_FAB2(SCH_1):PAGE102
  Q4W1    2 GATE<0> FET_N_DUAL_SMLF-2N7002DW,FET,DA   I102 @BASEBOARD_FAB2_LIB.BASEBOARD_FAB2(SCH_1):PAGE102
  R4W2    2      B RES_0402-1.00K,1%,1/16W,CHIP,GA   I103 @BASEBOARD_FAB2_LIB.BASEBOARD_FAB2(SCH_1):PAGE102

P3V3_RTC_STBY @BASEBOARD_FAB2_LIB.BASEBOARD_FAB2(SCH_1):P3V3_RTC_STBY
  U7C1 AJ27 VCCPRTC LBG_CORE_QAT_EXT_D_BGA1-IC,H91A    I63 @BASEBOARD_FAB2_LIB.BASEBOARD_FAB2(SCH_1):PAGE122
 R7C10    1      A RES_0402-20.0K,1%,1/16W,CHIP,GA    I13 @BASEBOARD_FAB2_LIB.BASEBOARD_FAB2(SCH_1):PAGE137
  R3N4    1      A RES_0402-20.0K,1%,1/16W,CHIP,GA    I19 @BASEBOARD_FAB2_LIB.BASEBOARD_FAB2(SCH_1):PAGE137
 CR2U1    3      C DIODE2A_DUAL_SMLF-BAS70-05,DIOA    I53 @BASEBOARD_FAB2_LIB.BASEBOARD_FAB2(SCH_1):PAGE196
 C2U26    1      A CAP_A_0402V-1.0UF,6.3V,10%,X6SA   I102 @BASEBOARD_FAB2_LIB.BASEBOARD_FAB2(SCH_1):PAGE196

P3V3_STBY @BASEBOARD_FAB2_LIB.BASEBOARD_FAB2(SCH_1):P3V3_STBY
  R5N2    1      A RES_0402-1.8K,1%,1/16W,CHIP,G2A   I227 @BASEBOARD_FAB2_LIB.BASEBOARD_FAB2(SCH_1):PAGE21
  R5N1    1      A RES_0402-10.0K,1%,1/16W,CHIP,GA   I238 @BASEBOARD_FAB2_LIB.BASEBOARD_FAB2(SCH_1):PAGE21
  R5N5    1      A RES_0402-10.0K,1%,1/16W,CHIP,GA   I239 @BASEBOARD_FAB2_LIB.BASEBOARD_FAB2(SCH_1):PAGE21
  R5N3    1      A RES_0402-10.0K,1%,1/16W,CHIP,GA   I240 @BASEBOARD_FAB2_LIB.BASEBOARD_FAB2(SCH_1):PAGE21
  R5N4    1      A RES_0402-1.8K,1%,1/16W,CHIP,G2A   I241 @BASEBOARD_FAB2_LIB.BASEBOARD_FAB2(SCH_1):PAGE21
  R4R5    1      A RES_0402-4.75K,1%,1/16W,CHIP,GA   I258 @BASEBOARD_FAB2_LIB.BASEBOARD_FAB2(SCH_1):PAGE21
  U5D1 CY55  VCC33 SKX_EXT_B_BGA1-IC,TBD    I34 @BASEBOARD_FAB2_LIB.BASEBOARD_FAB2(SCH_1):PAGE38
  R8N1    1      A RES_0402-1.8K,1%,1/16W,CHIP,G2A   I157 @BASEBOARD_FAB2_LIB.BASEBOARD_FAB2(SCH_1):PAGE55
  R8N4    1      A RES_0402-1.8K,1%,1/16W,CHIP,G2A   I158 @BASEBOARD_FAB2_LIB.BASEBOARD_FAB2(SCH_1):PAGE55
  R8N3    1      A RES_0402-10.0K,1%,1/16W,CHIP,GA   I159 @BASEBOARD_FAB2_LIB.BASEBOARD_FAB2(SCH_1):PAGE55
  R8N5    1      A RES_0402-10.0K,1%,1/16W,CHIP,GA   I160 @BASEBOARD_FAB2_LIB.BASEBOARD_FAB2(SCH_1):PAGE55
  R8N2    1      A RES_0402-10.0K,1%,1/16W,CHIP,GA   I161 @BASEBOARD_FAB2_LIB.BASEBOARD_FAB2(SCH_1):PAGE55
 R6P39    1      A RES_0402-4.75K,1%,1/16W,CHIP,GA   I181 @BASEBOARD_FAB2_LIB.BASEBOARD_FAB2(SCH_1):PAGE55
  U2D1 CY55  VCC33 SKX_EXT_B_BGA1-IC,TBD    I33 @BASEBOARD_FAB2_LIB.BASEBOARD_FAB2(SCH_1):PAGE72
 R8D29    1      A RES_0402-4.75K,1%,1/16W,CHIP,GA    I26 @BASEBOARD_FAB2_LIB.BASEBOARD_FAB2(SCH_1):PAGE89
 R8D31    1      A RES_0402-4.75K,1%,1/16W,CHIP,GA    I27 @BASEBOARD_FAB2_LIB.BASEBOARD_FAB2(SCH_1):PAGE89
  R4U1    1      A RES_0402-4.75K,1%,1/16W,CHIP,GA    I91 @BASEBOARD_FAB2_LIB.BASEBOARD_FAB2(SCH_1):PAGE94
  C7E3    1      A CAP_A_0402V-0.1UF,16V,10%,X7R,A    I92 @BASEBOARD_FAB2_LIB.BASEBOARD_FAB2(SCH_1):PAGE95
  C7E4    1      A CAP_A_0402V-0.1UF,16V,10%,X7R,A   I115 @BASEBOARD_FAB2_LIB.BASEBOARD_FAB2(SCH_1):PAGE95
 R3P36    1      A RES_0402-1.00K,1%,1/16W,CHIP,GA    I36 @BASEBOARD_FAB2_LIB.BASEBOARD_FAB2(SCH_1):PAGE96
  U3P1   14    VCC GTL2014_SM-IC,D66151-001    I42 @BASEBOARD_FAB2_LIB.BASEBOARD_FAB2(SCH_1):PAGE96
  U4C2   14    VCC GTL2014_SM-IC,D66151-001    I46 @BASEBOARD_FAB2_LIB.BASEBOARD_FAB2(SCH_1):PAGE96
  R4C8    1      A RES_0402-1.00K,1%,1/16W,CHIP,GA    I55 @BASEBOARD_FAB2_LIB.BASEBOARD_FAB2(SCH_1):PAGE96
 C3P42    1      A CAP_A_0402V-1.0UF,6.3V,10%,X6SA    I73 @BASEBOARD_FAB2_LIB.BASEBOARD_FAB2(SCH_1):PAGE96
  C4C3    1      A CAP_A_0402V-1.0UF,6.3V,10%,X6SA    I75 @BASEBOARD_FAB2_LIB.BASEBOARD_FAB2(SCH_1):PAGE96
 FB2T2    1      A FERRITE_SMLF-600,FB,656554-043   I114 @BASEBOARD_FAB2_LIB.BASEBOARD_FAB2(SCH_1):PAGE101
 C2T28    1      A CAP_A_0402V-1.0UF,6.3V,10%,X6SA   I116 @BASEBOARD_FAB2_LIB.BASEBOARD_FAB2(SCH_1):PAGE101
  J8G1   25   IO25 SCONN200_H68296001_SM-CONN,H68A   I258 @BASEBOARD_FAB2_LIB.BASEBOARD_FAB2(SCH_1):PAGE108
 C2U23    1      A CAP_A_0402V-0.1UF,16V,10%,X7R,A   I315 @BASEBOARD_FAB2_LIB.BASEBOARD_FAB2(SCH_1):PAGE108
 C2U22    1      A CAP_A_0402V-0.1UF,16V,10%,X7R,A   I318 @BASEBOARD_FAB2_LIB.BASEBOARD_FAB2(SCH_1):PAGE108
 R1L13    2      B RES_0402-1.00K,1%,1/16W,CHIP,GA     I6 @BASEBOARD_FAB2_LIB.BASEBOARD_FAB2(SCH_1):PAGE111
 R9A14    2      B RES_0402-1.00K,1%,1/16W,CHIP,GA    I11 @BASEBOARD_FAB2_LIB.BASEBOARD_FAB2(SCH_1):PAGE111
 R1L23    2      B RES_0402-1.00K,1%,1/16W,CHIP,GA    I13 @BASEBOARD_FAB2_LIB.BASEBOARD_FAB2(SCH_1):PAGE111
 C1L11    1      A CAP_A_0402V-0.1UF,16V,10%,X7R,A    I87 @BASEBOARD_FAB2_LIB.BASEBOARD_FAB2(SCH_1):PAGE111
  U1M7    5    VCC NC7SB3157_SMLF-IC,C99406-001    I40 @BASEBOARD_FAB2_LIB.BASEBOARD_FAB2(SCH_1):PAGE112
 C1M36    1      A CAP_A_0402V-0.01UF,25V,10%,X7RA    I42 @BASEBOARD_FAB2_LIB.BASEBOARD_FAB2(SCH_1):PAGE112
 C1M37    1      A CAP_A_0402V-1.0UF,6.3V,10%,X6SA    I47 @BASEBOARD_FAB2_LIB.BASEBOARD_FAB2(SCH_1):PAGE112
 C1M30    1      A CAP_A_0402V-0.01UF,25V,10%,X7RA   I131 @BASEBOARD_FAB2_LIB.BASEBOARD_FAB2(SCH_1):PAGE112
  C1L1    1      A CAP_0402-1.0UF,16V,10%,X6S,D97A   I136 @BASEBOARD_FAB2_LIB.BASEBOARD_FAB2(SCH_1):PAGE112
 C1L19    1      A CAP_0402-1.0UF,16V,10%,X6S,D97A   I140 @BASEBOARD_FAB2_LIB.BASEBOARD_FAB2(SCH_1):PAGE112
  U1M2    5    VCC NC7SB3157_SMLF-IC,C99406-001   I107 @BASEBOARD_FAB2_LIB.BASEBOARD_FAB2(SCH_1):PAGE113
 C1M31    1      A CAP_A_0402V-0.01UF,25V,10%,X7RA   I116 @BASEBOARD_FAB2_LIB.BASEBOARD_FAB2(SCH_1):PAGE113
 C1M32    1      A CAP_A_0402V-1.0UF,6.3V,10%,X6SA   I117 @BASEBOARD_FAB2_LIB.BASEBOARD_FAB2(SCH_1):PAGE113
 C1M28    1      A CAP_A_0402V-0.01UF,25V,10%,X7RA   I119 @BASEBOARD_FAB2_LIB.BASEBOARD_FAB2(SCH_1):PAGE113
  U2M1    5    VCC NC7SB3157_SMLF-IC,C99406-001   I255 @BASEBOARD_FAB2_LIB.BASEBOARD_FAB2(SCH_1):PAGE113
 C1M34    1      A CAP_A_0402V-0.01UF,25V,10%,X7RA   I265 @BASEBOARD_FAB2_LIB.BASEBOARD_FAB2(SCH_1):PAGE113
 C1M35    1      A CAP_A_0402V-0.01UF,25V,10%,X7RA   I266 @BASEBOARD_FAB2_LIB.BASEBOARD_FAB2(SCH_1):PAGE113
 C1L20    1      A CAP_A_0402V-0.01UF,25V,10%,X7RA   I267 @BASEBOARD_FAB2_LIB.BASEBOARD_FAB2(SCH_1):PAGE113
 R3N13    1      A RES_0402-4.75K,1%,1/16W,CHIP,GA    I71 @BASEBOARD_FAB2_LIB.BASEBOARD_FAB2(SCH_1):PAGE118
  R2N6    1      A RES_0402-10.0K,1%,1/16W,CHIP,GA   I128 @BASEBOARD_FAB2_LIB.BASEBOARD_FAB2(SCH_1):PAGE118
  C7D1    1      A CAP_A_0402V-0.1UF,16V,10%,X7R,A   I136 @BASEBOARD_FAB2_LIB.BASEBOARD_FAB2(SCH_1):PAGE118
 R7C23    1      A RES_0402-10.0K,1%,1/16W,CHIP,GA   I144 @BASEBOARD_FAB2_LIB.BASEBOARD_FAB2(SCH_1):PAGE118
 R9A20    2      B RES_0402-221,1.0%,1/16W,CHIP,GA   I178 @BASEBOARD_FAB2_LIB.BASEBOARD_FAB2(SCH_1):PAGE119
 R9A18    1      A RES_0402-4.75K,1%,1/16W,CHIP,GA   I183 @BASEBOARD_FAB2_LIB.BASEBOARD_FAB2(SCH_1):PAGE119
 R9A21    1      A RES_0402-4.75K,1%,1/16W,CHIP,GA   I186 @BASEBOARD_FAB2_LIB.BASEBOARD_FAB2(SCH_1):PAGE119
 R2U48    1      A RES_0402-4.75K,1%,1/16W,CHIP,GA   I213 @BASEBOARD_FAB2_LIB.BASEBOARD_FAB2(SCH_1):PAGE119
 R3N10    1      A RES_0402-10.0K,1%,1/16W,CHIP,GA    I37 @BASEBOARD_FAB2_LIB.BASEBOARD_FAB2(SCH_1):PAGE121
  U7C1 BA46 VCCP_3P3<0> LBG_CORE_QAT_EXT_D_BGA1-IC,H91A    I63 @BASEBOARD_FAB2_LIB.BASEBOARD_FAB2(SCH_1):PAGE122
  U7C1 BA45 VCCP_3P3<1> LBG_CORE_QAT_EXT_D_BGA1-IC,H91A    I63 @BASEBOARD_FAB2_LIB.BASEBOARD_FAB2(SCH_1):PAGE122
  U7C1 AD24 VCCP_3P3<2> LBG_CORE_QAT_EXT_D_BGA1-IC,H91A    I63 @BASEBOARD_FAB2_LIB.BASEBOARD_FAB2(SCH_1):PAGE122
  U7C1 AN24 VCCP_3P3<5> LBG_CORE_QAT_EXT_D_BGA1-IC,H91A    I63 @BASEBOARD_FAB2_LIB.BASEBOARD_FAB2(SCH_1):PAGE122
  U7C1 AH24 VCCPDSW_3P3 LBG_CORE_QAT_EXT_D_BGA1-IC,H91A    I63 @BASEBOARD_FAB2_LIB.BASEBOARD_FAB2(SCH_1):PAGE122
  U7C1 AW24 VCCPGPPA LBG_CORE_QAT_EXT_D_BGA1-IC,H91A    I63 @BASEBOARD_FAB2_LIB.BASEBOARD_FAB2(SCH_1):PAGE122
  U7C1 BE26 VCCPGPPB LBG_CORE_QAT_EXT_D_BGA1-IC,H91A    I63 @BASEBOARD_FAB2_LIB.BASEBOARD_FAB2(SCH_1):PAGE122
  U7C1 BE40 VCCPGPPC LBG_CORE_QAT_EXT_D_BGA1-IC,H91A    I63 @BASEBOARD_FAB2_LIB.BASEBOARD_FAB2(SCH_1):PAGE122
  U7C1 BA43 VCCPGPPD LBG_CORE_QAT_EXT_D_BGA1-IC,H91A    I63 @BASEBOARD_FAB2_LIB.BASEBOARD_FAB2(SCH_1):PAGE122
  U7C1 BE44 VCCPGPPE LBG_CORE_QAT_EXT_D_BGA1-IC,H91A    I63 @BASEBOARD_FAB2_LIB.BASEBOARD_FAB2(SCH_1):PAGE122
  U7C1 AU27 VCCPGPPF LBG_CORE_QAT_EXT_D_BGA1-IC,H91A    I63 @BASEBOARD_FAB2_LIB.BASEBOARD_FAB2(SCH_1):PAGE122
  U7C1 BA26 VCCPGPPG LBG_CORE_QAT_EXT_D_BGA1-IC,H91A    I63 @BASEBOARD_FAB2_LIB.BASEBOARD_FAB2(SCH_1):PAGE122
  U7C1 BA24 VCCPGPPH LBG_CORE_QAT_EXT_D_BGA1-IC,H91A    I63 @BASEBOARD_FAB2_LIB.BASEBOARD_FAB2(SCH_1):PAGE122
  U7C1 BB26 VCCPGPPJ LBG_CORE_QAT_EXT_D_BGA1-IC,H91A    I63 @BASEBOARD_FAB2_LIB.BASEBOARD_FAB2(SCH_1):PAGE122
  U7C1 AU24 VCCPGPPK LBG_CORE_QAT_EXT_D_BGA1-IC,H91A    I63 @BASEBOARD_FAB2_LIB.BASEBOARD_FAB2(SCH_1):PAGE122
  U7C1 AG29 VCCPRTCPRIM_3P3 LBG_CORE_QAT_EXT_D_BGA1-IC,H91A    I63 @BASEBOARD_FAB2_LIB.BASEBOARD_FAB2(SCH_1):PAGE122
  U7C1 AR24 VCCPSPI LBG_CORE_QAT_EXT_D_BGA1-IC,H91A    I63 @BASEBOARD_FAB2_LIB.BASEBOARD_FAB2(SCH_1):PAGE122
  U7C1 BA48 VCCPUSBDSW_3P3 LBG_CORE_QAT_EXT_D_BGA1-IC,H91A    I63 @BASEBOARD_FAB2_LIB.BASEBOARD_FAB2(SCH_1):PAGE122
  R8E6    1      A RES_0402-1.00K,1%,1/16W,EMPTY,A    I21 @BASEBOARD_FAB2_LIB.BASEBOARD_FAB2(SCH_1):PAGE125
 R8C18    1      A RES_0402-1.00K,1%,1/16W,CHIP,GA    I40 @BASEBOARD_FAB2_LIB.BASEBOARD_FAB2(SCH_1):PAGE125
 R7D13    1      A RES_0402-8.2K,1%,1/16W,EMPTY,GA    I60 @BASEBOARD_FAB2_LIB.BASEBOARD_FAB2(SCH_1):PAGE125
  R3N2    1      A RES_0402-4.75K,1%,1/16W,EMPTY,A    I72 @BASEBOARD_FAB2_LIB.BASEBOARD_FAB2(SCH_1):PAGE125
 R3N17    1      A RES_0402-1.00K,1%,1/16W,EMPTY,A    I78 @BASEBOARD_FAB2_LIB.BASEBOARD_FAB2(SCH_1):PAGE125
 R2N14    1      A RES_0402-1.00K,1%,1/16W,EMPTY,A    I83 @BASEBOARD_FAB2_LIB.BASEBOARD_FAB2(SCH_1):PAGE125
 R1D35    1      A RES_0402-4.75K,1%,1/16W,CHIP,GA    I12 @BASEBOARD_FAB2_LIB.BASEBOARD_FAB2(SCH_1):PAGE126
  R8C9    1      A RES_0402-4.75K,1%,1/16W,CHIP,GA    I20 @BASEBOARD_FAB2_LIB.BASEBOARD_FAB2(SCH_1):PAGE126
 R3P62    1      A RES_0402-4.75K,1%,1/16W,EMPTY,A    I22 @BASEBOARD_FAB2_LIB.BASEBOARD_FAB2(SCH_1):PAGE126
  C7D2    1      A CAP_0603-10UF,6.3V,20%,X6S,E15A     I2 @BASEBOARD_FAB2_LIB.BASEBOARD_FAB2(SCH_1):PAGE130
 C2N26    1      A CAP_A_0402V-1.0UF,6.3V,10%,X6SA     I4 @BASEBOARD_FAB2_LIB.BASEBOARD_FAB2(SCH_1):PAGE130
 C2N19    1      A CAP_A_0402V-1.0UF,6.3V,10%,X6SA     I7 @BASEBOARD_FAB2_LIB.BASEBOARD_FAB2(SCH_1):PAGE130
 C2N24    1      A CAP_0603-10UF,6.3V,20%,X6S,E15A     I8 @BASEBOARD_FAB2_LIB.BASEBOARD_FAB2(SCH_1):PAGE130
 C2N22    1      A CAP_0603-10UF,6.3V,20%,X6S,E15A     I9 @BASEBOARD_FAB2_LIB.BASEBOARD_FAB2(SCH_1):PAGE130
 C2N20    1      A CAP_A_0402V-1.0UF,6.3V,10%,X6SA    I12 @BASEBOARD_FAB2_LIB.BASEBOARD_FAB2(SCH_1):PAGE130
 C2N21    1      A CAP_0603-10UF,6.3V,20%,X6S,E15A    I15 @BASEBOARD_FAB2_LIB.BASEBOARD_FAB2(SCH_1):PAGE130
  C8C3    1      A CAP_0603-10UF,6.3V,20%,X6S,E15A    I19 @BASEBOARD_FAB2_LIB.BASEBOARD_FAB2(SCH_1):PAGE130
  C8C4    1      A CAP_0603-10UF,6.3V,20%,X6S,E15A    I20 @BASEBOARD_FAB2_LIB.BASEBOARD_FAB2(SCH_1):PAGE130
  C8C5    1      A CAP_0603-10UF,6.3V,20%,X6S,E15A    I21 @BASEBOARD_FAB2_LIB.BASEBOARD_FAB2(SCH_1):PAGE130
  C8C6    1      A CAP_0603-10UF,6.3V,20%,X6S,E15A    I22 @BASEBOARD_FAB2_LIB.BASEBOARD_FAB2(SCH_1):PAGE130
 C2N23    1      A CAP_0603-10UF,6.3V,20%,X6S,E15A    I24 @BASEBOARD_FAB2_LIB.BASEBOARD_FAB2(SCH_1):PAGE130
 C2N14    1      A CAP_0603-10UF,6.3V,20%,X6S,E15A    I25 @BASEBOARD_FAB2_LIB.BASEBOARD_FAB2(SCH_1):PAGE130
 C2N17    1      A CAP_0603-10UF,6.3V,20%,X6S,E15A    I28 @BASEBOARD_FAB2_LIB.BASEBOARD_FAB2(SCH_1):PAGE130
 C2N18    1      A CAP_A_0402V-1.0UF,6.3V,10%,X6SA    I29 @BASEBOARD_FAB2_LIB.BASEBOARD_FAB2(SCH_1):PAGE130
 C2N25    1      A CAP_A_0402V-1.0UF,6.3V,10%,X6SA    I34 @BASEBOARD_FAB2_LIB.BASEBOARD_FAB2(SCH_1):PAGE130
 C2M16    1      A CAP_A_0402V-1.0UF,6.3V,10%,X6SA    I37 @BASEBOARD_FAB2_LIB.BASEBOARD_FAB2(SCH_1):PAGE130
 C3N23    1      A CAP_A_0402V-1.0UF,6.3V,10%,X6SA    I42 @BASEBOARD_FAB2_LIB.BASEBOARD_FAB2(SCH_1):PAGE130
  R7D8    1      A RES_0402-10.0K,1%,1/16W,CHIP,GA   I200 @BASEBOARD_FAB2_LIB.BASEBOARD_FAB2(SCH_1):PAGE133
 R7D10    1      A RES_0402-10.0K,1%,1/16W,CHIP,GA   I202 @BASEBOARD_FAB2_LIB.BASEBOARD_FAB2(SCH_1):PAGE133
 R7D12    1      A RES_0402-10.0K,1%,1/16W,CHIP,GA   I237 @BASEBOARD_FAB2_LIB.BASEBOARD_FAB2(SCH_1):PAGE133
  R7D3    1      A RES_0402-4.75K,1%,1/16W,CHIP,GA   I243 @BASEBOARD_FAB2_LIB.BASEBOARD_FAB2(SCH_1):PAGE133
  R7D4    1      A RES_0402-10.0K,1%,1/16W,CHIP,GA   I245 @BASEBOARD_FAB2_LIB.BASEBOARD_FAB2(SCH_1):PAGE133
 R2N16    1      A RES_0402-10.0K,1%,1/16W,CHIP,GA   I247 @BASEBOARD_FAB2_LIB.BASEBOARD_FAB2(SCH_1):PAGE133
  R2R5    1      A RES_0402-1.00K,1%,1/16W,CHIP,GA   I258 @BASEBOARD_FAB2_LIB.BASEBOARD_FAB2(SCH_1):PAGE133
  R2N9    1      A RES_0402-10.0K,1%,1/16W,CHIP,GA   I267 @BASEBOARD_FAB2_LIB.BASEBOARD_FAB2(SCH_1):PAGE133
 R8B23    1      A RES_0402-1.00K,1%,1/16W,CHIP,GA   I280 @BASEBOARD_FAB2_LIB.BASEBOARD_FAB2(SCH_1):PAGE133
 R8B30    1      A RES_0402-1.00K,1%,1/16W,CHIP,GA   I282 @BASEBOARD_FAB2_LIB.BASEBOARD_FAB2(SCH_1):PAGE133
  R2M4    1      A RES_0402-1.00K,1%,1/16W,CHIP,GA   I284 @BASEBOARD_FAB2_LIB.BASEBOARD_FAB2(SCH_1):PAGE133
  R8C4    1      A RES_0402-1.00K,1%,1/16W,CHIP,GA   I286 @BASEBOARD_FAB2_LIB.BASEBOARD_FAB2(SCH_1):PAGE133
  R7B6    1      A RES_0402-10.0K,1%,1/16W,CHIP,GA   I295 @BASEBOARD_FAB2_LIB.BASEBOARD_FAB2(SCH_1):PAGE133
  R7C8    1      A RES_0402-10.0K,1%,1/16W,CHIP,GA   I296 @BASEBOARD_FAB2_LIB.BASEBOARD_FAB2(SCH_1):PAGE133
  R7C5    1      A RES_0402-10.0K,1%,1/16W,CHIP,GA   I297 @BASEBOARD_FAB2_LIB.BASEBOARD_FAB2(SCH_1):PAGE133
 R8D14    1      A RES_0402-4.75K,1%,1/16W,CHIP,GA   I301 @BASEBOARD_FAB2_LIB.BASEBOARD_FAB2(SCH_1):PAGE133
  R8C6    1      A RES_0402-4.75K,1%,1/16W,CHIP,GA   I303 @BASEBOARD_FAB2_LIB.BASEBOARD_FAB2(SCH_1):PAGE133
  R8C2    1      A RES_0402-4.75K,1%,1/16W,CHIP,GA   I304 @BASEBOARD_FAB2_LIB.BASEBOARD_FAB2(SCH_1):PAGE133
  R7D6    1      A RES_0402-4.75K,1%,1/16W,CHIP,GA   I306 @BASEBOARD_FAB2_LIB.BASEBOARD_FAB2(SCH_1):PAGE133
 R8B31    1      A RES_0402-4.75K,1%,1/16W,CHIP,GA   I307 @BASEBOARD_FAB2_LIB.BASEBOARD_FAB2(SCH_1):PAGE133
  R2N7    1      A RES_0402-4.75K,1%,1/16W,CHIP,GA   I309 @BASEBOARD_FAB2_LIB.BASEBOARD_FAB2(SCH_1):PAGE133
  R8C1    1      A RES_0402-4.75K,1%,1/16W,CHIP,GA   I326 @BASEBOARD_FAB2_LIB.BASEBOARD_FAB2(SCH_1):PAGE133
  R8C7    1      A RES_0402-4.75K,1%,1/16W,CHIP,GA   I327 @BASEBOARD_FAB2_LIB.BASEBOARD_FAB2(SCH_1):PAGE133
  R7D7    1      A RES_0402-1.00K,1%,1/16W,CHIP,GA   I331 @BASEBOARD_FAB2_LIB.BASEBOARD_FAB2(SCH_1):PAGE133
  R7D2    1      A RES_0402-1.00K,1%,1/16W,CHIP,GA   I332 @BASEBOARD_FAB2_LIB.BASEBOARD_FAB2(SCH_1):PAGE133
 R8C25    1      A RES_0402-4.75K,1%,1/16W,CHIP,GA   I333 @BASEBOARD_FAB2_LIB.BASEBOARD_FAB2(SCH_1):PAGE133
 R2N32    1      A RES_0402-4.75K,1%,1/16W,CHIP,GA   I341 @BASEBOARD_FAB2_LIB.BASEBOARD_FAB2(SCH_1):PAGE133
  R2M8    1      A RES_0402-1.5K,1%,1/16W,CHIP,G2A   I349 @BASEBOARD_FAB2_LIB.BASEBOARD_FAB2(SCH_1):PAGE133
 R2N29    1      A RES_0402-1.5K,1%,1/16W,CHIP,G2A   I352 @BASEBOARD_FAB2_LIB.BASEBOARD_FAB2(SCH_1):PAGE133
 R2P22    1      A RES_0402-10.0K,1%,1/16W,CHIP,GA   I360 @BASEBOARD_FAB2_LIB.BASEBOARD_FAB2(SCH_1):PAGE133
 R8D44    1      A RES_0402-10.0K,1%,1/16W,CHIP,GA   I362 @BASEBOARD_FAB2_LIB.BASEBOARD_FAB2(SCH_1):PAGE133
 R2P17    1      A RES_0402-4.75K,1%,1/16W,CHIP,GA     I3 @BASEBOARD_FAB2_LIB.BASEBOARD_FAB2(SCH_1):PAGE134
 R2P19    1      A RES_0402-10.0K,1%,1/16W,CHIP,GA   I107 @BASEBOARD_FAB2_LIB.BASEBOARD_FAB2(SCH_1):PAGE135
 R2N23    1      A RES_0402-10.0K,1%,1/16W,CHIP,GA   I112 @BASEBOARD_FAB2_LIB.BASEBOARD_FAB2(SCH_1):PAGE135
 R9A12    2      B RES_0402-2.21K,1%,1/16W,CHIP,GA   I117 @BASEBOARD_FAB2_LIB.BASEBOARD_FAB2(SCH_1):PAGE135
 R8D21    1      A RES_0402-1.00K,1%,1/16W,CHIP,GA   I120 @BASEBOARD_FAB2_LIB.BASEBOARD_FAB2(SCH_1):PAGE135
 R7D30    1      A RES_0402-4.75K,1%,1/16W,CHIP,GA   I121 @BASEBOARD_FAB2_LIB.BASEBOARD_FAB2(SCH_1):PAGE135
 R9A16    2      B RES_0402-2.21K,1%,1/16W,CHIP,GA   I129 @BASEBOARD_FAB2_LIB.BASEBOARD_FAB2(SCH_1):PAGE135
 R7G26    1      A RES_0402-10.0K,1%,1/16W,CHIP,GA   I101 @BASEBOARD_FAB2_LIB.BASEBOARD_FAB2(SCH_1):PAGE136
  C8E8    1      A CAP_A_0402V-0.1UF,16V,10%,X7R,A   I128 @BASEBOARD_FAB2_LIB.BASEBOARD_FAB2(SCH_1):PAGE136
 R8E14    1      A RES_0402-4.75K,1%,1/16W,CHIP,GA   I133 @BASEBOARD_FAB2_LIB.BASEBOARD_FAB2(SCH_1):PAGE136
 R7G31    1      A RES_0402-1.00K,1%,1/16W,CHIP,GA   I139 @BASEBOARD_FAB2_LIB.BASEBOARD_FAB2(SCH_1):PAGE136
 R2N28    1      A RES_0402-10.0K,1%,1/16W,CHIP,GA   I147 @BASEBOARD_FAB2_LIB.BASEBOARD_FAB2(SCH_1):PAGE136
 R7G27    1      A RES_0402-1.00K,1%,1/16W,CHIP,GA   I155 @BASEBOARD_FAB2_LIB.BASEBOARD_FAB2(SCH_1):PAGE136
 R7C13    1      A RES_0402-10.0K,1%,1/16W,CHIP,GA    I67 @BASEBOARD_FAB2_LIB.BASEBOARD_FAB2(SCH_1):PAGE137
 R2T53    1      A RES_0402-665,1.0%,1/16W,CHIP,GA    I83 @BASEBOARD_FAB2_LIB.BASEBOARD_FAB2(SCH_1):PAGE138
 R2T54    1      A RES_0402-665,1.0%,1/16W,CHIP,GA    I84 @BASEBOARD_FAB2_LIB.BASEBOARD_FAB2(SCH_1):PAGE138
 R8D17    1      A RES_0402-1.37K,1%,1/16W,CHIP,GA    I87 @BASEBOARD_FAB2_LIB.BASEBOARD_FAB2(SCH_1):PAGE138
 R8D15    1      A RES_0402-1.37K,1%,1/16W,CHIP,GA    I88 @BASEBOARD_FAB2_LIB.BASEBOARD_FAB2(SCH_1):PAGE138
  R2N8    1      A RES_0402-665,1.0%,1/16W,CHIP,GA    I89 @BASEBOARD_FAB2_LIB.BASEBOARD_FAB2(SCH_1):PAGE138
  R2N5    1      A RES_0402-665,1.0%,1/16W,CHIP,GA    I90 @BASEBOARD_FAB2_LIB.BASEBOARD_FAB2(SCH_1):PAGE138
 R2U11    1      A RES_0402-665,1.0%,1/16W,CHIP,GA    I97 @BASEBOARD_FAB2_LIB.BASEBOARD_FAB2(SCH_1):PAGE138
  R2U3    1      A RES_0402-665,1.0%,1/16W,CHIP,GA    I98 @BASEBOARD_FAB2_LIB.BASEBOARD_FAB2(SCH_1):PAGE138
 EU9E1   64 VDD3P3<0> SPRINGVILLE_SM1-IC,G47144-004    I72 @BASEBOARD_FAB2_LIB.BASEBOARD_FAB2(SCH_1):PAGE139
 EU9E1   41 VDD3P3<2> SPRINGVILLE_SM1-IC,G47144-004    I72 @BASEBOARD_FAB2_LIB.BASEBOARD_FAB2(SCH_1):PAGE139
 EU9E1   27 VDD3P3<3> SPRINGVILLE_SM1-IC,G47144-004    I72 @BASEBOARD_FAB2_LIB.BASEBOARD_FAB2(SCH_1):PAGE139
 EU9E1   10 VDD3P3<4> SPRINGVILLE_SM1-IC,G47144-004    I72 @BASEBOARD_FAB2_LIB.BASEBOARD_FAB2(SCH_1):PAGE139
 C1R22    1      A CAP_0603-10UF,6.3V,20%,X6S,E15A   I136 @BASEBOARD_FAB2_LIB.BASEBOARD_FAB2(SCH_1):PAGE139
 C1R13    1      A CAP_0603-10UF,6.3V,20%,X6S,E15A   I142 @BASEBOARD_FAB2_LIB.BASEBOARD_FAB2(SCH_1):PAGE139
 C1R20    1      A CAP_A_0402V-0.1UF,16V,10%,X7R,A   I143 @BASEBOARD_FAB2_LIB.BASEBOARD_FAB2(SCH_1):PAGE139
  C1T3    1      A CAP_A_0402V-0.1UF,16V,10%,X7R,A   I144 @BASEBOARD_FAB2_LIB.BASEBOARD_FAB2(SCH_1):PAGE139
 C1R14    1      A CAP_A_0402V-0.1UF,16V,10%,X7R,A   I145 @BASEBOARD_FAB2_LIB.BASEBOARD_FAB2(SCH_1):PAGE139
 C1R21    1      A CAP_A_0402V-0.1UF,16V,10%,X7R,A   I146 @BASEBOARD_FAB2_LIB.BASEBOARD_FAB2(SCH_1):PAGE139
  R9F5    1      A RES_0402-3.32K,1%,1/16W,CHIP,GA   I173 @BASEBOARD_FAB2_LIB.BASEBOARD_FAB2(SCH_1):PAGE139
  R9E2    1      A RES_0402-10.0K,1%,1/16W,CHIP,GA   I177 @BASEBOARD_FAB2_LIB.BASEBOARD_FAB2(SCH_1):PAGE139
  R9E3    1      A RES_0402-10.0K,1%,1/16W,CHIP,GA   I178 @BASEBOARD_FAB2_LIB.BASEBOARD_FAB2(SCH_1):PAGE139
  R9E1    1      A RES_0402-10.0K,1%,1/16W,CHIP,GA   I179 @BASEBOARD_FAB2_LIB.BASEBOARD_FAB2(SCH_1):PAGE139
 R9E22    2      B RES_0402-10.0K,1%,1/16W,CHIP,GA   I181 @BASEBOARD_FAB2_LIB.BASEBOARD_FAB2(SCH_1):PAGE139
  R9E7    1      A RES_0402-3.32K,1%,1/16W,CHIP,GA   I193 @BASEBOARD_FAB2_LIB.BASEBOARD_FAB2(SCH_1):PAGE139
  R9E4    1      A RES_0402-10.0K,1%,1/16W,CHIP,GA   I200 @BASEBOARD_FAB2_LIB.BASEBOARD_FAB2(SCH_1):PAGE139
 R1T34    1      A RES_0603-0,5.0%,1/10W,CHIP,G22A   I239 @BASEBOARD_FAB2_LIB.BASEBOARD_FAB2(SCH_1):PAGE139
  U9E1    8    VCC M25PE16_SM-IC,H77797-001     I1 @BASEBOARD_FAB2_LIB.BASEBOARD_FAB2(SCH_1):PAGE140
 C1R25    1      A CAP_A_0402V-0.1UF,16V,10%,X7R,A     I3 @BASEBOARD_FAB2_LIB.BASEBOARD_FAB2(SCH_1):PAGE140
  R1R9    1      A RES_0402-3.32K,1%,1/16W,CHIP,GA    I10 @BASEBOARD_FAB2_LIB.BASEBOARD_FAB2(SCH_1):PAGE140
  R1R3    1      A RES_0402-3.32K,1%,1/16W,CHIP,GA    I11 @BASEBOARD_FAB2_LIB.BASEBOARD_FAB2(SCH_1):PAGE140
  R1R7    1      A RES_0402-20.0K,1%,1/16W,CHIP,GA    I12 @BASEBOARD_FAB2_LIB.BASEBOARD_FAB2(SCH_1):PAGE140
 R8E23    2      B RES_0402-4.75K,1%,1/16W,CHIP,GA     I3 @BASEBOARD_FAB2_LIB.BASEBOARD_FAB2(SCH_1):PAGE142
  C8E5    1      A CAP_A_0402V-0.1UF,16V,10%,X7R,A    I20 @BASEBOARD_FAB2_LIB.BASEBOARD_FAB2(SCH_1):PAGE142
  R7F6    1      A RES_0402-4.75K,1%,1/16W,EMPTY,A    I90 @BASEBOARD_FAB2_LIB.BASEBOARD_FAB2(SCH_1):PAGE153
  R7F5    1      A RES_0402-4.75K,1%,1/16W,CHIP,GA    I94 @BASEBOARD_FAB2_LIB.BASEBOARD_FAB2(SCH_1):PAGE153
  C7F2    1      A CAP_A_0402V-1.0UF,6.3V,10%,X6SA   I130 @BASEBOARD_FAB2_LIB.BASEBOARD_FAB2(SCH_1):PAGE153
  C7F1    1      A CAP_A_0402V-0.01UF,25V,10%,X7RA   I131 @BASEBOARD_FAB2_LIB.BASEBOARD_FAB2(SCH_1):PAGE153
  C3T5    1      A CAP_A_0402V-0.01UF,25V,10%,X7RA   I136 @BASEBOARD_FAB2_LIB.BASEBOARD_FAB2(SCH_1):PAGE153
  C3T4    1      A CAP_A_0402V-1.0UF,6.3V,10%,X6SA   I138 @BASEBOARD_FAB2_LIB.BASEBOARD_FAB2(SCH_1):PAGE153
 R7F32    1      A RES_0402-10.0K,1%,1/16W,CHIP,GA   I140 @BASEBOARD_FAB2_LIB.BASEBOARD_FAB2(SCH_1):PAGE153
  U7F1    2    VCC W25Q256_XSOI-IC,H25002-001   I146 @BASEBOARD_FAB2_LIB.BASEBOARD_FAB2(SCH_1):PAGE153
  R3T3    1      A RES_0402-4.75K,1%,1/16W,EMPTY,A   I150 @BASEBOARD_FAB2_LIB.BASEBOARD_FAB2(SCH_1):PAGE153
  R3T5    1      A RES_0402-4.75K,1%,1/16W,CHIP,GA   I152 @BASEBOARD_FAB2_LIB.BASEBOARD_FAB2(SCH_1):PAGE153
 R7F28    1      A RES_0402-10.0K,1%,1/16W,CHIP,GA   I168 @BASEBOARD_FAB2_LIB.BASEBOARD_FAB2(SCH_1):PAGE153
  R3T4    1      A RES_0402-10.0K,1%,1/16W,CHIP,GA   I174 @BASEBOARD_FAB2_LIB.BASEBOARD_FAB2(SCH_1):PAGE153
 R3T12    1      A RES_0402-10.0K,1%,1/16W,CHIP,GA   I178 @BASEBOARD_FAB2_LIB.BASEBOARD_FAB2(SCH_1):PAGE153
 C8E18    1      A CAP_A_0402V-0.1UF,16V,10%,X7R,A    I14 @BASEBOARD_FAB2_LIB.BASEBOARD_FAB2(SCH_1):PAGE154
  U8F1   16    VCC PI3B3257A_TSSOPLF-IC,E16801-001    I74 @BASEBOARD_FAB2_LIB.BASEBOARD_FAB2(SCH_1):PAGE154
  U2T1   16    VCC PI3B3257A_TSSOPLF-IC,E16801-001    I75 @BASEBOARD_FAB2_LIB.BASEBOARD_FAB2(SCH_1):PAGE154
  C2T1    1      A CAP_A_0402V-0.1UF,16V,10%,X7R,A    I94 @BASEBOARD_FAB2_LIB.BASEBOARD_FAB2(SCH_1):PAGE154
 R2T11    1      A RES_0402-4.75K,1%,1/16W,CHIP,GA   I105 @BASEBOARD_FAB2_LIB.BASEBOARD_FAB2(SCH_1):PAGE154
  R2T8    1      A RES_0402-10.0K,1%,1/16W,CHIP,GA   I106 @BASEBOARD_FAB2_LIB.BASEBOARD_FAB2(SCH_1):PAGE154
  R2T6    1      A RES_0402-4.75K,1%,1/16W,CHIP,GA   I127 @BASEBOARD_FAB2_LIB.BASEBOARD_FAB2(SCH_1):PAGE154
 C2T12    1      A CAP_A_0402V-0.1UF,16V,10%,X7R,A   I132 @BASEBOARD_FAB2_LIB.BASEBOARD_FAB2(SCH_1):PAGE154
  C2T8    1      A CAP_A_0402V-0.1UF,16V,10%,X7R,A   I135 @BASEBOARD_FAB2_LIB.BASEBOARD_FAB2(SCH_1):PAGE154
  R9A7    1      A RES_0402-2.21K,1%,1/16W,CHIP,GA    I80 @BASEBOARD_FAB2_LIB.BASEBOARD_FAB2(SCH_1):PAGE155
 C1T56    1      A CAP_A_0402V-0.1UF,16V,10%,X7R,A   I184 @BASEBOARD_FAB2_LIB.BASEBOARD_FAB2(SCH_1):PAGE155
 R2T34    1      A RES_0402-4.75K,1%,1/16W,CHIP,GA   I206 @BASEBOARD_FAB2_LIB.BASEBOARD_FAB2(SCH_1):PAGE156
 R2T35    1      A RES_0402-4.75K,1%,1/16W,CHIP,GA   I207 @BASEBOARD_FAB2_LIB.BASEBOARD_FAB2(SCH_1):PAGE156
 R2T22    1      A RES_0402-10.0K,1%,1/16W,CHIP,GA   I210 @BASEBOARD_FAB2_LIB.BASEBOARD_FAB2(SCH_1):PAGE156
 R8F26    1      A RES_0402-10.0K,1%,1/16W,CHIP,GA   I211 @BASEBOARD_FAB2_LIB.BASEBOARD_FAB2(SCH_1):PAGE156
 R8E22    1      A RES_0402-4.75K,1%,1/16W,CHIP,GA   I215 @BASEBOARD_FAB2_LIB.BASEBOARD_FAB2(SCH_1):PAGE156
  R2U2    1      A RES_0402-4.75K,1%,1/16W,CHIP,GA   I265 @BASEBOARD_FAB2_LIB.BASEBOARD_FAB2(SCH_1):PAGE156
  R8G2    1      A RES_0402-4.75K,1%,1/16W,CHIP,GA   I267 @BASEBOARD_FAB2_LIB.BASEBOARD_FAB2(SCH_1):PAGE156
 C2T35    1      A CAP_A_0402V-0.1UF,16V,10%,X7R,A   I273 @BASEBOARD_FAB2_LIB.BASEBOARD_FAB2(SCH_1):PAGE156
 C8F16    1      A CAP_A_0402V-0.1UF,16V,10%,X7R,A   I275 @BASEBOARD_FAB2_LIB.BASEBOARD_FAB2(SCH_1):PAGE156
 R1C34    1      A RES_0402-10.0K,1%,1/16W,CHIP,GA   I320 @BASEBOARD_FAB2_LIB.BASEBOARD_FAB2(SCH_1):PAGE156
 R3P54    1      A RES_0402-3.32K,1%,1/16W,EMPTY,A   I331 @BASEBOARD_FAB2_LIB.BASEBOARD_FAB2(SCH_1):PAGE156
 R1C35    1      A RES_0402-3.32K,1%,1/16W,EMPTY,A   I336 @BASEBOARD_FAB2_LIB.BASEBOARD_FAB2(SCH_1):PAGE156
 R8F23    1      A RES_0402-2.21K,1%,1/16W,CHIP,GA   I296 @BASEBOARD_FAB2_LIB.BASEBOARD_FAB2(SCH_1):PAGE157
 R2T29    1      A RES_0402-2.21K,1%,1/16W,CHIP,GA   I298 @BASEBOARD_FAB2_LIB.BASEBOARD_FAB2(SCH_1):PAGE157
 R8F24    1      A RES_0402-4.75K,1%,1/16W,CHIP,GA   I316 @BASEBOARD_FAB2_LIB.BASEBOARD_FAB2(SCH_1):PAGE157
  R2T5    1      A RES_0402-1.00K,1%,1/16W,CHIP,GA   I326 @BASEBOARD_FAB2_LIB.BASEBOARD_FAB2(SCH_1):PAGE157
  R2T7    1      A RES_0402-1.00K,1%,1/16W,CHIP,GA   I327 @BASEBOARD_FAB2_LIB.BASEBOARD_FAB2(SCH_1):PAGE157
 R8D25    1      A RES_0402-4.75K,1%,1/16W,CHIP,GA   I335 @BASEBOARD_FAB2_LIB.BASEBOARD_FAB2(SCH_1):PAGE157
 R3N12    1      A RES_0402-4.75K,1%,1/16W,CHIP,GA   I342 @BASEBOARD_FAB2_LIB.BASEBOARD_FAB2(SCH_1):PAGE157
 R3N11    1      A RES_0402-4.75K,1%,1/16W,CHIP,GA   I344 @BASEBOARD_FAB2_LIB.BASEBOARD_FAB2(SCH_1):PAGE157
  R2M2    1      A RES_0402-4.75K,1%,1/16W,CHIP,GA   I346 @BASEBOARD_FAB2_LIB.BASEBOARD_FAB2(SCH_1):PAGE157
  R2M5    1      A RES_0402-4.75K,1%,1/16W,CHIP,GA   I348 @BASEBOARD_FAB2_LIB.BASEBOARD_FAB2(SCH_1):PAGE157
 R8E19    1      A RES_0402-4.75K,1%,1/16W,EMPTY,A   I361 @BASEBOARD_FAB2_LIB.BASEBOARD_FAB2(SCH_1):PAGE157
  R2U4    1      A RES_0402-4.75K,1%,1/16W,CHIP,GA   I367 @BASEBOARD_FAB2_LIB.BASEBOARD_FAB2(SCH_1):PAGE157
  C2T3    1      A CAP_A_0402V-0.1UF,16V,10%,X7R,A   I370 @BASEBOARD_FAB2_LIB.BASEBOARD_FAB2(SCH_1):PAGE157
  C8D1    1      A CAP_A_0402V-0.1UF,16V,10%,X7R,A   I376 @BASEBOARD_FAB2_LIB.BASEBOARD_FAB2(SCH_1):PAGE157
  R1L7    1      A RES_0402-4.75K,1%,1/16W,CHIP,GA   I382 @BASEBOARD_FAB2_LIB.BASEBOARD_FAB2(SCH_1):PAGE157
 R8E32    1      A RES_0402-4.75K,1%,1/16W,CHIP,GA   I385 @BASEBOARD_FAB2_LIB.BASEBOARD_FAB2(SCH_1):PAGE157
 C1T10    1      A CAP_A_0402V-0.1UF,16V,10%,X7R,A    I70 @BASEBOARD_FAB2_LIB.BASEBOARD_FAB2(SCH_1):PAGE158
  U9F2    8    VCC FSA3357_SM-IC,C63273-001    I74 @BASEBOARD_FAB2_LIB.BASEBOARD_FAB2(SCH_1):PAGE158
  U9F1    8    VCC FSA3357_SM-IC,C63273-001    I75 @BASEBOARD_FAB2_LIB.BASEBOARD_FAB2(SCH_1):PAGE158
 C1T11    1      A CAP_A_0402V-0.1UF,16V,10%,X7R,A    I97 @BASEBOARD_FAB2_LIB.BASEBOARD_FAB2(SCH_1):PAGE158
 R1L43    2      B RES_0402-330,5%,1/16W,CHIP,G21A   I131 @BASEBOARD_FAB2_LIB.BASEBOARD_FAB2(SCH_1):PAGE158
 R1L44    2      B RES_0402-330,5%,1/16W,CHIP,G21A   I136 @BASEBOARD_FAB2_LIB.BASEBOARD_FAB2(SCH_1):PAGE158
  R8G3    1      A RES_0402-2.26K,1.0%,1/16W,EMPTA   I210 @BASEBOARD_FAB2_LIB.BASEBOARD_FAB2(SCH_1):PAGE159
  R8G6    1      A RES_0402-2.26K,1.0%,1/16W,EMPTA   I212 @BASEBOARD_FAB2_LIB.BASEBOARD_FAB2(SCH_1):PAGE159
  R2U5    1      A RES_0402-2.26K,1.0%,1/16W,CHIPA   I214 @BASEBOARD_FAB2_LIB.BASEBOARD_FAB2(SCH_1):PAGE159
 R2U13    1      A RES_0402-2.26K,1.0%,1/16W,CHIPA   I216 @BASEBOARD_FAB2_LIB.BASEBOARD_FAB2(SCH_1):PAGE159
  R1T3    1      A RES_0402-665,1.0%,1/16W,CHIP,GA    I46 @BASEBOARD_FAB2_LIB.BASEBOARD_FAB2(SCH_1):PAGE160
  R1T2    1      A RES_0402-665,1.0%,1/16W,CHIP,GA    I49 @BASEBOARD_FAB2_LIB.BASEBOARD_FAB2(SCH_1):PAGE160
  R1F1    1      A RES_0402-4.75K,1%,1/16W,CHIP,GA    I45 @BASEBOARD_FAB2_LIB.BASEBOARD_FAB2(SCH_1):PAGE161
 R1B21    1      A RES_0402-4.75K,1%,1/16W,CHIP,GA    I70 @BASEBOARD_FAB2_LIB.BASEBOARD_FAB2(SCH_1):PAGE161
 C2U27    1      A CAP_A_0402V-0.1UF,16V,10%,X7R,A    I90 @BASEBOARD_FAB2_LIB.BASEBOARD_FAB2(SCH_1):PAGE161
 C2U28    1      A CAP_A_0402V-0.1UF,16V,10%,X7R,A    I93 @BASEBOARD_FAB2_LIB.BASEBOARD_FAB2(SCH_1):PAGE161
 C1E22    1      A CAP_A_0402V-0.1UF,16V,10%,X7R,A   I113 @BASEBOARD_FAB2_LIB.BASEBOARD_FAB2(SCH_1):PAGE161
 R1E11    1      A RES_0402-10.0K,1%,1/16W,EMPTY,A   I120 @BASEBOARD_FAB2_LIB.BASEBOARD_FAB2(SCH_1):PAGE161
 R8F16    1      A RES_0402-4.75K,1%,1/16W,EMPTY,A     I8 @BASEBOARD_FAB2_LIB.BASEBOARD_FAB2(SCH_1):PAGE162
 R8F14    1      A RES_0402-4.75K,1%,1/16W,CHIP,GA     I9 @BASEBOARD_FAB2_LIB.BASEBOARD_FAB2(SCH_1):PAGE162
 R8F34    1      A RES_0402-4.75K,1%,1/16W,CHIP,GA    I22 @BASEBOARD_FAB2_LIB.BASEBOARD_FAB2(SCH_1):PAGE162
  C8F5    1      A CAP_A_0402V-0.01UF,25V,10%,X7RA    I28 @BASEBOARD_FAB2_LIB.BASEBOARD_FAB2(SCH_1):PAGE162
  C8F4    1      A CAP_A_0402V-1.0UF,6.3V,10%,X6SA    I30 @BASEBOARD_FAB2_LIB.BASEBOARD_FAB2(SCH_1):PAGE162
  U8F2    2    VCC W25Q128_SKT16-IC,H12709-001    I32 @BASEBOARD_FAB2_LIB.BASEBOARD_FAB2(SCH_1):PAGE162
  C9M7    1      A CAP_A_0402V-0.1UF,16V,10%,X7R,A    I12 @BASEBOARD_FAB2_LIB.BASEBOARD_FAB2(SCH_1):PAGE163
 R9M17    1      A RES_0402-2.0K,1%,1/16W,CHIP,G2A    I15 @BASEBOARD_FAB2_LIB.BASEBOARD_FAB2(SCH_1):PAGE163
 R9M16    1      A RES_0402-2.0K,1%,1/16W,CHIP,G2A    I16 @BASEBOARD_FAB2_LIB.BASEBOARD_FAB2(SCH_1):PAGE163
  R1T5    1      A RES_0402-2.7K,1%,1/16W,EMPTY,GA    I11 @BASEBOARD_FAB2_LIB.BASEBOARD_FAB2(SCH_1):PAGE164
  U9B4    8     VP TMP421_TSSOP-IC,G62962-001     I1 @BASEBOARD_FAB2_LIB.BASEBOARD_FAB2(SCH_1):PAGE167
  U1E1    8     VP TMP421_TSSOP-IC,G62962-001    I30 @BASEBOARD_FAB2_LIB.BASEBOARD_FAB2(SCH_1):PAGE167
  R1E9    1      A RES_0402-1.00K,1%,1/16W,CHIP,GA    I34 @BASEBOARD_FAB2_LIB.BASEBOARD_FAB2(SCH_1):PAGE167
  R9B6    1      A RES_0402-1.00K,1%,1/16W,CHIP,GA    I35 @BASEBOARD_FAB2_LIB.BASEBOARD_FAB2(SCH_1):PAGE167
 R1E10    1      A RES_0402-1.00K,1%,1/16W,CHIP,GA    I38 @BASEBOARD_FAB2_LIB.BASEBOARD_FAB2(SCH_1):PAGE167
  C9B7    1      A CAP_A_0402V-0.1UF,16V,10%,X7R,A    I39 @BASEBOARD_FAB2_LIB.BASEBOARD_FAB2(SCH_1):PAGE167
 C9R14    1      A CAP_A_0402V-0.1UF,16V,10%,X7R,A    I41 @BASEBOARD_FAB2_LIB.BASEBOARD_FAB2(SCH_1):PAGE167
 C9R13    1      A CAP_A_0402V-0.1UF,16V,10%,X7R,A    I42 @BASEBOARD_FAB2_LIB.BASEBOARD_FAB2(SCH_1):PAGE167
 R8D28    1      A RES_0402-1.00K,1%,1/16W,CHIP,GA    I70 @BASEBOARD_FAB2_LIB.BASEBOARD_FAB2(SCH_1):PAGE167
 R2U38    1      A RES_0402-665,1.0%,1/16W,CHIP,GA    I80 @BASEBOARD_FAB2_LIB.BASEBOARD_FAB2(SCH_1):PAGE167
 R2U39    1      A RES_0402-665,1.0%,1/16W,CHIP,GA    I83 @BASEBOARD_FAB2_LIB.BASEBOARD_FAB2(SCH_1):PAGE167
 R1L36    1      A RES_0402-1.00K,1%,1/16W,CHIP,GA    I11 @BASEBOARD_FAB2_LIB.BASEBOARD_FAB2(SCH_1):PAGE168
 R1L38    1      A RES_0402-1.00K,1%,1/16W,CHIP,GA    I22 @BASEBOARD_FAB2_LIB.BASEBOARD_FAB2(SCH_1):PAGE168
 R1U39    1      A RES_0402-5.11K,1%,1/16W,CHIP,GA    I88 @BASEBOARD_FAB2_LIB.BASEBOARD_FAB2(SCH_1):PAGE169
 R1U49    1      A RES_0402-2.7K,1%,1/16W,CHIP,G2A   I163 @BASEBOARD_FAB2_LIB.BASEBOARD_FAB2(SCH_1):PAGE169
 R9G35    1      A RES_0402-2.7K,1%,1/16W,CHIP,G2A   I164 @BASEBOARD_FAB2_LIB.BASEBOARD_FAB2(SCH_1):PAGE169
  R2P3    1      A RES_0402-4.75K,1%,1/16W,CHIP,GA     I2 @BASEBOARD_FAB2_LIB.BASEBOARD_FAB2(SCH_1):PAGE170
  C2P1    1      A CAP_A_0402V-0.1UF,16V,10%,X7R,A     I8 @BASEBOARD_FAB2_LIB.BASEBOARD_FAB2(SCH_1):PAGE170
 C1R27    1      A CAP_A_0402V-0.1UF,16V,10%,X7R,A    I30 @BASEBOARD_FAB2_LIB.BASEBOARD_FAB2(SCH_1):PAGE170
  C8D2    1      A CAP_A_0402V-0.1UF,16V,10%,X7R,A    I33 @BASEBOARD_FAB2_LIB.BASEBOARD_FAB2(SCH_1):PAGE170
  C8E2    1      A CAP_A_0402V-0.1UF,16V,10%,X7R,A    I40 @BASEBOARD_FAB2_LIB.BASEBOARD_FAB2(SCH_1):PAGE170
 C1R28    1      A CAP_A_0402V-0.1UF,16V,10%,X7R,A    I49 @BASEBOARD_FAB2_LIB.BASEBOARD_FAB2(SCH_1):PAGE170
  R2T3    1      A RES_0402-4.75K,1%,1/16W,CHIP,GA    I54 @BASEBOARD_FAB2_LIB.BASEBOARD_FAB2(SCH_1):PAGE170
  R2P5    1      A RES_0402-4.75K,1%,1/16W,CHIP,GA    I56 @BASEBOARD_FAB2_LIB.BASEBOARD_FAB2(SCH_1):PAGE170
 R2P13    1      A RES_0402-4.75K,1%,1/16W,CHIP,GA    I61 @BASEBOARD_FAB2_LIB.BASEBOARD_FAB2(SCH_1):PAGE170
  R9F3    1      A RES_0402-4.75K,1%,1/16W,CHIP,GA    I65 @BASEBOARD_FAB2_LIB.BASEBOARD_FAB2(SCH_1):PAGE170
 R8D26    1      A RES_0402-4.75K,1%,1/16W,CHIP,GA    I71 @BASEBOARD_FAB2_LIB.BASEBOARD_FAB2(SCH_1):PAGE170
  R1R5    1      A RES_0402-4.75K,1%,1/16W,CHIP,GA    I73 @BASEBOARD_FAB2_LIB.BASEBOARD_FAB2(SCH_1):PAGE170
 R1L27    1      A RES_0402-4.75K,1%,1/16W,CHIP,GA     I5 @BASEBOARD_FAB2_LIB.BASEBOARD_FAB2(SCH_1):PAGE175
 C1L17    1      A CAP_A_0402V-0.1UF,16V,10%,X7R,A    I37 @BASEBOARD_FAB2_LIB.BASEBOARD_FAB2(SCH_1):PAGE175
  C1L9    1      A CAP_A_0402V-0.1UF,16V,10%,X7R,A    I38 @BASEBOARD_FAB2_LIB.BASEBOARD_FAB2(SCH_1):PAGE175
  C9A3    1      A CAP_A_0402V-0.1UF,16V,10%,X7R,A    I40 @BASEBOARD_FAB2_LIB.BASEBOARD_FAB2(SCH_1):PAGE175
 R1L33    2      B RES_0402-221,1.0%,1/16W,CHIP,GA    I45 @BASEBOARD_FAB2_LIB.BASEBOARD_FAB2(SCH_1):PAGE175
 R1M24    1      A RES_0402-10.0K,1%,1/16W,CHIP,GA   I105 @BASEBOARD_FAB2_LIB.BASEBOARD_FAB2(SCH_1):PAGE176
 R9F28    1      A RES_0402-221,1.0%,1/16W,CHIP,GA    I72 @BASEBOARD_FAB2_LIB.BASEBOARD_FAB2(SCH_1):PAGE177
 R9F30    1      A RES_0402-4.75K,1%,1/16W,CHIP,GA    I76 @BASEBOARD_FAB2_LIB.BASEBOARD_FAB2(SCH_1):PAGE177
 R9F52    1      A RES_0402-4.75K,1%,1/16W,CHIP,GA    I82 @BASEBOARD_FAB2_LIB.BASEBOARD_FAB2(SCH_1):PAGE177
 R2L12    1      A RES_0402-2.0K,1%,1/16W,CHIP,G2A     I2 @BASEBOARD_FAB2_LIB.BASEBOARD_FAB2(SCH_1):PAGE178
 R2L15    1      A RES_0402-2.0K,1%,1/16W,CHIP,G2A    I12 @BASEBOARD_FAB2_LIB.BASEBOARD_FAB2(SCH_1):PAGE178
 R2L11    1      A RES_0402-2.0K,1%,1/16W,CHIP,G2A    I13 @BASEBOARD_FAB2_LIB.BASEBOARD_FAB2(SCH_1):PAGE178
  R2L6    1      A RES_0402-2.0K,1%,1/16W,CHIP,G2A    I17 @BASEBOARD_FAB2_LIB.BASEBOARD_FAB2(SCH_1):PAGE178
  R2L4    1      A RES_0402-2.0K,1%,1/16W,CHIP,G2A    I18 @BASEBOARD_FAB2_LIB.BASEBOARD_FAB2(SCH_1):PAGE178
  R2L5    1      A RES_0402-2.0K,1%,1/16W,CHIP,G2A    I20 @BASEBOARD_FAB2_LIB.BASEBOARD_FAB2(SCH_1):PAGE178
  J8E1    7    IO7 SCONN11_H67026001_SM-CONN,H670A    I87 @BASEBOARD_FAB2_LIB.BASEBOARD_FAB2(SCH_1):PAGE184
 R2P16    1      A RES_0402-10.0K,1%,1/16W,CHIP,GA   I113 @BASEBOARD_FAB2_LIB.BASEBOARD_FAB2(SCH_1):PAGE185
  C2P9    1      A CAP_A_0402V-0.1UF,16V,10%,X7R,A   I117 @BASEBOARD_FAB2_LIB.BASEBOARD_FAB2(SCH_1):PAGE185
 C1M20    1      A CAP_A_0402V-0.1UF,16V,10%,X7R,A   I270 @BASEBOARD_FAB2_LIB.BASEBOARD_FAB2(SCH_1):PAGE186
 C1M25    1      A CAP_A_0402V-1.0UF,6.3V,10%,X6SA   I335 @BASEBOARD_FAB2_LIB.BASEBOARD_FAB2(SCH_1):PAGE186
  J9B3   12   IO12 SCONN120_A28699018_SM-SCONN,A2A   I336 @BASEBOARD_FAB2_LIB.BASEBOARD_FAB2(SCH_1):PAGE186
  J9B3   13   IO13 SCONN120_A28699018_SM-SCONN,A2A   I336 @BASEBOARD_FAB2_LIB.BASEBOARD_FAB2(SCH_1):PAGE186
 R1R18    1      A RES_0402-2.21K,1%,1/16W,CHIP,GA    I88 @BASEBOARD_FAB2_LIB.BASEBOARD_FAB2(SCH_1):PAGE188
 R1R19    1      A RES_0402-2.21K,1%,1/16W,CHIP,GA    I89 @BASEBOARD_FAB2_LIB.BASEBOARD_FAB2(SCH_1):PAGE188
 R1R21    1      A RES_0402-2.21K,1%,1/16W,CHIP,GA    I90 @BASEBOARD_FAB2_LIB.BASEBOARD_FAB2(SCH_1):PAGE188
 R1R20    1      A RES_0402-2.21K,1%,1/16W,CHIP,GA    I91 @BASEBOARD_FAB2_LIB.BASEBOARD_FAB2(SCH_1):PAGE188
 R1R22    1      A RES_0402-2.21K,1%,1/16W,CHIP,GA    I92 @BASEBOARD_FAB2_LIB.BASEBOARD_FAB2(SCH_1):PAGE188
 R1R16    1      A RES_0402-2.21K,1%,1/16W,CHIP,GA    I93 @BASEBOARD_FAB2_LIB.BASEBOARD_FAB2(SCH_1):PAGE188
 R1R17    1      A RES_0402-2.21K,1%,1/16W,CHIP,GA    I94 @BASEBOARD_FAB2_LIB.BASEBOARD_FAB2(SCH_1):PAGE188
 R1R23    1      A RES_0402-2.21K,1%,1/16W,CHIP,GA    I95 @BASEBOARD_FAB2_LIB.BASEBOARD_FAB2(SCH_1):PAGE188
 R3R15    1      A RES_0402-1.00K,1%,1/16W,CHIP,GA    I44 @BASEBOARD_FAB2_LIB.BASEBOARD_FAB2(SCH_1):PAGE189
 CR3U1    2      A DIODE_SMLF-1N5819HW,IC,D55839-A    I49 @BASEBOARD_FAB2_LIB.BASEBOARD_FAB2(SCH_1):PAGE189
 R8G20    1      A RES_0402-10.0K,1%,1/16W,CHIP,GA    I50 @BASEBOARD_FAB2_LIB.BASEBOARD_FAB2(SCH_1):PAGE189
 R7G23    1      A RES_0402-10.0K,1%,1/16W,CHIP,GA    I51 @BASEBOARD_FAB2_LIB.BASEBOARD_FAB2(SCH_1):PAGE189
 R7G22    1      A RES_0402-10.0K,1%,1/16W,CHIP,GA    I53 @BASEBOARD_FAB2_LIB.BASEBOARD_FAB2(SCH_1):PAGE189
  R2R7    1      A RES_0402-4.75K,1%,1/16W,CHIP,GA   I172 @BASEBOARD_FAB2_LIB.BASEBOARD_FAB2(SCH_1):PAGE191
 R7D42    1      A RES_0402-4.75K,1%,1/16W,CHIP,GA   I193 @BASEBOARD_FAB2_LIB.BASEBOARD_FAB2(SCH_1):PAGE191
  C2P8    1      A CAP_A_0402V-0.01UF,25V,10%,X7RA     I1 @BASEBOARD_FAB2_LIB.BASEBOARD_FAB2(SCH_1):PAGE192
  C2P5    1      A CAP_A_0402V-0.1UF,16V,10%,X7R,A     I3 @BASEBOARD_FAB2_LIB.BASEBOARD_FAB2(SCH_1):PAGE192
  C3R1    1      A CAP_A_0402V-0.1UF,16V,10%,X7R,A     I4 @BASEBOARD_FAB2_LIB.BASEBOARD_FAB2(SCH_1):PAGE192
 C3P43    1      A CAP_A_0402V-0.1UF,16V,10%,X7R,A     I6 @BASEBOARD_FAB2_LIB.BASEBOARD_FAB2(SCH_1):PAGE192
  C3R3    1      A CAP_A_0402V-0.1UF,16V,10%,X7R,A     I7 @BASEBOARD_FAB2_LIB.BASEBOARD_FAB2(SCH_1):PAGE192
  C2R1    1      A CAP_A_0402V-0.1UF,16V,10%,X7R,A     I8 @BASEBOARD_FAB2_LIB.BASEBOARD_FAB2(SCH_1):PAGE192
  C2P2    1      A CAP_A_0402V-0.1UF,16V,10%,X7R,A     I9 @BASEBOARD_FAB2_LIB.BASEBOARD_FAB2(SCH_1):PAGE192
  C3R2    1      A CAP_A_0402V-0.1UF,16V,10%,X7R,A    I10 @BASEBOARD_FAB2_LIB.BASEBOARD_FAB2(SCH_1):PAGE192
 C3P51    1      A CAP_A_0402V-0.1UF,16V,10%,X7R,A    I11 @BASEBOARD_FAB2_LIB.BASEBOARD_FAB2(SCH_1):PAGE192
 C3P47    1      A CAP_A_0402V-0.1UF,16V,10%,X7R,A    I12 @BASEBOARD_FAB2_LIB.BASEBOARD_FAB2(SCH_1):PAGE192
  U8D7   A1 VCC<0> LCMXO2_A_256BGA-IC,H63395-001    I14 @BASEBOARD_FAB2_LIB.BASEBOARD_FAB2(SCH_1):PAGE192
  U8D7  A16 VCC<1> LCMXO2_A_256BGA-IC,H63395-001    I14 @BASEBOARD_FAB2_LIB.BASEBOARD_FAB2(SCH_1):PAGE192
  U8D7   T1 VCC<2> LCMXO2_A_256BGA-IC,H63395-001    I14 @BASEBOARD_FAB2_LIB.BASEBOARD_FAB2(SCH_1):PAGE192
  U8D7  T16 VCC<3> LCMXO2_A_256BGA-IC,H63395-001    I14 @BASEBOARD_FAB2_LIB.BASEBOARD_FAB2(SCH_1):PAGE192
  U8D7   G7 VCC<4> LCMXO2_A_256BGA-IC,H63395-001    I14 @BASEBOARD_FAB2_LIB.BASEBOARD_FAB2(SCH_1):PAGE192
  U8D7  G10 VCC<5> LCMXO2_A_256BGA-IC,H63395-001    I14 @BASEBOARD_FAB2_LIB.BASEBOARD_FAB2(SCH_1):PAGE192
  U8D7   K7 VCC<6> LCMXO2_A_256BGA-IC,H63395-001    I14 @BASEBOARD_FAB2_LIB.BASEBOARD_FAB2(SCH_1):PAGE192
  U8D7  K10 VCC<7> LCMXO2_A_256BGA-IC,H63395-001    I14 @BASEBOARD_FAB2_LIB.BASEBOARD_FAB2(SCH_1):PAGE192
  U8D7   G8 VCCIO0<0> LCMXO2_A_256BGA-IC,H63395-001    I14 @BASEBOARD_FAB2_LIB.BASEBOARD_FAB2(SCH_1):PAGE192
  U8D7  D12 VCCIO0<1> LCMXO2_A_256BGA-IC,H63395-001    I14 @BASEBOARD_FAB2_LIB.BASEBOARD_FAB2(SCH_1):PAGE192
  U8D7   G9 VCCIO0<2> LCMXO2_A_256BGA-IC,H63395-001    I14 @BASEBOARD_FAB2_LIB.BASEBOARD_FAB2(SCH_1):PAGE192
  U8D7   D5 VCCIO0<3> LCMXO2_A_256BGA-IC,H63395-001    I14 @BASEBOARD_FAB2_LIB.BASEBOARD_FAB2(SCH_1):PAGE192
  U8D7  E13 VCCIO1<0> LCMXO2_A_256BGA-IC,H63395-001    I14 @BASEBOARD_FAB2_LIB.BASEBOARD_FAB2(SCH_1):PAGE192
  U8D7  H10 VCCIO1<1> LCMXO2_A_256BGA-IC,H63395-001    I14 @BASEBOARD_FAB2_LIB.BASEBOARD_FAB2(SCH_1):PAGE192
  U8D7  J10 VCCIO1<2> LCMXO2_A_256BGA-IC,H63395-001    I14 @BASEBOARD_FAB2_LIB.BASEBOARD_FAB2(SCH_1):PAGE192
  U8D7  M13 VCCIO1<3> LCMXO2_A_256BGA-IC,H63395-001    I14 @BASEBOARD_FAB2_LIB.BASEBOARD_FAB2(SCH_1):PAGE192
  U8D7   K9 VCCIO2<0> LCMXO2_A_256BGA-IC,H63395-001    I14 @BASEBOARD_FAB2_LIB.BASEBOARD_FAB2(SCH_1):PAGE192
  U8D7  N12 VCCIO2<1> LCMXO2_A_256BGA-IC,H63395-001    I14 @BASEBOARD_FAB2_LIB.BASEBOARD_FAB2(SCH_1):PAGE192
  U8D7   K8 VCCIO2<2> LCMXO2_A_256BGA-IC,H63395-001    I14 @BASEBOARD_FAB2_LIB.BASEBOARD_FAB2(SCH_1):PAGE192
  U8D7   N5 VCCIO2<3> LCMXO2_A_256BGA-IC,H63395-001    I14 @BASEBOARD_FAB2_LIB.BASEBOARD_FAB2(SCH_1):PAGE192
  U8D7   M4 VCCIO3<0> LCMXO2_A_256BGA-IC,H63395-001    I14 @BASEBOARD_FAB2_LIB.BASEBOARD_FAB2(SCH_1):PAGE192
  U8D7   J7 VCCIO4<0> LCMXO2_A_256BGA-IC,H63395-001    I14 @BASEBOARD_FAB2_LIB.BASEBOARD_FAB2(SCH_1):PAGE192
  U8D7   H7 VCCIO4<1> LCMXO2_A_256BGA-IC,H63395-001    I14 @BASEBOARD_FAB2_LIB.BASEBOARD_FAB2(SCH_1):PAGE192
  U8D7   E4 VCCIO5<0> LCMXO2_A_256BGA-IC,H63395-001    I14 @BASEBOARD_FAB2_LIB.BASEBOARD_FAB2(SCH_1):PAGE192
  C2R5    1      A CAP_A_0402V-0.1UF,16V,10%,X7R,A    I15 @BASEBOARD_FAB2_LIB.BASEBOARD_FAB2(SCH_1):PAGE192
  C2P4    1      A CAP_A_0402V-0.1UF,16V,10%,X7R,A    I16 @BASEBOARD_FAB2_LIB.BASEBOARD_FAB2(SCH_1):PAGE192
 C3P52    1      A CAP_A_0402V-0.1UF,16V,10%,X7R,A    I17 @BASEBOARD_FAB2_LIB.BASEBOARD_FAB2(SCH_1):PAGE192
  C2P6    1      A CAP_A_0402V-0.1UF,16V,10%,X7R,A    I18 @BASEBOARD_FAB2_LIB.BASEBOARD_FAB2(SCH_1):PAGE192
  C2R3    1      A CAP_A_0402V-0.1UF,16V,10%,X7R,A    I19 @BASEBOARD_FAB2_LIB.BASEBOARD_FAB2(SCH_1):PAGE192
  C2P7    1      A CAP_A_0402V-0.1UF,16V,10%,X7R,A    I20 @BASEBOARD_FAB2_LIB.BASEBOARD_FAB2(SCH_1):PAGE192
  C2R4    1      A CAP_A_0402V-0.1UF,16V,10%,X7R,A    I21 @BASEBOARD_FAB2_LIB.BASEBOARD_FAB2(SCH_1):PAGE192
  C2P3    1      A CAP_A_0402V-0.1UF,16V,10%,X7R,A    I22 @BASEBOARD_FAB2_LIB.BASEBOARD_FAB2(SCH_1):PAGE192
 C3P44    1      A CAP_A_0402V-0.1UF,16V,10%,X7R,A    I23 @BASEBOARD_FAB2_LIB.BASEBOARD_FAB2(SCH_1):PAGE192
 C3P48    1      A CAP_A_0402V-0.1UF,16V,10%,X7R,A    I25 @BASEBOARD_FAB2_LIB.BASEBOARD_FAB2(SCH_1):PAGE192
  C2R2    1      A CAP_A_0402V-0.1UF,16V,10%,X7R,A    I28 @BASEBOARD_FAB2_LIB.BASEBOARD_FAB2(SCH_1):PAGE192
  R7E6    1      A RES_0402-10.0K,1%,1/16W,CHIP,GA    I33 @BASEBOARD_FAB2_LIB.BASEBOARD_FAB2(SCH_1):PAGE192
  R2R1    1      A RES_0402-10.0K,1%,1/16W,CHIP,GA    I34 @BASEBOARD_FAB2_LIB.BASEBOARD_FAB2(SCH_1):PAGE192
  R7E5    1      A RES_0402-10.0K,1%,1/16W,CHIP,GA    I38 @BASEBOARD_FAB2_LIB.BASEBOARD_FAB2(SCH_1):PAGE192
  R2R3    1      A RES_0402-10.0K,1%,1/16W,CHIP,GA    I41 @BASEBOARD_FAB2_LIB.BASEBOARD_FAB2(SCH_1):PAGE192
 R7E18    1      A RES_0402-4.75K,1%,1/16W,CHIP,GA    I55 @BASEBOARD_FAB2_LIB.BASEBOARD_FAB2(SCH_1):PAGE192
 R7E19    1      A RES_0402-1.00K,1%,1/16W,EMPTY,A    I57 @BASEBOARD_FAB2_LIB.BASEBOARD_FAB2(SCH_1):PAGE192
  J4B2  A11  IOA11 SCONN120_H61426002_SM-CONN,H61A    I46 @BASEBOARD_FAB2_LIB.BASEBOARD_FAB2(SCH_1):PAGE193
  J4B2  B11  IOB11 SCONN120_H61426002_SM-CONN,H61A    I46 @BASEBOARD_FAB2_LIB.BASEBOARD_FAB2(SCH_1):PAGE193
  J4B2  C11  IOC11 SCONN120_H61426002_SM-CONN,H61A    I46 @BASEBOARD_FAB2_LIB.BASEBOARD_FAB2(SCH_1):PAGE193
  J6B1  A11  IOA11 SCONN120_H61426002_SM-CONN,H61A    I56 @BASEBOARD_FAB2_LIB.BASEBOARD_FAB2(SCH_1):PAGE194
  J6B1  B11  IOB11 SCONN120_H61426002_SM-CONN,H61A    I56 @BASEBOARD_FAB2_LIB.BASEBOARD_FAB2(SCH_1):PAGE194
  J6B1  C11  IOC11 SCONN120_H61426002_SM-CONN,H61A    I56 @BASEBOARD_FAB2_LIB.BASEBOARD_FAB2(SCH_1):PAGE194
 CR2U1    1     A1 DIODE2A_DUAL_SMLF-BAS70-05,DIOA    I53 @BASEBOARD_FAB2_LIB.BASEBOARD_FAB2(SCH_1):PAGE196
 R3P44    1      A RES_0402-4.75K,1%,1/16W,CHIP,GA    I59 @BASEBOARD_FAB2_LIB.BASEBOARD_FAB2(SCH_1):PAGE196
  U7D3    6    VCC ADM1085_SMT-IC,H46130-001    I70 @BASEBOARD_FAB2_LIB.BASEBOARD_FAB2(SCH_1):PAGE196
 R3P50    1      A RES_0402-10.0K,1%,1/16W,EMPTY,A    I71 @BASEBOARD_FAB2_LIB.BASEBOARD_FAB2(SCH_1):PAGE196
 C3P46    1      A CAP_A_0402V-0.1UF,16V,10%,X7R,A    I72 @BASEBOARD_FAB2_LIB.BASEBOARD_FAB2(SCH_1):PAGE196
  U8D8    2    VDD TPS3700_SM-IC,H69492-001   I104 @BASEBOARD_FAB2_LIB.BASEBOARD_FAB2(SCH_1):PAGE196
  C8D4    1      A CAP_A_0402V-0.1UF,16V,10%,X7R,A   I105 @BASEBOARD_FAB2_LIB.BASEBOARD_FAB2(SCH_1):PAGE196
 R8D41    1      A RES_0402-10.0K,1%,1/16W,CHIP,GA   I120 @BASEBOARD_FAB2_LIB.BASEBOARD_FAB2(SCH_1):PAGE196
 R2P18    1      A RES_0402-10.0K,1%,1/16W,CHIP,GA   I121 @BASEBOARD_FAB2_LIB.BASEBOARD_FAB2(SCH_1):PAGE196
 R2P21    1      A RES_0402-10.0K,1%,1/16W,CHIP,GA   I122 @BASEBOARD_FAB2_LIB.BASEBOARD_FAB2(SCH_1):PAGE196
 EU2T1    5      D SLG55021_SM-IC,G56246-001     I1 @BASEBOARD_FAB2_LIB.BASEBOARD_FAB2(SCH_1):PAGE198
 C2T36    1      A CAP_A_0402V-0.1UF,16V,10%,X7R,A    I43 @BASEBOARD_FAB2_LIB.BASEBOARD_FAB2(SCH_1):PAGE198
  C2U1    1      A CAP_0805-10UF,16V,10%,X6S,C953A    I44 @BASEBOARD_FAB2_LIB.BASEBOARD_FAB2(SCH_1):PAGE198
 R8E12    1      A RES_0402-4.75K,1%,1/16W,EMPTY,A    I78 @BASEBOARD_FAB2_LIB.BASEBOARD_FAB2(SCH_1):PAGE198
  Q8G1    5    DRN MOSFET_N_LCC3-BSZ019N03LS,NFETA    I85 @BASEBOARD_FAB2_LIB.BASEBOARD_FAB2(SCH_1):PAGE198
 R9P20    1      A RES_0402-2.7K,1%,1/16W,CHIP,G2A    I86 @BASEBOARD_FAB2_LIB.BASEBOARD_FAB2(SCH_1):PAGE200
  R9P6    1      A RES_0402-10.0K,1%,1/16W,CHIP,GA   I149 @BASEBOARD_FAB2_LIB.BASEBOARD_FAB2(SCH_1):PAGE200
 R1D22    1      A RES_0402-10.0K,1%,1/16W,CHIP,GA   I158 @BASEBOARD_FAB2_LIB.BASEBOARD_FAB2(SCH_1):PAGE200
 R1D23    1      A RES_0402-10.0K,1%,1/16W,CHIP,GA   I191 @BASEBOARD_FAB2_LIB.BASEBOARD_FAB2(SCH_1):PAGE200
 R9P10    1      A RES_0402-10.0K,1%,1/16W,CHIP,GA   I192 @BASEBOARD_FAB2_LIB.BASEBOARD_FAB2(SCH_1):PAGE200
  U9P2    2    VDD TPS3700_SM-IC,H69492-001   I200 @BASEBOARD_FAB2_LIB.BASEBOARD_FAB2(SCH_1):PAGE200
 C9P11    1      A CAP_A_0402V-0.1UF,16V,10%,X7R,A   I201 @BASEBOARD_FAB2_LIB.BASEBOARD_FAB2(SCH_1):PAGE200
 R1D21    1      A RES_0402-4.75K,1%,1/16W,CHIP,GA   I204 @BASEBOARD_FAB2_LIB.BASEBOARD_FAB2(SCH_1):PAGE200
  R9P4    1      A RES_0402-2.7K,1%,1/16W,CHIP,G2A   I210 @BASEBOARD_FAB2_LIB.BASEBOARD_FAB2(SCH_1):PAGE200
  R9P5    1      A RES_0402-10.0K,1%,1/16W,CHIP,GA   I215 @BASEBOARD_FAB2_LIB.BASEBOARD_FAB2(SCH_1):PAGE200
 R4D31    1      A RES_0402-2.26K,1.0%,1/16W,EMPTA    I22 @BASEBOARD_FAB2_LIB.BASEBOARD_FAB2(SCH_1):PAGE201
 R4D58    1      A RES_0402-1.00K,1%,1/16W,CHIP,GA    I25 @BASEBOARD_FAB2_LIB.BASEBOARD_FAB2(SCH_1):PAGE201
  R4E5    1      A RES_0402-1.00K,1%,1/16W,CHIP,GA    I27 @BASEBOARD_FAB2_LIB.BASEBOARD_FAB2(SCH_1):PAGE201
 R4D26    1      A RES_0402-0.0,5%,1/16W,CHIP,G21A    I40 @BASEBOARD_FAB2_LIB.BASEBOARD_FAB2(SCH_1):PAGE201
 R6P32    1      A RES_0402-2.0K,1%,1/16W,EMPTY,GA   I102 @BASEBOARD_FAB2_LIB.BASEBOARD_FAB2(SCH_1):PAGE201
 R6P37    1      A RES_0402-2.0K,1%,1/16W,EMPTY,GA   I103 @BASEBOARD_FAB2_LIB.BASEBOARD_FAB2(SCH_1):PAGE201
  R4E3    1      A RES_0402-1.00K,1%,1/16W,CHIP,GA   I111 @BASEBOARD_FAB2_LIB.BASEBOARD_FAB2(SCH_1):PAGE201
 R4E20    1      A RES_0402-2.26K,1.0%,1/16W,EMPTA   I116 @BASEBOARD_FAB2_LIB.BASEBOARD_FAB2(SCH_1):PAGE201
  R1D6    1      A RES_0402-1.00K,1%,1/16W,CHIP,GA     I6 @BASEBOARD_FAB2_LIB.BASEBOARD_FAB2(SCH_1):PAGE206
 R1D53    1      A RES_0402-2.26K,1.0%,1/16W,EMPTA    I33 @BASEBOARD_FAB2_LIB.BASEBOARD_FAB2(SCH_1):PAGE206
 R1C18    1      A RES_0402-2.26K,1.0%,1/16W,EMPTA    I34 @BASEBOARD_FAB2_LIB.BASEBOARD_FAB2(SCH_1):PAGE206
 R1C28    1      A RES_0402-1.00K,1%,1/16W,CHIP,GA    I35 @BASEBOARD_FAB2_LIB.BASEBOARD_FAB2(SCH_1):PAGE206
  R1D8    1      A RES_0402-1.00K,1%,1/16W,CHIP,GA    I36 @BASEBOARD_FAB2_LIB.BASEBOARD_FAB2(SCH_1):PAGE206
 R1C14    1      A RES_0402-0.0,5%,1/16W,CHIP,G21A    I46 @BASEBOARD_FAB2_LIB.BASEBOARD_FAB2(SCH_1):PAGE206
 R3P22    1      A RES_0402-0.0,5%,1/16W,CHIP,G21A    I24 @BASEBOARD_FAB2_LIB.BASEBOARD_FAB2(SCH_1):PAGE211
 R3P25    1      A RES_0402-1.00K,1%,1/16W,CHIP,GA    I56 @BASEBOARD_FAB2_LIB.BASEBOARD_FAB2(SCH_1):PAGE211
 R3N23    1      A RES_0402-2.26K,1.0%,1/16W,EMPTA    I60 @BASEBOARD_FAB2_LIB.BASEBOARD_FAB2(SCH_1):PAGE211
 R3P18    1      A RES_0402-1.00K,1%,1/16W,CHIP,GA    I64 @BASEBOARD_FAB2_LIB.BASEBOARD_FAB2(SCH_1):PAGE211
 R3P21    1      A RES_0402-100.0K,1%,1/16W,EMPTYA    I88 @BASEBOARD_FAB2_LIB.BASEBOARD_FAB2(SCH_1):PAGE211
 R6P49    1      A RES_0402-2.26K,1.0%,1/16W,EMPTA    I14 @BASEBOARD_FAB2_LIB.BASEBOARD_FAB2(SCH_1):PAGE213
 R4D42    1      A RES_0402-1.00K,1%,1/16W,CHIP,GA    I15 @BASEBOARD_FAB2_LIB.BASEBOARD_FAB2(SCH_1):PAGE213
 R4D47    1      A RES_0402-0.0,5%,1/16W,CHIP,G21A    I25 @BASEBOARD_FAB2_LIB.BASEBOARD_FAB2(SCH_1):PAGE213
 R4D49    1      A RES_0402-1.00K,1%,1/16W,CHIP,GA    I63 @BASEBOARD_FAB2_LIB.BASEBOARD_FAB2(SCH_1):PAGE213
 R6P40    1      A RES_0402-100.0K,1%,1/16W,EMPTYA    I91 @BASEBOARD_FAB2_LIB.BASEBOARD_FAB2(SCH_1):PAGE213
  R3M5    1      A RES_0402-100.0K,1%,1/16W,EMPTYA    I34 @BASEBOARD_FAB2_LIB.BASEBOARD_FAB2(SCH_1):PAGE218
  R3M1    1      A RES_0402-0.0,5%,1/16W,CHIP,G21A    I35 @BASEBOARD_FAB2_LIB.BASEBOARD_FAB2(SCH_1):PAGE218
  R1B2    1      A RES_0402-1.00K,1%,1/16W,CHIP,GA    I50 @BASEBOARD_FAB2_LIB.BASEBOARD_FAB2(SCH_1):PAGE226
 R7F19    1      A RES_0402-1.00K,1%,1/16W,CHIP,GA   I143 @BASEBOARD_FAB2_LIB.BASEBOARD_FAB2(SCH_1):PAGE231
 R7B17    1      A RES_0402-1.00K,1%,1/16W,CHIP,GA   I210 @BASEBOARD_FAB2_LIB.BASEBOARD_FAB2(SCH_1):PAGE232
 R4G14    1      A RES_0402-1.00K,1%,1/16W,CHIP,GA   I185 @BASEBOARD_FAB2_LIB.BASEBOARD_FAB2(SCH_1):PAGE233
 R4B10    1      A RES_0402-1.00K,1%,1/16W,CHIP,GA   I143 @BASEBOARD_FAB2_LIB.BASEBOARD_FAB2(SCH_1):PAGE234
 R2L24    1      A RES_0402-2.26K,1.0%,1/16W,EMPTA   I148 @BASEBOARD_FAB2_LIB.BASEBOARD_FAB2(SCH_1):PAGE235
  R8A6    1      A RES_0402-1.00K,1%,1/16W,CHIP,GA   I149 @BASEBOARD_FAB2_LIB.BASEBOARD_FAB2(SCH_1):PAGE235
 R2L14    1      A RES_0402-0.0,5%,1/16W,CHIP,G21A   I159 @BASEBOARD_FAB2_LIB.BASEBOARD_FAB2(SCH_1):PAGE235
  R8A5    1      A RES_0402-1.00K,1%,1/16W,CHIP,GA   I216 @BASEBOARD_FAB2_LIB.BASEBOARD_FAB2(SCH_1):PAGE235
  R8A7    1      A RES_0402-100.0K,1%,1/16W,EMPTYA   I222 @BASEBOARD_FAB2_LIB.BASEBOARD_FAB2(SCH_1):PAGE235
 R8A10    1      A RES_0402-5.11K,1%,1/16W,CHIP,GA     I3 @BASEBOARD_FAB2_LIB.BASEBOARD_FAB2(SCH_1):PAGE237
  C8A6    1      A CAP_0603-10UF,6.3V,20%,X6S,E15A    I29 @BASEBOARD_FAB2_LIB.BASEBOARD_FAB2(SCH_1):PAGE237
  C8A4    1      A CAP_0603LF-0.1UF,25V,10%,X7R,6A    I31 @BASEBOARD_FAB2_LIB.BASEBOARD_FAB2(SCH_1):PAGE237
 EU8A2   10    VDD RT9059_DFN-IC,H65765-001    I86 @BASEBOARD_FAB2_LIB.BASEBOARD_FAB2(SCH_1):PAGE237
 EU8A2    7 VIN<0> RT9059_DFN-IC,H65765-001    I86 @BASEBOARD_FAB2_LIB.BASEBOARD_FAB2(SCH_1):PAGE237
 EU8A2    8 VIN<1> RT9059_DFN-IC,H65765-001    I86 @BASEBOARD_FAB2_LIB.BASEBOARD_FAB2(SCH_1):PAGE237
 EU8A2    9 VIN<2> RT9059_DFN-IC,H65765-001    I86 @BASEBOARD_FAB2_LIB.BASEBOARD_FAB2(SCH_1):PAGE237
  C9F3    1      A CAP_0603-10UF,6.3V,20%,X6S,E15A     I7 @BASEBOARD_FAB2_LIB.BASEBOARD_FAB2(SCH_1):PAGE238
 R9F13    1      A RES_0402-10.0K,1%,1/16W,CHIP,GA    I21 @BASEBOARD_FAB2_LIB.BASEBOARD_FAB2(SCH_1):PAGE238
 C9E11    1      A CAP_0402-1.0UF,16V,10%,X6S,D97A    I39 @BASEBOARD_FAB2_LIB.BASEBOARD_FAB2(SCH_1):PAGE238
 EU9F1   10    VDD RT9059_DFN-IC,H65765-001    I40 @BASEBOARD_FAB2_LIB.BASEBOARD_FAB2(SCH_1):PAGE238
 EU9F1    7 VIN<0> RT9059_DFN-IC,H65765-001    I40 @BASEBOARD_FAB2_LIB.BASEBOARD_FAB2(SCH_1):PAGE238
 EU9F1    8 VIN<1> RT9059_DFN-IC,H65765-001    I40 @BASEBOARD_FAB2_LIB.BASEBOARD_FAB2(SCH_1):PAGE238
 EU9F1    9 VIN<2> RT9059_DFN-IC,H65765-001    I40 @BASEBOARD_FAB2_LIB.BASEBOARD_FAB2(SCH_1):PAGE238
 R9F12    1      A RES_0402-10.0K,1%,1/16W,CHIP,GA     I6 @BASEBOARD_FAB2_LIB.BASEBOARD_FAB2(SCH_1):PAGE239
  C1T7    1      A CAP_0603-10UF,6.3V,20%,X6S,E15A    I22 @BASEBOARD_FAB2_LIB.BASEBOARD_FAB2(SCH_1):PAGE239
 EU9F2   10    VDD RT9059_DFN-IC,H65765-001    I70 @BASEBOARD_FAB2_LIB.BASEBOARD_FAB2(SCH_1):PAGE239
 EU9F2    7 VIN<0> RT9059_DFN-IC,H65765-001    I70 @BASEBOARD_FAB2_LIB.BASEBOARD_FAB2(SCH_1):PAGE239
 EU9F2    8 VIN<1> RT9059_DFN-IC,H65765-001    I70 @BASEBOARD_FAB2_LIB.BASEBOARD_FAB2(SCH_1):PAGE239
 EU9F2    9 VIN<2> RT9059_DFN-IC,H65765-001    I70 @BASEBOARD_FAB2_LIB.BASEBOARD_FAB2(SCH_1):PAGE239
  C9F5    1      A CAP_A_0402V-0.1UF,16V,10%,X7R,A    I71 @BASEBOARD_FAB2_LIB.BASEBOARD_FAB2(SCH_1):PAGE239
  R8F5    1      A RES_0402-1.00K,1%,1/16W,CHIP,GA   I117 @BASEBOARD_FAB2_LIB.BASEBOARD_FAB2(SCH_1):PAGE240
 R8E25    1      A RES_0402-0.0,5%,1/16W,CHIP,G21A   I144 @BASEBOARD_FAB2_LIB.BASEBOARD_FAB2(SCH_1):PAGE240
  R2T4    1      A RES_0402-1.0K,0.1%,1/16W,CHIP,A   I152 @BASEBOARD_FAB2_LIB.BASEBOARD_FAB2(SCH_1):PAGE240
  C2T7    1      A CAP_0805-22UF,6.3V,20%,X6S,C95A   I158 @BASEBOARD_FAB2_LIB.BASEBOARD_FAB2(SCH_1):PAGE240
  C2T6    1      A CAP_0805-22UF,6.3V,20%,X6S,C95A   I160 @BASEBOARD_FAB2_LIB.BASEBOARD_FAB2(SCH_1):PAGE240
  C2T9    1      A CAP_0805-22UF,6.3V,20%,X6S,C95A   I174 @BASEBOARD_FAB2_LIB.BASEBOARD_FAB2(SCH_1):PAGE240
 R8E40    1      A RES_0402-100.0K,1%,1/16W,EMPTYA   I177 @BASEBOARD_FAB2_LIB.BASEBOARD_FAB2(SCH_1):PAGE240
 RN8F3    1      A RES_0402-4.75K,1%,1/16W,CHIP,GA    I11 @BASEBOARD_FAB2_LIB.BASEBOARD_FAB2(SCH_1):PAGE246
 RN8F4    1      A RES_0402-4.75K,1%,1/16W,EMPTY,A    I12 @BASEBOARD_FAB2_LIB.BASEBOARD_FAB2(SCH_1):PAGE246
 UN8F2    2    VCC W25Q256_XSOI-IC,H25002-001    I17 @BASEBOARD_FAB2_LIB.BASEBOARD_FAB2(SCH_1):PAGE246
 R6W10    1      A RES_0402-4.75K,1%,1/16W,CHIP,GA     I1 @BASEBOARD_FAB2_LIB.BASEBOARD_FAB2(SCH_1):PAGE247
  R3W7    1      A RES_0402-4.75K,1%,1/16W,CHIP,GA     I8 @BASEBOARD_FAB2_LIB.BASEBOARD_FAB2(SCH_1):PAGE249
EU25F2   10    VDD RT9059_DFN-IC,H65765-001    I73 @BASEBOARD_FAB2_LIB.BASEBOARD_FAB2(SCH_1):PAGE239
EU25F2    7 VIN<0> RT9059_DFN-IC,H65765-001    I73 @BASEBOARD_FAB2_LIB.BASEBOARD_FAB2(SCH_1):PAGE239
EU25F2    8 VIN<1> RT9059_DFN-IC,H65765-001    I73 @BASEBOARD_FAB2_LIB.BASEBOARD_FAB2(SCH_1):PAGE239
EU25F2    9 VIN<2> RT9059_DFN-IC,H65765-001    I73 @BASEBOARD_FAB2_LIB.BASEBOARD_FAB2(SCH_1):PAGE239
 R9W12    1      A RES_0402-10.0K,1%,1/16W,CHIP,GA    I79 @BASEBOARD_FAB2_LIB.BASEBOARD_FAB2(SCH_1):PAGE239
  C9W5    1      A CAP_A_0402V-0.1UF,16V,10%,X7R,A    I90 @BASEBOARD_FAB2_LIB.BASEBOARD_FAB2(SCH_1):PAGE239
  C1W7    1      A CAP_0603-10UF,6.3V,20%,X6S,E15A    I92 @BASEBOARD_FAB2_LIB.BASEBOARD_FAB2(SCH_1):PAGE239
  Y9F2    4    VDD OSC_C_SM4-24MHZ,OSC,D34520-021     I8 @BASEBOARD_FAB2_LIB.BASEBOARD_FAB2(SCH_1):PAGE145
 R9F61    1      A RES_0402-10.0K,1%,1/16W,CHIP,GA    I14 @BASEBOARD_FAB2_LIB.BASEBOARD_FAB2(SCH_1):PAGE145
 C9F23    1      A CAP_A_0402V-0.1UF,16V,10%,X7R,A    I15 @BASEBOARD_FAB2_LIB.BASEBOARD_FAB2(SCH_1):PAGE145
R25W79    1      A RES_0402-10.0K,1%,1/16W,CHIP,GA    I42 @BASEBOARD_FAB2_LIB.BASEBOARD_FAB2(SCH_1):PAGE147
R25W80    1      A RES_0402-10.0K,1%,1/16W,CHIP,GA    I43 @BASEBOARD_FAB2_LIB.BASEBOARD_FAB2(SCH_1):PAGE147
R25W59    1      A RES_0402-0.0,5%,1/16W,CHIP,G21A    I16 @BASEBOARD_FAB2_LIB.BASEBOARD_FAB2(SCH_1):PAGE148
  C6W3    1      A CAP_A_0402V-0.1UF,16V,10%,X7R,A    I85 @BASEBOARD_FAB2_LIB.BASEBOARD_FAB2(SCH_1):PAGE247
 R6W21    1      A RES_0402-1.00K,1%,1/16W,CHIP,GA    I90 @BASEBOARD_FAB2_LIB.BASEBOARD_FAB2(SCH_1):PAGE247
 U25W4  J17 LPVDD0 AST2520A1-GP-GP_ASIC2-GB1-AST2A    I28 @BASEBOARD_FAB2_LIB.BASEBOARD_FAB2(SCH_1):PAGE148
 U25W4  K17 LPVDD1 AST2520A1-GP-GP_ASIC2-GB1-AST2A    I28 @BASEBOARD_FAB2_LIB.BASEBOARD_FAB2(SCH_1):PAGE148
 U25W4  F10 R1VDD0 AST2520A1-GP-GP_ASIC2-GB1-AST2A    I28 @BASEBOARD_FAB2_LIB.BASEBOARD_FAB2(SCH_1):PAGE148
 U25W4  F11 R1VDD1 AST2520A1-GP-GP_ASIC2-GB1-AST2A    I28 @BASEBOARD_FAB2_LIB.BASEBOARD_FAB2(SCH_1):PAGE148
 U25W4   F7 R2VDD0 AST2520A1-GP-GP_ASIC2-GB1-AST2A    I28 @BASEBOARD_FAB2_LIB.BASEBOARD_FAB2(SCH_1):PAGE148
 U25W4   F8 R2VDD1 AST2520A1-GP-GP_ASIC2-GB1-AST2A    I28 @BASEBOARD_FAB2_LIB.BASEBOARD_FAB2(SCH_1):PAGE148
  U3T1    2    VCC W25Q256FVFIG-GP_MEMORY-G4-W25QA   I185 @BASEBOARD_FAB2_LIB.BASEBOARD_FAB2(SCH_1):PAGE153
 R6W11    2      B RES_0402-4.75K,1%,1/16W,CHIP,GA    I98 @BASEBOARD_FAB2_LIB.BASEBOARD_FAB2(SCH_1):PAGE247
 R6W12    2      B RES_0402-4.75K,1%,1/16W,CHIP,GA    I99 @BASEBOARD_FAB2_LIB.BASEBOARD_FAB2(SCH_1):PAGE247
 FB2T1    1      1 HCB1608KF-800T30-GP_DISCRET-G9A    I22 @BASEBOARD_FAB2_LIB.BASEBOARD_FAB2(SCH_1):PAGE149
C25W50    1      A CAP_0603-4.7UF,6.3V,10%,X6S,E1A    I31 @BASEBOARD_FAB2_LIB.BASEBOARD_FAB2(SCH_1):PAGE149
C25W62    1      A CAP_0603-4.7UF,6.3V,10%,X6S,E1A    I40 @BASEBOARD_FAB2_LIB.BASEBOARD_FAB2(SCH_1):PAGE149
 FB2T3    1      1 HCB1608KF-800T30-GP_DISCRET-G9A    I85 @BASEBOARD_FAB2_LIB.BASEBOARD_FAB2(SCH_1):PAGE149
 FB2T4    1      1 HCB1608KF-800T30-GP_DISCRET-G9A    I86 @BASEBOARD_FAB2_LIB.BASEBOARD_FAB2(SCH_1):PAGE149
 FB2T5    1      1 HCB1608KF-800T30-GP_DISCRET-G9A    I88 @BASEBOARD_FAB2_LIB.BASEBOARD_FAB2(SCH_1):PAGE149
 R9E24    2      B RES_0402-221,1.0%,1/16W,CHIP,GA   I138 @BASEBOARD_FAB2_LIB.BASEBOARD_FAB2(SCH_1):PAGE151
 R9E21    1      A RES_0402-4.75K,1%,1/16W,CHIP,GA   I173 @BASEBOARD_FAB2_LIB.BASEBOARD_FAB2(SCH_1):PAGE151
 R8B25    1      A RES_0402-4.75K,1%,1/16W,CHIP,GA   I175 @BASEBOARD_FAB2_LIB.BASEBOARD_FAB2(SCH_1):PAGE151
R25W95    1      A RES_0402-4.75K,1%,1/16W,CHIP,GA   I144 @BASEBOARD_FAB2_LIB.BASEBOARD_FAB2(SCH_1):PAGE150
R25W96    1      A RES_0402-4.75K,1%,1/16W,CHIP,GA   I145 @BASEBOARD_FAB2_LIB.BASEBOARD_FAB2(SCH_1):PAGE150
R25W97    1      A RES_0402-4.75K,1%,1/16W,EMPTY,A   I146 @BASEBOARD_FAB2_LIB.BASEBOARD_FAB2(SCH_1):PAGE150
R25W106    1      A RES_0402-4.75K,1%,1/16W,EMPTY,A   I175 @BASEBOARD_FAB2_LIB.BASEBOARD_FAB2(SCH_1):PAGE150
R25W111    1      A RES_0402-4.75K,1%,1/16W,EMPTY,A   I180 @BASEBOARD_FAB2_LIB.BASEBOARD_FAB2(SCH_1):PAGE150
 R6W24    1      A RES_0402-4.75K,1%,1/16W,CHIP,GA   I100 @BASEBOARD_FAB2_LIB.BASEBOARD_FAB2(SCH_1):PAGE247
 R6W25    1      A RES_0402-4.75K,1%,1/16W,CHIP,GA   I101 @BASEBOARD_FAB2_LIB.BASEBOARD_FAB2(SCH_1):PAGE247
  C6W4    1      A CAP_A_0402V-0.1UF,16V,10%,X7R,A   I105 @BASEBOARD_FAB2_LIB.BASEBOARD_FAB2(SCH_1):PAGE247
  C6W2    1      A CAP_A_0402V-0.1UF,16V,10%,X7R,A   I107 @BASEBOARD_FAB2_LIB.BASEBOARD_FAB2(SCH_1):PAGE247
  C9W7    1      A CAP_A_0402V-0.1UF,16V,10%,X7R,A    I32 @BASEBOARD_FAB2_LIB.BASEBOARD_FAB2(SCH_1):PAGE248
 R9W16    1      A RES_0402-2.0K,1%,1/16W,CHIP,G2A    I34 @BASEBOARD_FAB2_LIB.BASEBOARD_FAB2(SCH_1):PAGE248
 R9W17    1      A RES_0402-2.0K,1%,1/16W,CHIP,G2A    I35 @BASEBOARD_FAB2_LIB.BASEBOARD_FAB2(SCH_1):PAGE248
 R1U23    1      A RES_0402-2.7K,1%,1/16W,CHIP,G2A    I34 @BASEBOARD_FAB2_LIB.BASEBOARD_FAB2(SCH_1):PAGE164
 R6W28    1      A RES_0402-4.75K,1%,1/16W,CHIP,GA   I112 @BASEBOARD_FAB2_LIB.BASEBOARD_FAB2(SCH_1):PAGE247
R25W93    1      A RES_0603-0,5.0%,1/10W,CHIP,G22A    I90 @BASEBOARD_FAB2_LIB.BASEBOARD_FAB2(SCH_1):PAGE149
R25W120    1      A RES_0603-0,5.0%,1/10W,CHIP,G22A    I91 @BASEBOARD_FAB2_LIB.BASEBOARD_FAB2(SCH_1):PAGE149
  R1W6    1      1 1MR2F-L-GP_SMD-RG1-1MR2F-L-GP,A     I2 @BASEBOARD_FAB2_LIB.BASEBOARD_FAB2(SCH_1):PAGE250
  R1W7    2      B RES_0402-10.0K,1%,1/16W,CHIP,GA     I6 @BASEBOARD_FAB2_LIB.BASEBOARD_FAB2(SCH_1):PAGE250
 RN8F2    1      A RES_0402-4.75K,1%,1/16W,EMPTY,A    I20 @BASEBOARD_FAB2_LIB.BASEBOARD_FAB2(SCH_1):PAGE246
  R9W1    1      A RES_0402-10.0K,1%,1/16W,CHIP,GA   I356 @BASEBOARD_FAB2_LIB.BASEBOARD_FAB2(SCH_1):PAGE186
  R2W1    1      A RES_0402-10.0K,1%,1/16W,CHIP,GA   I174 @BASEBOARD_FAB2_LIB.BASEBOARD_FAB2(SCH_1):PAGE187
C25W60    1      A CAP_0402-1.0UF,16V,10%,X6S,D97A   I109 @BASEBOARD_FAB2_LIB.BASEBOARD_FAB2(SCH_1):PAGE149
C25W48    1      A CAP_0402-1.0UF,16V,10%,X6S,D97A   I112 @BASEBOARD_FAB2_LIB.BASEBOARD_FAB2(SCH_1):PAGE149
  R3W3    1      A RES_0402-10.0K,1%,1/16W,EMPTY,A    I36 @BASEBOARD_FAB2_LIB.BASEBOARD_FAB2(SCH_1):PAGE249
  U2R1    5    VCC TC7PZ14FU-GP_DISCRET-GA1-TC7PZA   I390 @BASEBOARD_FAB2_LIB.BASEBOARD_FAB2(SCH_1):PAGE157
  U9A3    5    VCC TC7PZ14FU-GP_DISCRET-GA1-TC7PZA    I93 @BASEBOARD_FAB2_LIB.BASEBOARD_FAB2(SCH_1):PAGE175
  U9A4    5    VCC TC7PZ14FU-GP_DISCRET-GA1-TC7PZA    I97 @BASEBOARD_FAB2_LIB.BASEBOARD_FAB2(SCH_1):PAGE175
  U8F3    5    VCC SN74LVC2G07DCKR-GP_DISCRET-G4-A   I340 @BASEBOARD_FAB2_LIB.BASEBOARD_FAB2(SCH_1):PAGE156
  U8G1    5    VCC SN74LVC2G07DCKR-GP_DISCRET-G4-A   I342 @BASEBOARD_FAB2_LIB.BASEBOARD_FAB2(SCH_1):PAGE156
 R10W2    1      A RES_0402-4.75K,1%,1/16W,CHIP,GA    I15 @BASEBOARD_FAB2_LIB.BASEBOARD_FAB2(SCH_1):PAGE251
 C10W4    1      A CAP_A_0402V-0.1UF,16V,10%,X7R,A    I21 @BASEBOARD_FAB2_LIB.BASEBOARD_FAB2(SCH_1):PAGE251
  R1W1    1      1 1MR2F-L-GP_SMD-RG1-1MR2F-L-GP,A    I18 @BASEBOARD_FAB2_LIB.BASEBOARD_FAB2(SCH_1):PAGE250
  R1W4    2      B RES_0402-10.0K,1%,1/16W,CHIP,GA    I22 @BASEBOARD_FAB2_LIB.BASEBOARD_FAB2(SCH_1):PAGE250
  R1W3    1      1 1MR2F-L-GP_SMD-RG1-1MR2F-L-GP,A    I27 @BASEBOARD_FAB2_LIB.BASEBOARD_FAB2(SCH_1):PAGE250
 R1D10    1      A RES_0402-10.0K,1%,1/16W,CHIP,GA   I244 @BASEBOARD_FAB2_LIB.BASEBOARD_FAB2(SCH_1):PAGE200
R25W107    1      A RES_0402-4.75K,1%,1/16W,CHIP,GA   I190 @BASEBOARD_FAB2_LIB.BASEBOARD_FAB2(SCH_1):PAGE150
R25W108    1      A RES_0402-4.75K,1%,1/16W,EMPTY,A   I191 @BASEBOARD_FAB2_LIB.BASEBOARD_FAB2(SCH_1):PAGE150
  U1B2    8   VCCB TCA9517DGKR-GP_DISCRET-G8-TCA9A    I28 @BASEBOARD_FAB2_LIB.BASEBOARD_FAB2(SCH_1):PAGE163
  U6W2    1   VCCA TCA9517DGKR-GP_DISCRET-G8-TCA9A   I118 @BASEBOARD_FAB2_LIB.BASEBOARD_FAB2(SCH_1):PAGE247
  U6W2    8   VCCB TCA9517DGKR-GP_DISCRET-G8-TCA9A   I118 @BASEBOARD_FAB2_LIB.BASEBOARD_FAB2(SCH_1):PAGE247
  U1W2    8   VCCB TCA9517DGKR-GP_DISCRET-G8-TCA9A    I49 @BASEBOARD_FAB2_LIB.BASEBOARD_FAB2(SCH_1):PAGE248
 R8D16    1      A RES_0402-10.0K,1%,1/16W,CHIP,GA    I85 @BASEBOARD_FAB2_LIB.BASEBOARD_FAB2(SCH_1):PAGE125
 R8D13    1      A RES_0402-10.0K,1%,1/16W,EMPTY,A    I87 @BASEBOARD_FAB2_LIB.BASEBOARD_FAB2(SCH_1):PAGE125
C22W34    1      1 SC22U16V5MX-4-GP_SMD-BCG5-SC22A   I244 @BASEBOARD_FAB2_LIB.BASEBOARD_FAB2(SCH_1):PAGE139
  C9F2    1      1 SC22U16V5MX-4-GP_SMD-BCG5-SC22A   I245 @BASEBOARD_FAB2_LIB.BASEBOARD_FAB2(SCH_1):PAGE139
 R2N10    1      A RES_0402-4.75K,1%,1/16W,EMPTY,A    I27 @BASEBOARD_FAB2_LIB.BASEBOARD_FAB2(SCH_1):PAGE126
  U6W1   24    VCC TCA9555PWR-GP_DISCRET-GC1-TCA9A   I120 @BASEBOARD_FAB2_LIB.BASEBOARD_FAB2(SCH_1):PAGE247
 R2U30    1      A RES_0402-4.75K,1%,1/16W,EMPTY,A    I88 @BASEBOARD_FAB2_LIB.BASEBOARD_FAB2(SCH_1):PAGE125
 R9F55    1      A RES_0402-4.75K,1%,1/16W,CHIP,GA     I3 @BASEBOARD_FAB2_LIB.BASEBOARD_FAB2(SCH_1):PAGE183
  C9G2    1      A CAP_0402LF-470PF,50V,10%,X7R,AA   I152 @BASEBOARD_FAB2_LIB.BASEBOARD_FAB2(SCH_1):PAGE141
  R9G4    2      B RES_0402-0.0,5%,1/16W,CHIP,G21A   I156 @BASEBOARD_FAB2_LIB.BASEBOARD_FAB2(SCH_1):PAGE141
 R1L19    1      A RES_0402-4.75K,1%,1/16W,CHIP,GA    I99 @BASEBOARD_FAB2_LIB.BASEBOARD_FAB2(SCH_1):PAGE175
 R1L28    1      A RES_0402-4.75K,1%,1/16W,EMPTY,A    I97 @BASEBOARD_FAB2_LIB.BASEBOARD_FAB2(SCH_1):PAGE111
  L8F1    2      2 IND-1UH-361-GP_DISCRET-GC1-INDA   I188 @BASEBOARD_FAB2_LIB.BASEBOARD_FAB2(SCH_1):PAGE240
 C8F14    1      1 ST470U6D3VDM-7-GP_SMD-TCG4-ST4A   I189 @BASEBOARD_FAB2_LIB.BASEBOARD_FAB2(SCH_1):PAGE240
  C8F8    1      1 ST470U6D3VDM-7-GP_SMD-TCG4-ST4A   I190 @BASEBOARD_FAB2_LIB.BASEBOARD_FAB2(SCH_1):PAGE240
  R4W1    1      A RES_0402-4.75K,1%,1/16W,CHIP,GA   I195 @BASEBOARD_FAB2_LIB.BASEBOARD_FAB2(SCH_1):PAGE191
  R4E4    1      A RES_0402-1.00K,1%,1/16W,CHIP,GA   I187 @BASEBOARD_FAB2_LIB.BASEBOARD_FAB2(SCH_1):PAGE201
  R1D7    1      A RES_0402-1.00K,1%,1/16W,CHIP,GA   I155 @BASEBOARD_FAB2_LIB.BASEBOARD_FAB2(SCH_1):PAGE206
R25W105    1      A RES_0402-4.75K,1%,1/16W,EMPTY,A   I196 @BASEBOARD_FAB2_LIB.BASEBOARD_FAB2(SCH_1):PAGE150
 R8F13    1      A RES_0402-4.75K,1%,1/16W,CHIP,GA    I35 @BASEBOARD_FAB2_LIB.BASEBOARD_FAB2(SCH_1):PAGE162
R25W98    1      A RES_0402-4.75K,1%,1/16W,EMPTY,A   I209 @BASEBOARD_FAB2_LIB.BASEBOARD_FAB2(SCH_1):PAGE150
R25W99    1      A RES_0402-4.75K,1%,1/16W,EMPTY,A   I210 @BASEBOARD_FAB2_LIB.BASEBOARD_FAB2(SCH_1):PAGE150
R25W100    1      A RES_0402-4.75K,1%,1/16W,CHIP,GA   I211 @BASEBOARD_FAB2_LIB.BASEBOARD_FAB2(SCH_1):PAGE150
R25W103    1      A RES_0402-4.75K,1%,1/16W,EMPTY,A   I214 @BASEBOARD_FAB2_LIB.BASEBOARD_FAB2(SCH_1):PAGE150
R25W104    1      A RES_0402-4.75K,1%,1/16W,CHIP,GA   I215 @BASEBOARD_FAB2_LIB.BASEBOARD_FAB2(SCH_1):PAGE150
R25W112    1      A RES_0402-4.75K,1%,1/16W,EMPTY,A   I228 @BASEBOARD_FAB2_LIB.BASEBOARD_FAB2(SCH_1):PAGE150
R25W113    1      A RES_0402-4.75K,1%,1/16W,EMPTY,A   I230 @BASEBOARD_FAB2_LIB.BASEBOARD_FAB2(SCH_1):PAGE150
R25W114    1      A RES_0402-4.75K,1%,1/16W,EMPTY,A   I218 @BASEBOARD_FAB2_LIB.BASEBOARD_FAB2(SCH_1):PAGE150
R25W110    1      A RES_0402-4.75K,1%,1/16W,EMPTY,A   I233 @BASEBOARD_FAB2_LIB.BASEBOARD_FAB2(SCH_1):PAGE150
R25W109    1      A RES_0402-4.75K,1%,1/16W,CHIP,GA   I236 @BASEBOARD_FAB2_LIB.BASEBOARD_FAB2(SCH_1):PAGE150
R25W102    1      A RES_0402-4.75K,1%,1/16W,EMPTY,A   I239 @BASEBOARD_FAB2_LIB.BASEBOARD_FAB2(SCH_1):PAGE150
 R8B24    1      A RES_0402-3.3K,5%,1/16W,CHIP,G2A   I186 @BASEBOARD_FAB2_LIB.BASEBOARD_FAB2(SCH_1):PAGE138
 R8B26    1      A RES_0402-3.3K,5%,1/16W,CHIP,G2A   I187 @BASEBOARD_FAB2_LIB.BASEBOARD_FAB2(SCH_1):PAGE138
R25W153    1      A RES_0402-4.75K,1%,1/16W,CHIP,GA   I396 @BASEBOARD_FAB2_LIB.BASEBOARD_FAB2(SCH_1):PAGE157
 RN8F1    1      A RES_0402-4.75K,1%,1/16W,CHIP,GA   I142 @BASEBOARD_FAB2_LIB.BASEBOARD_FAB2(SCH_1):PAGE137
 R7F20    1      A RES_0402-100.0K,1%,1/16W,EMPTYA    I29 @BASEBOARD_FAB2_LIB.BASEBOARD_FAB2(SCH_1):PAGE215
 R3T13    1      A RES_0402-0.0,5%,1/16W,CHIP,G21A    I33 @BASEBOARD_FAB2_LIB.BASEBOARD_FAB2(SCH_1):PAGE215
 R7F27    1      A RES_0402-1.00K,1%,1/16W,CHIP,GA    I50 @BASEBOARD_FAB2_LIB.BASEBOARD_FAB2(SCH_1):PAGE215
 R7F22    1      A RES_0402-1.00K,1%,1/16W,CHIP,GA    I51 @BASEBOARD_FAB2_LIB.BASEBOARD_FAB2(SCH_1):PAGE215
  R7B4    1      A RES_0402-1.00K,1%,1/16W,CHIP,GA    I57 @BASEBOARD_FAB2_LIB.BASEBOARD_FAB2(SCH_1):PAGE218
  R7B5    1      A RES_0402-1.00K,1%,1/16W,CHIP,GA    I58 @BASEBOARD_FAB2_LIB.BASEBOARD_FAB2(SCH_1):PAGE218
  R9U8    1      A RES_0402-100.0K,1%,1/16W,EMPTYA    I31 @BASEBOARD_FAB2_LIB.BASEBOARD_FAB2(SCH_1):PAGE223
 R1G16    1      A RES_0402-1.00K,1%,1/16W,CHIP,GA    I48 @BASEBOARD_FAB2_LIB.BASEBOARD_FAB2(SCH_1):PAGE223
 R1G11    1      A RES_0402-1.00K,1%,1/16W,CHIP,GA    I49 @BASEBOARD_FAB2_LIB.BASEBOARD_FAB2(SCH_1):PAGE223
 R9U10    1      A RES_0402-0.0,5%,1/16W,CHIP,G21A    I32 @BASEBOARD_FAB2_LIB.BASEBOARD_FAB2(SCH_1):PAGE223
  R9M5    1      A RES_0402-100.0K,1%,1/16W,EMPTYA    I34 @BASEBOARD_FAB2_LIB.BASEBOARD_FAB2(SCH_1):PAGE226
  R1B1    1      A RES_0402-1.00K,1%,1/16W,CHIP,GA    I49 @BASEBOARD_FAB2_LIB.BASEBOARD_FAB2(SCH_1):PAGE226
  R9M3    1      A RES_0402-0.0,5%,1/16W,CHIP,G21A    I36 @BASEBOARD_FAB2_LIB.BASEBOARD_FAB2(SCH_1):PAGE226
  C8E1    1      A CAP_A_0402V-0.1UF,16V,10%,X7R,A    I34 @BASEBOARD_FAB2_LIB.BASEBOARD_FAB2(SCH_1):PAGE181
  R7D9    1      A RES_0402-2.26K,1.0%,1/16W,CHIPA    I80 @BASEBOARD_FAB2_LIB.BASEBOARD_FAB2(SCH_1):PAGE181
 R3P61    1      A RES_0402-2.26K,1.0%,1/16W,CHIPA    I81 @BASEBOARD_FAB2_LIB.BASEBOARD_FAB2(SCH_1):PAGE181
  R7D5    1      A RES_0402-2.26K,1.0%,1/16W,CHIPA    I82 @BASEBOARD_FAB2_LIB.BASEBOARD_FAB2(SCH_1):PAGE181
  J1F3    1    IO1 CONN8_H62179001_PIP-CONN,H6217A   I106 @BASEBOARD_FAB2_LIB.BASEBOARD_FAB2(SCH_1):PAGE181
 R24W1    1      A RES_0402-3.3K,5%,1/16W,CHIP,G2A   I198 @BASEBOARD_FAB2_LIB.BASEBOARD_FAB2(SCH_1):PAGE138
 R24W2    1      A RES_0402-3.3K,5%,1/16W,CHIP,G2A   I199 @BASEBOARD_FAB2_LIB.BASEBOARD_FAB2(SCH_1):PAGE138
 R1U21    1      A RES_0402-2.7K,1%,1/16W,CHIP,G2A    I41 @BASEBOARD_FAB2_LIB.BASEBOARD_FAB2(SCH_1):PAGE164
 R1U22    1      A RES_0402-2.7K,1%,1/16W,CHIP,G2A    I43 @BASEBOARD_FAB2_LIB.BASEBOARD_FAB2(SCH_1):PAGE164
 CN8F1    1      A CAP_A_0402V-1.0UF,6.3V,10%,X6SA    I21 @BASEBOARD_FAB2_LIB.BASEBOARD_FAB2(SCH_1):PAGE246
 CN8F2    1      A CAP_A_0402V-0.01UF,25V,10%,X7RA    I22 @BASEBOARD_FAB2_LIB.BASEBOARD_FAB2(SCH_1):PAGE246
C25W49    1      A CAP_A_0402V-0.1UF,16V,10%,X7R,A   I123 @BASEBOARD_FAB2_LIB.BASEBOARD_FAB2(SCH_1):PAGE149
C25W61    1      A CAP_A_0402V-0.1UF,16V,10%,X7R,A   I126 @BASEBOARD_FAB2_LIB.BASEBOARD_FAB2(SCH_1):PAGE149
  C6W1    1      A CAP_A_0402V-0.1UF,16V,10%,X7R,A   I151 @BASEBOARD_FAB2_LIB.BASEBOARD_FAB2(SCH_1):PAGE247
 C6W10    1      A CAP_A_0402V-0.1UF,16V,10%,X7R,A   I139 @BASEBOARD_FAB2_LIB.BASEBOARD_FAB2(SCH_1):PAGE176
  U7W1    5    VCC PI5A3157BC6E-GP_DISCRET-GC2-PIA    I34 @BASEBOARD_FAB2_LIB.BASEBOARD_FAB2(SCH_1):PAGE166
  C7W1    1      A CAP_A_0402V-0.1UF,16V,10%,X7R,A    I36 @BASEBOARD_FAB2_LIB.BASEBOARD_FAB2(SCH_1):PAGE166
  R7W3    1      A RES_0402-10.0K,1%,1/16W,EMPTY,A    I46 @BASEBOARD_FAB2_LIB.BASEBOARD_FAB2(SCH_1):PAGE166
  R8W7    1      A RES_0402-1.37K,1%,1/16W,CHIP,GA   I202 @BASEBOARD_FAB2_LIB.BASEBOARD_FAB2(SCH_1):PAGE138
  R8W6    1      A RES_0402-1.37K,1%,1/16W,CHIP,GA   I205 @BASEBOARD_FAB2_LIB.BASEBOARD_FAB2(SCH_1):PAGE138
 R8C15    1      A RES_0402-2.0K,1%,1/16W,CHIP,G2A   I235 @BASEBOARD_FAB2_LIB.BASEBOARD_FAB2(SCH_1):PAGE159
 R8C16    1      A RES_0402-2.0K,1%,1/16W,CHIP,G2A   I237 @BASEBOARD_FAB2_LIB.BASEBOARD_FAB2(SCH_1):PAGE159
  R8W8    1      A RES_0402-1.00K,1%,1/16W,CHIP,GA   I249 @BASEBOARD_FAB2_LIB.BASEBOARD_FAB2(SCH_1):PAGE235
  R8W9    1      A RES_0402-4.75K,1%,1/16W,CHIP,GA    I49 @BASEBOARD_FAB2_LIB.BASEBOARD_FAB2(SCH_1):PAGE89
 R2N17    1      A RES_0402-2.7K,1%,1/16W,CHIP,G2A    I46 @BASEBOARD_FAB2_LIB.BASEBOARD_FAB2(SCH_1):PAGE164
 R1U24    1      A RES_0402-2.7K,1%,1/16W,CHIP,G2A    I47 @BASEBOARD_FAB2_LIB.BASEBOARD_FAB2(SCH_1):PAGE164
 R2L25    1      A RES_0402-100.0K,1%,1/16W,CHIP,A   I252 @BASEBOARD_FAB2_LIB.BASEBOARD_FAB2(SCH_1):PAGE235
 R2L26    1      A RES_0402-100.0K,1%,1/16W,CHIP,A   I253 @BASEBOARD_FAB2_LIB.BASEBOARD_FAB2(SCH_1):PAGE235
  R2P8    1      A RES_0402-4.75K,1%,1/16W,CHIP,GA    I75 @BASEBOARD_FAB2_LIB.BASEBOARD_FAB2(SCH_1):PAGE170
R25W156    1      A RES_0402-3.32K,1%,1/16W,EMPTY,A   I240 @BASEBOARD_FAB2_LIB.BASEBOARD_FAB2(SCH_1):PAGE150
  R6W1    1      A RES_0402-4.75K,1%,1/16W,CHIP,GA   I149 @BASEBOARD_FAB2_LIB.BASEBOARD_FAB2(SCH_1):PAGE137
 R6W30    1      A RES_0603-100.0K,1%,1/10W,CHIP,A   I147 @BASEBOARD_FAB2_LIB.BASEBOARD_FAB2(SCH_1):PAGE176
 R6W39    2      B RES_0402-10.0K,1%,1/16W,CHIP,GA   I158 @BASEBOARD_FAB2_LIB.BASEBOARD_FAB2(SCH_1):PAGE176
  U1W3    1   VCCA PCA9617_SSOP-IC,G81764-001-GNDA   I162 @BASEBOARD_FAB2_LIB.BASEBOARD_FAB2(SCH_1):PAGE176
  U1W3    8   VCCB PCA9617_SSOP-IC,G81764-001-GNDA   I162 @BASEBOARD_FAB2_LIB.BASEBOARD_FAB2(SCH_1):PAGE176
 C1W18    1      A CAP_A_0402V-0.1UF,16V,10%,X7R,A   I163 @BASEBOARD_FAB2_LIB.BASEBOARD_FAB2(SCH_1):PAGE176
 C1W19    1      A CAP_A_0402V-0.1UF,16V,10%,X7R,A   I166 @BASEBOARD_FAB2_LIB.BASEBOARD_FAB2(SCH_1):PAGE176
 R1W36    1      A RES_0402-4.75K,1%,1/16W,CHIP,GA   I172 @BASEBOARD_FAB2_LIB.BASEBOARD_FAB2(SCH_1):PAGE176
 R1W37    1      A RES_0402-4.75K,1%,1/16W,CHIP,GA   I173 @BASEBOARD_FAB2_LIB.BASEBOARD_FAB2(SCH_1):PAGE176
 R8E36    1      1 2K15R2F-1-GP_SMD-RG1-2K15R2F-1A    I34 @BASEBOARD_FAB2_LIB.BASEBOARD_FAB2(SCH_1):PAGE142
 R8E30    1      1 2K15R2F-1-GP_SMD-RG1-2K15R2F-1A    I35 @BASEBOARD_FAB2_LIB.BASEBOARD_FAB2(SCH_1):PAGE142
 R6W40    1      A RES_0402-10.0K,1%,1/16W,CHIP,GA   I201 @BASEBOARD_FAB2_LIB.BASEBOARD_FAB2(SCH_1):PAGE155
  R1T6    1      A RES_0402-2.7K,1%,1/16W,CHIP,G2A    I51 @BASEBOARD_FAB2_LIB.BASEBOARD_FAB2(SCH_1):PAGE164
  R6W4    1      A RES_0402-4.75K,1%,1/16W,CHIP,GA   I159 @BASEBOARD_FAB2_LIB.BASEBOARD_FAB2(SCH_1):PAGE247
  R6W5    1      A RES_0402-4.75K,1%,1/16W,CHIP,GA   I160 @BASEBOARD_FAB2_LIB.BASEBOARD_FAB2(SCH_1):PAGE247
  R6W6    1      A RES_0402-4.75K,1%,1/16W,CHIP,GA   I161 @BASEBOARD_FAB2_LIB.BASEBOARD_FAB2(SCH_1):PAGE247
 R10W7    1      A RES_0402-4.75K,1%,1/16W,CHIP,GA    I31 @BASEBOARD_FAB2_LIB.BASEBOARD_FAB2(SCH_1):PAGE251
 R6W35    1      A RES_0402-100.0K,1%,1/16W,CHIP,A   I165 @BASEBOARD_FAB2_LIB.BASEBOARD_FAB2(SCH_1):PAGE247
 U32W1    8   VCCB TCA9517DGKR-GP_DISCRET-G8-TCA9A   I191 @BASEBOARD_FAB2_LIB.BASEBOARD_FAB2(SCH_1):PAGE185
 C32W2    1      A CAP_A_0402V-0.1UF,16V,10%,X7R,A   I193 @BASEBOARD_FAB2_LIB.BASEBOARD_FAB2(SCH_1):PAGE185
 C32W4    1      A CAP_A_0402V-0.1UF,16V,10%,X7R,A   I196 @BASEBOARD_FAB2_LIB.BASEBOARD_FAB2(SCH_1):PAGE185
 U32W2    8   VCCB TCA9517DGKR-GP_DISCRET-G8-TCA9A   I204 @BASEBOARD_FAB2_LIB.BASEBOARD_FAB2(SCH_1):PAGE185
  R3W6    1      A RES_0402-4.75K,1%,1/16W,CHIP,GA    I48 @BASEBOARD_FAB2_LIB.BASEBOARD_FAB2(SCH_1):PAGE249
  R3W5    1      A RES_0402-10.0K,1%,1/16W,CHIP,GA    I58 @BASEBOARD_FAB2_LIB.BASEBOARD_FAB2(SCH_1):PAGE249
 C6W14    1      A CAP_A_0402V-0.1UF,16V,10%,X7R,A    I66 @BASEBOARD_FAB2_LIB.BASEBOARD_FAB2(SCH_1):PAGE164
 R6W44    1      A RES_0402-4.75K,1%,1/16W,CHIP,GA    I78 @BASEBOARD_FAB2_LIB.BASEBOARD_FAB2(SCH_1):PAGE164
 R6W41    1      A RES_0402-4.75K,1%,1/16W,CHIP,GA    I87 @BASEBOARD_FAB2_LIB.BASEBOARD_FAB2(SCH_1):PAGE164
R25W174    1      A RES_0402-10.0K,1%,1/16W,CHIP,GA     I4 @BASEBOARD_FAB2_LIB.BASEBOARD_FAB2(SCH_1):PAGE269
R25W177    1      A RES_0402-1.00K,1%,1/16W,CHIP,GA    I18 @BASEBOARD_FAB2_LIB.BASEBOARD_FAB2(SCH_1):PAGE269
R25W178    1      A RES_0402-1.00K,1%,1/16W,CHIP,GA    I19 @BASEBOARD_FAB2_LIB.BASEBOARD_FAB2(SCH_1):PAGE269
R25W160    1      A RES_0402-1.00K,1%,1/16W,CHIP,GA    I20 @BASEBOARD_FAB2_LIB.BASEBOARD_FAB2(SCH_1):PAGE269
R25W161    1      A RES_0402-1.00K,1%,1/16W,CHIP,GA    I21 @BASEBOARD_FAB2_LIB.BASEBOARD_FAB2(SCH_1):PAGE269
R25W158    1      A RES_0402-1.00K,1%,1/16W,CHIP,GA    I22 @BASEBOARD_FAB2_LIB.BASEBOARD_FAB2(SCH_1):PAGE269
C25W91    1      A CAP_A_0402V-1.0UF,6.3V,10%,X6SA    I26 @BASEBOARD_FAB2_LIB.BASEBOARD_FAB2(SCH_1):PAGE269
C25W94    1      A CAP_0402-1.0UF,16V,10%,X6S,D97A    I32 @BASEBOARD_FAB2_LIB.BASEBOARD_FAB2(SCH_1):PAGE269
U25W10   14    VCC GTL2014_SM-IC,D66151-001    I49 @BASEBOARD_FAB2_LIB.BASEBOARD_FAB2(SCH_1):PAGE269
R25W180    1      A RES_0402-1.00K,1%,1/16W,CHIP,GA     I2 @BASEBOARD_FAB2_LIB.BASEBOARD_FAB2(SCH_1):PAGE268
C25W97    1      A CAP_A_0402V-0.1UF,16V,10%,X7R,A     I4 @BASEBOARD_FAB2_LIB.BASEBOARD_FAB2(SCH_1):PAGE268
R25W179    1      A RES_0402-1.00K,1%,1/16W,CHIP,GA     I7 @BASEBOARD_FAB2_LIB.BASEBOARD_FAB2(SCH_1):PAGE268
C25W96    1      A CAP_A_0402V-0.1UF,16V,10%,X7R,A     I9 @BASEBOARD_FAB2_LIB.BASEBOARD_FAB2(SCH_1):PAGE268
C25W92    1      A CAP_0402-1.0UF,16V,10%,X6S,D97A    I23 @BASEBOARD_FAB2_LIB.BASEBOARD_FAB2(SCH_1):PAGE268
U25W11   14    VCC GTL2014_SM-IC,D66151-001    I33 @BASEBOARD_FAB2_LIB.BASEBOARD_FAB2(SCH_1):PAGE268
U25W13    2     V+ MAX4564EKA-GP_SCRET-GC1-MAX456A    I53 @BASEBOARD_FAB2_LIB.BASEBOARD_FAB2(SCH_1):PAGE269
C25W95    1      A CAP_A_0402V-0.1UF,16V,10%,X7R,A    I56 @BASEBOARD_FAB2_LIB.BASEBOARD_FAB2(SCH_1):PAGE269
 R6W42    1      A RES_0402-4.75K,1%,1/16W,EMPTY,A    I95 @BASEBOARD_FAB2_LIB.BASEBOARD_FAB2(SCH_1):PAGE164
 R6W43    1      A RES_0402-4.75K,1%,1/16W,EMPTY,A    I96 @BASEBOARD_FAB2_LIB.BASEBOARD_FAB2(SCH_1):PAGE164
R25W183    1      1 374R2F-1-GP_SMD-RG-374R2F-1-GPA    I36 @BASEBOARD_FAB2_LIB.BASEBOARD_FAB2(SCH_1):PAGE268
 R6W16    1      A RES_0402-1.00K,1%,1/16W,CHIP,GA    I46 @BASEBOARD_FAB2_LIB.BASEBOARD_FAB2(SCH_1):PAGE168
 U6W11   16    VCC PCA9554PWR-GP_DISCRET-G1-PCA95A    I97 @BASEBOARD_FAB2_LIB.BASEBOARD_FAB2(SCH_1):PAGE164
C1L119    1      A CAP_0402-1.0UF,16V,10%,X6S,D97A    I69 @BASEBOARD_FAB2_LIB.BASEBOARD_FAB2(SCH_1):PAGE189
  R8E3    1      A RES_0402-4.75K,1%,1/16W,CHIP,GA   I371 @BASEBOARD_FAB2_LIB.BASEBOARD_FAB2(SCH_1):PAGE133
 R7F36    1      A RES_0402-2.26K,1.0%,1/16W,CHIPA    I75 @BASEBOARD_FAB2_LIB.BASEBOARD_FAB2(SCH_1):PAGE215
  R7A9    1      A RES_0402-2.26K,1.0%,1/16W,CHIPA    I76 @BASEBOARD_FAB2_LIB.BASEBOARD_FAB2(SCH_1):PAGE218
  R1G6    1      A RES_0402-2.26K,1.0%,1/16W,CHIPA    I76 @BASEBOARD_FAB2_LIB.BASEBOARD_FAB2(SCH_1):PAGE223
 R1B13    1      A RES_0402-2.26K,1.0%,1/16W,CHIPA    I75 @BASEBOARD_FAB2_LIB.BASEBOARD_FAB2(SCH_1):PAGE226
C25W98    1      A CAP_0402-1.0UF,16V,10%,X6S,D97A    I40 @BASEBOARD_FAB2_LIB.BASEBOARD_FAB2(SCH_1):PAGE268
R25W185    1      A RES_0402-4.75K,1%,1/16W,CHIP,GA    I54 @BASEBOARD_FAB2_LIB.BASEBOARD_FAB2(SCH_1):PAGE268
C25W99    1      A CAP_A_0402V-0.1UF,16V,10%,X7R,A    I62 @BASEBOARD_FAB2_LIB.BASEBOARD_FAB2(SCH_1):PAGE269
C25W100    1      A CAP_A_0402V-0.1UF,16V,10%,X7R,A    I60 @BASEBOARD_FAB2_LIB.BASEBOARD_FAB2(SCH_1):PAGE268
 R9W33    1      A RES_0402-4.75K,1%,1/16W,CHIP,GA   I153 @BASEBOARD_FAB2_LIB.BASEBOARD_FAB2(SCH_1):PAGE158
 R9W34    1      A RES_0402-4.75K,1%,1/16W,CHIP,GA   I154 @BASEBOARD_FAB2_LIB.BASEBOARD_FAB2(SCH_1):PAGE158
 R9W35    1      A RES_0402-4.75K,1%,1/16W,CHIP,GA   I155 @BASEBOARD_FAB2_LIB.BASEBOARD_FAB2(SCH_1):PAGE158
 C9W14    1      A CAP_0603-10UF,6.3V,20%,X6S,E15A    I46 @BASEBOARD_FAB2_LIB.BASEBOARD_FAB2(SCH_1):PAGE238
 C9W17    1      A CAP_0603-10UF,6.3V,20%,X6S,E15A   I104 @BASEBOARD_FAB2_LIB.BASEBOARD_FAB2(SCH_1):PAGE239
 R9W36    1      A RES_0402-10.0K,1%,1/16W,CHIP,GA   I252 @BASEBOARD_FAB2_LIB.BASEBOARD_FAB2(SCH_1):PAGE139
 R6W50    1      A RES_0402-4.75K,1%,1/16W,CHIP,GA   I178 @BASEBOARD_FAB2_LIB.BASEBOARD_FAB2(SCH_1):PAGE176
 R1W40    1      A RES_0402-4.75K,1%,1/16W,CHIP,GA   I128 @BASEBOARD_FAB2_LIB.BASEBOARD_FAB2(SCH_1):PAGE188
 R1W42    1      A RES_0402-4.75K,1%,1/16W,CHIP,GA   I131 @BASEBOARD_FAB2_LIB.BASEBOARD_FAB2(SCH_1):PAGE188
 R1W43    1      A RES_0402-4.75K,1%,1/16W,CHIP,GA   I132 @BASEBOARD_FAB2_LIB.BASEBOARD_FAB2(SCH_1):PAGE188
 R1W44    1      A RES_0402-4.75K,1%,1/16W,CHIP,GA   I133 @BASEBOARD_FAB2_LIB.BASEBOARD_FAB2(SCH_1):PAGE188
 R1W45    1      A RES_0402-4.75K,1%,1/16W,CHIP,GA   I134 @BASEBOARD_FAB2_LIB.BASEBOARD_FAB2(SCH_1):PAGE188
C25W101    1      A CAP_A_0402V-0.1UF,16V,10%,X7R,A    I79 @BASEBOARD_FAB2_LIB.BASEBOARD_FAB2(SCH_1):PAGE269
  U8W2    5    VCC NC7SB3157_SMLF-IC,C99406-001    I66 @BASEBOARD_FAB2_LIB.BASEBOARD_FAB2(SCH_1):PAGE245
  C8W6    1      A CAP_A_0402V-0.01UF,25V,10%,X7RA    I71 @BASEBOARD_FAB2_LIB.BASEBOARD_FAB2(SCH_1):PAGE245
  C8W5    1      A CAP_A_0402V-1.0UF,6.3V,10%,X6SA    I74 @BASEBOARD_FAB2_LIB.BASEBOARD_FAB2(SCH_1):PAGE245
 R8W15    1      A RES_0402-4.75K,1%,1/16W,CHIP,GA    I78 @BASEBOARD_FAB2_LIB.BASEBOARD_FAB2(SCH_1):PAGE245
 R7W19    1      A RES_0402-4.75K,1%,1/16W,CHIP,GA   I180 @BASEBOARD_FAB2_LIB.BASEBOARD_FAB2(SCH_1):PAGE118
 R7W20    1      A RES_0402-4.75K,1%,1/16W,CHIP,GA   I278 @BASEBOARD_FAB2_LIB.BASEBOARD_FAB2(SCH_1):PAGE120
  R1T4    1      A RES_0402-2.7K,1%,1/16W,CHIP,G2A   I100 @BASEBOARD_FAB2_LIB.BASEBOARD_FAB2(SCH_1):PAGE164
R25W101    1      A RES_0402-4.75K,1%,1/16W,EMPTY,A   I241 @BASEBOARD_FAB2_LIB.BASEBOARD_FAB2(SCH_1):PAGE150
 U6W12    5    VCC NC7SB3157_SMLF-IC,C99406-001   I182 @BASEBOARD_FAB2_LIB.BASEBOARD_FAB2(SCH_1):PAGE176
 R7W22    1      A RES_0402-4.75K,1%,1/16W,CHIP,GA   I230 @BASEBOARD_FAB2_LIB.BASEBOARD_FAB2(SCH_1):PAGE119
 R7W21    1      A RES_0402-4.75K,1%,1/16W,CHIP,GA   I183 @BASEBOARD_FAB2_LIB.BASEBOARD_FAB2(SCH_1):PAGE118
R25W115    1      A RES_0402-4.75K,1%,1/16W,EMPTY,A   I242 @BASEBOARD_FAB2_LIB.BASEBOARD_FAB2(SCH_1):PAGE150

P3V3_STBY_BMC_ADCVREFN @BASEBOARD_FAB2_LIB.BASEBOARD_FAB2(SCH_1):P3V3_STBY_BMC_ADCVREFN
 U25W4   H1 ADCVREFN AST2520A1-GP-GP_ASIC2-GB1-AST2A   I106 @BASEBOARD_FAB2_LIB.BASEBOARD_FAB2(SCH_1):PAGE147
 C25W9    2      B CAP_A_0402V-0.1UF,16V,10%,X7R,A   I160 @BASEBOARD_FAB2_LIB.BASEBOARD_FAB2(SCH_1):PAGE147
 C25W8    1      A CAP_A_0402V-0.1UF,16V,10%,X7R,A   I162 @BASEBOARD_FAB2_LIB.BASEBOARD_FAB2(SCH_1):PAGE147

P3V3_STBY_BMC_ADCVREFP @BASEBOARD_FAB2_LIB.BASEBOARD_FAB2(SCH_1):P3V3_STBY_BMC_ADCVREFP
 U25W4   H2 ADCVREFP AST2520A1-GP-GP_ASIC2-GB1-AST2A   I106 @BASEBOARD_FAB2_LIB.BASEBOARD_FAB2(SCH_1):PAGE147
 C25W9    1      A CAP_A_0402V-0.1UF,16V,10%,X7R,A   I160 @BASEBOARD_FAB2_LIB.BASEBOARD_FAB2(SCH_1):PAGE147
 C25W7    1      A CAP_A_0402V-0.1UF,16V,10%,X7R,A   I161 @BASEBOARD_FAB2_LIB.BASEBOARD_FAB2(SCH_1):PAGE147

P3V3_STBY_MNG @BASEBOARD_FAB2_LIB.BASEBOARD_FAB2(SCH_1):P3V3_STBY_MNG
 EU8F2   12 VDD32K ICS9FGP204_MLFP-IC,E95226-001    I34 @BASEBOARD_FAB2_LIB.BASEBOARD_FAB2(SCH_1):PAGE101
 EU8F2   23  VDD33 ICS9FGP204_MLFP-IC,E95226-001    I34 @BASEBOARD_FAB2_LIB.BASEBOARD_FAB2(SCH_1):PAGE101
 EU8F2    2  VDD96 ICS9FGP204_MLFP-IC,E95226-001    I34 @BASEBOARD_FAB2_LIB.BASEBOARD_FAB2(SCH_1):PAGE101
 EU8F2   15 VDDREF ICS9FGP204_MLFP-IC,E95226-001    I34 @BASEBOARD_FAB2_LIB.BASEBOARD_FAB2(SCH_1):PAGE101
 R2T23    1      A RES_0603-2.2,1.0%,1/10W,CHIP,GA    I94 @BASEBOARD_FAB2_LIB.BASEBOARD_FAB2(SCH_1):PAGE101
 R2T52    1      A RES_0603-2.2,1.0%,1/10W,CHIP,GA    I95 @BASEBOARD_FAB2_LIB.BASEBOARD_FAB2(SCH_1):PAGE101
 R2T21    1      A RES_0603-2.2,1.0%,1/10W,CHIP,GA   I105 @BASEBOARD_FAB2_LIB.BASEBOARD_FAB2(SCH_1):PAGE101
 C2T34    1      A CAP_A_0402V-0.1UF,16V,10%,X7R,A   I109 @BASEBOARD_FAB2_LIB.BASEBOARD_FAB2(SCH_1):PAGE101
 C2T30    1      A CAP_A_0402V-0.1UF,16V,10%,X7R,A   I110 @BASEBOARD_FAB2_LIB.BASEBOARD_FAB2(SCH_1):PAGE101
 C2T25    1      A CAP_A_0402V-0.1UF,16V,10%,X7R,A   I111 @BASEBOARD_FAB2_LIB.BASEBOARD_FAB2(SCH_1):PAGE101
 C2T17    1      A CAP_A_0402V-0.1UF,16V,10%,X7R,A   I112 @BASEBOARD_FAB2_LIB.BASEBOARD_FAB2(SCH_1):PAGE101
 C2T22    1      A CAP_0805-10UF,16V,10%,X6S,C953A   I113 @BASEBOARD_FAB2_LIB.BASEBOARD_FAB2(SCH_1):PAGE101
 FB2T2    2      B FERRITE_SMLF-600,FB,656554-043   I114 @BASEBOARD_FAB2_LIB.BASEBOARD_FAB2(SCH_1):PAGE101

P3V3_STBY_MNG_CPU @BASEBOARD_FAB2_LIB.BASEBOARD_FAB2(SCH_1):P3V3_STBY_MNG_CPU
 EU8F2    9 VDDCPU ICS9FGP204_MLFP-IC,E95226-001    I34 @BASEBOARD_FAB2_LIB.BASEBOARD_FAB2(SCH_1):PAGE101
 C2T18    1      A CAP_A_0402V-0.01UF,25V,10%,X7RA   I104 @BASEBOARD_FAB2_LIB.BASEBOARD_FAB2(SCH_1):PAGE101
 R2T21    2      B RES_0603-2.2,1.0%,1/10W,CHIP,GA   I105 @BASEBOARD_FAB2_LIB.BASEBOARD_FAB2(SCH_1):PAGE101
 C2T19    1      A CAP_A_0402V-1.0UF,6.3V,10%,X6SA   I106 @BASEBOARD_FAB2_LIB.BASEBOARD_FAB2(SCH_1):PAGE101

P3V3_STBY_MNG_RGMII @BASEBOARD_FAB2_LIB.BASEBOARD_FAB2(SCH_1):P3V3_STBY_MNG_RGMII
 EU8F2   34 VDD_RGMII ICS9FGP204_MLFP-IC,E95226-001    I34 @BASEBOARD_FAB2_LIB.BASEBOARD_FAB2(SCH_1):PAGE101
 C2T31    1      A CAP_A_0402V-1.0UF,6.3V,10%,X6SA    I89 @BASEBOARD_FAB2_LIB.BASEBOARD_FAB2(SCH_1):PAGE101
 C2T27    1      A CAP_A_0402V-0.01UF,25V,10%,X7RA    I90 @BASEBOARD_FAB2_LIB.BASEBOARD_FAB2(SCH_1):PAGE101
 R2T23    2      B RES_0603-2.2,1.0%,1/10W,CHIP,GA    I94 @BASEBOARD_FAB2_LIB.BASEBOARD_FAB2(SCH_1):PAGE101

P3V3_STBY_MNG_RMII @BASEBOARD_FAB2_LIB.BASEBOARD_FAB2(SCH_1):P3V3_STBY_MNG_RMII
 EU8F2   26 VDDRMII<0> ICS9FGP204_MLFP-IC,E95226-001    I34 @BASEBOARD_FAB2_LIB.BASEBOARD_FAB2(SCH_1):PAGE101
 EU8F2   31 VDDRMII<1> ICS9FGP204_MLFP-IC,E95226-001    I34 @BASEBOARD_FAB2_LIB.BASEBOARD_FAB2(SCH_1):PAGE101
 R2T52    2      B RES_0603-2.2,1.0%,1/10W,CHIP,GA    I95 @BASEBOARD_FAB2_LIB.BASEBOARD_FAB2(SCH_1):PAGE101
 C2T38    1      A CAP_A_0402V-1.0UF,6.3V,10%,X6SA    I97 @BASEBOARD_FAB2_LIB.BASEBOARD_FAB2(SCH_1):PAGE101
 C2T37    1      A CAP_A_0402V-0.01UF,25V,10%,X7RA    I99 @BASEBOARD_FAB2_LIB.BASEBOARD_FAB2(SCH_1):PAGE101
 C1W17    1      A CAP_0805-10UF,16V,10%,EMPTY,C9A   I139 @BASEBOARD_FAB2_LIB.BASEBOARD_FAB2(SCH_1):PAGE101

P3V3_STBY_P1V5_LAN_I210 @BASEBOARD_FAB2_LIB.BASEBOARD_FAB2(SCH_1):P3V3_STBY_P1V5_LAN_I210
 EU9E1   51 VDD3P3<1> SPRINGVILLE_SM1-IC,G47144-004    I72 @BASEBOARD_FAB2_LIB.BASEBOARD_FAB2(SCH_1):PAGE139
 R1T34    2      B RES_0603-0,5.0%,1/10W,CHIP,G22A   I239 @BASEBOARD_FAB2_LIB.BASEBOARD_FAB2(SCH_1):PAGE139
 R1T33    2      B RES_0603-0,5.0%,1/10W,EMPTY,G2A   I240 @BASEBOARD_FAB2_LIB.BASEBOARD_FAB2(SCH_1):PAGE139

P3V3_STBY_PLD_D @BASEBOARD_FAB2_LIB.BASEBOARD_FAB2(SCH_1):P3V3_STBY_PLD_D
  J7G2    1    IO1 CONN8_C77962004_PIP-CONN,C7796A    I47 @BASEBOARD_FAB2_LIB.BASEBOARD_FAB2(SCH_1):PAGE189
 CR3U1    1      C DIODE_SMLF-1N5819HW,IC,D55839-A    I49 @BASEBOARD_FAB2_LIB.BASEBOARD_FAB2(SCH_1):PAGE189

P3V3_SWITCH_G @BASEBOARD_FAB2_LIB.BASEBOARD_FAB2(SCH_1):P3V3_SWITCH_G
 EU2T1    7      G SLG55021_SM-IC,G56246-001     I1 @BASEBOARD_FAB2_LIB.BASEBOARD_FAB2(SCH_1):PAGE198
  Q8G1    4   GATE MOSFET_N_LCC3-BSZ019N03LS,NFETA    I85 @BASEBOARD_FAB2_LIB.BASEBOARD_FAB2(SCH_1):PAGE198

P3V3_USB2A_ALG @BASEBOARD_FAB2_LIB.BASEBOARD_FAB2(SCH_1):P3V3_USB2A_ALG
 U25W4   C7 USB2AV33 AST2520A1-GP-GP_ASIC2-GB1-AST2A    I28 @BASEBOARD_FAB2_LIB.BASEBOARD_FAB2(SCH_1):PAGE148
C25W70    1      A CAP_0603-4.7UF,6.3V,10%,X6S,E1A     I5 @BASEBOARD_FAB2_LIB.BASEBOARD_FAB2(SCH_1):PAGE149
R25W120    2      B RES_0603-0,5.0%,1/10W,CHIP,G22A    I91 @BASEBOARD_FAB2_LIB.BASEBOARD_FAB2(SCH_1):PAGE149
C25W71    1      A CAP_0402-1.0UF,16V,10%,X6S,D97A   I115 @BASEBOARD_FAB2_LIB.BASEBOARD_FAB2(SCH_1):PAGE149

P3V_BAT_SOURCE @BASEBOARD_FAB2_LIB.BASEBOARD_FAB2(SCH_1):P3V_BAT_SOURCE
 R2U43    1      A RES_0402-1.00K,1%,1/16W,CHIP,GA    I46 @BASEBOARD_FAB2_LIB.BASEBOARD_FAB2(SCH_1):PAGE196
XBT8G1    1     P1 VERT_BATT_3PIN_PIP-3PVERT,C686A    I51 @BASEBOARD_FAB2_LIB.BASEBOARD_FAB2(SCH_1):PAGE196
XBT8G1    2     P2 VERT_BATT_3PIN_PIP-3PVERT,C686A    I51 @BASEBOARD_FAB2_LIB.BASEBOARD_FAB2(SCH_1):PAGE196

P3V_BAT_SOURCE_R @BASEBOARD_FAB2_LIB.BASEBOARD_FAB2(SCH_1):P3V_BAT_SOURCE_R
 R1U50    2      B RES_0402-200.0K,1%,1/16W,CHIP,A   I126 @BASEBOARD_FAB2_LIB.BASEBOARD_FAB2(SCH_1):PAGE169
  Q9G1    3 DRAIN<0> FET_N_DUAL_SMLF-NTJD4001N,FET,A   I157 @BASEBOARD_FAB2_LIB.BASEBOARD_FAB2(SCH_1):PAGE169

P5V @BASEBOARD_FAB2_LIB.BASEBOARD_FAB2(SCH_1):P5V
 R1U29    1      A RES_0402-5.11K,1%,1/16W,CHIP,GA   I141 @BASEBOARD_FAB2_LIB.BASEBOARD_FAB2(SCH_1):PAGE169
 R8D39    1      A RES_0402-49.9K,1%,1/16W,CHIP,GA   I114 @BASEBOARD_FAB2_LIB.BASEBOARD_FAB2(SCH_1):PAGE196
 EU8B1    6      S SLG55021_SM-IC,G56246-001    I13 @BASEBOARD_FAB2_LIB.BASEBOARD_FAB2(SCH_1):PAGE198
  C8B6    1      A CAP_0805-10UF,16V,10%,X6S,C953A    I40 @BASEBOARD_FAB2_LIB.BASEBOARD_FAB2(SCH_1):PAGE198
  C8B7    1      A CAP_A_0402V-0.1UF,16V,10%,X7R,A    I41 @BASEBOARD_FAB2_LIB.BASEBOARD_FAB2(SCH_1):PAGE198
  Q8B1    1    SRC MOSFET_N_LCC3-BSZ019N03LS,NFETA    I87 @BASEBOARD_FAB2_LIB.BASEBOARD_FAB2(SCH_1):PAGE198
 R1W11    1      A RES_0805-0.0,5%,1/8W,EMPTY,G22A   I133 @BASEBOARD_FAB2_LIB.BASEBOARD_FAB2(SCH_1):PAGE176
 D25W8    A  ANODE RB551V30-GP_DISCRET-G-RB551V30A   I128 @BASEBOARD_FAB2_LIB.BASEBOARD_FAB2(SCH_1):PAGE255
  F8B1    2      2 FUSE-3A75V-GP_DISCRET-G5-FUSE-A    I71 @BASEBOARD_FAB2_LIB.BASEBOARD_FAB2(SCH_1):PAGE172

P5V_HDD_SATA @BASEBOARD_FAB2_LIB.BASEBOARD_FAB2(SCH_1):P5V_HDD_SATA
  C9B1    1      A CAP_0805-10UF,16V,10%,X6S,C953A    I39 @BASEBOARD_FAB2_LIB.BASEBOARD_FAB2(SCH_1):PAGE172
  J2W1   P1     P1 SKT-SATA7P-6P-165-GP-U1_SOCKETA    I67 @BASEBOARD_FAB2_LIB.BASEBOARD_FAB2(SCH_1):PAGE172
  J2W1   P2     P2 SKT-SATA7P-6P-165-GP-U1_SOCKETA    I67 @BASEBOARD_FAB2_LIB.BASEBOARD_FAB2(SCH_1):PAGE172
  J2W2   P1     P1 SKT-SATA7P-6P-165-GP-U1_SOCKETA    I68 @BASEBOARD_FAB2_LIB.BASEBOARD_FAB2(SCH_1):PAGE172
  J2W2   P2     P2 SKT-SATA7P-6P-165-GP-U1_SOCKETA    I68 @BASEBOARD_FAB2_LIB.BASEBOARD_FAB2(SCH_1):PAGE172
  F8B1    1      1 FUSE-3A75V-GP_DISCRET-G5-FUSE-A    I71 @BASEBOARD_FAB2_LIB.BASEBOARD_FAB2(SCH_1):PAGE172

P5V_STBY @BASEBOARD_FAB2_LIB.BASEBOARD_FAB2(SCH_1):P5V_STBY
  Q1L2    6 DRAIN<0> FET_N_DUAL_SMLF-NTJD4001N,FET,A   I188 @BASEBOARD_FAB2_LIB.BASEBOARD_FAB2(SCH_1):PAGE155
 CR1E1    1      C DIODE_SM-SDMK0340L,EMPTY,H7179A    I50 @BASEBOARD_FAB2_LIB.BASEBOARD_FAB2(SCH_1):PAGE161
 R1E12    1      A RES_0402-4.75K,1%,1/16W,CHIP,GA    I51 @BASEBOARD_FAB2_LIB.BASEBOARD_FAB2(SCH_1):PAGE161
 CR1B1    1      C DIODE_SM-SDMK0340L,EMPTY,H7179A    I64 @BASEBOARD_FAB2_LIB.BASEBOARD_FAB2(SCH_1):PAGE161
 R7F33    1      A RES_0402-4.75K,1%,1/16W,CHIP,GA    I65 @BASEBOARD_FAB2_LIB.BASEBOARD_FAB2(SCH_1):PAGE161
 R1U47    1      A RES_0402-5.11K,1%,1/16W,CHIP,GA   I115 @BASEBOARD_FAB2_LIB.BASEBOARD_FAB2(SCH_1):PAGE169
  R1L8    1      A RES_0402-470.0,5%,1/16W,CHIP,GA    I58 @BASEBOARD_FAB2_LIB.BASEBOARD_FAB2(SCH_1):PAGE175
  C1L4    1      A CAP_A_0402V-0.1UF,16V,10%,X7R,A    I64 @BASEBOARD_FAB2_LIB.BASEBOARD_FAB2(SCH_1):PAGE175
 R1L37    1      A RES_0402-301.0,1%,1/16W,CHIP,GA    I33 @BASEBOARD_FAB2_LIB.BASEBOARD_FAB2(SCH_1):PAGE177
  J9B3    3    IO3 SCONN120_A28699018_SM-SCONN,A2A   I336 @BASEBOARD_FAB2_LIB.BASEBOARD_FAB2(SCH_1):PAGE186
  J9B3    5    IO5 SCONN120_A28699018_SM-SCONN,A2A   I336 @BASEBOARD_FAB2_LIB.BASEBOARD_FAB2(SCH_1):PAGE186
  J9B3    7    IO7 SCONN120_A28699018_SM-SCONN,A2A   I336 @BASEBOARD_FAB2_LIB.BASEBOARD_FAB2(SCH_1):PAGE186
 C9B10    1      A CAP_A_0402V-0.1UF,16V,10%,X7R,A   I345 @BASEBOARD_FAB2_LIB.BASEBOARD_FAB2(SCH_1):PAGE186
  J4B2  A13  IOA13 SCONN120_H61426002_SM-CONN,H61A    I46 @BASEBOARD_FAB2_LIB.BASEBOARD_FAB2(SCH_1):PAGE193
  J4B2  B13  IOB13 SCONN120_H61426002_SM-CONN,H61A    I46 @BASEBOARD_FAB2_LIB.BASEBOARD_FAB2(SCH_1):PAGE193
  J4B2  C13  IOC13 SCONN120_H61426002_SM-CONN,H61A    I46 @BASEBOARD_FAB2_LIB.BASEBOARD_FAB2(SCH_1):PAGE193
  J6B1  A13  IOA13 SCONN120_H61426002_SM-CONN,H61A    I56 @BASEBOARD_FAB2_LIB.BASEBOARD_FAB2(SCH_1):PAGE194
  J6B1  B13  IOB13 SCONN120_H61426002_SM-CONN,H61A    I56 @BASEBOARD_FAB2_LIB.BASEBOARD_FAB2(SCH_1):PAGE194
  J6B1  C13  IOC13 SCONN120_H61426002_SM-CONN,H61A    I56 @BASEBOARD_FAB2_LIB.BASEBOARD_FAB2(SCH_1):PAGE194
 EU2T1    3 SHDN_N SLG55021_SM-IC,G56246-001     I1 @BASEBOARD_FAB2_LIB.BASEBOARD_FAB2(SCH_1):PAGE198
 EU2T1    1    VCC SLG55021_SM-IC,G56246-001     I1 @BASEBOARD_FAB2_LIB.BASEBOARD_FAB2(SCH_1):PAGE198
 EU8B1    5      D SLG55021_SM-IC,G56246-001    I13 @BASEBOARD_FAB2_LIB.BASEBOARD_FAB2(SCH_1):PAGE198
 EU8B1    3 SHDN_N SLG55021_SM-IC,G56246-001    I13 @BASEBOARD_FAB2_LIB.BASEBOARD_FAB2(SCH_1):PAGE198
 EU8B1    1    VCC SLG55021_SM-IC,G56246-001    I13 @BASEBOARD_FAB2_LIB.BASEBOARD_FAB2(SCH_1):PAGE198
 EU7E1    3 SHDN_N SLG55021_SM-IC,G56246-001    I19 @BASEBOARD_FAB2_LIB.BASEBOARD_FAB2(SCH_1):PAGE198
 EU7E1    1    VCC SLG55021_SM-IC,G56246-001    I19 @BASEBOARD_FAB2_LIB.BASEBOARD_FAB2(SCH_1):PAGE198
 C8F17    1      A CAP_A_0402V-0.1UF,16V,10%,X7R,A    I24 @BASEBOARD_FAB2_LIB.BASEBOARD_FAB2(SCH_1):PAGE198
  C8B8    1      A CAP_A_0402V-0.1UF,16V,10%,X7R,A    I26 @BASEBOARD_FAB2_LIB.BASEBOARD_FAB2(SCH_1):PAGE198
 C8E19    1      A CAP_A_0402V-0.1UF,16V,10%,X7R,A    I28 @BASEBOARD_FAB2_LIB.BASEBOARD_FAB2(SCH_1):PAGE198
  C8B5    1      A CAP_A_0402V-0.1UF,16V,10%,X7R,A    I37 @BASEBOARD_FAB2_LIB.BASEBOARD_FAB2(SCH_1):PAGE198
 C8B12    1      A CAP_0805-10UF,16V,10%,X6S,C953A    I38 @BASEBOARD_FAB2_LIB.BASEBOARD_FAB2(SCH_1):PAGE198
  C9M6    1      A CAP_A_0402V-0.1UF,16V,10%,X7R,A    I67 @BASEBOARD_FAB2_LIB.BASEBOARD_FAB2(SCH_1):PAGE198
 EU9M1    3 SHDN_N SLG55021_SM-IC,G56246-001    I69 @BASEBOARD_FAB2_LIB.BASEBOARD_FAB2(SCH_1):PAGE198
 EU9M1    1    VCC SLG55021_SM-IC,G56246-001    I69 @BASEBOARD_FAB2_LIB.BASEBOARD_FAB2(SCH_1):PAGE198
  Q8B1    5    DRN MOSFET_N_LCC3-BSZ019N03LS,NFETA    I87 @BASEBOARD_FAB2_LIB.BASEBOARD_FAB2(SCH_1):PAGE198
  C4E5    1      A CAP_0402-0.22UF,16V,10%,X7R,A3A    I18 @BASEBOARD_FAB2_LIB.BASEBOARD_FAB2(SCH_1):PAGE202
 C4E27    1      A CAP_0402-0.22UF,16V,10%,X7R,A3A    I24 @BASEBOARD_FAB2_LIB.BASEBOARD_FAB2(SCH_1):PAGE202
 EU4E1   35     EN IR354XX_SM-IR35411,IC,H73688-0A    I63 @BASEBOARD_FAB2_LIB.BASEBOARD_FAB2(SCH_1):PAGE202
 EU4E1    4   VDRV IR354XX_SM-IR35411,IC,H73688-0A    I63 @BASEBOARD_FAB2_LIB.BASEBOARD_FAB2(SCH_1):PAGE202
 EU4D6   35     EN IR354XX_SM-IR35411,IC,H73688-0A    I64 @BASEBOARD_FAB2_LIB.BASEBOARD_FAB2(SCH_1):PAGE202
 EU4D6    4   VDRV IR354XX_SM-IR35411,IC,H73688-0A    I64 @BASEBOARD_FAB2_LIB.BASEBOARD_FAB2(SCH_1):PAGE202
 C4D13    1      A CAP_0402-0.22UF,16V,10%,X7R,A3A    I40 @BASEBOARD_FAB2_LIB.BASEBOARD_FAB2(SCH_1):PAGE203
  C4D5    1      A CAP_0402-0.22UF,16V,10%,X7R,A3A    I48 @BASEBOARD_FAB2_LIB.BASEBOARD_FAB2(SCH_1):PAGE203
 EU4D3   35     EN IR354XX_SM-IR35411,IC,H73688-0A    I70 @BASEBOARD_FAB2_LIB.BASEBOARD_FAB2(SCH_1):PAGE203
 EU4D3    4   VDRV IR354XX_SM-IR35411,IC,H73688-0A    I70 @BASEBOARD_FAB2_LIB.BASEBOARD_FAB2(SCH_1):PAGE203
 EU4D1   35     EN IR354XX_SM-IR35411,IC,H73688-0A    I71 @BASEBOARD_FAB2_LIB.BASEBOARD_FAB2(SCH_1):PAGE203
 EU4D1    4   VDRV IR354XX_SM-IR35411,IC,H73688-0A    I71 @BASEBOARD_FAB2_LIB.BASEBOARD_FAB2(SCH_1):PAGE203
 C4D47    1      A CAP_0402-0.22UF,16V,10%,X7R,A3A    I18 @BASEBOARD_FAB2_LIB.BASEBOARD_FAB2(SCH_1):PAGE204
 EU4C2   35     EN IR354XX_SM-IR35411,IC,H73688-0A    I71 @BASEBOARD_FAB2_LIB.BASEBOARD_FAB2(SCH_1):PAGE204
 EU4C2    4   VDRV IR354XX_SM-IR35411,IC,H73688-0A    I71 @BASEBOARD_FAB2_LIB.BASEBOARD_FAB2(SCH_1):PAGE204
  C4C5    1      A CAP_0402-0.22UF,16V,10%,X7R,A3A    I16 @BASEBOARD_FAB2_LIB.BASEBOARD_FAB2(SCH_1):PAGE205
 EU4C1   35     EN IR354XX_SM-IR35412,IC,H73684-0A    I46 @BASEBOARD_FAB2_LIB.BASEBOARD_FAB2(SCH_1):PAGE205
 EU4C1    4   VDRV IR354XX_SM-IR35412,IC,H73684-0A    I46 @BASEBOARD_FAB2_LIB.BASEBOARD_FAB2(SCH_1):PAGE205
 EU1E2   35     EN IR354XX_SM-IR35411,IC,H73688-0A    I20 @BASEBOARD_FAB2_LIB.BASEBOARD_FAB2(SCH_1):PAGE207
 EU1E2    4   VDRV IR354XX_SM-IR35411,IC,H73688-0A    I20 @BASEBOARD_FAB2_LIB.BASEBOARD_FAB2(SCH_1):PAGE207
  C1E7    1      A CAP_0402-0.22UF,16V,10%,X7R,A3A    I28 @BASEBOARD_FAB2_LIB.BASEBOARD_FAB2(SCH_1):PAGE207
 C1E25    1      A CAP_0402-0.22UF,16V,10%,X7R,A3A    I36 @BASEBOARD_FAB2_LIB.BASEBOARD_FAB2(SCH_1):PAGE207
 EU1D3   35     EN IR354XX_SM-IR35411,IC,H73688-0A    I27 @BASEBOARD_FAB2_LIB.BASEBOARD_FAB2(SCH_1):PAGE208
 EU1D3    4   VDRV IR354XX_SM-IR35411,IC,H73688-0A    I27 @BASEBOARD_FAB2_LIB.BASEBOARD_FAB2(SCH_1):PAGE208
 C1D16    1      A CAP_0402-0.22UF,16V,10%,X7R,A3A    I38 @BASEBOARD_FAB2_LIB.BASEBOARD_FAB2(SCH_1):PAGE208
  C1D6    1      A CAP_0402-0.22UF,16V,10%,X7R,A3A    I46 @BASEBOARD_FAB2_LIB.BASEBOARD_FAB2(SCH_1):PAGE208
 EU1D1   35     EN IR354XX_SM-IR35411,IC,H73688-0A    I71 @BASEBOARD_FAB2_LIB.BASEBOARD_FAB2(SCH_1):PAGE208
 EU1D1    4   VDRV IR354XX_SM-IR35411,IC,H73688-0A    I71 @BASEBOARD_FAB2_LIB.BASEBOARD_FAB2(SCH_1):PAGE208
 C1D33    1      A CAP_0402-0.22UF,16V,10%,X7R,A3A    I22 @BASEBOARD_FAB2_LIB.BASEBOARD_FAB2(SCH_1):PAGE209
 EU1C3   35     EN IR354XX_SM-IR35411,IC,H73688-0A    I56 @BASEBOARD_FAB2_LIB.BASEBOARD_FAB2(SCH_1):PAGE209
 EU1C3    4   VDRV IR354XX_SM-IR35411,IC,H73688-0A    I56 @BASEBOARD_FAB2_LIB.BASEBOARD_FAB2(SCH_1):PAGE209
  C1C4    1      A CAP_0402-0.22UF,16V,10%,X7R,A3A    I22 @BASEBOARD_FAB2_LIB.BASEBOARD_FAB2(SCH_1):PAGE210
 EU1C1   35     EN IR354XX_SM-IR35412,IC,H73684-0A    I51 @BASEBOARD_FAB2_LIB.BASEBOARD_FAB2(SCH_1):PAGE210
 EU1C1    4   VDRV IR354XX_SM-IR35412,IC,H73684-0A    I51 @BASEBOARD_FAB2_LIB.BASEBOARD_FAB2(SCH_1):PAGE210
 C7C18    1      A CAP_0402-0.22UF,16V,10%,X7R,A3A    I33 @BASEBOARD_FAB2_LIB.BASEBOARD_FAB2(SCH_1):PAGE212
 EU7C1   35     EN IR354XX_SM-IR35412,IC,H73684-0A   I101 @BASEBOARD_FAB2_LIB.BASEBOARD_FAB2(SCH_1):PAGE212
 EU7C1    4   VDRV IR354XX_SM-IR35412,IC,H73684-0A   I101 @BASEBOARD_FAB2_LIB.BASEBOARD_FAB2(SCH_1):PAGE212
 C4E23    1      A CAP_0402-0.22UF,16V,10%,X7R,A3A    I73 @BASEBOARD_FAB2_LIB.BASEBOARD_FAB2(SCH_1):PAGE214
 EU4E2   35     EN IR354XX_SM-IR35412,IC,H73684-0A   I126 @BASEBOARD_FAB2_LIB.BASEBOARD_FAB2(SCH_1):PAGE214
 EU4E2    4   VDRV IR354XX_SM-IR35412,IC,H73684-0A   I126 @BASEBOARD_FAB2_LIB.BASEBOARD_FAB2(SCH_1):PAGE214
 C7G34    1      A CAP_0402-0.22UF,16V,10%,X7R,A3A    I54 @BASEBOARD_FAB2_LIB.BASEBOARD_FAB2(SCH_1):PAGE216
 C7G41    1      A CAP_0402-0.22UF,16V,10%,X7R,A3A    I72 @BASEBOARD_FAB2_LIB.BASEBOARD_FAB2(SCH_1):PAGE216
 EU7G2   35     EN IR354XX_SM-IR35411,IC,H73688-0A   I102 @BASEBOARD_FAB2_LIB.BASEBOARD_FAB2(SCH_1):PAGE216
 EU7G2    4   VDRV IR354XX_SM-IR35411,IC,H73688-0A   I102 @BASEBOARD_FAB2_LIB.BASEBOARD_FAB2(SCH_1):PAGE216
 EU7G3   35     EN IR354XX_SM-IR35411,IC,H73688-0A   I103 @BASEBOARD_FAB2_LIB.BASEBOARD_FAB2(SCH_1):PAGE216
 EU7G3    4   VDRV IR354XX_SM-IR35411,IC,H73688-0A   I103 @BASEBOARD_FAB2_LIB.BASEBOARD_FAB2(SCH_1):PAGE216
 C7A17    1      A CAP_0402-0.22UF,16V,10%,X7R,A3A    I54 @BASEBOARD_FAB2_LIB.BASEBOARD_FAB2(SCH_1):PAGE219
 C7A25    1      A CAP_0402-0.22UF,16V,10%,X7R,A3A    I72 @BASEBOARD_FAB2_LIB.BASEBOARD_FAB2(SCH_1):PAGE219
 EU7A1   35     EN IR354XX_SM-IR35411,IC,H73688-0A   I106 @BASEBOARD_FAB2_LIB.BASEBOARD_FAB2(SCH_1):PAGE219
 EU7A1    4   VDRV IR354XX_SM-IR35411,IC,H73688-0A   I106 @BASEBOARD_FAB2_LIB.BASEBOARD_FAB2(SCH_1):PAGE219
 EU7A4   35     EN IR354XX_SM-IR35411,IC,H73688-0A   I107 @BASEBOARD_FAB2_LIB.BASEBOARD_FAB2(SCH_1):PAGE219
 EU7A4    4   VDRV IR354XX_SM-IR35411,IC,H73688-0A   I107 @BASEBOARD_FAB2_LIB.BASEBOARD_FAB2(SCH_1):PAGE219
  C1G5    1      A CAP_0402-0.22UF,16V,10%,X7R,A3A    I54 @BASEBOARD_FAB2_LIB.BASEBOARD_FAB2(SCH_1):PAGE224
 C1G29    1      A CAP_0402-0.22UF,16V,10%,X7R,A3A    I72 @BASEBOARD_FAB2_LIB.BASEBOARD_FAB2(SCH_1):PAGE224
 EU1G1   35     EN IR354XX_SM-IR35411,IC,H73688-0A   I110 @BASEBOARD_FAB2_LIB.BASEBOARD_FAB2(SCH_1):PAGE224
 EU1G1    4   VDRV IR354XX_SM-IR35411,IC,H73688-0A   I110 @BASEBOARD_FAB2_LIB.BASEBOARD_FAB2(SCH_1):PAGE224
 EU1F1   35     EN IR354XX_SM-IR35411,IC,H73688-0A   I111 @BASEBOARD_FAB2_LIB.BASEBOARD_FAB2(SCH_1):PAGE224
 EU1F1    4   VDRV IR354XX_SM-IR35411,IC,H73688-0A   I111 @BASEBOARD_FAB2_LIB.BASEBOARD_FAB2(SCH_1):PAGE224
 C1B21    1      A CAP_0402-0.22UF,16V,10%,X7R,A3A    I54 @BASEBOARD_FAB2_LIB.BASEBOARD_FAB2(SCH_1):PAGE227
 C1A13    1      A CAP_0402-0.22UF,16V,10%,X7R,A3A    I72 @BASEBOARD_FAB2_LIB.BASEBOARD_FAB2(SCH_1):PAGE227
 EU1A2   35     EN IR354XX_SM-IR35411,IC,H73688-0A   I101 @BASEBOARD_FAB2_LIB.BASEBOARD_FAB2(SCH_1):PAGE227
 EU1A2    4   VDRV IR354XX_SM-IR35411,IC,H73688-0A   I101 @BASEBOARD_FAB2_LIB.BASEBOARD_FAB2(SCH_1):PAGE227
 EU1A1   35     EN IR354XX_SM-IR35411,IC,H73688-0A   I102 @BASEBOARD_FAB2_LIB.BASEBOARD_FAB2(SCH_1):PAGE227
 EU1A1    4   VDRV IR354XX_SM-IR35411,IC,H73688-0A   I102 @BASEBOARD_FAB2_LIB.BASEBOARD_FAB2(SCH_1):PAGE227
  C7A8    1      A CAP_0402-0.22UF,16V,10%,X7R,A3A    I16 @BASEBOARD_FAB2_LIB.BASEBOARD_FAB2(SCH_1):PAGE236
 C7A41    1      A CAP_0402-0.22UF,16V,10%,X7R,A3A    I39 @BASEBOARD_FAB2_LIB.BASEBOARD_FAB2(SCH_1):PAGE236
 EU7A3   35     EN IR354XX_SM-IR35412,IC,H73684-0A   I116 @BASEBOARD_FAB2_LIB.BASEBOARD_FAB2(SCH_1):PAGE236
 EU7A3    4   VDRV IR354XX_SM-IR35412,IC,H73684-0A   I116 @BASEBOARD_FAB2_LIB.BASEBOARD_FAB2(SCH_1):PAGE236
 EU7A2   35     EN IR354XX_SM-IR35412,IC,H73684-0A   I117 @BASEBOARD_FAB2_LIB.BASEBOARD_FAB2(SCH_1):PAGE236
 EU7A2    4   VDRV IR354XX_SM-IR35412,IC,H73684-0A   I117 @BASEBOARD_FAB2_LIB.BASEBOARD_FAB2(SCH_1):PAGE236
 EU8F1    5    VCC RT8240_QFN-IC,H66262-001   I125 @BASEBOARD_FAB2_LIB.BASEBOARD_FAB2(SCH_1):PAGE240
 R8E18    1      A RES_0402-1.0K,0.1%,1/16W,CHIP,A     I9 @BASEBOARD_FAB2_LIB.BASEBOARD_FAB2(SCH_1):PAGE241
 R7E12    1      A RES_0402-1.00K,1%,1/16W,CHIP,GA    I11 @BASEBOARD_FAB2_LIB.BASEBOARD_FAB2(SCH_1):PAGE241
 R8E37    2      B RES_0402-0.0,5%,1/16W,CHIP,G21A    I78 @BASEBOARD_FAB2_LIB.BASEBOARD_FAB2(SCH_1):PAGE241
  L8E1    2    INB INDUCTOR_SM-2.2UH,IND,E98761-0A    I90 @BASEBOARD_FAB2_LIB.BASEBOARD_FAB2(SCH_1):PAGE241
  Q9W4    5    VCC LMV331IDCKRG4-GP_DISCRET-G-LMVA    I15 @BASEBOARD_FAB2_LIB.BASEBOARD_FAB2(SCH_1):PAGE249
 R1W10    1      A RES_0805-0.0,5%,1/8W,CHIP,G221A   I132 @BASEBOARD_FAB2_LIB.BASEBOARD_FAB2(SCH_1):PAGE176
CR10W2    1      C DIODE_SM-SDMK0340L,EMPTY,H7179A    I10 @BASEBOARD_FAB2_LIB.BASEBOARD_FAB2(SCH_1):PAGE251
 R10W3    1      A RES_0402-4.75K,1%,1/16W,CHIP,GA    I11 @BASEBOARD_FAB2_LIB.BASEBOARD_FAB2(SCH_1):PAGE251
 R6P19    2      B RES_0402-0.0,5%,1/16W,CHIP,G21A   I128 @BASEBOARD_FAB2_LIB.BASEBOARD_FAB2(SCH_1):PAGE203
 R6P10    2      B RES_0402-0.0,5%,1/16W,CHIP,G21A   I129 @BASEBOARD_FAB2_LIB.BASEBOARD_FAB2(SCH_1):PAGE203
  R6R2    2      B RES_0402-0.0,5%,1/16W,CHIP,G21A   I107 @BASEBOARD_FAB2_LIB.BASEBOARD_FAB2(SCH_1):PAGE202
  R6R6    2      B RES_0402-0.0,5%,1/16W,CHIP,G21A   I108 @BASEBOARD_FAB2_LIB.BASEBOARD_FAB2(SCH_1):PAGE202
  R6N3    2      B RES_0402-0.0,5%,1/16W,CHIP,G21A    I81 @BASEBOARD_FAB2_LIB.BASEBOARD_FAB2(SCH_1):PAGE205
 R6P47    2      B RES_0402-0.0,5%,1/16W,CHIP,G21A   I103 @BASEBOARD_FAB2_LIB.BASEBOARD_FAB2(SCH_1):PAGE204
 R9R11    2      B RES_0402-0.0,5%,1/16W,CHIP,G21A   I105 @BASEBOARD_FAB2_LIB.BASEBOARD_FAB2(SCH_1):PAGE207
  R9R2    2      B RES_0402-0.0,5%,1/16W,CHIP,G21A   I106 @BASEBOARD_FAB2_LIB.BASEBOARD_FAB2(SCH_1):PAGE207
 R9P22    2      B RES_0402-0.0,5%,1/16W,CHIP,G21A   I114 @BASEBOARD_FAB2_LIB.BASEBOARD_FAB2(SCH_1):PAGE208
  R9P8    2      B RES_0402-0.0,5%,1/16W,CHIP,G21A   I115 @BASEBOARD_FAB2_LIB.BASEBOARD_FAB2(SCH_1):PAGE208
 R9P32    2      B RES_0402-0.0,5%,1/16W,CHIP,G21A    I79 @BASEBOARD_FAB2_LIB.BASEBOARD_FAB2(SCH_1):PAGE209
  R9N3    2      B RES_0402-0.0,5%,1/16W,CHIP,G21A    I71 @BASEBOARD_FAB2_LIB.BASEBOARD_FAB2(SCH_1):PAGE210
  R3N7    2      B RES_0402-0.0,5%,1/16W,CHIP,G21A   I140 @BASEBOARD_FAB2_LIB.BASEBOARD_FAB2(SCH_1):PAGE212
  R6R5    2      B RES_0402-0.0,5%,1/16W,CHIP,G21A   I173 @BASEBOARD_FAB2_LIB.BASEBOARD_FAB2(SCH_1):PAGE214
  R3U6    2      B RES_0402-0.0,5%,1/16W,CHIP,G21A   I145 @BASEBOARD_FAB2_LIB.BASEBOARD_FAB2(SCH_1):PAGE216
  R3U9    2      B RES_0402-0.0,5%,1/16W,CHIP,G21A   I146 @BASEBOARD_FAB2_LIB.BASEBOARD_FAB2(SCH_1):PAGE216
  R3L6    2      B RES_0402-0.0,5%,1/16W,CHIP,G21A   I147 @BASEBOARD_FAB2_LIB.BASEBOARD_FAB2(SCH_1):PAGE219
  R3L8    2      B RES_0402-0.0,5%,1/16W,CHIP,G21A   I148 @BASEBOARD_FAB2_LIB.BASEBOARD_FAB2(SCH_1):PAGE219
  R9U1    2      B RES_0402-0.0,5%,1/16W,CHIP,G21A   I150 @BASEBOARD_FAB2_LIB.BASEBOARD_FAB2(SCH_1):PAGE224
 R9U12    2      B RES_0402-0.0,5%,1/16W,CHIP,G21A   I151 @BASEBOARD_FAB2_LIB.BASEBOARD_FAB2(SCH_1):PAGE224
  R3L1    2      B RES_0402-0.0,5%,1/16W,CHIP,G21A   I175 @BASEBOARD_FAB2_LIB.BASEBOARD_FAB2(SCH_1):PAGE236
  R3L4    2      B RES_0402-0.0,5%,1/16W,CHIP,G21A   I177 @BASEBOARD_FAB2_LIB.BASEBOARD_FAB2(SCH_1):PAGE236
  C8E4    1      1 ST220U10VDM-LGP_SMD-TCG-ST220UA   I100 @BASEBOARD_FAB2_LIB.BASEBOARD_FAB2(SCH_1):PAGE241
 C2R11    1      1 SC4D7U16V3KX-GP_SMD-BCG5-SC4D7A   I191 @BASEBOARD_FAB2_LIB.BASEBOARD_FAB2(SCH_1):PAGE240
  C9B9    1      1 SC1U10V2KX-4-GP_SMD-BCG6-SC1U1A   I357 @BASEBOARD_FAB2_LIB.BASEBOARD_FAB2(SCH_1):PAGE186
 C1C18    1      1 SC1U10V2KX-4-GP_SMD-BCG6-SC1U1A    I89 @BASEBOARD_FAB2_LIB.BASEBOARD_FAB2(SCH_1):PAGE209
 C1A11    1      1 SC1U10V2KX-4-GP_SMD-BCG6-SC1U1A   I147 @BASEBOARD_FAB2_LIB.BASEBOARD_FAB2(SCH_1):PAGE227
  C1A2    1      1 SC1U10V2KX-4-GP_SMD-BCG6-SC1U1A   I148 @BASEBOARD_FAB2_LIB.BASEBOARD_FAB2(SCH_1):PAGE227
  C1C3    1      1 SC1U10V2KX-4-GP_SMD-BCG6-SC1U1A    I73 @BASEBOARD_FAB2_LIB.BASEBOARD_FAB2(SCH_1):PAGE210
 C1D15    1      1 SC1U10V2KX-4-GP_SMD-BCG6-SC1U1A   I118 @BASEBOARD_FAB2_LIB.BASEBOARD_FAB2(SCH_1):PAGE208
  C1D5    1      1 SC1U10V2KX-4-GP_SMD-BCG6-SC1U1A   I119 @BASEBOARD_FAB2_LIB.BASEBOARD_FAB2(SCH_1):PAGE208
 C1E23    1      1 SC1U10V2KX-4-GP_SMD-BCG6-SC1U1A   I109 @BASEBOARD_FAB2_LIB.BASEBOARD_FAB2(SCH_1):PAGE207
  C1E6    1      1 SC1U10V2KX-4-GP_SMD-BCG6-SC1U1A   I110 @BASEBOARD_FAB2_LIB.BASEBOARD_FAB2(SCH_1):PAGE207
 C1F21    1      1 SC1U10V2KX-4-GP_SMD-BCG6-SC1U1A   I154 @BASEBOARD_FAB2_LIB.BASEBOARD_FAB2(SCH_1):PAGE224
  C1G4    1      1 SC1U10V2KX-4-GP_SMD-BCG6-SC1U1A   I155 @BASEBOARD_FAB2_LIB.BASEBOARD_FAB2(SCH_1):PAGE224
  C3L1    1      1 SC1U10V2KX-4-GP_SMD-BCG6-SC1U1A   I180 @BASEBOARD_FAB2_LIB.BASEBOARD_FAB2(SCH_1):PAGE236
 C3L29    1      1 SC1U10V2KX-4-GP_SMD-BCG6-SC1U1A   I181 @BASEBOARD_FAB2_LIB.BASEBOARD_FAB2(SCH_1):PAGE236
  C4C4    1      1 SC1U10V2KX-4-GP_SMD-BCG6-SC1U1A    I83 @BASEBOARD_FAB2_LIB.BASEBOARD_FAB2(SCH_1):PAGE205
 C4C14    1      1 SC1U10V2KX-4-GP_SMD-BCG6-SC1U1A   I113 @BASEBOARD_FAB2_LIB.BASEBOARD_FAB2(SCH_1):PAGE204
 C4D14    1      1 SC1U10V2KX-4-GP_SMD-BCG6-SC1U1A   I132 @BASEBOARD_FAB2_LIB.BASEBOARD_FAB2(SCH_1):PAGE203
  C4D6    1      1 SC1U10V2KX-4-GP_SMD-BCG6-SC1U1A   I133 @BASEBOARD_FAB2_LIB.BASEBOARD_FAB2(SCH_1):PAGE203
 C4E25    1      1 SC1U10V2KX-4-GP_SMD-BCG6-SC1U1A   I111 @BASEBOARD_FAB2_LIB.BASEBOARD_FAB2(SCH_1):PAGE202
  C4E6    1      1 SC1U10V2KX-4-GP_SMD-BCG6-SC1U1A   I112 @BASEBOARD_FAB2_LIB.BASEBOARD_FAB2(SCH_1):PAGE202
 C4E28    1      1 SC1U10V2KX-4-GP_SMD-BCG6-SC1U1A   I175 @BASEBOARD_FAB2_LIB.BASEBOARD_FAB2(SCH_1):PAGE214
 C7A18    1      1 SC1U10V2KX-4-GP_SMD-BCG6-SC1U1A   I151 @BASEBOARD_FAB2_LIB.BASEBOARD_FAB2(SCH_1):PAGE219
 C7A26    1      1 SC1U10V2KX-4-GP_SMD-BCG6-SC1U1A   I152 @BASEBOARD_FAB2_LIB.BASEBOARD_FAB2(SCH_1):PAGE219
 C7C20    1      1 SC1U10V2KX-4-GP_SMD-BCG6-SC1U1A   I143 @BASEBOARD_FAB2_LIB.BASEBOARD_FAB2(SCH_1):PAGE212
 C7G35    1      1 SC1U10V2KX-4-GP_SMD-BCG6-SC1U1A   I149 @BASEBOARD_FAB2_LIB.BASEBOARD_FAB2(SCH_1):PAGE216
 C7G42    1      1 SC1U10V2KX-4-GP_SMD-BCG6-SC1U1A   I150 @BASEBOARD_FAB2_LIB.BASEBOARD_FAB2(SCH_1):PAGE216
  C8W2    1      A CAP_A_0402V-0.1UF,16V,10%,X7R,A    I37 @BASEBOARD_FAB2_LIB.BASEBOARD_FAB2(SCH_1):PAGE249
  C8E7    1      1 SC22U16V5MX-4-GP_SMD-BCG5-SC22A   I103 @BASEBOARD_FAB2_LIB.BASEBOARD_FAB2(SCH_1):PAGE241
  C8E9    1      1 SC22U16V5MX-4-GP_SMD-BCG5-SC22A   I104 @BASEBOARD_FAB2_LIB.BASEBOARD_FAB2(SCH_1):PAGE241
  R9A5    1      A RES_0402-20.0K,1%,1/16W,CHIP,GA   I198 @BASEBOARD_FAB2_LIB.BASEBOARD_FAB2(SCH_1):PAGE155
 EU1D4   35     EN IR354XX_SM-IR35411,IC,H73688-0A   I113 @BASEBOARD_FAB2_LIB.BASEBOARD_FAB2(SCH_1):PAGE207
 EU1D4    4   VDRV IR354XX_SM-IR35411,IC,H73688-0A   I113 @BASEBOARD_FAB2_LIB.BASEBOARD_FAB2(SCH_1):PAGE207
  R9L9    2      B RES_0402-0.0,5%,1/16W,CHIP,G21A   I154 @BASEBOARD_FAB2_LIB.BASEBOARD_FAB2(SCH_1):PAGE227
  R9L4    2      B RES_0402-0.0,5%,1/16W,CHIP,G21A   I155 @BASEBOARD_FAB2_LIB.BASEBOARD_FAB2(SCH_1):PAGE227
 F30W1    1      1 POLYSW-1D1A6V-2-GP-U_DISCRET-GA    I44 @BASEBOARD_FAB2_LIB.BASEBOARD_FAB2(SCH_1):PAGE253

P5V_STBY_DBG @BASEBOARD_FAB2_LIB.BASEBOARD_FAB2(SCH_1):P5V_STBY_DBG
  F1L1    1   A<0> FUSE_SMT-IC,H45581-001   I129 @BASEBOARD_FAB2_LIB.BASEBOARD_FAB2(SCH_1):PAGE155
  Q1L2    1 SOURCE<0> FET_N_DUAL_SMLF-NTJD4001N,FET,A   I188 @BASEBOARD_FAB2_LIB.BASEBOARD_FAB2(SCH_1):PAGE155

P5V_STBY_DGB_FS @BASEBOARD_FAB2_LIB.BASEBOARD_FAB2(SCH_1):P5V_STBY_DGB_FS
  C9A1    1      A CAP_A_0402V-0.1UF,16V,10%,X7R,A   I127 @BASEBOARD_FAB2_LIB.BASEBOARD_FAB2(SCH_1):PAGE155
  F1L1    2   B<0> FUSE_SMT-IC,H45581-001   I129 @BASEBOARD_FAB2_LIB.BASEBOARD_FAB2(SCH_1):PAGE155
  J9A2   14   IO14 CONN14_H54902001_PIP-CONN,H549A   I171 @BASEBOARD_FAB2_LIB.BASEBOARD_FAB2(SCH_1):PAGE155

P5V_STBY_USBC @BASEBOARD_FAB2_LIB.BASEBOARD_FAB2(SCH_1):P5V_STBY_USBC
 J30W1   A4 VBUS<0> SKT-USB32-8-GP_SOCKET-G4-SKT-UA    I26 @BASEBOARD_FAB2_LIB.BASEBOARD_FAB2(SCH_1):PAGE253
 J30W1   A9 VBUS<1> SKT-USB32-8-GP_SOCKET-G4-SKT-UA    I26 @BASEBOARD_FAB2_LIB.BASEBOARD_FAB2(SCH_1):PAGE253
 J30W1   B4 VBUS<2> SKT-USB32-8-GP_SOCKET-G4-SKT-UA    I26 @BASEBOARD_FAB2_LIB.BASEBOARD_FAB2(SCH_1):PAGE253
 J30W1   B9 VBUS<3> SKT-USB32-8-GP_SOCKET-G4-SKT-UA    I26 @BASEBOARD_FAB2_LIB.BASEBOARD_FAB2(SCH_1):PAGE253
 C30W3    1      1 SC22U16V5MX-4-GP_SMD-BCG5-SC22A    I35 @BASEBOARD_FAB2_LIB.BASEBOARD_FAB2(SCH_1):PAGE253
 C30W4    1      1 SC22U16V5MX-4-GP_SMD-BCG5-SC22A    I36 @BASEBOARD_FAB2_LIB.BASEBOARD_FAB2(SCH_1):PAGE253
 C30W6    1      1 SC22U16V5MX-4-GP_SMD-BCG5-SC22A    I37 @BASEBOARD_FAB2_LIB.BASEBOARD_FAB2(SCH_1):PAGE253
 C30W5    1      1 SC22U16V5MX-4-GP_SMD-BCG5-SC22A    I38 @BASEBOARD_FAB2_LIB.BASEBOARD_FAB2(SCH_1):PAGE253
 C30W9    1      1 SC22U16V5MX-4-GP_SMD-BCG5-SC22A    I40 @BASEBOARD_FAB2_LIB.BASEBOARD_FAB2(SCH_1):PAGE253
 C30W8    1      1 SC22U16V5MX-4-GP_SMD-BCG5-SC22A    I41 @BASEBOARD_FAB2_LIB.BASEBOARD_FAB2(SCH_1):PAGE253
 C30W7    1      1 SC22U16V5MX-4-GP_SMD-BCG5-SC22A    I42 @BASEBOARD_FAB2_LIB.BASEBOARD_FAB2(SCH_1):PAGE253
 F30W1    2      2 POLYSW-1D1A6V-2-GP-U_DISCRET-GA    I44 @BASEBOARD_FAB2_LIB.BASEBOARD_FAB2(SCH_1):PAGE253

P5V_SWITCH_G @BASEBOARD_FAB2_LIB.BASEBOARD_FAB2(SCH_1):P5V_SWITCH_G
 EU8B1    7      G SLG55021_SM-IC,G56246-001    I13 @BASEBOARD_FAB2_LIB.BASEBOARD_FAB2(SCH_1):PAGE198
  Q8B1    4   GATE MOSFET_N_LCC3-BSZ019N03LS,NFETA    I87 @BASEBOARD_FAB2_LIB.BASEBOARD_FAB2(SCH_1):PAGE198

P5V_TPS2061 @BASEBOARD_FAB2_LIB.BASEBOARD_FAB2(SCH_1):P5V_TPS2061
  U1M3    5     IN TPS2061_SM-IC,H66405-001   I100 @BASEBOARD_FAB2_LIB.BASEBOARD_FAB2(SCH_1):PAGE176
 C1M38    1      A CAP_A_0402V-0.1UF,16V,10%,X7R,A   I108 @BASEBOARD_FAB2_LIB.BASEBOARD_FAB2(SCH_1):PAGE176
 R1W10    2      B RES_0805-0.0,5%,1/8W,CHIP,G221A   I132 @BASEBOARD_FAB2_LIB.BASEBOARD_FAB2(SCH_1):PAGE176
 R1W11    2      B RES_0805-0.0,5%,1/8W,EMPTY,G22A   I133 @BASEBOARD_FAB2_LIB.BASEBOARD_FAB2(SCH_1):PAGE176

P5V_USB @BASEBOARD_FAB2_LIB.BASEBOARD_FAB2(SCH_1):P5V_USB
  J9B1    1   VBUS CONN9_H51826001_PIP2-CONN,H518A    I69 @BASEBOARD_FAB2_LIB.BASEBOARD_FAB2(SCH_1):PAGE176
  U1M3    1    OUT TPS2061_SM-IC,H66405-001   I100 @BASEBOARD_FAB2_LIB.BASEBOARD_FAB2(SCH_1):PAGE176
  C9B8    1      A CAPP_7343HLF-330UF,10V,20%,POSA   I113 @BASEBOARD_FAB2_LIB.BASEBOARD_FAB2(SCH_1):PAGE176

P5V_VGA @BASEBOARD_FAB2_LIB.BASEBOARD_FAB2(SCH_1):P5V_VGA
C25P83    1      A CAP_A_0402V-0.1UF,16V,10%,X7R,A    I74 @BASEBOARD_FAB2_LIB.BASEBOARD_FAB2(SCH_1):PAGE255
 F25W1    1      1 POLYSW-D5A6V-2-GP-U_DISCRET-GAA    I89 @BASEBOARD_FAB2_LIB.BASEBOARD_FAB2(SCH_1):PAGE255
 J25W1   13     13 SMC-CON13-GP_CONN-GC2-SMC-CON1A   I136 @BASEBOARD_FAB2_LIB.BASEBOARD_FAB2(SCH_1):PAGE255

P5V_VGA_D @BASEBOARD_FAB2_LIB.BASEBOARD_FAB2(SCH_1):P5V_VGA_D
R25W132    1      A RES_0402-4.75K,1%,1/16W,CHIP,GA    I31 @BASEBOARD_FAB2_LIB.BASEBOARD_FAB2(SCH_1):PAGE255
R25W135    1      A RES_0402-4.75K,1%,1/16W,CHIP,GA    I44 @BASEBOARD_FAB2_LIB.BASEBOARD_FAB2(SCH_1):PAGE255
 F25W1    2      2 POLYSW-D5A6V-2-GP-U_DISCRET-GAA    I89 @BASEBOARD_FAB2_LIB.BASEBOARD_FAB2(SCH_1):PAGE255
 U25W7    5    VCC U74AHCT1G125G-AL5-R-GP-U_TTL-GA   I111 @BASEBOARD_FAB2_LIB.BASEBOARD_FAB2(SCH_1):PAGE255
 U25W8    5    VCC U74AHCT1G125G-AL5-R-GP-U_TTL-GA   I112 @BASEBOARD_FAB2_LIB.BASEBOARD_FAB2(SCH_1):PAGE255
C25W90    1      A CAP_A_0402V-0.1UF,16V,10%,X7R,A   I118 @BASEBOARD_FAB2_LIB.BASEBOARD_FAB2(SCH_1):PAGE255
 D25W8    K CATHODE RB551V30-GP_DISCRET-G-RB551V30A   I128 @BASEBOARD_FAB2_LIB.BASEBOARD_FAB2(SCH_1):PAGE255
C25P80    1      A CAP_A_0402V-0.1UF,16V,10%,X7R,A   I134 @BASEBOARD_FAB2_LIB.BASEBOARD_FAB2(SCH_1):PAGE255

PCA9554_A0 @BASEBOARD_FAB2_LIB.BASEBOARD_FAB2(SCH_1):PCA9554_A0
 R6W47    1      A RES_0402-4.75K,1%,1/16W,EMPTY,A    I76 @BASEBOARD_FAB2_LIB.BASEBOARD_FAB2(SCH_1):PAGE164
 R6W44    2      B RES_0402-4.75K,1%,1/16W,CHIP,GA    I78 @BASEBOARD_FAB2_LIB.BASEBOARD_FAB2(SCH_1):PAGE164
 U6W11    1     A0 PCA9554PWR-GP_DISCRET-G1-PCA95A    I97 @BASEBOARD_FAB2_LIB.BASEBOARD_FAB2(SCH_1):PAGE164

PCA9554_A1 @BASEBOARD_FAB2_LIB.BASEBOARD_FAB2(SCH_1):PCA9554_A1
 R6W46    1      A RES_0402-4.75K,1%,1/16W,CHIP,GA    I93 @BASEBOARD_FAB2_LIB.BASEBOARD_FAB2(SCH_1):PAGE164
 R6W43    2      B RES_0402-4.75K,1%,1/16W,EMPTY,A    I96 @BASEBOARD_FAB2_LIB.BASEBOARD_FAB2(SCH_1):PAGE164
 U6W11    2     A1 PCA9554PWR-GP_DISCRET-G1-PCA95A    I97 @BASEBOARD_FAB2_LIB.BASEBOARD_FAB2(SCH_1):PAGE164

PCA9554_A2 @BASEBOARD_FAB2_LIB.BASEBOARD_FAB2(SCH_1):PCA9554_A2
 R6W45    1      A RES_0402-4.75K,1%,1/16W,CHIP,GA    I94 @BASEBOARD_FAB2_LIB.BASEBOARD_FAB2(SCH_1):PAGE164
 R6W42    2      B RES_0402-4.75K,1%,1/16W,EMPTY,A    I95 @BASEBOARD_FAB2_LIB.BASEBOARD_FAB2(SCH_1):PAGE164
 U6W11    3     A2 PCA9554PWR-GP_DISCRET-G1-PCA95A    I97 @BASEBOARD_FAB2_LIB.BASEBOARD_FAB2(SCH_1):PAGE164

PCA9554_INT_N @BASEBOARD_FAB2_LIB.BASEBOARD_FAB2(SCH_1):PCA9554_INT_N
 R6W41    2      B RES_0402-4.75K,1%,1/16W,CHIP,GA    I87 @BASEBOARD_FAB2_LIB.BASEBOARD_FAB2(SCH_1):PAGE164
 U6W11   13   INT# PCA9554PWR-GP_DISCRET-G1-PCA95A    I97 @BASEBOARD_FAB2_LIB.BASEBOARD_FAB2(SCH_1):PAGE164

PCA9555_A0 @BASEBOARD_FAB2_LIB.BASEBOARD_FAB2(SCH_1):PCA9555_A0
  U6W1   21     A0 TCA9555PWR-GP_DISCRET-GC1-TCA9A   I120 @BASEBOARD_FAB2_LIB.BASEBOARD_FAB2(SCH_1):PAGE247
  R6W6    2      B RES_0402-4.75K,1%,1/16W,CHIP,GA   I161 @BASEBOARD_FAB2_LIB.BASEBOARD_FAB2(SCH_1):PAGE247
  R6W9    1      A RES_0402-4.75K,1%,1/16W,EMPTY,A   I162 @BASEBOARD_FAB2_LIB.BASEBOARD_FAB2(SCH_1):PAGE247

PCA9555_A1 @BASEBOARD_FAB2_LIB.BASEBOARD_FAB2(SCH_1):PCA9555_A1
  U6W1    2     A1 TCA9555PWR-GP_DISCRET-GC1-TCA9A   I120 @BASEBOARD_FAB2_LIB.BASEBOARD_FAB2(SCH_1):PAGE247
  R6W5    2      B RES_0402-4.75K,1%,1/16W,CHIP,GA   I160 @BASEBOARD_FAB2_LIB.BASEBOARD_FAB2(SCH_1):PAGE247
  R6W8    1      A RES_0402-4.75K,1%,1/16W,EMPTY,A   I163 @BASEBOARD_FAB2_LIB.BASEBOARD_FAB2(SCH_1):PAGE247

PCA9555_A2 @BASEBOARD_FAB2_LIB.BASEBOARD_FAB2(SCH_1):PCA9555_A2
  U6W1    3     A2 TCA9555PWR-GP_DISCRET-GC1-TCA9A   I120 @BASEBOARD_FAB2_LIB.BASEBOARD_FAB2(SCH_1):PAGE247
  R6W4    2      B RES_0402-4.75K,1%,1/16W,CHIP,GA   I159 @BASEBOARD_FAB2_LIB.BASEBOARD_FAB2(SCH_1):PAGE247
  R6W7    1      A RES_0402-4.75K,1%,1/16W,EMPTY,A   I164 @BASEBOARD_FAB2_LIB.BASEBOARD_FAB2(SCH_1):PAGE247

PCA9555_INT_N @BASEBOARD_FAB2_LIB.BASEBOARD_FAB2(SCH_1):PCA9555_INT_N
 R6W10    2      B RES_0402-4.75K,1%,1/16W,CHIP,GA     I1 @BASEBOARD_FAB2_LIB.BASEBOARD_FAB2(SCH_1):PAGE247
  U6W1    1   INT# TCA9555PWR-GP_DISCRET-GC1-TCA9A   I120 @BASEBOARD_FAB2_LIB.BASEBOARD_FAB2(SCH_1):PAGE247

PD_ADCREXT @BASEBOARD_FAB2_LIB.BASEBOARD_FAB2(SCH_1):PD_ADCREXT
 U25W4   J1 ADCREXT AST2520A1-GP-GP_ASIC2-GB1-AST2A   I106 @BASEBOARD_FAB2_LIB.BASEBOARD_FAB2(SCH_1):PAGE147
R25W57    1      A RES_0402-49.9K,1%,1/16W,CHIP,GA   I151 @BASEBOARD_FAB2_LIB.BASEBOARD_FAB2(SCH_1):PAGE147

PD_CKMNG_OE @BASEBOARD_FAB2_LIB.BASEBOARD_FAB2(SCH_1):PD_CKMNG_OE
 EU8F2    5  OE_96 ICS9FGP204_MLFP-IC,E95226-001    I34 @BASEBOARD_FAB2_LIB.BASEBOARD_FAB2(SCH_1):PAGE101
 EU8F2    6 OE_CPU ICS9FGP204_MLFP-IC,E95226-001    I34 @BASEBOARD_FAB2_LIB.BASEBOARD_FAB2(SCH_1):PAGE101
 R2T25    1      A RES_0402-1.00K,1%,1/16W,CHIP,GA    I48 @BASEBOARD_FAB2_LIB.BASEBOARD_FAB2(SCH_1):PAGE101

PD_CPU0_BIST_ENABLE @BASEBOARD_FAB2_LIB.BASEBOARD_FAB2(SCH_1):PD_CPU0_BIST_ENABLE
  U5D1 BA20 BIST_ENABLE SKX_EXT_B_BGA1-IC,TBD   I259 @BASEBOARD_FAB2_LIB.BASEBOARD_FAB2(SCH_1):PAGE21
  R4P1    2      B RES_0402-240,1.0%,1/16W,EMPTY,A    I98 @BASEBOARD_FAB2_LIB.BASEBOARD_FAB2(SCH_1):PAGE90

PD_CPU0_DMIMODE_OVERRIDE @BASEBOARD_FAB2_LIB.BASEBOARD_FAB2(SCH_1):PD_CPU0_DMIMODE_OVERRIDE
  U5D1 AW12 DMIMODE_OVERRIDE SKX_EXT_B_BGA1-IC,TBD   I204 @BASEBOARD_FAB2_LIB.BASEBOARD_FAB2(SCH_1):PAGE22
  R4P6    2      B RES_0402-240,1.0%,1/16W,EMPTY,A    I68 @BASEBOARD_FAB2_LIB.BASEBOARD_FAB2(SCH_1):PAGE90

PD_CPU0_EAR_N @BASEBOARD_FAB2_LIB.BASEBOARD_FAB2(SCH_1):PD_CPU0_EAR_N
  U5D1 AJ14  EAR_N SKX_EXT_B_BGA1-IC,TBD   I259 @BASEBOARD_FAB2_LIB.BASEBOARD_FAB2(SCH_1):PAGE21
 R6D14    2      B RES_0402-240,1.0%,1/16W,EMPTY,A    I52 @BASEBOARD_FAB2_LIB.BASEBOARD_FAB2(SCH_1):PAGE90

PD_CPU0_KSFC_DIS @BASEBOARD_FAB2_LIB.BASEBOARD_FAB2(SCH_1):PD_CPU0_KSFC_DIS
  U5D1 AW14 TEST_15 SKX_EXT_B_BGA1-IC,TBD   I259 @BASEBOARD_FAB2_LIB.BASEBOARD_FAB2(SCH_1):PAGE21
  R4P7    2      B RES_0402-240,1.0%,1/16W,EMPTY,A    I72 @BASEBOARD_FAB2_LIB.BASEBOARD_FAB2(SCH_1):PAGE90

PD_CPU0_MCP01_DMON @BASEBOARD_FAB2_LIB.BASEBOARD_FAB2(SCH_1):PD_CPU0_MCP01_DMON
  U5D1 CN28 RSVD<75> SKX_EXT_B_BGA1-IC,TBD   I127 @BASEBOARD_FAB2_LIB.BASEBOARD_FAB2(SCH_1):PAGE39
  R4P5    2      B RES_0402-10.0K,1%,1/16W,CHIP,GA    I80 @BASEBOARD_FAB2_LIB.BASEBOARD_FAB2(SCH_1):PAGE97

PD_CPU0_RSVD_TEST_1 @BASEBOARD_FAB2_LIB.BASEBOARD_FAB2(SCH_1):PD_CPU0_RSVD_TEST_1
  R5R1    1      A RES_0402-49.9,1%,1/16W,CHIP,G2A   I188 @BASEBOARD_FAB2_LIB.BASEBOARD_FAB2(SCH_1):PAGE22
  U5D1 AF45 TEST_1 SKX_EXT_B_BGA1-IC,TBD   I204 @BASEBOARD_FAB2_LIB.BASEBOARD_FAB2(SCH_1):PAGE22

PD_CPU0_RSVD_TEST_2 @BASEBOARD_FAB2_LIB.BASEBOARD_FAB2(SCH_1):PD_CPU0_RSVD_TEST_2
  R5P4    1      A RES_0402-49.9,1%,1/16W,CHIP,G2A   I190 @BASEBOARD_FAB2_LIB.BASEBOARD_FAB2(SCH_1):PAGE22
  U5D1 AG46 TEST_2 SKX_EXT_B_BGA1-IC,TBD   I204 @BASEBOARD_FAB2_LIB.BASEBOARD_FAB2(SCH_1):PAGE22

PD_CPU0_TEST12 @BASEBOARD_FAB2_LIB.BASEBOARD_FAB2(SCH_1):PD_CPU0_TEST12
  U5D1 AY19 TEST_12 SKX_EXT_B_BGA1-IC,TBD   I259 @BASEBOARD_FAB2_LIB.BASEBOARD_FAB2(SCH_1):PAGE21
  R6D5    1      A RES_0402-49.9,1%,1/16W,CHIP,G2A    I81 @BASEBOARD_FAB2_LIB.BASEBOARD_FAB2(SCH_1):PAGE90

PD_CPU0_TEST13 @BASEBOARD_FAB2_LIB.BASEBOARD_FAB2(SCH_1):PD_CPU0_TEST13
  U5D1 DB51 TEST_13 SKX_EXT_B_BGA1-IC,TBD   I259 @BASEBOARD_FAB2_LIB.BASEBOARD_FAB2(SCH_1):PAGE21
  R5P3    1      A RES_0402-49.9,1%,1/16W,CHIP,G2A    I80 @BASEBOARD_FAB2_LIB.BASEBOARD_FAB2(SCH_1):PAGE90

PD_CPU0_TEST14 @BASEBOARD_FAB2_LIB.BASEBOARD_FAB2(SCH_1):PD_CPU0_TEST14
  U5D1 DC50 TEST_14 SKX_EXT_B_BGA1-IC,TBD   I259 @BASEBOARD_FAB2_LIB.BASEBOARD_FAB2(SCH_1):PAGE21
  R5P2    1      A RES_0402-49.9,1%,1/16W,CHIP,G2A    I79 @BASEBOARD_FAB2_LIB.BASEBOARD_FAB2(SCH_1):PAGE90

PD_CPU0_TXT_PLTEN @BASEBOARD_FAB2_LIB.BASEBOARD_FAB2(SCH_1):PD_CPU0_TXT_PLTEN
  U5D1 AV15 TXT_PLTEN SKX_EXT_B_BGA1-IC,TBD   I259 @BASEBOARD_FAB2_LIB.BASEBOARD_FAB2(SCH_1):PAGE21
  R6D6    2      B RES_0402-240,1.0%,1/16W,EMPTY,A   I101 @BASEBOARD_FAB2_LIB.BASEBOARD_FAB2(SCH_1):PAGE90

PD_CPU1_BIST_ENABLE @BASEBOARD_FAB2_LIB.BASEBOARD_FAB2(SCH_1):PD_CPU1_BIST_ENABLE
  U2D1 BA20 BIST_ENABLE SKX_EXT_B_BGA1-IC,TBD   I172 @BASEBOARD_FAB2_LIB.BASEBOARD_FAB2(SCH_1):PAGE55
 R3D13    2      B RES_0402-240,1.0%,1/16W,EMPTY,A    I99 @BASEBOARD_FAB2_LIB.BASEBOARD_FAB2(SCH_1):PAGE90

PD_CPU1_DMIMODE_OVERRIDE @BASEBOARD_FAB2_LIB.BASEBOARD_FAB2(SCH_1):PD_CPU1_DMIMODE_OVERRIDE
  U2D1 AW12 DMIMODE_OVERRIDE SKX_EXT_B_BGA1-IC,TBD   I169 @BASEBOARD_FAB2_LIB.BASEBOARD_FAB2(SCH_1):PAGE56
 R7P14    2      B RES_0402-240,1.0%,1/16W,CHIP,GA   I100 @BASEBOARD_FAB2_LIB.BASEBOARD_FAB2(SCH_1):PAGE90

PD_CPU1_EAR_N @BASEBOARD_FAB2_LIB.BASEBOARD_FAB2(SCH_1):PD_CPU1_EAR_N
  U2D1 AJ14  EAR_N SKX_EXT_B_BGA1-IC,TBD   I172 @BASEBOARD_FAB2_LIB.BASEBOARD_FAB2(SCH_1):PAGE55
 R3D25    2      B RES_0402-240,1.0%,1/16W,EMPTY,A    I66 @BASEBOARD_FAB2_LIB.BASEBOARD_FAB2(SCH_1):PAGE90

PD_CPU1_KSFC_DIS @BASEBOARD_FAB2_LIB.BASEBOARD_FAB2(SCH_1):PD_CPU1_KSFC_DIS
  U2D1 AW14 TEST_15 SKX_EXT_B_BGA1-IC,TBD   I172 @BASEBOARD_FAB2_LIB.BASEBOARD_FAB2(SCH_1):PAGE55
 R7P15    2      B RES_0402-240,1.0%,1/16W,EMPTY,A    I74 @BASEBOARD_FAB2_LIB.BASEBOARD_FAB2(SCH_1):PAGE90

PD_CPU1_MCP01_DMON @BASEBOARD_FAB2_LIB.BASEBOARD_FAB2(SCH_1):PD_CPU1_MCP01_DMON
  U2D1 CN28 RSVD<75> SKX_EXT_B_BGA1-IC,TBD   I107 @BASEBOARD_FAB2_LIB.BASEBOARD_FAB2(SCH_1):PAGE73
 R7P13    2      B RES_0402-10.0K,1%,1/16W,CHIP,GA    I81 @BASEBOARD_FAB2_LIB.BASEBOARD_FAB2(SCH_1):PAGE97

PD_CPU1_RSVD_TEST_1 @BASEBOARD_FAB2_LIB.BASEBOARD_FAB2(SCH_1):PD_CPU1_RSVD_TEST_1
  U2D1 AF45 TEST_1 SKX_EXT_B_BGA1-IC,TBD   I169 @BASEBOARD_FAB2_LIB.BASEBOARD_FAB2(SCH_1):PAGE56
  R8R1    1      A RES_0402-49.9,1%,1/16W,CHIP,G2A   I174 @BASEBOARD_FAB2_LIB.BASEBOARD_FAB2(SCH_1):PAGE56

PD_CPU1_RSVD_TEST_2 @BASEBOARD_FAB2_LIB.BASEBOARD_FAB2(SCH_1):PD_CPU1_RSVD_TEST_2
  U2D1 AG46 TEST_2 SKX_EXT_B_BGA1-IC,TBD   I169 @BASEBOARD_FAB2_LIB.BASEBOARD_FAB2(SCH_1):PAGE56
  R8P3    1      A RES_0402-49.9,1%,1/16W,CHIP,G2A   I173 @BASEBOARD_FAB2_LIB.BASEBOARD_FAB2(SCH_1):PAGE56

PD_CPU1_TEST12 @BASEBOARD_FAB2_LIB.BASEBOARD_FAB2(SCH_1):PD_CPU1_TEST12
  U2D1 AY19 TEST_12 SKX_EXT_B_BGA1-IC,TBD   I172 @BASEBOARD_FAB2_LIB.BASEBOARD_FAB2(SCH_1):PAGE55
  R3D9    1      A RES_0402-49.9,1%,1/16W,CHIP,G2A    I88 @BASEBOARD_FAB2_LIB.BASEBOARD_FAB2(SCH_1):PAGE90

PD_CPU1_TEST13 @BASEBOARD_FAB2_LIB.BASEBOARD_FAB2(SCH_1):PD_CPU1_TEST13
  U2D1 DB51 TEST_13 SKX_EXT_B_BGA1-IC,TBD   I172 @BASEBOARD_FAB2_LIB.BASEBOARD_FAB2(SCH_1):PAGE55
  R8P2    1      A RES_0402-49.9,1%,1/16W,CHIP,G2A    I86 @BASEBOARD_FAB2_LIB.BASEBOARD_FAB2(SCH_1):PAGE90

PD_CPU1_TEST14 @BASEBOARD_FAB2_LIB.BASEBOARD_FAB2(SCH_1):PD_CPU1_TEST14
  U2D1 DC50 TEST_14 SKX_EXT_B_BGA1-IC,TBD   I172 @BASEBOARD_FAB2_LIB.BASEBOARD_FAB2(SCH_1):PAGE55
  R8P1    1      A RES_0402-49.9,1%,1/16W,CHIP,G2A    I85 @BASEBOARD_FAB2_LIB.BASEBOARD_FAB2(SCH_1):PAGE90

PD_CPU1_TXT_PLTEN @BASEBOARD_FAB2_LIB.BASEBOARD_FAB2(SCH_1):PD_CPU1_TXT_PLTEN
  U2D1 AV15 TXT_PLTEN SKX_EXT_B_BGA1-IC,TBD   I172 @BASEBOARD_FAB2_LIB.BASEBOARD_FAB2(SCH_1):PAGE55
 R3D12    2      B RES_0402-240,1.0%,1/16W,EMPTY,A   I102 @BASEBOARD_FAB2_LIB.BASEBOARD_FAB2(SCH_1):PAGE90

PD_DIR_2 @BASEBOARD_FAB2_LIB.BASEBOARD_FAB2(SCH_1):PD_DIR_2
  U9G1    1    DIR GTL2014_SM-IC,D66151-001     I1 @BASEBOARD_FAB2_LIB.BASEBOARD_FAB2(SCH_1):PAGE152
 R1U30    1      A RES_0402-1.00K,1%,1/16W,CHIP,GA     I2 @BASEBOARD_FAB2_LIB.BASEBOARD_FAB2(SCH_1):PAGE152

PD_FRU_WP @BASEBOARD_FAB2_LIB.BASEBOARD_FAB2(SCH_1):PD_FRU_WP
  U8D4    7     WP AT24C64_SOICLF-IC,C47049-001-GA    I49 @BASEBOARD_FAB2_LIB.BASEBOARD_FAB2(SCH_1):PAGE167
 R8D27    1      A RES_0402-1.00K,1%,1/16W,CHIP,GA    I50 @BASEBOARD_FAB2_LIB.BASEBOARD_FAB2(SCH_1):PAGE167

PD_GTL2014_1_VREF @BASEBOARD_FAB2_LIB.BASEBOARD_FAB2(SCH_1):PD_GTL2014_1_VREF
  U3P1    4   VREF GTL2014_SM-IC,D66151-001    I42 @BASEBOARD_FAB2_LIB.BASEBOARD_FAB2(SCH_1):PAGE96
 R3P32    2      B RES_0402-1.00K,1%,1/16W,CHIP,GA    I71 @BASEBOARD_FAB2_LIB.BASEBOARD_FAB2(SCH_1):PAGE96

PD_GTL2014_2_VREF @BASEBOARD_FAB2_LIB.BASEBOARD_FAB2(SCH_1):PD_GTL2014_2_VREF
  U4C2    4   VREF GTL2014_SM-IC,D66151-001    I46 @BASEBOARD_FAB2_LIB.BASEBOARD_FAB2(SCH_1):PAGE96
  R4C9    2      B RES_0402-1.00K,1%,1/16W,CHIP,GA    I69 @BASEBOARD_FAB2_LIB.BASEBOARD_FAB2(SCH_1):PAGE96

PD_GTL2014_3_VREF @BASEBOARD_FAB2_LIB.BASEBOARD_FAB2(SCH_1):PD_GTL2014_3_VREF
R25W159    2      B RES_0402-1.00K,1%,1/16W,CHIP,GA    I24 @BASEBOARD_FAB2_LIB.BASEBOARD_FAB2(SCH_1):PAGE269
U25W10    4   VREF GTL2014_SM-IC,D66151-001    I49 @BASEBOARD_FAB2_LIB.BASEBOARD_FAB2(SCH_1):PAGE269

PD_GTL2014_6_B0 @BASEBOARD_FAB2_LIB.BASEBOARD_FAB2(SCH_1):PD_GTL2014_6_B0
R25W175    1      A RES_0402-1.00K,1%,1/16W,CHIP,GA    I17 @BASEBOARD_FAB2_LIB.BASEBOARD_FAB2(SCH_1):PAGE268
U25W11    2     B0 GTL2014_SM-IC,D66151-001    I33 @BASEBOARD_FAB2_LIB.BASEBOARD_FAB2(SCH_1):PAGE268

PD_GTL2014_6_B2 @BASEBOARD_FAB2_LIB.BASEBOARD_FAB2(SCH_1):PD_GTL2014_6_B2
R25W176    1      A RES_0402-1.00K,1%,1/16W,CHIP,GA    I14 @BASEBOARD_FAB2_LIB.BASEBOARD_FAB2(SCH_1):PAGE268
U25W11    5     B2 GTL2014_SM-IC,D66151-001    I33 @BASEBOARD_FAB2_LIB.BASEBOARD_FAB2(SCH_1):PAGE268

PD_GTL2014_DIR_6 @BASEBOARD_FAB2_LIB.BASEBOARD_FAB2(SCH_1):PD_GTL2014_DIR_6
R25W166    1      A RES_0402-1.00K,1%,1/16W,CHIP,GA    I26 @BASEBOARD_FAB2_LIB.BASEBOARD_FAB2(SCH_1):PAGE268
U25W11    1    DIR GTL2014_SM-IC,D66151-001    I33 @BASEBOARD_FAB2_LIB.BASEBOARD_FAB2(SCH_1):PAGE268

PD_GTL2104_4_DIR @BASEBOARD_FAB2_LIB.BASEBOARD_FAB2(SCH_1):PD_GTL2104_4_DIR
  U2T4    1    DIR GTL2014_SM-IC,D66151-001    I30 @BASEBOARD_FAB2_LIB.BASEBOARD_FAB2(SCH_1):PAGE93
 R2T50    1      A RES_0402-1.00K,1%,1/16W,CHIP,GA   I127 @BASEBOARD_FAB2_LIB.BASEBOARD_FAB2(SCH_1):PAGE93

PD_GTL2104_DIR_0 @BASEBOARD_FAB2_LIB.BASEBOARD_FAB2(SCH_1):PD_GTL2104_DIR_0
  U7D2    1    DIR GTL2014_SM-IC,D66151-001    I32 @BASEBOARD_FAB2_LIB.BASEBOARD_FAB2(SCH_1):PAGE92
 R7D26    1      A RES_0402-1.00K,1%,1/16W,CHIP,GA    I54 @BASEBOARD_FAB2_LIB.BASEBOARD_FAB2(SCH_1):PAGE92

PD_GTL2104_DIR_1 @BASEBOARD_FAB2_LIB.BASEBOARD_FAB2(SCH_1):PD_GTL2104_DIR_1
  U3P2    1    DIR GTL2014_SM-IC,D66151-001     I1 @BASEBOARD_FAB2_LIB.BASEBOARD_FAB2(SCH_1):PAGE92
  R3R1    1      A RES_0402-1.00K,1%,1/16W,CHIP,GA    I46 @BASEBOARD_FAB2_LIB.BASEBOARD_FAB2(SCH_1):PAGE92

PD_HSC_RETRY_N @BASEBOARD_FAB2_LIB.BASEBOARD_FAB2(SCH_1):PD_HSC_RETRY_N
 EU1D2   17 RETRY_N ADM1278_SM-IC,G99251-001    I10 @BASEBOARD_FAB2_LIB.BASEBOARD_FAB2(SCH_1):PAGE199
 R1D28    1      A RES_0402-100.0,1%,1/16W,EMPTY,A    I26 @BASEBOARD_FAB2_LIB.BASEBOARD_FAB2(SCH_1):PAGE199

PD_ID_EEPROM_WP @BASEBOARD_FAB2_LIB.BASEBOARD_FAB2(SCH_1):PD_ID_EEPROM_WP
  U6W3    7     WP AT24C64_SOICLF-IC,C47049-001-GA    I89 @BASEBOARD_FAB2_LIB.BASEBOARD_FAB2(SCH_1):PAGE247
 R6W23    1      A RES_0402-1.00K,1%,1/16W,CHIP,GA    I92 @BASEBOARD_FAB2_LIB.BASEBOARD_FAB2(SCH_1):PAGE247

PD_IE_DEBUG_MODE @BASEBOARD_FAB2_LIB.BASEBOARD_FAB2(SCH_1):PD_IE_DEBUG_MODE
 R1U64    1      A RES_0402-1.00K,1%,1/16W,CHIP,GA    I69 @BASEBOARD_FAB2_LIB.BASEBOARD_FAB2(SCH_1):PAGE137
  J9G1   11   IO11 CONN12_C73564003_PIP-CONN,C735A   I128 @BASEBOARD_FAB2_LIB.BASEBOARD_FAB2(SCH_1):PAGE137

PD_ME_RCVR_N @BASEBOARD_FAB2_LIB.BASEBOARD_FAB2(SCH_1):PD_ME_RCVR_N
 R7G28    1      A RES_0402-1.00K,1%,1/16W,CHIP,GA   I102 @BASEBOARD_FAB2_LIB.BASEBOARD_FAB2(SCH_1):PAGE136
  J7G3    5    IO5 CONN12_C73564003_PIP-CONN,C735A   I174 @BASEBOARD_FAB2_LIB.BASEBOARD_FAB2(SCH_1):PAGE136

PD_PASSWORD_CLEAR @BASEBOARD_FAB2_LIB.BASEBOARD_FAB2(SCH_1):PD_PASSWORD_CLEAR
 R7G29    1      A RES_0402-1.00K,1%,1/16W,CHIP,GA   I148 @BASEBOARD_FAB2_LIB.BASEBOARD_FAB2(SCH_1):PAGE136
  J7G3   11   IO11 CONN12_C73564003_PIP-CONN,C735A   I174 @BASEBOARD_FAB2_LIB.BASEBOARD_FAB2(SCH_1):PAGE136

PD_PEREXT @BASEBOARD_FAB2_LIB.BASEBOARD_FAB2(SCH_1):PD_PEREXT
 U25W4  K20 PEREXT AST2520A1-GP-GP_ASIC2-GB1-AST2A   I117 @BASEBOARD_FAB2_LIB.BASEBOARD_FAB2(SCH_1):PAGE145
R25W67    1      1 200R2F-L1-GP_SMD-RG4-200R2F-L1A   I118 @BASEBOARD_FAB2_LIB.BASEBOARD_FAB2(SCH_1):PAGE145

PD_PIROM_CPU0_ADDR0 @BASEBOARD_FAB2_LIB.BASEBOARD_FAB2(SCH_1):PD_PIROM_CPU0_ADDR0
  U5D1 CU58 PIROM_ADDR<0> SKX_EXT_B_BGA1-IC,TBD   I259 @BASEBOARD_FAB2_LIB.BASEBOARD_FAB2(SCH_1):PAGE21
 R6N14    2      B RES_0402-1.00K,1%,1/16W,CHIP,GA   I302 @BASEBOARD_FAB2_LIB.BASEBOARD_FAB2(SCH_1):PAGE156

PD_PIROM_CPU0_ADDR1 @BASEBOARD_FAB2_LIB.BASEBOARD_FAB2(SCH_1):PD_PIROM_CPU0_ADDR1
  U5D1 CV57 PIROM_ADDR<1> SKX_EXT_B_BGA1-IC,TBD   I259 @BASEBOARD_FAB2_LIB.BASEBOARD_FAB2(SCH_1):PAGE21
 R6N13    2      B RES_0402-1.00K,1%,1/16W,CHIP,GA   I303 @BASEBOARD_FAB2_LIB.BASEBOARD_FAB2(SCH_1):PAGE156

PD_PIROM_CPU0_ADDR2 @BASEBOARD_FAB2_LIB.BASEBOARD_FAB2(SCH_1):PD_PIROM_CPU0_ADDR2
  U5D1 CW56 PIROM_ADDR<2> SKX_EXT_B_BGA1-IC,TBD   I259 @BASEBOARD_FAB2_LIB.BASEBOARD_FAB2(SCH_1):PAGE21
 R6N15    2      B RES_0402-1.00K,1%,1/16W,CHIP,GA   I304 @BASEBOARD_FAB2_LIB.BASEBOARD_FAB2(SCH_1):PAGE156

PD_PIROM_CPU1_ADDR1 @BASEBOARD_FAB2_LIB.BASEBOARD_FAB2(SCH_1):PD_PIROM_CPU1_ADDR1
  U2D1 CV57 PIROM_ADDR<1> SKX_EXT_B_BGA1-IC,TBD   I172 @BASEBOARD_FAB2_LIB.BASEBOARD_FAB2(SCH_1):PAGE55
 R1C33    2      B RES_0402-1.00K,1%,1/16W,CHIP,GA   I313 @BASEBOARD_FAB2_LIB.BASEBOARD_FAB2(SCH_1):PAGE156

PD_PIROM_CPU1_ADDR2 @BASEBOARD_FAB2_LIB.BASEBOARD_FAB2(SCH_1):PD_PIROM_CPU1_ADDR2
  U2D1 CW56 PIROM_ADDR<2> SKX_EXT_B_BGA1-IC,TBD   I172 @BASEBOARD_FAB2_LIB.BASEBOARD_FAB2(SCH_1):PAGE55
 R1C32    2      B RES_0402-1.00K,1%,1/16W,CHIP,GA   I312 @BASEBOARD_FAB2_LIB.BASEBOARD_FAB2(SCH_1):PAGE156

PD_RST_RTCRST_N @BASEBOARD_FAB2_LIB.BASEBOARD_FAB2(SCH_1):PD_RST_RTCRST_N
 R1U63    1      A RES_0402-1.00K,1%,1/16W,CHIP,GA    I15 @BASEBOARD_FAB2_LIB.BASEBOARD_FAB2(SCH_1):PAGE137
  J9G1    6    IO6 CONN12_C73564003_PIP-CONN,C735A   I128 @BASEBOARD_FAB2_LIB.BASEBOARD_FAB2(SCH_1):PAGE137

PD_SATA0_CONTROLLER_TYPE_R @BASEBOARD_FAB2_LIB.BASEBOARD_FAB2(SCH_1):PD_SATA0_CONTROLLER_TYPE_R
  J8A1  1D2 SIDEBANDA_6 CONN72_G97614002_A_CP-CONN,G97A   I163 @BASEBOARD_FAB2_LIB.BASEBOARD_FAB2(SCH_1):PAGE173
 R2L18    1      A RES_0402-1.00K,1%,1/16W,CHIP,GA   I266 @BASEBOARD_FAB2_LIB.BASEBOARD_FAB2(SCH_1):PAGE173

PD_SATA1_CONTROLLER_TYPE_R @BASEBOARD_FAB2_LIB.BASEBOARD_FAB2(SCH_1):PD_SATA1_CONTROLLER_TYPE_R
  J8A1  2D2 SIDEBANDB_6 CONN72_G97614002_A_CP-CONN,G97A   I163 @BASEBOARD_FAB2_LIB.BASEBOARD_FAB2(SCH_1):PAGE173
 R2L22    1      A RES_0402-1.00K,1%,1/16W,CHIP,GA   I264 @BASEBOARD_FAB2_LIB.BASEBOARD_FAB2(SCH_1):PAGE173

PD_SMB_M2_EN @BASEBOARD_FAB2_LIB.BASEBOARD_FAB2(SCH_1):PD_SMB_M2_EN
 U32W1    5     EN TCA9517DGKR-GP_DISCRET-G8-TCA9A   I191 @BASEBOARD_FAB2_LIB.BASEBOARD_FAB2(SCH_1):PAGE185
 R32W9    1      A RES_0402-10.0K,1%,1/16W,CHIP,GA   I200 @BASEBOARD_FAB2_LIB.BASEBOARD_FAB2(SCH_1):PAGE185
 U32W2    5     EN TCA9517DGKR-GP_DISCRET-G8-TCA9A   I204 @BASEBOARD_FAB2_LIB.BASEBOARD_FAB2(SCH_1):PAGE185

PD_SPI_BMC_BT_CS0_N @BASEBOARD_FAB2_LIB.BASEBOARD_FAB2(SCH_1):PD_SPI_BMC_BT_CS0_N
  J9G1   12   IO12 CONN12_C73564003_PIP-CONN,C735A   I128 @BASEBOARD_FAB2_LIB.BASEBOARD_FAB2(SCH_1):PAGE137
R25W94    2      B RES_0402-4.75K,1%,1/16W,CHIP,GA   I140 @BASEBOARD_FAB2_LIB.BASEBOARD_FAB2(SCH_1):PAGE137

PD_SPRV_RSET @BASEBOARD_FAB2_LIB.BASEBOARD_FAB2(SCH_1):PD_SPRV_RSET
 EU9E1   48   RSET SPRINGVILLE_SM1-IC,G47144-004    I72 @BASEBOARD_FAB2_LIB.BASEBOARD_FAB2(SCH_1):PAGE139
 R9E23    1      A RES_0402-4.99K,1%,1/16W,CHIP,GA   I174 @BASEBOARD_FAB2_LIB.BASEBOARD_FAB2(SCH_1):PAGE139

PD_SP_ENTEST @BASEBOARD_FAB2_LIB.BASEBOARD_FAB2(SCH_1):PD_SP_ENTEST
  R1U7    2      B RES_0402-10.0K,1%,1/16W,CHIP,GA    I78 @BASEBOARD_FAB2_LIB.BASEBOARD_FAB2(SCH_1):PAGE146
 U25W4   K3 ENTEST AST2520A1-GP-GP_ASIC2-GB1-AST2A   I105 @BASEBOARD_FAB2_LIB.BASEBOARD_FAB2(SCH_1):PAGE146

PD_TMP421_1_A0 @BASEBOARD_FAB2_LIB.BASEBOARD_FAB2(SCH_1):PD_TMP421_1_A0
  U9B4    4   A<0> TMP421_TSSOP-IC,G62962-001     I1 @BASEBOARD_FAB2_LIB.BASEBOARD_FAB2(SCH_1):PAGE167
  R9B8    1      A RES_0402-1.00K,1%,1/16W,CHIP,GA    I10 @BASEBOARD_FAB2_LIB.BASEBOARD_FAB2(SCH_1):PAGE167

PD_TMP421_2_A1 @BASEBOARD_FAB2_LIB.BASEBOARD_FAB2(SCH_1):PD_TMP421_2_A1
  U1E1    3   A<1> TMP421_TSSOP-IC,G62962-001    I30 @BASEBOARD_FAB2_LIB.BASEBOARD_FAB2(SCH_1):PAGE167
 R1E10    2      B RES_0402-1.00K,1%,1/16W,CHIP,GA    I38 @BASEBOARD_FAB2_LIB.BASEBOARD_FAB2(SCH_1):PAGE167

PD_UV_HIGH_SET @BASEBOARD_FAB2_LIB.BASEBOARD_FAB2(SCH_1):PD_UV_HIGH_SET
  J9G1    5    IO5 CONN12_C73564003_PIP-CONN,C735A   I128 @BASEBOARD_FAB2_LIB.BASEBOARD_FAB2(SCH_1):PAGE137
  R6W2    1      A RES_0402-10.0K,1%,1/16W,CHIP,GA   I144 @BASEBOARD_FAB2_LIB.BASEBOARD_FAB2(SCH_1):PAGE137

PECI_BMC @BASEBOARD_FAB2_LIB.BASEBOARD_FAB2(SCH_1):PECI_BMC
 R7C17    2      B RES_0402-4.75K,1%,1/16W,CHIP,GA    I28 @BASEBOARD_FAB2_LIB.BASEBOARD_FAB2(SCH_1):PAGE166
 R9F33    1      A RES_0402-0.0,5%,1/16W,CHIP,G21A    I20 @BASEBOARD_FAB2_LIB.BASEBOARD_FAB2(SCH_1):PAGE145
 R9F20    1      A RES_0402-348,1%,1/16W,EMPTY,G2A    I22 @BASEBOARD_FAB2_LIB.BASEBOARD_FAB2(SCH_1):PAGE145
  U7W1    1     B1 PI5A3157BC6E-GP_DISCRET-GC2-PIA    I34 @BASEBOARD_FAB2_LIB.BASEBOARD_FAB2(SCH_1):PAGE166

PECI_BMC_R @BASEBOARD_FAB2_LIB.BASEBOARD_FAB2(SCH_1):PECI_BMC_R
 R9F33    2      B RES_0402-0.0,5%,1/16W,CHIP,G21A    I20 @BASEBOARD_FAB2_LIB.BASEBOARD_FAB2(SCH_1):PAGE145
 U25W4 AB18   PECI AST2520A1-GP-GP_ASIC2-GB1-AST2A   I117 @BASEBOARD_FAB2_LIB.BASEBOARD_FAB2(SCH_1):PAGE145

PECI_CPU_G @BASEBOARD_FAB2_LIB.BASEBOARD_FAB2(SCH_1):PECI_CPU_G
  U5D1 AU12   PECI SKX_EXT_B_BGA1-IC,TBD   I259 @BASEBOARD_FAB2_LIB.BASEBOARD_FAB2(SCH_1):PAGE21
  U2D1 AU12   PECI SKX_EXT_B_BGA1-IC,TBD   I172 @BASEBOARD_FAB2_LIB.BASEBOARD_FAB2(SCH_1):PAGE55
  U7W1    4      A PI5A3157BC6E-GP_DISCRET-GC2-PIA    I34 @BASEBOARD_FAB2_LIB.BASEBOARD_FAB2(SCH_1):PAGE166
  R7W2    1      A RES_0402-10.0K,1%,1/16W,EMPTY,A    I42 @BASEBOARD_FAB2_LIB.BASEBOARD_FAB2(SCH_1):PAGE166

PECI_PCH @BASEBOARD_FAB2_LIB.BASEBOARD_FAB2(SCH_1):PECI_PCH
  U7C1   U9   PECI LBG_CORE_QAT_EXT_D_BGA1-IC,H91A    I73 @BASEBOARD_FAB2_LIB.BASEBOARD_FAB2(SCH_1):PAGE118
 R7D15    1      A RES_0402-348,1%,1/16W,CHIP,G21A    I32 @BASEBOARD_FAB2_LIB.BASEBOARD_FAB2(SCH_1):PAGE166
  U7W1    3     B0 PI5A3157BC6E-GP_DISCRET-GC2-PIA    I34 @BASEBOARD_FAB2_LIB.BASEBOARD_FAB2(SCH_1):PAGE166

PECI_SEL @BASEBOARD_FAB2_LIB.BASEBOARD_FAB2(SCH_1):PECI_SEL
 U25W4  U22 GPIOAA4_VPOR6_NORD4_SALT11 AST2520A1-GP-GP_ASIC2-GB1-AST2A   I104 @BASEBOARD_FAB2_LIB.BASEBOARD_FAB2(SCH_1):PAGE146
  U7W1    6      S PI5A3157BC6E-GP_DISCRET-GC2-PIA    I34 @BASEBOARD_FAB2_LIB.BASEBOARD_FAB2(SCH_1):PAGE166
  R7W3    2      B RES_0402-10.0K,1%,1/16W,EMPTY,A    I46 @BASEBOARD_FAB2_LIB.BASEBOARD_FAB2(SCH_1):PAGE166

PE_PCH_SPRV_RX_C_DN @BASEBOARD_FAB2_LIB.BASEBOARD_FAB2(SCH_1):PE_PCH_SPRV_RX_C_DN
  U7C1 AM69 PCIE5_GBE_RXN LBG_CORE_QAT_EXT_D_BGA1-IC,H91A   I220 @BASEBOARD_FAB2_LIB.BASEBOARD_FAB2(SCH_1):PAGE116
  C9E5    2      B CAP_A_0402V-0.1UF,16V,10%,X7R,A    I87 @BASEBOARD_FAB2_LIB.BASEBOARD_FAB2(SCH_1):PAGE139

PE_PCH_SPRV_RX_C_DP @BASEBOARD_FAB2_LIB.BASEBOARD_FAB2(SCH_1):PE_PCH_SPRV_RX_C_DP
  U7C1 AM71 PCIE5_GBE_RXP LBG_CORE_QAT_EXT_D_BGA1-IC,H91A   I220 @BASEBOARD_FAB2_LIB.BASEBOARD_FAB2(SCH_1):PAGE116
  C9E4    2      B CAP_A_0402V-0.1UF,16V,10%,X7R,A    I88 @BASEBOARD_FAB2_LIB.BASEBOARD_FAB2(SCH_1):PAGE139

PE_PCH_SPRV_RX_DN @BASEBOARD_FAB2_LIB.BASEBOARD_FAB2(SCH_1):PE_PCH_SPRV_RX_DN
 EU9E1   20  PE_TN SPRINGVILLE_SM1-IC,G47144-004    I72 @BASEBOARD_FAB2_LIB.BASEBOARD_FAB2(SCH_1):PAGE139
  C9E5    1      A CAP_A_0402V-0.1UF,16V,10%,X7R,A    I87 @BASEBOARD_FAB2_LIB.BASEBOARD_FAB2(SCH_1):PAGE139

PE_PCH_SPRV_RX_DP @BASEBOARD_FAB2_LIB.BASEBOARD_FAB2(SCH_1):PE_PCH_SPRV_RX_DP
 EU9E1   21  PE_TP SPRINGVILLE_SM1-IC,G47144-004    I72 @BASEBOARD_FAB2_LIB.BASEBOARD_FAB2(SCH_1):PAGE139
  C9E4    1      A CAP_A_0402V-0.1UF,16V,10%,X7R,A    I88 @BASEBOARD_FAB2_LIB.BASEBOARD_FAB2(SCH_1):PAGE139

PE_PCH_SPRV_TX_C_DN @BASEBOARD_FAB2_LIB.BASEBOARD_FAB2(SCH_1):PE_PCH_SPRV_TX_C_DN
 EU9E1   23  PE_RN SPRINGVILLE_SM1-IC,G47144-004    I72 @BASEBOARD_FAB2_LIB.BASEBOARD_FAB2(SCH_1):PAGE139
 C2M24    2      B CAP_A_0402V-0.1UF,16V,10%,X7R,A    I90 @BASEBOARD_FAB2_LIB.BASEBOARD_FAB2(SCH_1):PAGE139

PE_PCH_SPRV_TX_C_DP @BASEBOARD_FAB2_LIB.BASEBOARD_FAB2(SCH_1):PE_PCH_SPRV_TX_C_DP
 EU9E1   24  PE_RP SPRINGVILLE_SM1-IC,G47144-004    I72 @BASEBOARD_FAB2_LIB.BASEBOARD_FAB2(SCH_1):PAGE139
 C2M23    2      B CAP_A_0402V-0.1UF,16V,10%,X7R,A    I89 @BASEBOARD_FAB2_LIB.BASEBOARD_FAB2(SCH_1):PAGE139

PE_PCH_SPRV_TX_DN @BASEBOARD_FAB2_LIB.BASEBOARD_FAB2(SCH_1):PE_PCH_SPRV_TX_DN
  U7C1 BH65 PCIE5_GBE_TXN LBG_CORE_QAT_EXT_D_BGA1-IC,H91A   I220 @BASEBOARD_FAB2_LIB.BASEBOARD_FAB2(SCH_1):PAGE116
 C2M24    1      A CAP_A_0402V-0.1UF,16V,10%,X7R,A    I90 @BASEBOARD_FAB2_LIB.BASEBOARD_FAB2(SCH_1):PAGE139

PE_PCH_SPRV_TX_DP @BASEBOARD_FAB2_LIB.BASEBOARD_FAB2(SCH_1):PE_PCH_SPRV_TX_DP
  U7C1 BJ63 PCIE5_GBE_TXP LBG_CORE_QAT_EXT_D_BGA1-IC,H91A   I220 @BASEBOARD_FAB2_LIB.BASEBOARD_FAB2(SCH_1):PAGE116
 C2M23    1      A CAP_A_0402V-0.1UF,16V,10%,X7R,A    I89 @BASEBOARD_FAB2_LIB.BASEBOARD_FAB2(SCH_1):PAGE139

PUMP_PWM_OUT @BASEBOARD_FAB2_LIB.BASEBOARD_FAB2(SCH_1):PUMP_PWM_OUT
 U25W4   Y3 GPION6_PWM6_VPIG6 AST2520A1-GP-GP_ASIC2-GB1-AST2A   I106 @BASEBOARD_FAB2_LIB.BASEBOARD_FAB2(SCH_1):PAGE147
 U10W1    2      A TTL1G07_A_SOP-74LVC1G07,IC,C88B    I19 @BASEBOARD_FAB2_LIB.BASEBOARD_FAB2(SCH_1):PAGE251

PUMP_PWM_OUT_BUF @BASEBOARD_FAB2_LIB.BASEBOARD_FAB2(SCH_1):PUMP_PWM_OUT_BUF
 R10W4    1      A RES_0402-221,1.0%,1/16W,CHIP,GA    I14 @BASEBOARD_FAB2_LIB.BASEBOARD_FAB2(SCH_1):PAGE251
 U10W1    4      Y TTL1G07_A_SOP-74LVC1G07,IC,C88B    I19 @BASEBOARD_FAB2_LIB.BASEBOARD_FAB2(SCH_1):PAGE251

PUMP_PWM_OUT_R @BASEBOARD_FAB2_LIB.BASEBOARD_FAB2(SCH_1):PUMP_PWM_OUT_R
CR10W2    2      A DIODE_SM-SDMK0340L,EMPTY,H7179A    I10 @BASEBOARD_FAB2_LIB.BASEBOARD_FAB2(SCH_1):PAGE251
 R10W3    2      B RES_0402-4.75K,1%,1/16W,CHIP,GA    I11 @BASEBOARD_FAB2_LIB.BASEBOARD_FAB2(SCH_1):PAGE251
 R10W4    2      B RES_0402-221,1.0%,1/16W,CHIP,GA    I14 @BASEBOARD_FAB2_LIB.BASEBOARD_FAB2(SCH_1):PAGE251
  J1B2    4    IO4 CONN6_C74770005_PIP-HDR,C74770A    I25 @BASEBOARD_FAB2_LIB.BASEBOARD_FAB2(SCH_1):PAGE251

PUMP_TACH0 @BASEBOARD_FAB2_LIB.BASEBOARD_FAB2(SCH_1):PUMP_TACH0
 U25W4  AB3 GPIOO4_TACH4_VPIR2 AST2520A1-GP-GP_ASIC2-GB1-AST2A   I106 @BASEBOARD_FAB2_LIB.BASEBOARD_FAB2(SCH_1):PAGE147
 R1T24    1      A RES_0402-0.0,5%,1/16W,EMPTY,G2A   I129 @BASEBOARD_FAB2_LIB.BASEBOARD_FAB2(SCH_1):PAGE147
 R10W1    1      A RES_0402-100.0,1%,1/16W,CHIP,GA    I13 @BASEBOARD_FAB2_LIB.BASEBOARD_FAB2(SCH_1):PAGE251
 R10W2    2      B RES_0402-4.75K,1%,1/16W,CHIP,GA    I15 @BASEBOARD_FAB2_LIB.BASEBOARD_FAB2(SCH_1):PAGE251
 C10W3    1      A CAP_A_0402V-0.01UF,25V,10%,X7RA    I16 @BASEBOARD_FAB2_LIB.BASEBOARD_FAB2(SCH_1):PAGE251
R25W157    1      A RES_0402-100.0K,1%,1/16W,CHIP,A   I164 @BASEBOARD_FAB2_LIB.BASEBOARD_FAB2(SCH_1):PAGE147

PUMP_TACH1 @BASEBOARD_FAB2_LIB.BASEBOARD_FAB2(SCH_1):PUMP_TACH1
 U25W4   Y4 GPIOO5_TACH5_VPIR3 AST2520A1-GP-GP_ASIC2-GB1-AST2A   I106 @BASEBOARD_FAB2_LIB.BASEBOARD_FAB2(SCH_1):PAGE147
R25W142    1      A RES_0402-100.0K,1%,1/16W,CHIP,A   I156 @BASEBOARD_FAB2_LIB.BASEBOARD_FAB2(SCH_1):PAGE147
 R10W6    1      A RES_0402-100.0,1%,1/16W,CHIP,GA    I27 @BASEBOARD_FAB2_LIB.BASEBOARD_FAB2(SCH_1):PAGE251
 C10W5    1      A CAP_A_0402V-0.01UF,25V,10%,X7RA    I29 @BASEBOARD_FAB2_LIB.BASEBOARD_FAB2(SCH_1):PAGE251
 R10W7    2      B RES_0402-4.75K,1%,1/16W,CHIP,GA    I31 @BASEBOARD_FAB2_LIB.BASEBOARD_FAB2(SCH_1):PAGE251

PUMP_TACH1_D @BASEBOARD_FAB2_LIB.BASEBOARD_FAB2(SCH_1):PUMP_TACH1_D
  J1B2    5    IO5 CONN6_C74770005_PIP-HDR,C74770A    I25 @BASEBOARD_FAB2_LIB.BASEBOARD_FAB2(SCH_1):PAGE251
CR10W3    1      C DIODE_SM-SDMK0340L,IC,H71799-0A    I26 @BASEBOARD_FAB2_LIB.BASEBOARD_FAB2(SCH_1):PAGE251

PUMP_TACH1_R @BASEBOARD_FAB2_LIB.BASEBOARD_FAB2(SCH_1):PUMP_TACH1_R
CR10W3    2      A DIODE_SM-SDMK0340L,IC,H71799-0A    I26 @BASEBOARD_FAB2_LIB.BASEBOARD_FAB2(SCH_1):PAGE251
 R10W6    2      B RES_0402-100.0,1%,1/16W,CHIP,GA    I27 @BASEBOARD_FAB2_LIB.BASEBOARD_FAB2(SCH_1):PAGE251

PUMP_TACH_D @BASEBOARD_FAB2_LIB.BASEBOARD_FAB2(SCH_1):PUMP_TACH_D
CR10W1    1      C DIODE_SM-SDMK0340L,IC,H71799-0A    I12 @BASEBOARD_FAB2_LIB.BASEBOARD_FAB2(SCH_1):PAGE251
  J1B2    3    IO3 CONN6_C74770005_PIP-HDR,C74770A    I25 @BASEBOARD_FAB2_LIB.BASEBOARD_FAB2(SCH_1):PAGE251

PUMP_TACH_R @BASEBOARD_FAB2_LIB.BASEBOARD_FAB2(SCH_1):PUMP_TACH_R
CR10W1    2      A DIODE_SM-SDMK0340L,IC,H71799-0A    I12 @BASEBOARD_FAB2_LIB.BASEBOARD_FAB2(SCH_1):PAGE251
 R10W1    2      B RES_0402-100.0,1%,1/16W,CHIP,GA    I13 @BASEBOARD_FAB2_LIB.BASEBOARD_FAB2(SCH_1):PAGE251

PU_10GBE_LOM_PCI_DISABLE_N @BASEBOARD_FAB2_LIB.BASEBOARD_FAB2(SCH_1):PU_10GBE_LOM_PCI_DISABLE_N
  U7C1 BW22 GPP_I8_PCI_DIS_N LBG_CORE_QAT_EXT_D_BGA1-IC,H91A   I147 @BASEBOARD_FAB2_LIB.BASEBOARD_FAB2(SCH_1):PAGE120
  R2N9    2      B RES_0402-10.0K,1%,1/16W,CHIP,GA   I267 @BASEBOARD_FAB2_LIB.BASEBOARD_FAB2(SCH_1):PAGE133

PU_24M_OSC_OE @BASEBOARD_FAB2_LIB.BASEBOARD_FAB2(SCH_1):PU_24M_OSC_OE
  Y9F2    1 ENABLE_CONTROL OSC_C_SM4-24MHZ,OSC,D34520-021     I8 @BASEBOARD_FAB2_LIB.BASEBOARD_FAB2(SCH_1):PAGE145
 R9F61    2      B RES_0402-10.0K,1%,1/16W,CHIP,GA    I14 @BASEBOARD_FAB2_LIB.BASEBOARD_FAB2(SCH_1):PAGE145

PU_33P_33M_SMBADR @BASEBOARD_FAB2_LIB.BASEBOARD_FAB2(SCH_1):PU_33P_33M_SMBADR
 EU8F2   22 33MHZ_SMBADR ICS9FGP204_MLFP-IC,E95226-001    I34 @BASEBOARD_FAB2_LIB.BASEBOARD_FAB2(SCH_1):PAGE101
 R1W25    1      A RES_0402-1.00K,1%,1/16W,CHIP,GA   I140 @BASEBOARD_FAB2_LIB.BASEBOARD_FAB2(SCH_1):PAGE101

PU_ADR_TIMER_HOLD_OFF_N @BASEBOARD_FAB2_LIB.BASEBOARD_FAB2(SCH_1):PU_ADR_TIMER_HOLD_OFF_N
  U7C1  BB3 GPP_H15_SML3ALERT_N_IE_N LBG_CORE_QAT_EXT_D_BGA1-IC,H91A   I147 @BASEBOARD_FAB2_LIB.BASEBOARD_FAB2(SCH_1):PAGE120
  R8D5    1      A RES_0402-1.00K,1%,1/16W,EMPTY,A    I50 @BASEBOARD_FAB2_LIB.BASEBOARD_FAB2(SCH_1):PAGE125
 R8D13    2      B RES_0402-10.0K,1%,1/16W,EMPTY,A    I87 @BASEBOARD_FAB2_LIB.BASEBOARD_FAB2(SCH_1):PAGE125

PU_AT24C64_A2 @BASEBOARD_FAB2_LIB.BASEBOARD_FAB2(SCH_1):PU_AT24C64_A2
  U8D4    3     A2 AT24C64_SOICLF-IC,C47049-001-GA    I49 @BASEBOARD_FAB2_LIB.BASEBOARD_FAB2(SCH_1):PAGE167
 R8D28    2      B RES_0402-1.00K,1%,1/16W,CHIP,GA    I70 @BASEBOARD_FAB2_LIB.BASEBOARD_FAB2(SCH_1):PAGE167

PU_BIOS_RECOVER_BOOT @BASEBOARD_FAB2_LIB.BASEBOARD_FAB2(SCH_1):PU_BIOS_RECOVER_BOOT
 R7G31    2      B RES_0402-1.00K,1%,1/16W,CHIP,GA   I139 @BASEBOARD_FAB2_LIB.BASEBOARD_FAB2(SCH_1):PAGE136
  J7G3   12   IO12 CONN12_C73564003_PIP-CONN,C735A   I174 @BASEBOARD_FAB2_LIB.BASEBOARD_FAB2(SCH_1):PAGE136

PU_BIOS_SPI_HOLD0_N @BASEBOARD_FAB2_LIB.BASEBOARD_FAB2(SCH_1):PU_BIOS_SPI_HOLD0_N
  R7F3    2      B RES_0402-33.2,1%,1/16W,CHIP,G2A   I109 @BASEBOARD_FAB2_LIB.BASEBOARD_FAB2(SCH_1):PAGE153
 R7F32    2      B RES_0402-10.0K,1%,1/16W,CHIP,GA   I140 @BASEBOARD_FAB2_LIB.BASEBOARD_FAB2(SCH_1):PAGE153
  U7F1    1 HOLD_N_IO<3> W25Q256_XSOI-IC,H25002-001   I146 @BASEBOARD_FAB2_LIB.BASEBOARD_FAB2(SCH_1):PAGE153

PU_BIOS_SPI_HOLD1_N @BASEBOARD_FAB2_LIB.BASEBOARD_FAB2(SCH_1):PU_BIOS_SPI_HOLD1_N
  R3T1    2      B RES_0402-33.2,1%,1/16W,CHIP,G2A   I157 @BASEBOARD_FAB2_LIB.BASEBOARD_FAB2(SCH_1):PAGE153
  R3T4    2      B RES_0402-10.0K,1%,1/16W,CHIP,GA   I174 @BASEBOARD_FAB2_LIB.BASEBOARD_FAB2(SCH_1):PAGE153
  U3T1    1 HOLD#/IO3 W25Q256FVFIG-GP_MEMORY-G4-W25QA   I185 @BASEBOARD_FAB2_LIB.BASEBOARD_FAB2(SCH_1):PAGE153

PU_BIOS_SPI_WP0_N @BASEBOARD_FAB2_LIB.BASEBOARD_FAB2(SCH_1):PU_BIOS_SPI_WP0_N
 R7F37    2      B RES_0402-33.2,1%,1/16W,CHIP,G2A   I108 @BASEBOARD_FAB2_LIB.BASEBOARD_FAB2(SCH_1):PAGE153
  U7F1    9 WP_N_IO<2> W25Q256_XSOI-IC,H25002-001   I146 @BASEBOARD_FAB2_LIB.BASEBOARD_FAB2(SCH_1):PAGE153
 R7F28    2      B RES_0402-10.0K,1%,1/16W,CHIP,GA   I168 @BASEBOARD_FAB2_LIB.BASEBOARD_FAB2(SCH_1):PAGE153
 R7F30    1      A RES_0402-10.0K,1%,1/16W,EMPTY,A   I170 @BASEBOARD_FAB2_LIB.BASEBOARD_FAB2(SCH_1):PAGE153

PU_BIOS_SPI_WP1_N @BASEBOARD_FAB2_LIB.BASEBOARD_FAB2(SCH_1):PU_BIOS_SPI_WP1_N
  R3U1    2      B RES_0402-33.2,1%,1/16W,CHIP,G2A   I156 @BASEBOARD_FAB2_LIB.BASEBOARD_FAB2(SCH_1):PAGE153
 R3T12    2      B RES_0402-10.0K,1%,1/16W,CHIP,GA   I178 @BASEBOARD_FAB2_LIB.BASEBOARD_FAB2(SCH_1):PAGE153
  R3T9    1      A RES_0402-10.0K,1%,1/16W,EMPTY,A   I179 @BASEBOARD_FAB2_LIB.BASEBOARD_FAB2(SCH_1):PAGE153
  U3T1    9 WP#/IO2 W25Q256FVFIG-GP_MEMORY-G4-W25QA   I185 @BASEBOARD_FAB2_LIB.BASEBOARD_FAB2(SCH_1):PAGE153

PU_BIOS_USB_RECOVERY @BASEBOARD_FAB2_LIB.BASEBOARD_FAB2(SCH_1):PU_BIOS_USB_RECOVERY
 R7G27    2      B RES_0402-1.00K,1%,1/16W,CHIP,GA   I155 @BASEBOARD_FAB2_LIB.BASEBOARD_FAB2(SCH_1):PAGE136
  J7G3    6    IO6 CONN12_C73564003_PIP-CONN,C735A   I174 @BASEBOARD_FAB2_LIB.BASEBOARD_FAB2(SCH_1):PAGE136

PU_CPLD1_PT20D_PROGRAMN @BASEBOARD_FAB2_LIB.BASEBOARD_FAB2(SCH_1):PU_CPLD1_PT20D_PROGRAMN
  U8D7  B10 PT20D_PROGRAMN LCMXO2_A_256BGA-IC,H63395-001    I59 @BASEBOARD_FAB2_LIB.BASEBOARD_FAB2(SCH_1):PAGE191
  R4W1    2      B RES_0402-4.75K,1%,1/16W,CHIP,GA   I195 @BASEBOARD_FAB2_LIB.BASEBOARD_FAB2(SCH_1):PAGE191

PU_CPU0_FRMAGENT @BASEBOARD_FAB2_LIB.BASEBOARD_FAB2(SCH_1):PU_CPU0_FRMAGENT
  U5D1 AV17 FRMAGENT SKX_EXT_B_BGA1-IC,TBD   I259 @BASEBOARD_FAB2_LIB.BASEBOARD_FAB2(SCH_1):PAGE21
  R5D3    2      B RES_0402-240,1.0%,1/16W,CHIP,GA    I29 @BASEBOARD_FAB2_LIB.BASEBOARD_FAB2(SCH_1):PAGE90

PU_CPU0_LEGACY_SKT @BASEBOARD_FAB2_LIB.BASEBOARD_FAB2(SCH_1):PU_CPU0_LEGACY_SKT
  U5D1 AE20 LEGACY_SKT SKX_EXT_B_BGA1-IC,TBD   I259 @BASEBOARD_FAB2_LIB.BASEBOARD_FAB2(SCH_1):PAGE21
 R4P14    2      B RES_0402-240,1.0%,1/16W,CHIP,GA    I53 @BASEBOARD_FAB2_LIB.BASEBOARD_FAB2(SCH_1):PAGE90

PU_CPU0_SAFE_MODE_BOOT @BASEBOARD_FAB2_LIB.BASEBOARD_FAB2(SCH_1):PU_CPU0_SAFE_MODE_BOOT
  U5D1 AR18 SAFE_MODE_BOOT SKX_EXT_B_BGA1-IC,TBD   I259 @BASEBOARD_FAB2_LIB.BASEBOARD_FAB2(SCH_1):PAGE21
 R6D13    2      B RES_0402-240,1.0%,1/16W,EMPTY,A    I33 @BASEBOARD_FAB2_LIB.BASEBOARD_FAB2(SCH_1):PAGE90

PU_CPU0_SOCKET_ID_0 @BASEBOARD_FAB2_LIB.BASEBOARD_FAB2(SCH_1):PU_CPU0_SOCKET_ID_0
  U5D1 AU22 SOCKET_ID<0> SKX_EXT_B_BGA1-IC,TBD   I259 @BASEBOARD_FAB2_LIB.BASEBOARD_FAB2(SCH_1):PAGE21
 R6D15    2      B RES_0402-240,1.0%,1/16W,EMPTY,A    I48 @BASEBOARD_FAB2_LIB.BASEBOARD_FAB2(SCH_1):PAGE90

PU_CPU0_SOCKET_ID_1 @BASEBOARD_FAB2_LIB.BASEBOARD_FAB2(SCH_1):PU_CPU0_SOCKET_ID_1
  U5D1 AU16 SOCKET_ID<1> SKX_EXT_B_BGA1-IC,TBD   I259 @BASEBOARD_FAB2_LIB.BASEBOARD_FAB2(SCH_1):PAGE21
 R6D10    2      B RES_0402-240,1.0%,1/16W,EMPTY,A    I49 @BASEBOARD_FAB2_LIB.BASEBOARD_FAB2(SCH_1):PAGE90

PU_CPU0_TSC_SYNC @BASEBOARD_FAB2_LIB.BASEBOARD_FAB2(SCH_1):PU_CPU0_TSC_SYNC
  U5D1 AM11 TSC_SYNC SKX_EXT_B_BGA1-IC,TBD   I259 @BASEBOARD_FAB2_LIB.BASEBOARD_FAB2(SCH_1):PAGE21
 R4P21    2      B RES_0402-240,1.0%,1/16W,CHIP,GA    I72 @BASEBOARD_FAB2_LIB.BASEBOARD_FAB2(SCH_1):PAGE97

PU_CPU0_TXT_AGENT @BASEBOARD_FAB2_LIB.BASEBOARD_FAB2(SCH_1):PU_CPU0_TXT_AGENT
  U5D1 AW18 TXT_AGENT SKX_EXT_B_BGA1-IC,TBD   I259 @BASEBOARD_FAB2_LIB.BASEBOARD_FAB2(SCH_1):PAGE21
  R5D4    2      B RES_0402-240,1.0%,1/16W,CHIP,GA    I96 @BASEBOARD_FAB2_LIB.BASEBOARD_FAB2(SCH_1):PAGE90

PU_CPU1_FRMAGENT @BASEBOARD_FAB2_LIB.BASEBOARD_FAB2(SCH_1):PU_CPU1_FRMAGENT
  U2D1 AV17 FRMAGENT SKX_EXT_B_BGA1-IC,TBD   I172 @BASEBOARD_FAB2_LIB.BASEBOARD_FAB2(SCH_1):PAGE55
 R3D22    2      B RES_0402-240,1.0%,1/16W,EMPTY,A    I17 @BASEBOARD_FAB2_LIB.BASEBOARD_FAB2(SCH_1):PAGE90

PU_CPU1_LEGACY_SKT @BASEBOARD_FAB2_LIB.BASEBOARD_FAB2(SCH_1):PU_CPU1_LEGACY_SKT
  U2D1 AE20 LEGACY_SKT SKX_EXT_B_BGA1-IC,TBD   I172 @BASEBOARD_FAB2_LIB.BASEBOARD_FAB2(SCH_1):PAGE55
 R7P22    2      B RES_0402-240,1.0%,1/16W,EMPTY,A    I76 @BASEBOARD_FAB2_LIB.BASEBOARD_FAB2(SCH_1):PAGE90

PU_CPU1_SAFE_MODE_BOOT @BASEBOARD_FAB2_LIB.BASEBOARD_FAB2(SCH_1):PU_CPU1_SAFE_MODE_BOOT
  U2D1 AR18 SAFE_MODE_BOOT SKX_EXT_B_BGA1-IC,TBD   I172 @BASEBOARD_FAB2_LIB.BASEBOARD_FAB2(SCH_1):PAGE55
 R3D26    2      B RES_0402-240,1.0%,1/16W,EMPTY,A    I28 @BASEBOARD_FAB2_LIB.BASEBOARD_FAB2(SCH_1):PAGE90

PU_CPU1_SOCKET_ID_0 @BASEBOARD_FAB2_LIB.BASEBOARD_FAB2(SCH_1):PU_CPU1_SOCKET_ID_0
  U2D1 AU22 SOCKET_ID<0> SKX_EXT_B_BGA1-IC,TBD   I172 @BASEBOARD_FAB2_LIB.BASEBOARD_FAB2(SCH_1):PAGE55
 R3D24    2      B RES_0402-240,1.0%,1/16W,CHIP,GA    I59 @BASEBOARD_FAB2_LIB.BASEBOARD_FAB2(SCH_1):PAGE90

PU_CPU1_SOCKET_ID_1 @BASEBOARD_FAB2_LIB.BASEBOARD_FAB2(SCH_1):PU_CPU1_SOCKET_ID_1
  U2D1 AU16 SOCKET_ID<1> SKX_EXT_B_BGA1-IC,TBD   I172 @BASEBOARD_FAB2_LIB.BASEBOARD_FAB2(SCH_1):PAGE55
 R3D17    2      B RES_0402-240,1.0%,1/16W,EMPTY,A    I60 @BASEBOARD_FAB2_LIB.BASEBOARD_FAB2(SCH_1):PAGE90

PU_CPU1_TSC_SYNC @BASEBOARD_FAB2_LIB.BASEBOARD_FAB2(SCH_1):PU_CPU1_TSC_SYNC
  U2D1 AM11 TSC_SYNC SKX_EXT_B_BGA1-IC,TBD   I172 @BASEBOARD_FAB2_LIB.BASEBOARD_FAB2(SCH_1):PAGE55
 R4C10    2      B RES_0402-240,1.0%,1/16W,CHIP,GA    I76 @BASEBOARD_FAB2_LIB.BASEBOARD_FAB2(SCH_1):PAGE97

PU_CPU1_TXT_AGENT @BASEBOARD_FAB2_LIB.BASEBOARD_FAB2(SCH_1):PU_CPU1_TXT_AGENT
  U2D1 AW18 TXT_AGENT SKX_EXT_B_BGA1-IC,TBD   I172 @BASEBOARD_FAB2_LIB.BASEBOARD_FAB2(SCH_1):PAGE55
 R3D23    2      B RES_0402-240,1.0%,1/16W,EMPTY,A    I25 @BASEBOARD_FAB2_LIB.BASEBOARD_FAB2(SCH_1):PAGE90

PU_DATAIN1_SATA_0_R @BASEBOARD_FAB2_LIB.BASEBOARD_FAB2(SCH_1):PU_DATAIN1_SATA_0_R
  J8A1  1D1 SIDEBANDA_5 CONN72_G97614002_A_CP-CONN,G97A   I163 @BASEBOARD_FAB2_LIB.BASEBOARD_FAB2(SCH_1):PAGE173
 R2L21    2      B RES_0402-2.0K,1%,1/16W,CHIP,G2A   I263 @BASEBOARD_FAB2_LIB.BASEBOARD_FAB2(SCH_1):PAGE173

PU_DATAIN1_SATA_1_R @BASEBOARD_FAB2_LIB.BASEBOARD_FAB2(SCH_1):PU_DATAIN1_SATA_1_R
  J8A1  2D1 SIDEBANDB_5 CONN72_G97614002_A_CP-CONN,G97A   I163 @BASEBOARD_FAB2_LIB.BASEBOARD_FAB2(SCH_1):PAGE173
 R2L23    2      B RES_0402-2.0K,1%,1/16W,CHIP,G2A   I261 @BASEBOARD_FAB2_LIB.BASEBOARD_FAB2(SCH_1):PAGE173

PU_DEV_OFF_N @BASEBOARD_FAB2_LIB.BASEBOARD_FAB2(SCH_1):PU_DEV_OFF_N
 EU9E1   28 DEV_OFF_N SPRINGVILLE_SM1-IC,G47144-004    I72 @BASEBOARD_FAB2_LIB.BASEBOARD_FAB2(SCH_1):PAGE139
 R9W36    2      B RES_0402-10.0K,1%,1/16W,CHIP,GA   I252 @BASEBOARD_FAB2_LIB.BASEBOARD_FAB2(SCH_1):PAGE139

PU_FAB2_MARKER_CPLD @BASEBOARD_FAB2_LIB.BASEBOARD_FAB2(SCH_1):PU_FAB2_MARKER_CPLD
  U8D7  K16   PR9B LCMXO2_A_256BGA-IC,H63395-001    I59 @BASEBOARD_FAB2_LIB.BASEBOARD_FAB2(SCH_1):PAGE191
 R7D42    2      B RES_0402-4.75K,1%,1/16W,CHIP,GA   I193 @BASEBOARD_FAB2_LIB.BASEBOARD_FAB2(SCH_1):PAGE191

PU_FM_RCIN_N @BASEBOARD_FAB2_LIB.BASEBOARD_FAB2(SCH_1):PU_FM_RCIN_N
  U7C1   N3 GPP_A0_RCIN_N_ESPI_ALERT1_N LBG_CORE_QAT_EXT_D_BGA1-IC,H91A   I115 @BASEBOARD_FAB2_LIB.BASEBOARD_FAB2(SCH_1):PAGE119
  R7D2    2      B RES_0402-1.00K,1%,1/16W,CHIP,GA   I332 @BASEBOARD_FAB2_LIB.BASEBOARD_FAB2(SCH_1):PAGE133

PU_GTL2014_1_DIR @BASEBOARD_FAB2_LIB.BASEBOARD_FAB2(SCH_1):PU_GTL2014_1_DIR
 R3P36    2      B RES_0402-1.00K,1%,1/16W,CHIP,GA    I36 @BASEBOARD_FAB2_LIB.BASEBOARD_FAB2(SCH_1):PAGE96
  U3P1    1    DIR GTL2014_SM-IC,D66151-001    I42 @BASEBOARD_FAB2_LIB.BASEBOARD_FAB2(SCH_1):PAGE96

PU_GTL2014_2_DIR @BASEBOARD_FAB2_LIB.BASEBOARD_FAB2(SCH_1):PU_GTL2014_2_DIR
  U4C2    1    DIR GTL2014_SM-IC,D66151-001    I46 @BASEBOARD_FAB2_LIB.BASEBOARD_FAB2(SCH_1):PAGE96
  R4C8    2      B RES_0402-1.00K,1%,1/16W,CHIP,GA    I55 @BASEBOARD_FAB2_LIB.BASEBOARD_FAB2(SCH_1):PAGE96

PU_GTL2014_3_DIR @BASEBOARD_FAB2_LIB.BASEBOARD_FAB2(SCH_1):PU_GTL2014_3_DIR
R25W158    2      B RES_0402-1.00K,1%,1/16W,CHIP,GA    I22 @BASEBOARD_FAB2_LIB.BASEBOARD_FAB2(SCH_1):PAGE269
U25W10    1    DIR GTL2014_SM-IC,D66151-001    I49 @BASEBOARD_FAB2_LIB.BASEBOARD_FAB2(SCH_1):PAGE269

PU_ID_EEPROM_A0 @BASEBOARD_FAB2_LIB.BASEBOARD_FAB2(SCH_1):PU_ID_EEPROM_A0
  U6W3    1     A0 AT24C64_SOICLF-IC,C47049-001-GA    I89 @BASEBOARD_FAB2_LIB.BASEBOARD_FAB2(SCH_1):PAGE247
 R6W21    2      B RES_0402-1.00K,1%,1/16W,CHIP,GA    I90 @BASEBOARD_FAB2_LIB.BASEBOARD_FAB2(SCH_1):PAGE247

PU_IRQ_PCH_SCI_WHEA_N @BASEBOARD_FAB2_LIB.BASEBOARD_FAB2(SCH_1):PU_IRQ_PCH_SCI_WHEA_N
  U7C1   R1 GPP_A12_BMBUSY_N_SXEXITHLDOFF_N LBG_CORE_QAT_EXT_D_BGA1-IC,H91A   I115 @BASEBOARD_FAB2_LIB.BASEBOARD_FAB2(SCH_1):PAGE119
  R7D4    2      B RES_0402-10.0K,1%,1/16W,CHIP,GA   I245 @BASEBOARD_FAB2_LIB.BASEBOARD_FAB2(SCH_1):PAGE133

PU_IRQ_VRALERT_N @BASEBOARD_FAB2_LIB.BASEBOARD_FAB2(SCH_1):PU_IRQ_VRALERT_N
  U7C1 BN15 GPP_B2 LBG_CORE_QAT_EXT_D_BGA1-IC,H91A   I115 @BASEBOARD_FAB2_LIB.BASEBOARD_FAB2(SCH_1):PAGE119
 R2N16    2      B RES_0402-10.0K,1%,1/16W,CHIP,GA   I247 @BASEBOARD_FAB2_LIB.BASEBOARD_FAB2(SCH_1):PAGE133

PU_JTAG_BMC_RTCK @BASEBOARD_FAB2_LIB.BASEBOARD_FAB2(SCH_1):PU_JTAG_BMC_RTCK
 U25W4   C9   RTCK AST2520A1-GP-GP_ASIC2-GB1-AST2A    I95 @BASEBOARD_FAB2_LIB.BASEBOARD_FAB2(SCH_1):PAGE144
R25W105    2      B RES_0402-4.75K,1%,1/16W,EMPTY,A   I196 @BASEBOARD_FAB2_LIB.BASEBOARD_FAB2(SCH_1):PAGE150

PU_JTAG_SPRV_TCK @BASEBOARD_FAB2_LIB.BASEBOARD_FAB2(SCH_1):PU_JTAG_SPRV_TCK
 EU9E1   19 JTAG_CLK SPRINGVILLE_SM1-IC,G47144-004    I72 @BASEBOARD_FAB2_LIB.BASEBOARD_FAB2(SCH_1):PAGE139
  R9E2    2      B RES_0402-10.0K,1%,1/16W,CHIP,GA   I177 @BASEBOARD_FAB2_LIB.BASEBOARD_FAB2(SCH_1):PAGE139

PU_JTAG_SPRV_TDI @BASEBOARD_FAB2_LIB.BASEBOARD_FAB2(SCH_1):PU_JTAG_SPRV_TDI
 EU9E1   29 JTAG_TDI SPRINGVILLE_SM1-IC,G47144-004    I72 @BASEBOARD_FAB2_LIB.BASEBOARD_FAB2(SCH_1):PAGE139
  R9E1    2      B RES_0402-10.0K,1%,1/16W,CHIP,GA   I179 @BASEBOARD_FAB2_LIB.BASEBOARD_FAB2(SCH_1):PAGE139

PU_JTAG_SPRV_TDO @BASEBOARD_FAB2_LIB.BASEBOARD_FAB2(SCH_1):PU_JTAG_SPRV_TDO
 EU9E1    4 JTAG_TDO SPRINGVILLE_SM1-IC,G47144-004    I72 @BASEBOARD_FAB2_LIB.BASEBOARD_FAB2(SCH_1):PAGE139
 R9E22    1      A RES_0402-10.0K,1%,1/16W,CHIP,GA   I181 @BASEBOARD_FAB2_LIB.BASEBOARD_FAB2(SCH_1):PAGE139

PU_JTAG_SPRV_TMS @BASEBOARD_FAB2_LIB.BASEBOARD_FAB2(SCH_1):PU_JTAG_SPRV_TMS
 EU9E1   18 JTAG_TMS SPRINGVILLE_SM1-IC,G47144-004    I72 @BASEBOARD_FAB2_LIB.BASEBOARD_FAB2(SCH_1):PAGE139
  R9E3    2      B RES_0402-10.0K,1%,1/16W,CHIP,GA   I178 @BASEBOARD_FAB2_LIB.BASEBOARD_FAB2(SCH_1):PAGE139

PU_KEY_CONN_PIN2_R @BASEBOARD_FAB2_LIB.BASEBOARD_FAB2(SCH_1):PU_KEY_CONN_PIN2_R
 R9A16    1      A RES_0402-2.21K,1%,1/16W,CHIP,GA   I129 @BASEBOARD_FAB2_LIB.BASEBOARD_FAB2(SCH_1):PAGE135
  J9A1    2    IO2 CONN4_D42317002_PIP-CONN,D4231A   I131 @BASEBOARD_FAB2_LIB.BASEBOARD_FAB2(SCH_1):PAGE135

PU_LPC_CLKRUN_N @BASEBOARD_FAB2_LIB.BASEBOARD_FAB2(SCH_1):PU_LPC_CLKRUN_N
  U7C1  AB1 GPP_A8_CLKRUN_N LBG_CORE_QAT_EXT_D_BGA1-IC,H91A   I115 @BASEBOARD_FAB2_LIB.BASEBOARD_FAB2(SCH_1):PAGE119
  R7D8    2      B RES_0402-10.0K,1%,1/16W,CHIP,GA   I200 @BASEBOARD_FAB2_LIB.BASEBOARD_FAB2(SCH_1):PAGE133

PU_LPC_PME_N @BASEBOARD_FAB2_LIB.BASEBOARD_FAB2(SCH_1):PU_LPC_PME_N
  U7C1  AC2 GPP_A11_PME_N LBG_CORE_QAT_EXT_D_BGA1-IC,H91A   I115 @BASEBOARD_FAB2_LIB.BASEBOARD_FAB2(SCH_1):PAGE119
 R7D10    2      B RES_0402-10.0K,1%,1/16W,CHIP,GA   I202 @BASEBOARD_FAB2_LIB.BASEBOARD_FAB2(SCH_1):PAGE133

PU_M2_CLK_REQ_N @BASEBOARD_FAB2_LIB.BASEBOARD_FAB2(SCH_1):PU_M2_CLK_REQ_N
 R8F36    2      B RES_0402-10.0K,1%,1/16W,CHIP,GA   I136 @BASEBOARD_FAB2_LIB.BASEBOARD_FAB2(SCH_1):PAGE185
  J8F1   52     52 SKT-MINI67P-41-GP_SOCKET-G4-SKA   I143 @BASEBOARD_FAB2_LIB.BASEBOARD_FAB2(SCH_1):PAGE185

PU_NV_HOLD_N @BASEBOARD_FAB2_LIB.BASEBOARD_FAB2(SCH_1):PU_NV_HOLD_N
  U9E1    7 RESET_N M25PE16_SM-IC,H77797-001     I1 @BASEBOARD_FAB2_LIB.BASEBOARD_FAB2(SCH_1):PAGE140
  R1R9    2      B RES_0402-3.32K,1%,1/16W,CHIP,GA    I10 @BASEBOARD_FAB2_LIB.BASEBOARD_FAB2(SCH_1):PAGE140

PU_NV_WP_N @BASEBOARD_FAB2_LIB.BASEBOARD_FAB2(SCH_1):PU_NV_WP_N
  U9E1    3    W_N M25PE16_SM-IC,H77797-001     I1 @BASEBOARD_FAB2_LIB.BASEBOARD_FAB2(SCH_1):PAGE140
  R1R3    2      B RES_0402-3.32K,1%,1/16W,CHIP,GA    I11 @BASEBOARD_FAB2_LIB.BASEBOARD_FAB2(SCH_1):PAGE140

PU_PCH_TLS_ENABLE_STRAP @BASEBOARD_FAB2_LIB.BASEBOARD_FAB2(SCH_1):PU_PCH_TLS_ENABLE_STRAP
  J8G1   27   IO27 SCONN200_H68296001_SM-CONN,H68A   I258 @BASEBOARD_FAB2_LIB.BASEBOARD_FAB2(SCH_1):PAGE108
  U7C1 BY27 GPP_C2_SMBALERT_N LBG_CORE_QAT_EXT_D_BGA1-IC,H91A   I115 @BASEBOARD_FAB2_LIB.BASEBOARD_FAB2(SCH_1):PAGE119
 R8C18    2      B RES_0402-1.00K,1%,1/16W,CHIP,GA    I40 @BASEBOARD_FAB2_LIB.BASEBOARD_FAB2(SCH_1):PAGE125
 R8C17    1      A RES_0402-1.00K,1%,1/16W,EMPTY,A    I41 @BASEBOARD_FAB2_LIB.BASEBOARD_FAB2(SCH_1):PAGE125

PU_PIROM_CPU1_ADDR0 @BASEBOARD_FAB2_LIB.BASEBOARD_FAB2(SCH_1):PU_PIROM_CPU1_ADDR0
  U2D1 CU58 PIROM_ADDR<0> SKX_EXT_B_BGA1-IC,TBD   I172 @BASEBOARD_FAB2_LIB.BASEBOARD_FAB2(SCH_1):PAGE55
 R1C34    2      B RES_0402-10.0K,1%,1/16W,CHIP,GA   I320 @BASEBOARD_FAB2_LIB.BASEBOARD_FAB2(SCH_1):PAGE156

PU_PVNN_PCH_PINALRT_N @BASEBOARD_FAB2_LIB.BASEBOARD_FAB2(SCH_1):PU_PVNN_PCH_PINALRT_N
 EU8A1   12 PINALRT_N PXE1110B_QFN-IC,H89187-001   I229 @BASEBOARD_FAB2_LIB.BASEBOARD_FAB2(SCH_1):PAGE235
  R8W8    2      B RES_0402-1.00K,1%,1/16W,CHIP,GA   I249 @BASEBOARD_FAB2_LIB.BASEBOARD_FAB2(SCH_1):PAGE235

PU_PVNN_PCH_VCLK @BASEBOARD_FAB2_LIB.BASEBOARD_FAB2(SCH_1):PU_PVNN_PCH_VCLK
 EU8A1   15   VCLK PXE1110B_QFN-IC,H89187-001   I229 @BASEBOARD_FAB2_LIB.BASEBOARD_FAB2(SCH_1):PAGE235
  R8W2    1      A RES_0402-1.00K,1%,1/16W,CHIP,GA   I247 @BASEBOARD_FAB2_LIB.BASEBOARD_FAB2(SCH_1):PAGE235

PU_PVNN_PCH_VDIO @BASEBOARD_FAB2_LIB.BASEBOARD_FAB2(SCH_1):PU_PVNN_PCH_VDIO
 EU8A1   16   VDIO PXE1110B_QFN-IC,H89187-001   I229 @BASEBOARD_FAB2_LIB.BASEBOARD_FAB2(SCH_1):PAGE235
  R8W3    2      B RES_0402-1.00K,1%,1/16W,CHIP,GA   I248 @BASEBOARD_FAB2_LIB.BASEBOARD_FAB2(SCH_1):PAGE235

PU_RST_PERST_BIT0 @BASEBOARD_FAB2_LIB.BASEBOARD_FAB2(SCH_1):PU_RST_PERST_BIT0
  U8D7   F4   PL3C LCMXO2_A_256BGA-IC,H63395-001   I179 @BASEBOARD_FAB2_LIB.BASEBOARD_FAB2(SCH_1):PAGE190
  R2R1    2      B RES_0402-10.0K,1%,1/16W,CHIP,GA    I34 @BASEBOARD_FAB2_LIB.BASEBOARD_FAB2(SCH_1):PAGE192

PU_RST_PERST_BIT1 @BASEBOARD_FAB2_LIB.BASEBOARD_FAB2(SCH_1):PU_RST_PERST_BIT1
  U8D7   B9  PT19A LCMXO2_A_256BGA-IC,H63395-001    I59 @BASEBOARD_FAB2_LIB.BASEBOARD_FAB2(SCH_1):PAGE191
  R7E6    2      B RES_0402-10.0K,1%,1/16W,CHIP,GA    I33 @BASEBOARD_FAB2_LIB.BASEBOARD_FAB2(SCH_1):PAGE192

PU_SPI0_RST @BASEBOARD_FAB2_LIB.BASEBOARD_FAB2(SCH_1):PU_SPI0_RST
  R7F6    2      B RES_0402-4.75K,1%,1/16W,EMPTY,A    I90 @BASEBOARD_FAB2_LIB.BASEBOARD_FAB2(SCH_1):PAGE153
  U7F1    3 RESET_N W25Q256_XSOI-IC,H25002-001   I146 @BASEBOARD_FAB2_LIB.BASEBOARD_FAB2(SCH_1):PAGE153

PU_SPI1_RST @BASEBOARD_FAB2_LIB.BASEBOARD_FAB2(SCH_1):PU_SPI1_RST
  R3T3    2      B RES_0402-4.75K,1%,1/16W,EMPTY,A   I150 @BASEBOARD_FAB2_LIB.BASEBOARD_FAB2(SCH_1):PAGE153
  U3T1    3 RESET# W25Q256FVFIG-GP_MEMORY-G4-W25QA   I185 @BASEBOARD_FAB2_LIB.BASEBOARD_FAB2(SCH_1):PAGE153

PU_SPI_BMC_BT_CS0_N @BASEBOARD_FAB2_LIB.BASEBOARD_FAB2(SCH_1):PU_SPI_BMC_BT_CS0_N
  J9G1    8    IO8 CONN12_C73564003_PIP-CONN,C735A   I128 @BASEBOARD_FAB2_LIB.BASEBOARD_FAB2(SCH_1):PAGE137
 RN8F1    2      B RES_0402-4.75K,1%,1/16W,CHIP,GA   I142 @BASEBOARD_FAB2_LIB.BASEBOARD_FAB2(SCH_1):PAGE137

PU_SPI_BMC_BT_HOLD_N @BASEBOARD_FAB2_LIB.BASEBOARD_FAB2(SCH_1):PU_SPI_BMC_BT_HOLD_N
 R8F14    2      B RES_0402-4.75K,1%,1/16W,CHIP,GA     I9 @BASEBOARD_FAB2_LIB.BASEBOARD_FAB2(SCH_1):PAGE162
  U8F2    1 HOLD_N_IO<3> W25Q128_SKT16-IC,H12709-001    I32 @BASEBOARD_FAB2_LIB.BASEBOARD_FAB2(SCH_1):PAGE162

PU_SPI_BMC_BT_WP_N @BASEBOARD_FAB2_LIB.BASEBOARD_FAB2(SCH_1):PU_SPI_BMC_BT_WP_N
 R8F34    2      B RES_0402-4.75K,1%,1/16W,CHIP,GA    I22 @BASEBOARD_FAB2_LIB.BASEBOARD_FAB2(SCH_1):PAGE162
 R8F35    1      A RES_0402-1.00K,1%,1/16W,EMPTY,A    I24 @BASEBOARD_FAB2_LIB.BASEBOARD_FAB2(SCH_1):PAGE162
  U8F2    9 WP_N_IO<2> W25Q128_SKT16-IC,H12709-001    I32 @BASEBOARD_FAB2_LIB.BASEBOARD_FAB2(SCH_1):PAGE162

PU_SPI_FLASH_RESET_2_N @BASEBOARD_FAB2_LIB.BASEBOARD_FAB2(SCH_1):PU_SPI_FLASH_RESET_2_N
 R8F16    2      B RES_0402-4.75K,1%,1/16W,EMPTY,A     I8 @BASEBOARD_FAB2_LIB.BASEBOARD_FAB2(SCH_1):PAGE162
  U8F2    3 RESET_N W25Q128_SKT16-IC,H12709-001    I32 @BASEBOARD_FAB2_LIB.BASEBOARD_FAB2(SCH_1):PAGE162

PU_SPRV_LAN_PWR_GOOD @BASEBOARD_FAB2_LIB.BASEBOARD_FAB2(SCH_1):PU_SPRV_LAN_PWR_GOOD
 EU9E1    1 LAN_PWR_GOOD SPRINGVILLE_SM1-IC,G47144-004    I72 @BASEBOARD_FAB2_LIB.BASEBOARD_FAB2(SCH_1):PAGE139
  R9F5    2      B RES_0402-3.32K,1%,1/16W,CHIP,GA   I173 @BASEBOARD_FAB2_LIB.BASEBOARD_FAB2(SCH_1):PAGE139

PU_THERMTRIP_FORCE_N @BASEBOARD_FAB2_LIB.BASEBOARD_FAB2(SCH_1):PU_THERMTRIP_FORCE_N
  U8D7  A12  PT22B LCMXO2_A_256BGA-IC,H63395-001    I59 @BASEBOARD_FAB2_LIB.BASEBOARD_FAB2(SCH_1):PAGE191
  R7E5    2      B RES_0402-10.0K,1%,1/16W,CHIP,GA    I38 @BASEBOARD_FAB2_LIB.BASEBOARD_FAB2(SCH_1):PAGE192

PU_TMP421_1_A1 @BASEBOARD_FAB2_LIB.BASEBOARD_FAB2(SCH_1):PU_TMP421_1_A1
  U9B4    3   A<1> TMP421_TSSOP-IC,G62962-001     I1 @BASEBOARD_FAB2_LIB.BASEBOARD_FAB2(SCH_1):PAGE167
  R9B6    2      B RES_0402-1.00K,1%,1/16W,CHIP,GA    I35 @BASEBOARD_FAB2_LIB.BASEBOARD_FAB2(SCH_1):PAGE167

PU_TMP421_2_A0 @BASEBOARD_FAB2_LIB.BASEBOARD_FAB2(SCH_1):PU_TMP421_2_A0
  U1E1    4   A<0> TMP421_TSSOP-IC,G62962-001    I30 @BASEBOARD_FAB2_LIB.BASEBOARD_FAB2(SCH_1):PAGE167
  R1E9    2      B RES_0402-1.00K,1%,1/16W,CHIP,GA    I34 @BASEBOARD_FAB2_LIB.BASEBOARD_FAB2(SCH_1):PAGE167

PU_TPM_SPI_BMC_HOLD_N @BASEBOARD_FAB2_LIB.BASEBOARD_FAB2(SCH_1):PU_TPM_SPI_BMC_HOLD_N
 RN8F3    2      B RES_0402-4.75K,1%,1/16W,CHIP,GA    I11 @BASEBOARD_FAB2_LIB.BASEBOARD_FAB2(SCH_1):PAGE246
 UN8F2    1 HOLD_N_IO<3> W25Q256_XSOI-IC,H25002-001    I17 @BASEBOARD_FAB2_LIB.BASEBOARD_FAB2(SCH_1):PAGE246

PU_TPM_SPI_FLASH_RESET_2_N @BASEBOARD_FAB2_LIB.BASEBOARD_FAB2(SCH_1):PU_TPM_SPI_FLASH_RESET_2_N
 RN8F4    2      B RES_0402-4.75K,1%,1/16W,EMPTY,A    I12 @BASEBOARD_FAB2_LIB.BASEBOARD_FAB2(SCH_1):PAGE246
 UN8F2    3 RESET_N W25Q256_XSOI-IC,H25002-001    I17 @BASEBOARD_FAB2_LIB.BASEBOARD_FAB2(SCH_1):PAGE246

PU_TRI_STATE_EN @BASEBOARD_FAB2_LIB.BASEBOARD_FAB2(SCH_1):PU_TRI_STATE_EN
  U8E4    1     OE TTL1G126_A_SOT-74HC1G126,IC,A7B     I1 @BASEBOARD_FAB2_LIB.BASEBOARD_FAB2(SCH_1):PAGE142
 R8E23    1      A RES_0402-4.75K,1%,1/16W,CHIP,GA     I3 @BASEBOARD_FAB2_LIB.BASEBOARD_FAB2(SCH_1):PAGE142

PU_UV_HIGH_SET @BASEBOARD_FAB2_LIB.BASEBOARD_FAB2(SCH_1):PU_UV_HIGH_SET
  J9G1    1    IO1 CONN12_C73564003_PIP-CONN,C735A   I128 @BASEBOARD_FAB2_LIB.BASEBOARD_FAB2(SCH_1):PAGE137
  R6W1    2      B RES_0402-4.75K,1%,1/16W,CHIP,GA   I149 @BASEBOARD_FAB2_LIB.BASEBOARD_FAB2(SCH_1):PAGE137

PU_VR_PVCCIN_CPU0_FLT1_SMBALT_N @BASEBOARD_FAB2_LIB.BASEBOARD_FAB2(SCH_1):PU_VR_PVCCIN_CPU0_FLT1_SMBALT_N_IMON
 R4E20    2      B RES_0402-2.26K,1.0%,1/16W,EMPTA   I116 @BASEBOARD_FAB2_LIB.BASEBOARD_FAB2(SCH_1):PAGE201
 EU4D4   20    MP2 PXE1610B_QFN-IC,H79206-001   I155 @BASEBOARD_FAB2_LIB.BASEBOARD_FAB2(SCH_1):PAGE201

PU_VR_PVCCIN_CPU0_IMON @BASEBOARD_FAB2_LIB.BASEBOARD_FAB2(SCH_1):PU_VR_PVCCIN_CPU0_IMON
 R4D31    2      B RES_0402-2.26K,1.0%,1/16W,EMPTA    I22 @BASEBOARD_FAB2_LIB.BASEBOARD_FAB2(SCH_1):PAGE201
 EU4D4   39    MP3 PXE1610B_QFN-IC,H79206-001   I155 @BASEBOARD_FAB2_LIB.BASEBOARD_FAB2(SCH_1):PAGE201

PU_VR_PVCCIN_CPU1_FLT1_SMBALT_N @BASEBOARD_FAB2_LIB.BASEBOARD_FAB2(SCH_1):PU_VR_PVCCIN_CPU1_FLT1_SMBALT_N_IMON
 R1D53    2      B RES_0402-2.26K,1.0%,1/16W,EMPTA    I33 @BASEBOARD_FAB2_LIB.BASEBOARD_FAB2(SCH_1):PAGE206
 EU1C2   20    MP2 PXE1610B_QFN-IC,H79206-001   I130 @BASEBOARD_FAB2_LIB.BASEBOARD_FAB2(SCH_1):PAGE206

PU_VR_PVCCIN_CPU1_IMON @BASEBOARD_FAB2_LIB.BASEBOARD_FAB2(SCH_1):PU_VR_PVCCIN_CPU1_IMON
 R1C18    2      B RES_0402-2.26K,1.0%,1/16W,EMPTA    I34 @BASEBOARD_FAB2_LIB.BASEBOARD_FAB2(SCH_1):PAGE206
 EU1C2   39    MP3 PXE1610B_QFN-IC,H79206-001   I130 @BASEBOARD_FAB2_LIB.BASEBOARD_FAB2(SCH_1):PAGE206

PU_VR_PVCCIO_CPU0_FAULT1 @BASEBOARD_FAB2_LIB.BASEBOARD_FAB2(SCH_1):PU_VR_PVCCIO_CPU0_FAULT1
 R3N23    2      B RES_0402-2.26K,1.0%,1/16W,EMPTA    I60 @BASEBOARD_FAB2_LIB.BASEBOARD_FAB2(SCH_1):PAGE211
 EU3P1   32    MP4 PXE1110B_QFN-IC,H89187-001    I93 @BASEBOARD_FAB2_LIB.BASEBOARD_FAB2(SCH_1):PAGE211

PU_VR_PVCCIO_CPU1_FAULT1 @BASEBOARD_FAB2_LIB.BASEBOARD_FAB2(SCH_1):PU_VR_PVCCIO_CPU1_FAULT1
 R6P49    2      B RES_0402-2.26K,1.0%,1/16W,EMPTA    I14 @BASEBOARD_FAB2_LIB.BASEBOARD_FAB2(SCH_1):PAGE213
 EU4D5   32    MP4 PXE1110B_QFN-IC,H89187-001    I96 @BASEBOARD_FAB2_LIB.BASEBOARD_FAB2(SCH_1):PAGE213

PU_VR_PVDDQ_ABC_FAULT1 @BASEBOARD_FAB2_LIB.BASEBOARD_FAB2(SCH_1):PU_VR_PVDDQ_ABC_FAULT1
 EU7G1   13    MP0 PXM1310B_QFN-IC,H89186-001    I69 @BASEBOARD_FAB2_LIB.BASEBOARD_FAB2(SCH_1):PAGE215
R12W25    1      A RES_0402-0.0,5%,1/16W,CHIP,G21A    I74 @BASEBOARD_FAB2_LIB.BASEBOARD_FAB2(SCH_1):PAGE215

PU_VR_PVDDQ_DEF_FAULT1 @BASEBOARD_FAB2_LIB.BASEBOARD_FAB2(SCH_1):PU_VR_PVDDQ_DEF_FAULT1
 EU7A5   13    MP0 PXM1310B_QFN-IC,H89186-001    I69 @BASEBOARD_FAB2_LIB.BASEBOARD_FAB2(SCH_1):PAGE218
R12W28    1      A RES_0402-0.0,5%,1/16W,CHIP,G21A    I75 @BASEBOARD_FAB2_LIB.BASEBOARD_FAB2(SCH_1):PAGE218

PU_VR_PVDDQ_GHJ_FAULT1 @BASEBOARD_FAB2_LIB.BASEBOARD_FAB2(SCH_1):PU_VR_PVDDQ_GHJ_FAULT1
 EU1G2   13    MP0 PXM1310B_QFN-IC,H89186-001    I69 @BASEBOARD_FAB2_LIB.BASEBOARD_FAB2(SCH_1):PAGE223
R12W31    1      A RES_0402-0.0,5%,1/16W,CHIP,G21A    I75 @BASEBOARD_FAB2_LIB.BASEBOARD_FAB2(SCH_1):PAGE223

PU_VR_PVDDQ_KLM_FAULT1 @BASEBOARD_FAB2_LIB.BASEBOARD_FAB2(SCH_1):PU_VR_PVDDQ_KLM_FAULT1
 EU1B1   13    MP0 PXM1310B_QFN-IC,H89186-001    I69 @BASEBOARD_FAB2_LIB.BASEBOARD_FAB2(SCH_1):PAGE226
R12W34    1      A RES_0402-0.0,5%,1/16W,CHIP,G21A    I74 @BASEBOARD_FAB2_LIB.BASEBOARD_FAB2(SCH_1):PAGE226

PU_VR_PVNN_PCH_FAULT1 @BASEBOARD_FAB2_LIB.BASEBOARD_FAB2(SCH_1):PU_VR_PVNN_PCH_FAULT1
 R2L24    2      B RES_0402-2.26K,1.0%,1/16W,EMPTA   I148 @BASEBOARD_FAB2_LIB.BASEBOARD_FAB2(SCH_1):PAGE235
 EU8A1   32    MP4 PXE1110B_QFN-IC,H89187-001   I229 @BASEBOARD_FAB2_LIB.BASEBOARD_FAB2(SCH_1):PAGE235

PVCCIN_CPU0 @BASEBOARD_FAB2_LIB.BASEBOARD_FAB2(SCH_1):PVCCIN_CPU0
  R5P1    1      A RES_0603-100.0K,1%,1/10W,CHIP,A   I309 @BASEBOARD_FAB2_LIB.BASEBOARD_FAB2(SCH_1):PAGE37
  U5D1 BN78 VCCIN<130> SKX_EXT_B_BGA1-IC,TBD   I310 @BASEBOARD_FAB2_LIB.BASEBOARD_FAB2(SCH_1):PAGE37
  U5D1 BN76 VCCIN<131> SKX_EXT_B_BGA1-IC,TBD   I310 @BASEBOARD_FAB2_LIB.BASEBOARD_FAB2(SCH_1):PAGE37
  U5D1 BN74 VCCIN<132> SKX_EXT_B_BGA1-IC,TBD   I310 @BASEBOARD_FAB2_LIB.BASEBOARD_FAB2(SCH_1):PAGE37
  U5D1 BN72 VCCIN<133> SKX_EXT_B_BGA1-IC,TBD   I310 @BASEBOARD_FAB2_LIB.BASEBOARD_FAB2(SCH_1):PAGE37
  U5D1 BN70 VCCIN<134> SKX_EXT_B_BGA1-IC,TBD   I310 @BASEBOARD_FAB2_LIB.BASEBOARD_FAB2(SCH_1):PAGE37
  U5D1 BN68 VCCIN<135> SKX_EXT_B_BGA1-IC,TBD   I310 @BASEBOARD_FAB2_LIB.BASEBOARD_FAB2(SCH_1):PAGE37
  U5D1 BN66 VCCIN<136> SKX_EXT_B_BGA1-IC,TBD   I310 @BASEBOARD_FAB2_LIB.BASEBOARD_FAB2(SCH_1):PAGE37
  U5D1 BN64 VCCIN<137> SKX_EXT_B_BGA1-IC,TBD   I310 @BASEBOARD_FAB2_LIB.BASEBOARD_FAB2(SCH_1):PAGE37
  U5D1 BN62 VCCIN<138> SKX_EXT_B_BGA1-IC,TBD   I310 @BASEBOARD_FAB2_LIB.BASEBOARD_FAB2(SCH_1):PAGE37
  U5D1 BN60 VCCIN<139> SKX_EXT_B_BGA1-IC,TBD   I310 @BASEBOARD_FAB2_LIB.BASEBOARD_FAB2(SCH_1):PAGE37
  U5D1 BM83 VCCIN<140> SKX_EXT_B_BGA1-IC,TBD   I310 @BASEBOARD_FAB2_LIB.BASEBOARD_FAB2(SCH_1):PAGE37
  U5D1 BM81 VCCIN<141> SKX_EXT_B_BGA1-IC,TBD   I310 @BASEBOARD_FAB2_LIB.BASEBOARD_FAB2(SCH_1):PAGE37
  U5D1 BM79 VCCIN<142> SKX_EXT_B_BGA1-IC,TBD   I310 @BASEBOARD_FAB2_LIB.BASEBOARD_FAB2(SCH_1):PAGE37
  U5D1 BM77 VCCIN<143> SKX_EXT_B_BGA1-IC,TBD   I310 @BASEBOARD_FAB2_LIB.BASEBOARD_FAB2(SCH_1):PAGE37
  U5D1 BM75 VCCIN<144> SKX_EXT_B_BGA1-IC,TBD   I310 @BASEBOARD_FAB2_LIB.BASEBOARD_FAB2(SCH_1):PAGE37
  U5D1 BM73 VCCIN<145> SKX_EXT_B_BGA1-IC,TBD   I310 @BASEBOARD_FAB2_LIB.BASEBOARD_FAB2(SCH_1):PAGE37
  U5D1 BM71 VCCIN<146> SKX_EXT_B_BGA1-IC,TBD   I310 @BASEBOARD_FAB2_LIB.BASEBOARD_FAB2(SCH_1):PAGE37
  U5D1 BM69 VCCIN<147> SKX_EXT_B_BGA1-IC,TBD   I310 @BASEBOARD_FAB2_LIB.BASEBOARD_FAB2(SCH_1):PAGE37
  U5D1 BM67 VCCIN<148> SKX_EXT_B_BGA1-IC,TBD   I310 @BASEBOARD_FAB2_LIB.BASEBOARD_FAB2(SCH_1):PAGE37
  U5D1 BM65 VCCIN<149> SKX_EXT_B_BGA1-IC,TBD   I310 @BASEBOARD_FAB2_LIB.BASEBOARD_FAB2(SCH_1):PAGE37
  U5D1 BM63 VCCIN<150> SKX_EXT_B_BGA1-IC,TBD   I310 @BASEBOARD_FAB2_LIB.BASEBOARD_FAB2(SCH_1):PAGE37
  U5D1 BM61 VCCIN<151> SKX_EXT_B_BGA1-IC,TBD   I310 @BASEBOARD_FAB2_LIB.BASEBOARD_FAB2(SCH_1):PAGE37
  U5D1 BL84 VCCIN<152> SKX_EXT_B_BGA1-IC,TBD   I310 @BASEBOARD_FAB2_LIB.BASEBOARD_FAB2(SCH_1):PAGE37
  U5D1 BL62 VCCIN<153> SKX_EXT_B_BGA1-IC,TBD   I310 @BASEBOARD_FAB2_LIB.BASEBOARD_FAB2(SCH_1):PAGE37
  U5D1 BL60 VCCIN<154> SKX_EXT_B_BGA1-IC,TBD   I310 @BASEBOARD_FAB2_LIB.BASEBOARD_FAB2(SCH_1):PAGE37
  U5D1 BK83 VCCIN<155> SKX_EXT_B_BGA1-IC,TBD   I310 @BASEBOARD_FAB2_LIB.BASEBOARD_FAB2(SCH_1):PAGE37
  U5D1 BK81 VCCIN<156> SKX_EXT_B_BGA1-IC,TBD   I310 @BASEBOARD_FAB2_LIB.BASEBOARD_FAB2(SCH_1):PAGE37
  U5D1 BK79 VCCIN<157> SKX_EXT_B_BGA1-IC,TBD   I310 @BASEBOARD_FAB2_LIB.BASEBOARD_FAB2(SCH_1):PAGE37
  U5D1 BK77 VCCIN<158> SKX_EXT_B_BGA1-IC,TBD   I310 @BASEBOARD_FAB2_LIB.BASEBOARD_FAB2(SCH_1):PAGE37
  U5D1 BK75 VCCIN<159> SKX_EXT_B_BGA1-IC,TBD   I310 @BASEBOARD_FAB2_LIB.BASEBOARD_FAB2(SCH_1):PAGE37
  U5D1 BK73 VCCIN<160> SKX_EXT_B_BGA1-IC,TBD   I310 @BASEBOARD_FAB2_LIB.BASEBOARD_FAB2(SCH_1):PAGE37
  U5D1 BK71 VCCIN<161> SKX_EXT_B_BGA1-IC,TBD   I310 @BASEBOARD_FAB2_LIB.BASEBOARD_FAB2(SCH_1):PAGE37
  U5D1 BK69 VCCIN<162> SKX_EXT_B_BGA1-IC,TBD   I310 @BASEBOARD_FAB2_LIB.BASEBOARD_FAB2(SCH_1):PAGE37
  U5D1 BK67 VCCIN<163> SKX_EXT_B_BGA1-IC,TBD   I310 @BASEBOARD_FAB2_LIB.BASEBOARD_FAB2(SCH_1):PAGE37
  U5D1 BK65 VCCIN<164> SKX_EXT_B_BGA1-IC,TBD   I310 @BASEBOARD_FAB2_LIB.BASEBOARD_FAB2(SCH_1):PAGE37
  U5D1 BK63 VCCIN<165> SKX_EXT_B_BGA1-IC,TBD   I310 @BASEBOARD_FAB2_LIB.BASEBOARD_FAB2(SCH_1):PAGE37
  U5D1 BK61 VCCIN<166> SKX_EXT_B_BGA1-IC,TBD   I310 @BASEBOARD_FAB2_LIB.BASEBOARD_FAB2(SCH_1):PAGE37
  U5D1 BJ84 VCCIN<167> SKX_EXT_B_BGA1-IC,TBD   I310 @BASEBOARD_FAB2_LIB.BASEBOARD_FAB2(SCH_1):PAGE37
  U5D1 BJ82 VCCIN<168> SKX_EXT_B_BGA1-IC,TBD   I310 @BASEBOARD_FAB2_LIB.BASEBOARD_FAB2(SCH_1):PAGE37
  U5D1 BJ80 VCCIN<169> SKX_EXT_B_BGA1-IC,TBD   I310 @BASEBOARD_FAB2_LIB.BASEBOARD_FAB2(SCH_1):PAGE37
  U5D1 BJ78 VCCIN<170> SKX_EXT_B_BGA1-IC,TBD   I310 @BASEBOARD_FAB2_LIB.BASEBOARD_FAB2(SCH_1):PAGE37
  U5D1 BJ76 VCCIN<171> SKX_EXT_B_BGA1-IC,TBD   I310 @BASEBOARD_FAB2_LIB.BASEBOARD_FAB2(SCH_1):PAGE37
  U5D1 BJ74 VCCIN<172> SKX_EXT_B_BGA1-IC,TBD   I310 @BASEBOARD_FAB2_LIB.BASEBOARD_FAB2(SCH_1):PAGE37
  U5D1 BJ72 VCCIN<173> SKX_EXT_B_BGA1-IC,TBD   I310 @BASEBOARD_FAB2_LIB.BASEBOARD_FAB2(SCH_1):PAGE37
  U5D1 BJ70 VCCIN<174> SKX_EXT_B_BGA1-IC,TBD   I310 @BASEBOARD_FAB2_LIB.BASEBOARD_FAB2(SCH_1):PAGE37
  U5D1 BJ68 VCCIN<175> SKX_EXT_B_BGA1-IC,TBD   I310 @BASEBOARD_FAB2_LIB.BASEBOARD_FAB2(SCH_1):PAGE37
  U5D1 BJ66 VCCIN<176> SKX_EXT_B_BGA1-IC,TBD   I310 @BASEBOARD_FAB2_LIB.BASEBOARD_FAB2(SCH_1):PAGE37
  U5D1 BJ64 VCCIN<177> SKX_EXT_B_BGA1-IC,TBD   I310 @BASEBOARD_FAB2_LIB.BASEBOARD_FAB2(SCH_1):PAGE37
  U5D1 BJ62 VCCIN<178> SKX_EXT_B_BGA1-IC,TBD   I310 @BASEBOARD_FAB2_LIB.BASEBOARD_FAB2(SCH_1):PAGE37
  U5D1 BJ60 VCCIN<179> SKX_EXT_B_BGA1-IC,TBD   I310 @BASEBOARD_FAB2_LIB.BASEBOARD_FAB2(SCH_1):PAGE37
  U5D1 BH83 VCCIN<180> SKX_EXT_B_BGA1-IC,TBD   I310 @BASEBOARD_FAB2_LIB.BASEBOARD_FAB2(SCH_1):PAGE37
  U5D1 BH81 VCCIN<181> SKX_EXT_B_BGA1-IC,TBD   I310 @BASEBOARD_FAB2_LIB.BASEBOARD_FAB2(SCH_1):PAGE37
  U5D1 BH79 VCCIN<182> SKX_EXT_B_BGA1-IC,TBD   I310 @BASEBOARD_FAB2_LIB.BASEBOARD_FAB2(SCH_1):PAGE37
  U5D1 BH77 VCCIN<183> SKX_EXT_B_BGA1-IC,TBD   I310 @BASEBOARD_FAB2_LIB.BASEBOARD_FAB2(SCH_1):PAGE37
  U5D1 BH75 VCCIN<184> SKX_EXT_B_BGA1-IC,TBD   I310 @BASEBOARD_FAB2_LIB.BASEBOARD_FAB2(SCH_1):PAGE37
  U5D1 BH73 VCCIN<185> SKX_EXT_B_BGA1-IC,TBD   I310 @BASEBOARD_FAB2_LIB.BASEBOARD_FAB2(SCH_1):PAGE37
  U5D1 BH71 VCCIN<186> SKX_EXT_B_BGA1-IC,TBD   I310 @BASEBOARD_FAB2_LIB.BASEBOARD_FAB2(SCH_1):PAGE37
  U5D1 BH69 VCCIN<187> SKX_EXT_B_BGA1-IC,TBD   I310 @BASEBOARD_FAB2_LIB.BASEBOARD_FAB2(SCH_1):PAGE37
  U5D1 BH67 VCCIN<188> SKX_EXT_B_BGA1-IC,TBD   I310 @BASEBOARD_FAB2_LIB.BASEBOARD_FAB2(SCH_1):PAGE37
  U5D1 BH65 VCCIN<189> SKX_EXT_B_BGA1-IC,TBD   I310 @BASEBOARD_FAB2_LIB.BASEBOARD_FAB2(SCH_1):PAGE37
  U5D1 BH63 VCCIN<190> SKX_EXT_B_BGA1-IC,TBD   I310 @BASEBOARD_FAB2_LIB.BASEBOARD_FAB2(SCH_1):PAGE37
  U5D1 BH61 VCCIN<191> SKX_EXT_B_BGA1-IC,TBD   I310 @BASEBOARD_FAB2_LIB.BASEBOARD_FAB2(SCH_1):PAGE37
  U5D1 BG84 VCCIN<192> SKX_EXT_B_BGA1-IC,TBD   I310 @BASEBOARD_FAB2_LIB.BASEBOARD_FAB2(SCH_1):PAGE37
  U5D1 BG70 VCCIN<193> SKX_EXT_B_BGA1-IC,TBD   I310 @BASEBOARD_FAB2_LIB.BASEBOARD_FAB2(SCH_1):PAGE37
  U5D1 BG68 VCCIN<194> SKX_EXT_B_BGA1-IC,TBD   I310 @BASEBOARD_FAB2_LIB.BASEBOARD_FAB2(SCH_1):PAGE37
  U5D1 BG66 VCCIN<195> SKX_EXT_B_BGA1-IC,TBD   I310 @BASEBOARD_FAB2_LIB.BASEBOARD_FAB2(SCH_1):PAGE37
  U5D1 BG64 VCCIN<196> SKX_EXT_B_BGA1-IC,TBD   I310 @BASEBOARD_FAB2_LIB.BASEBOARD_FAB2(SCH_1):PAGE37
  U5D1 BG62 VCCIN<197> SKX_EXT_B_BGA1-IC,TBD   I310 @BASEBOARD_FAB2_LIB.BASEBOARD_FAB2(SCH_1):PAGE37
  U5D1 BG60 VCCIN<198> SKX_EXT_B_BGA1-IC,TBD   I310 @BASEBOARD_FAB2_LIB.BASEBOARD_FAB2(SCH_1):PAGE37
  U5D1 BF85 VCCIN<199> SKX_EXT_B_BGA1-IC,TBD   I310 @BASEBOARD_FAB2_LIB.BASEBOARD_FAB2(SCH_1):PAGE37
  U5D1 BF83 VCCIN<200> SKX_EXT_B_BGA1-IC,TBD   I310 @BASEBOARD_FAB2_LIB.BASEBOARD_FAB2(SCH_1):PAGE37
  U5D1 BF81 VCCIN<201> SKX_EXT_B_BGA1-IC,TBD   I310 @BASEBOARD_FAB2_LIB.BASEBOARD_FAB2(SCH_1):PAGE37
  U5D1 BF79 VCCIN<202> SKX_EXT_B_BGA1-IC,TBD   I310 @BASEBOARD_FAB2_LIB.BASEBOARD_FAB2(SCH_1):PAGE37
  U5D1 BF77 VCCIN<203> SKX_EXT_B_BGA1-IC,TBD   I310 @BASEBOARD_FAB2_LIB.BASEBOARD_FAB2(SCH_1):PAGE37
  U5D1 BF75 VCCIN<204> SKX_EXT_B_BGA1-IC,TBD   I310 @BASEBOARD_FAB2_LIB.BASEBOARD_FAB2(SCH_1):PAGE37
  U5D1 BF73 VCCIN<205> SKX_EXT_B_BGA1-IC,TBD   I310 @BASEBOARD_FAB2_LIB.BASEBOARD_FAB2(SCH_1):PAGE37
  U5D1 BF61 VCCIN<206> SKX_EXT_B_BGA1-IC,TBD   I310 @BASEBOARD_FAB2_LIB.BASEBOARD_FAB2(SCH_1):PAGE37
  U5D1 BE84 VCCIN<207> SKX_EXT_B_BGA1-IC,TBD   I310 @BASEBOARD_FAB2_LIB.BASEBOARD_FAB2(SCH_1):PAGE37
  U5D1 BE82 VCCIN<208> SKX_EXT_B_BGA1-IC,TBD   I310 @BASEBOARD_FAB2_LIB.BASEBOARD_FAB2(SCH_1):PAGE37
  U5D1 BE80 VCCIN<209> SKX_EXT_B_BGA1-IC,TBD   I310 @BASEBOARD_FAB2_LIB.BASEBOARD_FAB2(SCH_1):PAGE37
  U5D1 BE78 VCCIN<210> SKX_EXT_B_BGA1-IC,TBD   I310 @BASEBOARD_FAB2_LIB.BASEBOARD_FAB2(SCH_1):PAGE37
  U5D1 BE76 VCCIN<211> SKX_EXT_B_BGA1-IC,TBD   I310 @BASEBOARD_FAB2_LIB.BASEBOARD_FAB2(SCH_1):PAGE37
  U5D1 BE74 VCCIN<212> SKX_EXT_B_BGA1-IC,TBD   I310 @BASEBOARD_FAB2_LIB.BASEBOARD_FAB2(SCH_1):PAGE37
  U5D1 BE72 VCCIN<213> SKX_EXT_B_BGA1-IC,TBD   I310 @BASEBOARD_FAB2_LIB.BASEBOARD_FAB2(SCH_1):PAGE37
  U5D1 BE62 VCCIN<214> SKX_EXT_B_BGA1-IC,TBD   I310 @BASEBOARD_FAB2_LIB.BASEBOARD_FAB2(SCH_1):PAGE37
  U5D1 BE60 VCCIN<215> SKX_EXT_B_BGA1-IC,TBD   I310 @BASEBOARD_FAB2_LIB.BASEBOARD_FAB2(SCH_1):PAGE37
  U5D1 BD85 VCCIN<216> SKX_EXT_B_BGA1-IC,TBD   I310 @BASEBOARD_FAB2_LIB.BASEBOARD_FAB2(SCH_1):PAGE37
  U5D1 BD83 VCCIN<217> SKX_EXT_B_BGA1-IC,TBD   I310 @BASEBOARD_FAB2_LIB.BASEBOARD_FAB2(SCH_1):PAGE37
  U5D1 BD81 VCCIN<218> SKX_EXT_B_BGA1-IC,TBD   I310 @BASEBOARD_FAB2_LIB.BASEBOARD_FAB2(SCH_1):PAGE37
  U5D1 BD79 VCCIN<219> SKX_EXT_B_BGA1-IC,TBD   I310 @BASEBOARD_FAB2_LIB.BASEBOARD_FAB2(SCH_1):PAGE37
  U5D1 BD77 VCCIN<220> SKX_EXT_B_BGA1-IC,TBD   I310 @BASEBOARD_FAB2_LIB.BASEBOARD_FAB2(SCH_1):PAGE37
  U5D1 BD75 VCCIN<221> SKX_EXT_B_BGA1-IC,TBD   I310 @BASEBOARD_FAB2_LIB.BASEBOARD_FAB2(SCH_1):PAGE37
  U5D1 BD73 VCCIN<222> SKX_EXT_B_BGA1-IC,TBD   I310 @BASEBOARD_FAB2_LIB.BASEBOARD_FAB2(SCH_1):PAGE37
  U5D1 BD61 VCCIN<223> SKX_EXT_B_BGA1-IC,TBD   I310 @BASEBOARD_FAB2_LIB.BASEBOARD_FAB2(SCH_1):PAGE37
  U5D1 BC84 VCCIN<224> SKX_EXT_B_BGA1-IC,TBD   I310 @BASEBOARD_FAB2_LIB.BASEBOARD_FAB2(SCH_1):PAGE37
  U5D1 BC62 VCCIN<225> SKX_EXT_B_BGA1-IC,TBD   I310 @BASEBOARD_FAB2_LIB.BASEBOARD_FAB2(SCH_1):PAGE37
  U5D1 BC60 VCCIN<226> SKX_EXT_B_BGA1-IC,TBD   I310 @BASEBOARD_FAB2_LIB.BASEBOARD_FAB2(SCH_1):PAGE37
  U5D1 BB85 VCCIN<227> SKX_EXT_B_BGA1-IC,TBD   I310 @BASEBOARD_FAB2_LIB.BASEBOARD_FAB2(SCH_1):PAGE37
  U5D1 BB61 VCCIN<228> SKX_EXT_B_BGA1-IC,TBD   I310 @BASEBOARD_FAB2_LIB.BASEBOARD_FAB2(SCH_1):PAGE37
  U5D1 BA60 VCCIN<229> SKX_EXT_B_BGA1-IC,TBD   I310 @BASEBOARD_FAB2_LIB.BASEBOARD_FAB2(SCH_1):PAGE37
  U5D1 AY61 VCCIN<230> SKX_EXT_B_BGA1-IC,TBD   I310 @BASEBOARD_FAB2_LIB.BASEBOARD_FAB2(SCH_1):PAGE37
  U5D1 AW60 VCCIN<231> SKX_EXT_B_BGA1-IC,TBD   I310 @BASEBOARD_FAB2_LIB.BASEBOARD_FAB2(SCH_1):PAGE37
  U5D1 AV61 VCCIN<232> SKX_EXT_B_BGA1-IC,TBD   I310 @BASEBOARD_FAB2_LIB.BASEBOARD_FAB2(SCH_1):PAGE37
  U5D1 AV59 VCCIN<233> SKX_EXT_B_BGA1-IC,TBD   I310 @BASEBOARD_FAB2_LIB.BASEBOARD_FAB2(SCH_1):PAGE37
  U5D1 AU60 VCCIN<234> SKX_EXT_B_BGA1-IC,TBD   I310 @BASEBOARD_FAB2_LIB.BASEBOARD_FAB2(SCH_1):PAGE37
  U5D1 AU58 VCCIN<235> SKX_EXT_B_BGA1-IC,TBD   I310 @BASEBOARD_FAB2_LIB.BASEBOARD_FAB2(SCH_1):PAGE37
  U5D1 AT59 VCCIN<236> SKX_EXT_B_BGA1-IC,TBD   I310 @BASEBOARD_FAB2_LIB.BASEBOARD_FAB2(SCH_1):PAGE37
  U5D1 AT57 VCCIN<237> SKX_EXT_B_BGA1-IC,TBD   I310 @BASEBOARD_FAB2_LIB.BASEBOARD_FAB2(SCH_1):PAGE37
  U5D1 AR58 VCCIN<238> SKX_EXT_B_BGA1-IC,TBD   I310 @BASEBOARD_FAB2_LIB.BASEBOARD_FAB2(SCH_1):PAGE37
  U5D1 AR56 VCCIN<239> SKX_EXT_B_BGA1-IC,TBD   I310 @BASEBOARD_FAB2_LIB.BASEBOARD_FAB2(SCH_1):PAGE37
  U5D1 AP57 VCCIN<240> SKX_EXT_B_BGA1-IC,TBD   I310 @BASEBOARD_FAB2_LIB.BASEBOARD_FAB2(SCH_1):PAGE37
  U5D1 AP55 VCCIN<241> SKX_EXT_B_BGA1-IC,TBD   I310 @BASEBOARD_FAB2_LIB.BASEBOARD_FAB2(SCH_1):PAGE37
  U5D1 AN56 VCCIN<242> SKX_EXT_B_BGA1-IC,TBD   I310 @BASEBOARD_FAB2_LIB.BASEBOARD_FAB2(SCH_1):PAGE37
  U5D1 AN54 VCCIN<243> SKX_EXT_B_BGA1-IC,TBD   I310 @BASEBOARD_FAB2_LIB.BASEBOARD_FAB2(SCH_1):PAGE37
  U5D1 AN32 VCCIN<244> SKX_EXT_B_BGA1-IC,TBD   I310 @BASEBOARD_FAB2_LIB.BASEBOARD_FAB2(SCH_1):PAGE37
  U5D1 AM55 VCCIN<245> SKX_EXT_B_BGA1-IC,TBD   I310 @BASEBOARD_FAB2_LIB.BASEBOARD_FAB2(SCH_1):PAGE37
  U5D1 AM53 VCCIN<246> SKX_EXT_B_BGA1-IC,TBD   I310 @BASEBOARD_FAB2_LIB.BASEBOARD_FAB2(SCH_1):PAGE37
  U5D1 AM33 VCCIN<247> SKX_EXT_B_BGA1-IC,TBD   I310 @BASEBOARD_FAB2_LIB.BASEBOARD_FAB2(SCH_1):PAGE37
  U5D1 AL54 VCCIN<248> SKX_EXT_B_BGA1-IC,TBD   I310 @BASEBOARD_FAB2_LIB.BASEBOARD_FAB2(SCH_1):PAGE37
  U5D1 AL52 VCCIN<249> SKX_EXT_B_BGA1-IC,TBD   I310 @BASEBOARD_FAB2_LIB.BASEBOARD_FAB2(SCH_1):PAGE37
  U5D1 AL50 VCCIN<250> SKX_EXT_B_BGA1-IC,TBD   I310 @BASEBOARD_FAB2_LIB.BASEBOARD_FAB2(SCH_1):PAGE37
  U5D1 AL48 VCCIN<251> SKX_EXT_B_BGA1-IC,TBD   I310 @BASEBOARD_FAB2_LIB.BASEBOARD_FAB2(SCH_1):PAGE37
  U5D1 AL46 VCCIN<252> SKX_EXT_B_BGA1-IC,TBD   I310 @BASEBOARD_FAB2_LIB.BASEBOARD_FAB2(SCH_1):PAGE37
  U5D1 AL34 VCCIN<253> SKX_EXT_B_BGA1-IC,TBD   I310 @BASEBOARD_FAB2_LIB.BASEBOARD_FAB2(SCH_1):PAGE37
  U5D1 AK53 VCCIN<254> SKX_EXT_B_BGA1-IC,TBD   I310 @BASEBOARD_FAB2_LIB.BASEBOARD_FAB2(SCH_1):PAGE37
  U5D1 AK51 VCCIN<255> SKX_EXT_B_BGA1-IC,TBD   I310 @BASEBOARD_FAB2_LIB.BASEBOARD_FAB2(SCH_1):PAGE37
  U5D1 AK49 VCCIN<256> SKX_EXT_B_BGA1-IC,TBD   I310 @BASEBOARD_FAB2_LIB.BASEBOARD_FAB2(SCH_1):PAGE37
  U5D1 AK47 VCCIN<257> SKX_EXT_B_BGA1-IC,TBD   I310 @BASEBOARD_FAB2_LIB.BASEBOARD_FAB2(SCH_1):PAGE37
  U5D1 AK45 VCCIN<258> SKX_EXT_B_BGA1-IC,TBD   I310 @BASEBOARD_FAB2_LIB.BASEBOARD_FAB2(SCH_1):PAGE37
  U5D1 AK35 VCCIN<259> SKX_EXT_B_BGA1-IC,TBD   I310 @BASEBOARD_FAB2_LIB.BASEBOARD_FAB2(SCH_1):PAGE37
  U5D1 AJ36 VCCIN<260> SKX_EXT_B_BGA1-IC,TBD   I310 @BASEBOARD_FAB2_LIB.BASEBOARD_FAB2(SCH_1):PAGE37
  U5D1 AH41 VCCIN<261> SKX_EXT_B_BGA1-IC,TBD   I310 @BASEBOARD_FAB2_LIB.BASEBOARD_FAB2(SCH_1):PAGE37
  U5D1 AH39 VCCIN<262> SKX_EXT_B_BGA1-IC,TBD   I310 @BASEBOARD_FAB2_LIB.BASEBOARD_FAB2(SCH_1):PAGE37
  U5D1 AH37 VCCIN<263> SKX_EXT_B_BGA1-IC,TBD   I310 @BASEBOARD_FAB2_LIB.BASEBOARD_FAB2(SCH_1):PAGE37
  U5D1 AG42 VCCIN<264> SKX_EXT_B_BGA1-IC,TBD   I310 @BASEBOARD_FAB2_LIB.BASEBOARD_FAB2(SCH_1):PAGE37
  U5D1 AG40 VCCIN<265> SKX_EXT_B_BGA1-IC,TBD   I310 @BASEBOARD_FAB2_LIB.BASEBOARD_FAB2(SCH_1):PAGE37
  U5D1 AG38 VCCIN<266> SKX_EXT_B_BGA1-IC,TBD   I310 @BASEBOARD_FAB2_LIB.BASEBOARD_FAB2(SCH_1):PAGE37
  U5D1 AF43 VCCIN<267> SKX_EXT_B_BGA1-IC,TBD   I310 @BASEBOARD_FAB2_LIB.BASEBOARD_FAB2(SCH_1):PAGE37
  U5D1 CY49 VCCIN<0> SKX_EXT_B_BGA1-IC,TBD   I311 @BASEBOARD_FAB2_LIB.BASEBOARD_FAB2(SCH_1):PAGE37
  U5D1 CY47 VCCIN<1> SKX_EXT_B_BGA1-IC,TBD   I311 @BASEBOARD_FAB2_LIB.BASEBOARD_FAB2(SCH_1):PAGE37
  U5D1 CW50 VCCIN<2> SKX_EXT_B_BGA1-IC,TBD   I311 @BASEBOARD_FAB2_LIB.BASEBOARD_FAB2(SCH_1):PAGE37
  U5D1 CW48 VCCIN<3> SKX_EXT_B_BGA1-IC,TBD   I311 @BASEBOARD_FAB2_LIB.BASEBOARD_FAB2(SCH_1):PAGE37
  U5D1 CW46 VCCIN<4> SKX_EXT_B_BGA1-IC,TBD   I311 @BASEBOARD_FAB2_LIB.BASEBOARD_FAB2(SCH_1):PAGE37
  U5D1 CV51 VCCIN<5> SKX_EXT_B_BGA1-IC,TBD   I311 @BASEBOARD_FAB2_LIB.BASEBOARD_FAB2(SCH_1):PAGE37
  U5D1 CU54 VCCIN<6> SKX_EXT_B_BGA1-IC,TBD   I311 @BASEBOARD_FAB2_LIB.BASEBOARD_FAB2(SCH_1):PAGE37
  U5D1 CU52 VCCIN<7> SKX_EXT_B_BGA1-IC,TBD   I311 @BASEBOARD_FAB2_LIB.BASEBOARD_FAB2(SCH_1):PAGE37
  U5D1 CU42 VCCIN<8> SKX_EXT_B_BGA1-IC,TBD   I311 @BASEBOARD_FAB2_LIB.BASEBOARD_FAB2(SCH_1):PAGE37
  U5D1 CU40 VCCIN<9> SKX_EXT_B_BGA1-IC,TBD   I311 @BASEBOARD_FAB2_LIB.BASEBOARD_FAB2(SCH_1):PAGE37
  U5D1 CU38 VCCIN<10> SKX_EXT_B_BGA1-IC,TBD   I311 @BASEBOARD_FAB2_LIB.BASEBOARD_FAB2(SCH_1):PAGE37
  U5D1 CT55 VCCIN<11> SKX_EXT_B_BGA1-IC,TBD   I311 @BASEBOARD_FAB2_LIB.BASEBOARD_FAB2(SCH_1):PAGE37
  U5D1 CT53 VCCIN<12> SKX_EXT_B_BGA1-IC,TBD   I311 @BASEBOARD_FAB2_LIB.BASEBOARD_FAB2(SCH_1):PAGE37
  U5D1 CT41 VCCIN<13> SKX_EXT_B_BGA1-IC,TBD   I311 @BASEBOARD_FAB2_LIB.BASEBOARD_FAB2(SCH_1):PAGE37
  U5D1 CT39 VCCIN<14> SKX_EXT_B_BGA1-IC,TBD   I311 @BASEBOARD_FAB2_LIB.BASEBOARD_FAB2(SCH_1):PAGE37
  U5D1 CT37 VCCIN<15> SKX_EXT_B_BGA1-IC,TBD   I311 @BASEBOARD_FAB2_LIB.BASEBOARD_FAB2(SCH_1):PAGE37
  U5D1 CR56 VCCIN<16> SKX_EXT_B_BGA1-IC,TBD   I311 @BASEBOARD_FAB2_LIB.BASEBOARD_FAB2(SCH_1):PAGE37
  U5D1 CR54 VCCIN<17> SKX_EXT_B_BGA1-IC,TBD   I311 @BASEBOARD_FAB2_LIB.BASEBOARD_FAB2(SCH_1):PAGE37
  U5D1 CR34 VCCIN<18> SKX_EXT_B_BGA1-IC,TBD   I311 @BASEBOARD_FAB2_LIB.BASEBOARD_FAB2(SCH_1):PAGE37
  U5D1 CP57 VCCIN<19> SKX_EXT_B_BGA1-IC,TBD   I311 @BASEBOARD_FAB2_LIB.BASEBOARD_FAB2(SCH_1):PAGE37
  U5D1 CP55 VCCIN<20> SKX_EXT_B_BGA1-IC,TBD   I311 @BASEBOARD_FAB2_LIB.BASEBOARD_FAB2(SCH_1):PAGE37
  U5D1 CP33 VCCIN<21> SKX_EXT_B_BGA1-IC,TBD   I311 @BASEBOARD_FAB2_LIB.BASEBOARD_FAB2(SCH_1):PAGE37
  U5D1 CN58 VCCIN<22> SKX_EXT_B_BGA1-IC,TBD   I311 @BASEBOARD_FAB2_LIB.BASEBOARD_FAB2(SCH_1):PAGE37
  U5D1 CN56 VCCIN<23> SKX_EXT_B_BGA1-IC,TBD   I311 @BASEBOARD_FAB2_LIB.BASEBOARD_FAB2(SCH_1):PAGE37
  U5D1 CM59 VCCIN<24> SKX_EXT_B_BGA1-IC,TBD   I311 @BASEBOARD_FAB2_LIB.BASEBOARD_FAB2(SCH_1):PAGE37
  U5D1 CM57 VCCIN<25> SKX_EXT_B_BGA1-IC,TBD   I311 @BASEBOARD_FAB2_LIB.BASEBOARD_FAB2(SCH_1):PAGE37
  U5D1 CL60 VCCIN<26> SKX_EXT_B_BGA1-IC,TBD   I311 @BASEBOARD_FAB2_LIB.BASEBOARD_FAB2(SCH_1):PAGE37
  U5D1 CL58 VCCIN<27> SKX_EXT_B_BGA1-IC,TBD   I311 @BASEBOARD_FAB2_LIB.BASEBOARD_FAB2(SCH_1):PAGE37
  U5D1 CK61 VCCIN<28> SKX_EXT_B_BGA1-IC,TBD   I311 @BASEBOARD_FAB2_LIB.BASEBOARD_FAB2(SCH_1):PAGE37
  U5D1 CK59 VCCIN<29> SKX_EXT_B_BGA1-IC,TBD   I311 @BASEBOARD_FAB2_LIB.BASEBOARD_FAB2(SCH_1):PAGE37
  U5D1 CJ60 VCCIN<30> SKX_EXT_B_BGA1-IC,TBD   I311 @BASEBOARD_FAB2_LIB.BASEBOARD_FAB2(SCH_1):PAGE37
  U5D1 CH85 VCCIN<31> SKX_EXT_B_BGA1-IC,TBD   I311 @BASEBOARD_FAB2_LIB.BASEBOARD_FAB2(SCH_1):PAGE37
  U5D1 CH61 VCCIN<32> SKX_EXT_B_BGA1-IC,TBD   I311 @BASEBOARD_FAB2_LIB.BASEBOARD_FAB2(SCH_1):PAGE37
  U5D1 CG84 VCCIN<33> SKX_EXT_B_BGA1-IC,TBD   I311 @BASEBOARD_FAB2_LIB.BASEBOARD_FAB2(SCH_1):PAGE37
  U5D1 CG60 VCCIN<34> SKX_EXT_B_BGA1-IC,TBD   I311 @BASEBOARD_FAB2_LIB.BASEBOARD_FAB2(SCH_1):PAGE37
  U5D1 CF85 VCCIN<35> SKX_EXT_B_BGA1-IC,TBD   I311 @BASEBOARD_FAB2_LIB.BASEBOARD_FAB2(SCH_1):PAGE37
  U5D1 CF61 VCCIN<36> SKX_EXT_B_BGA1-IC,TBD   I311 @BASEBOARD_FAB2_LIB.BASEBOARD_FAB2(SCH_1):PAGE37
  U5D1 CE84 VCCIN<37> SKX_EXT_B_BGA1-IC,TBD   I311 @BASEBOARD_FAB2_LIB.BASEBOARD_FAB2(SCH_1):PAGE37
  U5D1 CE60 VCCIN<38> SKX_EXT_B_BGA1-IC,TBD   I311 @BASEBOARD_FAB2_LIB.BASEBOARD_FAB2(SCH_1):PAGE37
  U5D1 CD85 VCCIN<39> SKX_EXT_B_BGA1-IC,TBD   I311 @BASEBOARD_FAB2_LIB.BASEBOARD_FAB2(SCH_1):PAGE37
  U5D1 CD83 VCCIN<40> SKX_EXT_B_BGA1-IC,TBD   I311 @BASEBOARD_FAB2_LIB.BASEBOARD_FAB2(SCH_1):PAGE37
  U5D1 CD61 VCCIN<41> SKX_EXT_B_BGA1-IC,TBD   I311 @BASEBOARD_FAB2_LIB.BASEBOARD_FAB2(SCH_1):PAGE37
  U5D1 CC84 VCCIN<42> SKX_EXT_B_BGA1-IC,TBD   I311 @BASEBOARD_FAB2_LIB.BASEBOARD_FAB2(SCH_1):PAGE37
  U5D1 CC62 VCCIN<43> SKX_EXT_B_BGA1-IC,TBD   I311 @BASEBOARD_FAB2_LIB.BASEBOARD_FAB2(SCH_1):PAGE37
  U5D1 CC60 VCCIN<44> SKX_EXT_B_BGA1-IC,TBD   I311 @BASEBOARD_FAB2_LIB.BASEBOARD_FAB2(SCH_1):PAGE37
  U5D1 CB83 VCCIN<45> SKX_EXT_B_BGA1-IC,TBD   I311 @BASEBOARD_FAB2_LIB.BASEBOARD_FAB2(SCH_1):PAGE37
  U5D1 CB81 VCCIN<46> SKX_EXT_B_BGA1-IC,TBD   I311 @BASEBOARD_FAB2_LIB.BASEBOARD_FAB2(SCH_1):PAGE37
  U5D1 CB79 VCCIN<47> SKX_EXT_B_BGA1-IC,TBD   I311 @BASEBOARD_FAB2_LIB.BASEBOARD_FAB2(SCH_1):PAGE37
  U5D1 CB77 VCCIN<48> SKX_EXT_B_BGA1-IC,TBD   I311 @BASEBOARD_FAB2_LIB.BASEBOARD_FAB2(SCH_1):PAGE37
  U5D1 CB75 VCCIN<49> SKX_EXT_B_BGA1-IC,TBD   I311 @BASEBOARD_FAB2_LIB.BASEBOARD_FAB2(SCH_1):PAGE37
  U5D1 CB73 VCCIN<50> SKX_EXT_B_BGA1-IC,TBD   I311 @BASEBOARD_FAB2_LIB.BASEBOARD_FAB2(SCH_1):PAGE37
  U5D1 CB61 VCCIN<51> SKX_EXT_B_BGA1-IC,TBD   I311 @BASEBOARD_FAB2_LIB.BASEBOARD_FAB2(SCH_1):PAGE37
  U5D1 CA84 VCCIN<52> SKX_EXT_B_BGA1-IC,TBD   I311 @BASEBOARD_FAB2_LIB.BASEBOARD_FAB2(SCH_1):PAGE37
  U5D1 CA82 VCCIN<53> SKX_EXT_B_BGA1-IC,TBD   I311 @BASEBOARD_FAB2_LIB.BASEBOARD_FAB2(SCH_1):PAGE37
  U5D1 CA80 VCCIN<54> SKX_EXT_B_BGA1-IC,TBD   I311 @BASEBOARD_FAB2_LIB.BASEBOARD_FAB2(SCH_1):PAGE37
  U5D1 CA78 VCCIN<55> SKX_EXT_B_BGA1-IC,TBD   I311 @BASEBOARD_FAB2_LIB.BASEBOARD_FAB2(SCH_1):PAGE37
  U5D1 CA76 VCCIN<56> SKX_EXT_B_BGA1-IC,TBD   I311 @BASEBOARD_FAB2_LIB.BASEBOARD_FAB2(SCH_1):PAGE37
  U5D1 CA74 VCCIN<57> SKX_EXT_B_BGA1-IC,TBD   I311 @BASEBOARD_FAB2_LIB.BASEBOARD_FAB2(SCH_1):PAGE37
  U5D1 CA72 VCCIN<58> SKX_EXT_B_BGA1-IC,TBD   I311 @BASEBOARD_FAB2_LIB.BASEBOARD_FAB2(SCH_1):PAGE37
  U5D1 CA62 VCCIN<59> SKX_EXT_B_BGA1-IC,TBD   I311 @BASEBOARD_FAB2_LIB.BASEBOARD_FAB2(SCH_1):PAGE37
  U5D1 CA60 VCCIN<60> SKX_EXT_B_BGA1-IC,TBD   I311 @BASEBOARD_FAB2_LIB.BASEBOARD_FAB2(SCH_1):PAGE37
  U5D1 BY83 VCCIN<61> SKX_EXT_B_BGA1-IC,TBD   I311 @BASEBOARD_FAB2_LIB.BASEBOARD_FAB2(SCH_1):PAGE37
  U5D1 BY81 VCCIN<62> SKX_EXT_B_BGA1-IC,TBD   I311 @BASEBOARD_FAB2_LIB.BASEBOARD_FAB2(SCH_1):PAGE37
  U5D1 BY79 VCCIN<63> SKX_EXT_B_BGA1-IC,TBD   I311 @BASEBOARD_FAB2_LIB.BASEBOARD_FAB2(SCH_1):PAGE37
  U5D1 BY77 VCCIN<64> SKX_EXT_B_BGA1-IC,TBD   I311 @BASEBOARD_FAB2_LIB.BASEBOARD_FAB2(SCH_1):PAGE37
  U5D1 BY75 VCCIN<65> SKX_EXT_B_BGA1-IC,TBD   I311 @BASEBOARD_FAB2_LIB.BASEBOARD_FAB2(SCH_1):PAGE37
  U5D1 BY73 VCCIN<66> SKX_EXT_B_BGA1-IC,TBD   I311 @BASEBOARD_FAB2_LIB.BASEBOARD_FAB2(SCH_1):PAGE37
  U5D1 BY61 VCCIN<67> SKX_EXT_B_BGA1-IC,TBD   I311 @BASEBOARD_FAB2_LIB.BASEBOARD_FAB2(SCH_1):PAGE37
  U5D1 BW84 VCCIN<68> SKX_EXT_B_BGA1-IC,TBD   I311 @BASEBOARD_FAB2_LIB.BASEBOARD_FAB2(SCH_1):PAGE37
  U5D1 BW70 VCCIN<69> SKX_EXT_B_BGA1-IC,TBD   I311 @BASEBOARD_FAB2_LIB.BASEBOARD_FAB2(SCH_1):PAGE37
  U5D1 BW68 VCCIN<70> SKX_EXT_B_BGA1-IC,TBD   I311 @BASEBOARD_FAB2_LIB.BASEBOARD_FAB2(SCH_1):PAGE37
  U5D1 BW66 VCCIN<71> SKX_EXT_B_BGA1-IC,TBD   I311 @BASEBOARD_FAB2_LIB.BASEBOARD_FAB2(SCH_1):PAGE37
  U5D1 BW64 VCCIN<72> SKX_EXT_B_BGA1-IC,TBD   I311 @BASEBOARD_FAB2_LIB.BASEBOARD_FAB2(SCH_1):PAGE37
  U5D1 BW62 VCCIN<73> SKX_EXT_B_BGA1-IC,TBD   I311 @BASEBOARD_FAB2_LIB.BASEBOARD_FAB2(SCH_1):PAGE37
  U5D1 BW60 VCCIN<74> SKX_EXT_B_BGA1-IC,TBD   I311 @BASEBOARD_FAB2_LIB.BASEBOARD_FAB2(SCH_1):PAGE37
  U5D1 BV83 VCCIN<75> SKX_EXT_B_BGA1-IC,TBD   I311 @BASEBOARD_FAB2_LIB.BASEBOARD_FAB2(SCH_1):PAGE37
  U5D1 BV81 VCCIN<76> SKX_EXT_B_BGA1-IC,TBD   I311 @BASEBOARD_FAB2_LIB.BASEBOARD_FAB2(SCH_1):PAGE37
  U5D1 BV79 VCCIN<77> SKX_EXT_B_BGA1-IC,TBD   I311 @BASEBOARD_FAB2_LIB.BASEBOARD_FAB2(SCH_1):PAGE37
  U5D1 BV77 VCCIN<78> SKX_EXT_B_BGA1-IC,TBD   I311 @BASEBOARD_FAB2_LIB.BASEBOARD_FAB2(SCH_1):PAGE37
  U5D1 BV75 VCCIN<79> SKX_EXT_B_BGA1-IC,TBD   I311 @BASEBOARD_FAB2_LIB.BASEBOARD_FAB2(SCH_1):PAGE37
  U5D1 BV73 VCCIN<80> SKX_EXT_B_BGA1-IC,TBD   I311 @BASEBOARD_FAB2_LIB.BASEBOARD_FAB2(SCH_1):PAGE37
  U5D1 BV71 VCCIN<81> SKX_EXT_B_BGA1-IC,TBD   I311 @BASEBOARD_FAB2_LIB.BASEBOARD_FAB2(SCH_1):PAGE37
  U5D1 BV69 VCCIN<82> SKX_EXT_B_BGA1-IC,TBD   I311 @BASEBOARD_FAB2_LIB.BASEBOARD_FAB2(SCH_1):PAGE37
  U5D1 BV67 VCCIN<83> SKX_EXT_B_BGA1-IC,TBD   I311 @BASEBOARD_FAB2_LIB.BASEBOARD_FAB2(SCH_1):PAGE37
  U5D1 BV65 VCCIN<84> SKX_EXT_B_BGA1-IC,TBD   I311 @BASEBOARD_FAB2_LIB.BASEBOARD_FAB2(SCH_1):PAGE37
  U5D1 BV63 VCCIN<85> SKX_EXT_B_BGA1-IC,TBD   I311 @BASEBOARD_FAB2_LIB.BASEBOARD_FAB2(SCH_1):PAGE37
  U5D1 BV61 VCCIN<86> SKX_EXT_B_BGA1-IC,TBD   I311 @BASEBOARD_FAB2_LIB.BASEBOARD_FAB2(SCH_1):PAGE37
  U5D1 BU84 VCCIN<87> SKX_EXT_B_BGA1-IC,TBD   I311 @BASEBOARD_FAB2_LIB.BASEBOARD_FAB2(SCH_1):PAGE37
  U5D1 BU82 VCCIN<88> SKX_EXT_B_BGA1-IC,TBD   I311 @BASEBOARD_FAB2_LIB.BASEBOARD_FAB2(SCH_1):PAGE37
  U5D1 BU80 VCCIN<89> SKX_EXT_B_BGA1-IC,TBD   I311 @BASEBOARD_FAB2_LIB.BASEBOARD_FAB2(SCH_1):PAGE37
  U5D1 BU78 VCCIN<90> SKX_EXT_B_BGA1-IC,TBD   I311 @BASEBOARD_FAB2_LIB.BASEBOARD_FAB2(SCH_1):PAGE37
  U5D1 BU76 VCCIN<91> SKX_EXT_B_BGA1-IC,TBD   I311 @BASEBOARD_FAB2_LIB.BASEBOARD_FAB2(SCH_1):PAGE37
  U5D1 BU74 VCCIN<92> SKX_EXT_B_BGA1-IC,TBD   I311 @BASEBOARD_FAB2_LIB.BASEBOARD_FAB2(SCH_1):PAGE37
  U5D1 BU72 VCCIN<93> SKX_EXT_B_BGA1-IC,TBD   I311 @BASEBOARD_FAB2_LIB.BASEBOARD_FAB2(SCH_1):PAGE37
  U5D1 BU70 VCCIN<94> SKX_EXT_B_BGA1-IC,TBD   I311 @BASEBOARD_FAB2_LIB.BASEBOARD_FAB2(SCH_1):PAGE37
  U5D1 BU68 VCCIN<95> SKX_EXT_B_BGA1-IC,TBD   I311 @BASEBOARD_FAB2_LIB.BASEBOARD_FAB2(SCH_1):PAGE37
  U5D1 BU66 VCCIN<96> SKX_EXT_B_BGA1-IC,TBD   I311 @BASEBOARD_FAB2_LIB.BASEBOARD_FAB2(SCH_1):PAGE37
  U5D1 BU64 VCCIN<97> SKX_EXT_B_BGA1-IC,TBD   I311 @BASEBOARD_FAB2_LIB.BASEBOARD_FAB2(SCH_1):PAGE37
  U5D1 BU62 VCCIN<98> SKX_EXT_B_BGA1-IC,TBD   I311 @BASEBOARD_FAB2_LIB.BASEBOARD_FAB2(SCH_1):PAGE37
  U5D1 BU60 VCCIN<99> SKX_EXT_B_BGA1-IC,TBD   I311 @BASEBOARD_FAB2_LIB.BASEBOARD_FAB2(SCH_1):PAGE37
  U5D1 BT83 VCCIN<100> SKX_EXT_B_BGA1-IC,TBD   I311 @BASEBOARD_FAB2_LIB.BASEBOARD_FAB2(SCH_1):PAGE37
  U5D1 BT81 VCCIN<101> SKX_EXT_B_BGA1-IC,TBD   I311 @BASEBOARD_FAB2_LIB.BASEBOARD_FAB2(SCH_1):PAGE37
  U5D1 BT79 VCCIN<102> SKX_EXT_B_BGA1-IC,TBD   I311 @BASEBOARD_FAB2_LIB.BASEBOARD_FAB2(SCH_1):PAGE37
  U5D1 BT77 VCCIN<103> SKX_EXT_B_BGA1-IC,TBD   I311 @BASEBOARD_FAB2_LIB.BASEBOARD_FAB2(SCH_1):PAGE37
  U5D1 BT75 VCCIN<104> SKX_EXT_B_BGA1-IC,TBD   I311 @BASEBOARD_FAB2_LIB.BASEBOARD_FAB2(SCH_1):PAGE37
  U5D1 BT73 VCCIN<105> SKX_EXT_B_BGA1-IC,TBD   I311 @BASEBOARD_FAB2_LIB.BASEBOARD_FAB2(SCH_1):PAGE37
  U5D1 BT71 VCCIN<106> SKX_EXT_B_BGA1-IC,TBD   I311 @BASEBOARD_FAB2_LIB.BASEBOARD_FAB2(SCH_1):PAGE37
  U5D1 BT69 VCCIN<107> SKX_EXT_B_BGA1-IC,TBD   I311 @BASEBOARD_FAB2_LIB.BASEBOARD_FAB2(SCH_1):PAGE37
  U5D1 BT67 VCCIN<108> SKX_EXT_B_BGA1-IC,TBD   I311 @BASEBOARD_FAB2_LIB.BASEBOARD_FAB2(SCH_1):PAGE37
  U5D1 BT65 VCCIN<109> SKX_EXT_B_BGA1-IC,TBD   I311 @BASEBOARD_FAB2_LIB.BASEBOARD_FAB2(SCH_1):PAGE37
  U5D1 BT63 VCCIN<110> SKX_EXT_B_BGA1-IC,TBD   I311 @BASEBOARD_FAB2_LIB.BASEBOARD_FAB2(SCH_1):PAGE37
  U5D1 BT61 VCCIN<111> SKX_EXT_B_BGA1-IC,TBD   I311 @BASEBOARD_FAB2_LIB.BASEBOARD_FAB2(SCH_1):PAGE37
  U5D1 BR84 VCCIN<112> SKX_EXT_B_BGA1-IC,TBD   I311 @BASEBOARD_FAB2_LIB.BASEBOARD_FAB2(SCH_1):PAGE37
  U5D1 BR62 VCCIN<113> SKX_EXT_B_BGA1-IC,TBD   I311 @BASEBOARD_FAB2_LIB.BASEBOARD_FAB2(SCH_1):PAGE37
  U5D1 BR60 VCCIN<114> SKX_EXT_B_BGA1-IC,TBD   I311 @BASEBOARD_FAB2_LIB.BASEBOARD_FAB2(SCH_1):PAGE37
  U5D1 BP83 VCCIN<115> SKX_EXT_B_BGA1-IC,TBD   I311 @BASEBOARD_FAB2_LIB.BASEBOARD_FAB2(SCH_1):PAGE37
  U5D1 BP81 VCCIN<116> SKX_EXT_B_BGA1-IC,TBD   I311 @BASEBOARD_FAB2_LIB.BASEBOARD_FAB2(SCH_1):PAGE37
  U5D1 BP79 VCCIN<117> SKX_EXT_B_BGA1-IC,TBD   I311 @BASEBOARD_FAB2_LIB.BASEBOARD_FAB2(SCH_1):PAGE37
  U5D1 BP77 VCCIN<118> SKX_EXT_B_BGA1-IC,TBD   I311 @BASEBOARD_FAB2_LIB.BASEBOARD_FAB2(SCH_1):PAGE37
  U5D1 BP75 VCCIN<119> SKX_EXT_B_BGA1-IC,TBD   I311 @BASEBOARD_FAB2_LIB.BASEBOARD_FAB2(SCH_1):PAGE37
  U5D1 BP73 VCCIN<120> SKX_EXT_B_BGA1-IC,TBD   I311 @BASEBOARD_FAB2_LIB.BASEBOARD_FAB2(SCH_1):PAGE37
  U5D1 BP71 VCCIN<121> SKX_EXT_B_BGA1-IC,TBD   I311 @BASEBOARD_FAB2_LIB.BASEBOARD_FAB2(SCH_1):PAGE37
  U5D1 BP69 VCCIN<122> SKX_EXT_B_BGA1-IC,TBD   I311 @BASEBOARD_FAB2_LIB.BASEBOARD_FAB2(SCH_1):PAGE37
  U5D1 BP67 VCCIN<123> SKX_EXT_B_BGA1-IC,TBD   I311 @BASEBOARD_FAB2_LIB.BASEBOARD_FAB2(SCH_1):PAGE37
  U5D1 BP65 VCCIN<124> SKX_EXT_B_BGA1-IC,TBD   I311 @BASEBOARD_FAB2_LIB.BASEBOARD_FAB2(SCH_1):PAGE37
  U5D1 BP63 VCCIN<125> SKX_EXT_B_BGA1-IC,TBD   I311 @BASEBOARD_FAB2_LIB.BASEBOARD_FAB2(SCH_1):PAGE37
  U5D1 BP61 VCCIN<126> SKX_EXT_B_BGA1-IC,TBD   I311 @BASEBOARD_FAB2_LIB.BASEBOARD_FAB2(SCH_1):PAGE37
  U5D1 BN84 VCCIN<127> SKX_EXT_B_BGA1-IC,TBD   I311 @BASEBOARD_FAB2_LIB.BASEBOARD_FAB2(SCH_1):PAGE37
  U5D1 BN82 VCCIN<128> SKX_EXT_B_BGA1-IC,TBD   I311 @BASEBOARD_FAB2_LIB.BASEBOARD_FAB2(SCH_1):PAGE37
  U5D1 BN80 VCCIN<129> SKX_EXT_B_BGA1-IC,TBD   I311 @BASEBOARD_FAB2_LIB.BASEBOARD_FAB2(SCH_1):PAGE37
 C5P23    1      A CAP_0805-47UF,4V,20%,X6S,C9533A    I28 @BASEBOARD_FAB2_LIB.BASEBOARD_FAB2(SCH_1):PAGE42
 C5P24    1      A CAP_0805-47UF,4V,20%,X6S,C9533A    I33 @BASEBOARD_FAB2_LIB.BASEBOARD_FAB2(SCH_1):PAGE42
 C5P25    1      A CAP_0805-47UF,4V,20%,X6S,C9533A    I37 @BASEBOARD_FAB2_LIB.BASEBOARD_FAB2(SCH_1):PAGE42
 C5P14    1      A CAP_0805-47UF,4V,20%,X6S,C9533A    I41 @BASEBOARD_FAB2_LIB.BASEBOARD_FAB2(SCH_1):PAGE42
 C5P27    1      A CAP_0805-47UF,4V,20%,X6S,C9533A    I44 @BASEBOARD_FAB2_LIB.BASEBOARD_FAB2(SCH_1):PAGE42
 C5P33    1      A CAP_0805-47UF,4V,20%,X6S,C9533A    I50 @BASEBOARD_FAB2_LIB.BASEBOARD_FAB2(SCH_1):PAGE42
 C5P35    1      A CAP_0805-47UF,4V,20%,X6S,C9533A    I51 @BASEBOARD_FAB2_LIB.BASEBOARD_FAB2(SCH_1):PAGE42
 C5P32    1      A CAP_0805-47UF,4V,20%,X6S,C9533A    I53 @BASEBOARD_FAB2_LIB.BASEBOARD_FAB2(SCH_1):PAGE42
 C5P34    1      A CAP_0805-47UF,4V,20%,X6S,C9533A    I54 @BASEBOARD_FAB2_LIB.BASEBOARD_FAB2(SCH_1):PAGE42
 C5P22    1      A CAP_0805-47UF,4V,20%,X6S,C9533A    I55 @BASEBOARD_FAB2_LIB.BASEBOARD_FAB2(SCH_1):PAGE42
 C5P26    1      A CAP_0805-47UF,4V,20%,X6S,C9533A    I56 @BASEBOARD_FAB2_LIB.BASEBOARD_FAB2(SCH_1):PAGE42
 C5P40    1      A CAP_0805-47UF,4V,20%,X6S,C9533A    I57 @BASEBOARD_FAB2_LIB.BASEBOARD_FAB2(SCH_1):PAGE42
 C5P37    1      A CAP_0805-47UF,4V,20%,X6S,C9533A    I63 @BASEBOARD_FAB2_LIB.BASEBOARD_FAB2(SCH_1):PAGE42
 C5P36    1      A CAP_0805-47UF,4V,20%,X6S,C9533A    I65 @BASEBOARD_FAB2_LIB.BASEBOARD_FAB2(SCH_1):PAGE42
 C5D28    1      A CAP_A_0603V-22.0UF,4V,20%,X6S,A   I100 @BASEBOARD_FAB2_LIB.BASEBOARD_FAB2(SCH_1):PAGE42
 C5D29    1      A CAP_A_0603V-22.0UF,4V,20%,X6S,A   I102 @BASEBOARD_FAB2_LIB.BASEBOARD_FAB2(SCH_1):PAGE42
 C5D32    1      A CAP_A_0603V-22.0UF,4V,20%,X6S,A   I103 @BASEBOARD_FAB2_LIB.BASEBOARD_FAB2(SCH_1):PAGE42
 C5D47    1      A CAP_A_0603V-22.0UF,4V,20%,X6S,A   I104 @BASEBOARD_FAB2_LIB.BASEBOARD_FAB2(SCH_1):PAGE42
 C5D31    1      A CAP_A_0603V-22.0UF,4V,20%,X6S,A   I106 @BASEBOARD_FAB2_LIB.BASEBOARD_FAB2(SCH_1):PAGE42
 C5D46    1      A CAP_A_0603V-22.0UF,4V,20%,X6S,A   I107 @BASEBOARD_FAB2_LIB.BASEBOARD_FAB2(SCH_1):PAGE42
 C5D27    1      A CAP_A_0603V-22.0UF,4V,20%,X6S,A   I109 @BASEBOARD_FAB2_LIB.BASEBOARD_FAB2(SCH_1):PAGE42
 C5D30    1      A CAP_A_0603V-22.0UF,4V,20%,X6S,A   I111 @BASEBOARD_FAB2_LIB.BASEBOARD_FAB2(SCH_1):PAGE42
 C5D41    1      A CAP_A_0603V-22.0UF,4V,20%,X6S,A   I114 @BASEBOARD_FAB2_LIB.BASEBOARD_FAB2(SCH_1):PAGE42
 C5D40    1      A CAP_A_0603V-22.0UF,4V,20%,X6S,A   I115 @BASEBOARD_FAB2_LIB.BASEBOARD_FAB2(SCH_1):PAGE42
 C5D14    1      A CAP_A_0603V-22.0UF,4V,20%,X6S,A   I117 @BASEBOARD_FAB2_LIB.BASEBOARD_FAB2(SCH_1):PAGE42
 C5D17    1      A CAP_A_0603V-22.0UF,4V,20%,X6S,A   I118 @BASEBOARD_FAB2_LIB.BASEBOARD_FAB2(SCH_1):PAGE42
 C5D16    1      A CAP_A_0603V-22.0UF,4V,20%,X6S,A   I123 @BASEBOARD_FAB2_LIB.BASEBOARD_FAB2(SCH_1):PAGE42
  C5D5    1      A CAP_A_0603V-22.0UF,4V,20%,X6S,A   I125 @BASEBOARD_FAB2_LIB.BASEBOARD_FAB2(SCH_1):PAGE42
 C5D19    1      A CAP_A_0603V-22.0UF,4V,20%,X6S,A   I128 @BASEBOARD_FAB2_LIB.BASEBOARD_FAB2(SCH_1):PAGE42
 C5D43    1      A CAP_A_0603V-22.0UF,4V,20%,X6S,A   I131 @BASEBOARD_FAB2_LIB.BASEBOARD_FAB2(SCH_1):PAGE42
 C5D15    1      A CAP_A_0603V-22.0UF,4V,20%,X6S,A   I132 @BASEBOARD_FAB2_LIB.BASEBOARD_FAB2(SCH_1):PAGE42
 C5D18    1      A CAP_A_0603V-22.0UF,4V,20%,X6S,A   I134 @BASEBOARD_FAB2_LIB.BASEBOARD_FAB2(SCH_1):PAGE42
 C5D42    1      A CAP_A_0603V-22.0UF,4V,20%,X6S,A   I135 @BASEBOARD_FAB2_LIB.BASEBOARD_FAB2(SCH_1):PAGE42
 C5D24    1      A CAP_A_0603V-22.0UF,4V,20%,X6S,A   I138 @BASEBOARD_FAB2_LIB.BASEBOARD_FAB2(SCH_1):PAGE42
 C5D39    1      A CAP_A_0603V-22.0UF,4V,20%,X6S,A   I140 @BASEBOARD_FAB2_LIB.BASEBOARD_FAB2(SCH_1):PAGE42
 C5D44    1      A CAP_A_0603V-22.0UF,4V,20%,X6S,A   I142 @BASEBOARD_FAB2_LIB.BASEBOARD_FAB2(SCH_1):PAGE42
 C5D26    1      A CAP_A_0603V-22.0UF,4V,20%,X6S,A   I154 @BASEBOARD_FAB2_LIB.BASEBOARD_FAB2(SCH_1):PAGE42
 C5D25    1      A CAP_A_0603V-22.0UF,4V,20%,X6S,A   I155 @BASEBOARD_FAB2_LIB.BASEBOARD_FAB2(SCH_1):PAGE42
 C5D45    1      A CAP_A_0603V-22.0UF,4V,20%,X6S,A   I156 @BASEBOARD_FAB2_LIB.BASEBOARD_FAB2(SCH_1):PAGE42
 C5P15    1      A CAP_0805-47UF,4V,20%,X6S,C9533A   I187 @BASEBOARD_FAB2_LIB.BASEBOARD_FAB2(SCH_1):PAGE42
 C5P16    1      A CAP_0805-47UF,4V,20%,X6S,C9533A   I188 @BASEBOARD_FAB2_LIB.BASEBOARD_FAB2(SCH_1):PAGE42
 C5P17    1      A CAP_0805-47UF,4V,20%,X6S,C9533A   I190 @BASEBOARD_FAB2_LIB.BASEBOARD_FAB2(SCH_1):PAGE42
  C6R7    1      A CAP_A_0603V-22.0UF,4V,20%,X6S,A     I9 @BASEBOARD_FAB2_LIB.BASEBOARD_FAB2(SCH_1):PAGE202
 C4E11    1      A CAP_A_0603V-22.0UF,4V,20%,X6S,A    I27 @BASEBOARD_FAB2_LIB.BASEBOARD_FAB2(SCH_1):PAGE202
  C4E3    1      A CAP_A_0603V-22.0UF,4V,20%,X6S,A    I61 @BASEBOARD_FAB2_LIB.BASEBOARD_FAB2(SCH_1):PAGE202
 C6P16    1      A CAP_A_0603V-22.0UF,4V,20%,X6S,A    I62 @BASEBOARD_FAB2_LIB.BASEBOARD_FAB2(SCH_1):PAGE202
 EU4E1    1    VOS IR354XX_SM-IR35411,IC,H73688-0A    I63 @BASEBOARD_FAB2_LIB.BASEBOARD_FAB2(SCH_1):PAGE202
 EU4D6    1    VOS IR354XX_SM-IR35411,IC,H73688-0A    I64 @BASEBOARD_FAB2_LIB.BASEBOARD_FAB2(SCH_1):PAGE202
  C6R3    1      A CAPP_3018-470UF,2.5V,20%,ALUM,A    I16 @BASEBOARD_FAB2_LIB.BASEBOARD_FAB2(SCH_1):PAGE203
  C6R9    1      A CAPP_3018-470UF,2.5V,20%,ALUM,A    I18 @BASEBOARD_FAB2_LIB.BASEBOARD_FAB2(SCH_1):PAGE203
  C6P3    1      A CAP_A_0603V-22.0UF,4V,20%,X6S,A    I25 @BASEBOARD_FAB2_LIB.BASEBOARD_FAB2(SCH_1):PAGE203
 C6P23    1      A CAPP_3018-470UF,2.5V,20%,ALUM,A    I28 @BASEBOARD_FAB2_LIB.BASEBOARD_FAB2(SCH_1):PAGE203
 C6P14    1      A CAPP_3018-470UF,2.5V,20%,ALUM,A    I29 @BASEBOARD_FAB2_LIB.BASEBOARD_FAB2(SCH_1):PAGE203
 C6P18    1      A CAPP_3018-470UF,2.5V,20%,ALUM,A    I30 @BASEBOARD_FAB2_LIB.BASEBOARD_FAB2(SCH_1):PAGE203
  C6P8    1      A CAPP_3018-470UF,2.5V,20%,ALUM,A    I32 @BASEBOARD_FAB2_LIB.BASEBOARD_FAB2(SCH_1):PAGE203
  C6N9    1      A CAPP_3018-470UF,2.5V,20%,ALUM,A    I34 @BASEBOARD_FAB2_LIB.BASEBOARD_FAB2(SCH_1):PAGE203
 C6P21    1      A CAP_A_0603V-22.0UF,4V,20%,X6S,A    I66 @BASEBOARD_FAB2_LIB.BASEBOARD_FAB2(SCH_1):PAGE203
 R4E13    1      A RES_0603-100.0,1%,1/10W,CHIP,GA    I67 @BASEBOARD_FAB2_LIB.BASEBOARD_FAB2(SCH_1):PAGE203
 C4D34    1      A CAP_A_0603V-22.0UF,4V,20%,X6S,A    I68 @BASEBOARD_FAB2_LIB.BASEBOARD_FAB2(SCH_1):PAGE203
  C4D4    1      A CAP_A_0603V-22.0UF,4V,20%,X6S,A    I69 @BASEBOARD_FAB2_LIB.BASEBOARD_FAB2(SCH_1):PAGE203
 EU4D3    1    VOS IR354XX_SM-IR35411,IC,H73688-0A    I70 @BASEBOARD_FAB2_LIB.BASEBOARD_FAB2(SCH_1):PAGE203
 EU4D1    1    VOS IR354XX_SM-IR35411,IC,H73688-0A    I71 @BASEBOARD_FAB2_LIB.BASEBOARD_FAB2(SCH_1):PAGE203
 C4D12    1      A CAP_A_0603V-22.0UF,4V,20%,X6S,A     I9 @BASEBOARD_FAB2_LIB.BASEBOARD_FAB2(SCH_1):PAGE204
 R4E14    2      B RES_0402-100.0,1%,1/16W,CHIP,GA    I60 @BASEBOARD_FAB2_LIB.BASEBOARD_FAB2(SCH_1):PAGE204
  C6R2    1      A CAP_A_0603V-22.0UF,4V,20%,X6S,A    I70 @BASEBOARD_FAB2_LIB.BASEBOARD_FAB2(SCH_1):PAGE204
 EU4C2    1    VOS IR354XX_SM-IR35411,IC,H73688-0A    I71 @BASEBOARD_FAB2_LIB.BASEBOARD_FAB2(SCH_1):PAGE204
  L4E1    2      F IND-120NH-30-GP_DISCRET-GB2-INA   I109 @BASEBOARD_FAB2_LIB.BASEBOARD_FAB2(SCH_1):PAGE202
  L4D3    2      F IND-120NH-30-GP_DISCRET-GB2-INA   I110 @BASEBOARD_FAB2_LIB.BASEBOARD_FAB2(SCH_1):PAGE202
  L4D2    2      F IND-120NH-30-GP_DISCRET-GB2-INA   I130 @BASEBOARD_FAB2_LIB.BASEBOARD_FAB2(SCH_1):PAGE203
  L4D1    2      F IND-120NH-30-GP_DISCRET-GB2-INA   I131 @BASEBOARD_FAB2_LIB.BASEBOARD_FAB2(SCH_1):PAGE203
  L4C3    2      F IND-120NH-30-GP_DISCRET-GB2-INA   I104 @BASEBOARD_FAB2_LIB.BASEBOARD_FAB2(SCH_1):PAGE204
  C8W3    1      A CAP_0805-100UF,4V,20%,X5R,6024A   I211 @BASEBOARD_FAB2_LIB.BASEBOARD_FAB2(SCH_1):PAGE42

PVCCIN_CPU1 @BASEBOARD_FAB2_LIB.BASEBOARD_FAB2(SCH_1):PVCCIN_CPU1
 RT8P1    1      A RES_0603-100.0K,1%,1/10W,CHIP,A    I49 @BASEBOARD_FAB2_LIB.BASEBOARD_FAB2(SCH_1):PAGE71
  U2D1 BN78 VCCIN<130> SKX_EXT_B_BGA1-IC,TBD    I50 @BASEBOARD_FAB2_LIB.BASEBOARD_FAB2(SCH_1):PAGE71
  U2D1 BN76 VCCIN<131> SKX_EXT_B_BGA1-IC,TBD    I50 @BASEBOARD_FAB2_LIB.BASEBOARD_FAB2(SCH_1):PAGE71
  U2D1 BN74 VCCIN<132> SKX_EXT_B_BGA1-IC,TBD    I50 @BASEBOARD_FAB2_LIB.BASEBOARD_FAB2(SCH_1):PAGE71
  U2D1 BN72 VCCIN<133> SKX_EXT_B_BGA1-IC,TBD    I50 @BASEBOARD_FAB2_LIB.BASEBOARD_FAB2(SCH_1):PAGE71
  U2D1 BN70 VCCIN<134> SKX_EXT_B_BGA1-IC,TBD    I50 @BASEBOARD_FAB2_LIB.BASEBOARD_FAB2(SCH_1):PAGE71
  U2D1 BN68 VCCIN<135> SKX_EXT_B_BGA1-IC,TBD    I50 @BASEBOARD_FAB2_LIB.BASEBOARD_FAB2(SCH_1):PAGE71
  U2D1 BN66 VCCIN<136> SKX_EXT_B_BGA1-IC,TBD    I50 @BASEBOARD_FAB2_LIB.BASEBOARD_FAB2(SCH_1):PAGE71
  U2D1 BN64 VCCIN<137> SKX_EXT_B_BGA1-IC,TBD    I50 @BASEBOARD_FAB2_LIB.BASEBOARD_FAB2(SCH_1):PAGE71
  U2D1 BN62 VCCIN<138> SKX_EXT_B_BGA1-IC,TBD    I50 @BASEBOARD_FAB2_LIB.BASEBOARD_FAB2(SCH_1):PAGE71
  U2D1 BN60 VCCIN<139> SKX_EXT_B_BGA1-IC,TBD    I50 @BASEBOARD_FAB2_LIB.BASEBOARD_FAB2(SCH_1):PAGE71
  U2D1 BM83 VCCIN<140> SKX_EXT_B_BGA1-IC,TBD    I50 @BASEBOARD_FAB2_LIB.BASEBOARD_FAB2(SCH_1):PAGE71
  U2D1 BM81 VCCIN<141> SKX_EXT_B_BGA1-IC,TBD    I50 @BASEBOARD_FAB2_LIB.BASEBOARD_FAB2(SCH_1):PAGE71
  U2D1 BM79 VCCIN<142> SKX_EXT_B_BGA1-IC,TBD    I50 @BASEBOARD_FAB2_LIB.BASEBOARD_FAB2(SCH_1):PAGE71
  U2D1 BM77 VCCIN<143> SKX_EXT_B_BGA1-IC,TBD    I50 @BASEBOARD_FAB2_LIB.BASEBOARD_FAB2(SCH_1):PAGE71
  U2D1 BM75 VCCIN<144> SKX_EXT_B_BGA1-IC,TBD    I50 @BASEBOARD_FAB2_LIB.BASEBOARD_FAB2(SCH_1):PAGE71
  U2D1 BM73 VCCIN<145> SKX_EXT_B_BGA1-IC,TBD    I50 @BASEBOARD_FAB2_LIB.BASEBOARD_FAB2(SCH_1):PAGE71
  U2D1 BM71 VCCIN<146> SKX_EXT_B_BGA1-IC,TBD    I50 @BASEBOARD_FAB2_LIB.BASEBOARD_FAB2(SCH_1):PAGE71
  U2D1 BM69 VCCIN<147> SKX_EXT_B_BGA1-IC,TBD    I50 @BASEBOARD_FAB2_LIB.BASEBOARD_FAB2(SCH_1):PAGE71
  U2D1 BM67 VCCIN<148> SKX_EXT_B_BGA1-IC,TBD    I50 @BASEBOARD_FAB2_LIB.BASEBOARD_FAB2(SCH_1):PAGE71
  U2D1 BM65 VCCIN<149> SKX_EXT_B_BGA1-IC,TBD    I50 @BASEBOARD_FAB2_LIB.BASEBOARD_FAB2(SCH_1):PAGE71
  U2D1 BM63 VCCIN<150> SKX_EXT_B_BGA1-IC,TBD    I50 @BASEBOARD_FAB2_LIB.BASEBOARD_FAB2(SCH_1):PAGE71
  U2D1 BM61 VCCIN<151> SKX_EXT_B_BGA1-IC,TBD    I50 @BASEBOARD_FAB2_LIB.BASEBOARD_FAB2(SCH_1):PAGE71
  U2D1 BL84 VCCIN<152> SKX_EXT_B_BGA1-IC,TBD    I50 @BASEBOARD_FAB2_LIB.BASEBOARD_FAB2(SCH_1):PAGE71
  U2D1 BL62 VCCIN<153> SKX_EXT_B_BGA1-IC,TBD    I50 @BASEBOARD_FAB2_LIB.BASEBOARD_FAB2(SCH_1):PAGE71
  U2D1 BL60 VCCIN<154> SKX_EXT_B_BGA1-IC,TBD    I50 @BASEBOARD_FAB2_LIB.BASEBOARD_FAB2(SCH_1):PAGE71
  U2D1 BK83 VCCIN<155> SKX_EXT_B_BGA1-IC,TBD    I50 @BASEBOARD_FAB2_LIB.BASEBOARD_FAB2(SCH_1):PAGE71
  U2D1 BK81 VCCIN<156> SKX_EXT_B_BGA1-IC,TBD    I50 @BASEBOARD_FAB2_LIB.BASEBOARD_FAB2(SCH_1):PAGE71
  U2D1 BK79 VCCIN<157> SKX_EXT_B_BGA1-IC,TBD    I50 @BASEBOARD_FAB2_LIB.BASEBOARD_FAB2(SCH_1):PAGE71
  U2D1 BK77 VCCIN<158> SKX_EXT_B_BGA1-IC,TBD    I50 @BASEBOARD_FAB2_LIB.BASEBOARD_FAB2(SCH_1):PAGE71
  U2D1 BK75 VCCIN<159> SKX_EXT_B_BGA1-IC,TBD    I50 @BASEBOARD_FAB2_LIB.BASEBOARD_FAB2(SCH_1):PAGE71
  U2D1 BK73 VCCIN<160> SKX_EXT_B_BGA1-IC,TBD    I50 @BASEBOARD_FAB2_LIB.BASEBOARD_FAB2(SCH_1):PAGE71
  U2D1 BK71 VCCIN<161> SKX_EXT_B_BGA1-IC,TBD    I50 @BASEBOARD_FAB2_LIB.BASEBOARD_FAB2(SCH_1):PAGE71
  U2D1 BK69 VCCIN<162> SKX_EXT_B_BGA1-IC,TBD    I50 @BASEBOARD_FAB2_LIB.BASEBOARD_FAB2(SCH_1):PAGE71
  U2D1 BK67 VCCIN<163> SKX_EXT_B_BGA1-IC,TBD    I50 @BASEBOARD_FAB2_LIB.BASEBOARD_FAB2(SCH_1):PAGE71
  U2D1 BK65 VCCIN<164> SKX_EXT_B_BGA1-IC,TBD    I50 @BASEBOARD_FAB2_LIB.BASEBOARD_FAB2(SCH_1):PAGE71
  U2D1 BK63 VCCIN<165> SKX_EXT_B_BGA1-IC,TBD    I50 @BASEBOARD_FAB2_LIB.BASEBOARD_FAB2(SCH_1):PAGE71
  U2D1 BK61 VCCIN<166> SKX_EXT_B_BGA1-IC,TBD    I50 @BASEBOARD_FAB2_LIB.BASEBOARD_FAB2(SCH_1):PAGE71
  U2D1 BJ84 VCCIN<167> SKX_EXT_B_BGA1-IC,TBD    I50 @BASEBOARD_FAB2_LIB.BASEBOARD_FAB2(SCH_1):PAGE71
  U2D1 BJ82 VCCIN<168> SKX_EXT_B_BGA1-IC,TBD    I50 @BASEBOARD_FAB2_LIB.BASEBOARD_FAB2(SCH_1):PAGE71
  U2D1 BJ80 VCCIN<169> SKX_EXT_B_BGA1-IC,TBD    I50 @BASEBOARD_FAB2_LIB.BASEBOARD_FAB2(SCH_1):PAGE71
  U2D1 BJ78 VCCIN<170> SKX_EXT_B_BGA1-IC,TBD    I50 @BASEBOARD_FAB2_LIB.BASEBOARD_FAB2(SCH_1):PAGE71
  U2D1 BJ76 VCCIN<171> SKX_EXT_B_BGA1-IC,TBD    I50 @BASEBOARD_FAB2_LIB.BASEBOARD_FAB2(SCH_1):PAGE71
  U2D1 BJ74 VCCIN<172> SKX_EXT_B_BGA1-IC,TBD    I50 @BASEBOARD_FAB2_LIB.BASEBOARD_FAB2(SCH_1):PAGE71
  U2D1 BJ72 VCCIN<173> SKX_EXT_B_BGA1-IC,TBD    I50 @BASEBOARD_FAB2_LIB.BASEBOARD_FAB2(SCH_1):PAGE71
  U2D1 BJ70 VCCIN<174> SKX_EXT_B_BGA1-IC,TBD    I50 @BASEBOARD_FAB2_LIB.BASEBOARD_FAB2(SCH_1):PAGE71
  U2D1 BJ68 VCCIN<175> SKX_EXT_B_BGA1-IC,TBD    I50 @BASEBOARD_FAB2_LIB.BASEBOARD_FAB2(SCH_1):PAGE71
  U2D1 BJ66 VCCIN<176> SKX_EXT_B_BGA1-IC,TBD    I50 @BASEBOARD_FAB2_LIB.BASEBOARD_FAB2(SCH_1):PAGE71
  U2D1 BJ64 VCCIN<177> SKX_EXT_B_BGA1-IC,TBD    I50 @BASEBOARD_FAB2_LIB.BASEBOARD_FAB2(SCH_1):PAGE71
  U2D1 BJ62 VCCIN<178> SKX_EXT_B_BGA1-IC,TBD    I50 @BASEBOARD_FAB2_LIB.BASEBOARD_FAB2(SCH_1):PAGE71
  U2D1 BJ60 VCCIN<179> SKX_EXT_B_BGA1-IC,TBD    I50 @BASEBOARD_FAB2_LIB.BASEBOARD_FAB2(SCH_1):PAGE71
  U2D1 BH83 VCCIN<180> SKX_EXT_B_BGA1-IC,TBD    I50 @BASEBOARD_FAB2_LIB.BASEBOARD_FAB2(SCH_1):PAGE71
  U2D1 BH81 VCCIN<181> SKX_EXT_B_BGA1-IC,TBD    I50 @BASEBOARD_FAB2_LIB.BASEBOARD_FAB2(SCH_1):PAGE71
  U2D1 BH79 VCCIN<182> SKX_EXT_B_BGA1-IC,TBD    I50 @BASEBOARD_FAB2_LIB.BASEBOARD_FAB2(SCH_1):PAGE71
  U2D1 BH77 VCCIN<183> SKX_EXT_B_BGA1-IC,TBD    I50 @BASEBOARD_FAB2_LIB.BASEBOARD_FAB2(SCH_1):PAGE71
  U2D1 BH75 VCCIN<184> SKX_EXT_B_BGA1-IC,TBD    I50 @BASEBOARD_FAB2_LIB.BASEBOARD_FAB2(SCH_1):PAGE71
  U2D1 BH73 VCCIN<185> SKX_EXT_B_BGA1-IC,TBD    I50 @BASEBOARD_FAB2_LIB.BASEBOARD_FAB2(SCH_1):PAGE71
  U2D1 BH71 VCCIN<186> SKX_EXT_B_BGA1-IC,TBD    I50 @BASEBOARD_FAB2_LIB.BASEBOARD_FAB2(SCH_1):PAGE71
  U2D1 BH69 VCCIN<187> SKX_EXT_B_BGA1-IC,TBD    I50 @BASEBOARD_FAB2_LIB.BASEBOARD_FAB2(SCH_1):PAGE71
  U2D1 BH67 VCCIN<188> SKX_EXT_B_BGA1-IC,TBD    I50 @BASEBOARD_FAB2_LIB.BASEBOARD_FAB2(SCH_1):PAGE71
  U2D1 BH65 VCCIN<189> SKX_EXT_B_BGA1-IC,TBD    I50 @BASEBOARD_FAB2_LIB.BASEBOARD_FAB2(SCH_1):PAGE71
  U2D1 BH63 VCCIN<190> SKX_EXT_B_BGA1-IC,TBD    I50 @BASEBOARD_FAB2_LIB.BASEBOARD_FAB2(SCH_1):PAGE71
  U2D1 BH61 VCCIN<191> SKX_EXT_B_BGA1-IC,TBD    I50 @BASEBOARD_FAB2_LIB.BASEBOARD_FAB2(SCH_1):PAGE71
  U2D1 BG84 VCCIN<192> SKX_EXT_B_BGA1-IC,TBD    I50 @BASEBOARD_FAB2_LIB.BASEBOARD_FAB2(SCH_1):PAGE71
  U2D1 BG70 VCCIN<193> SKX_EXT_B_BGA1-IC,TBD    I50 @BASEBOARD_FAB2_LIB.BASEBOARD_FAB2(SCH_1):PAGE71
  U2D1 BG68 VCCIN<194> SKX_EXT_B_BGA1-IC,TBD    I50 @BASEBOARD_FAB2_LIB.BASEBOARD_FAB2(SCH_1):PAGE71
  U2D1 BG66 VCCIN<195> SKX_EXT_B_BGA1-IC,TBD    I50 @BASEBOARD_FAB2_LIB.BASEBOARD_FAB2(SCH_1):PAGE71
  U2D1 BG64 VCCIN<196> SKX_EXT_B_BGA1-IC,TBD    I50 @BASEBOARD_FAB2_LIB.BASEBOARD_FAB2(SCH_1):PAGE71
  U2D1 BG62 VCCIN<197> SKX_EXT_B_BGA1-IC,TBD    I50 @BASEBOARD_FAB2_LIB.BASEBOARD_FAB2(SCH_1):PAGE71
  U2D1 BG60 VCCIN<198> SKX_EXT_B_BGA1-IC,TBD    I50 @BASEBOARD_FAB2_LIB.BASEBOARD_FAB2(SCH_1):PAGE71
  U2D1 BF85 VCCIN<199> SKX_EXT_B_BGA1-IC,TBD    I50 @BASEBOARD_FAB2_LIB.BASEBOARD_FAB2(SCH_1):PAGE71
  U2D1 BF83 VCCIN<200> SKX_EXT_B_BGA1-IC,TBD    I50 @BASEBOARD_FAB2_LIB.BASEBOARD_FAB2(SCH_1):PAGE71
  U2D1 BF81 VCCIN<201> SKX_EXT_B_BGA1-IC,TBD    I50 @BASEBOARD_FAB2_LIB.BASEBOARD_FAB2(SCH_1):PAGE71
  U2D1 BF79 VCCIN<202> SKX_EXT_B_BGA1-IC,TBD    I50 @BASEBOARD_FAB2_LIB.BASEBOARD_FAB2(SCH_1):PAGE71
  U2D1 BF77 VCCIN<203> SKX_EXT_B_BGA1-IC,TBD    I50 @BASEBOARD_FAB2_LIB.BASEBOARD_FAB2(SCH_1):PAGE71
  U2D1 BF75 VCCIN<204> SKX_EXT_B_BGA1-IC,TBD    I50 @BASEBOARD_FAB2_LIB.BASEBOARD_FAB2(SCH_1):PAGE71
  U2D1 BF73 VCCIN<205> SKX_EXT_B_BGA1-IC,TBD    I50 @BASEBOARD_FAB2_LIB.BASEBOARD_FAB2(SCH_1):PAGE71
  U2D1 BF61 VCCIN<206> SKX_EXT_B_BGA1-IC,TBD    I50 @BASEBOARD_FAB2_LIB.BASEBOARD_FAB2(SCH_1):PAGE71
  U2D1 BE84 VCCIN<207> SKX_EXT_B_BGA1-IC,TBD    I50 @BASEBOARD_FAB2_LIB.BASEBOARD_FAB2(SCH_1):PAGE71
  U2D1 BE82 VCCIN<208> SKX_EXT_B_BGA1-IC,TBD    I50 @BASEBOARD_FAB2_LIB.BASEBOARD_FAB2(SCH_1):PAGE71
  U2D1 BE80 VCCIN<209> SKX_EXT_B_BGA1-IC,TBD    I50 @BASEBOARD_FAB2_LIB.BASEBOARD_FAB2(SCH_1):PAGE71
  U2D1 BE78 VCCIN<210> SKX_EXT_B_BGA1-IC,TBD    I50 @BASEBOARD_FAB2_LIB.BASEBOARD_FAB2(SCH_1):PAGE71
  U2D1 BE76 VCCIN<211> SKX_EXT_B_BGA1-IC,TBD    I50 @BASEBOARD_FAB2_LIB.BASEBOARD_FAB2(SCH_1):PAGE71
  U2D1 BE74 VCCIN<212> SKX_EXT_B_BGA1-IC,TBD    I50 @BASEBOARD_FAB2_LIB.BASEBOARD_FAB2(SCH_1):PAGE71
  U2D1 BE72 VCCIN<213> SKX_EXT_B_BGA1-IC,TBD    I50 @BASEBOARD_FAB2_LIB.BASEBOARD_FAB2(SCH_1):PAGE71
  U2D1 BE62 VCCIN<214> SKX_EXT_B_BGA1-IC,TBD    I50 @BASEBOARD_FAB2_LIB.BASEBOARD_FAB2(SCH_1):PAGE71
  U2D1 BE60 VCCIN<215> SKX_EXT_B_BGA1-IC,TBD    I50 @BASEBOARD_FAB2_LIB.BASEBOARD_FAB2(SCH_1):PAGE71
  U2D1 BD85 VCCIN<216> SKX_EXT_B_BGA1-IC,TBD    I50 @BASEBOARD_FAB2_LIB.BASEBOARD_FAB2(SCH_1):PAGE71
  U2D1 BD83 VCCIN<217> SKX_EXT_B_BGA1-IC,TBD    I50 @BASEBOARD_FAB2_LIB.BASEBOARD_FAB2(SCH_1):PAGE71
  U2D1 BD81 VCCIN<218> SKX_EXT_B_BGA1-IC,TBD    I50 @BASEBOARD_FAB2_LIB.BASEBOARD_FAB2(SCH_1):PAGE71
  U2D1 BD79 VCCIN<219> SKX_EXT_B_BGA1-IC,TBD    I50 @BASEBOARD_FAB2_LIB.BASEBOARD_FAB2(SCH_1):PAGE71
  U2D1 BD77 VCCIN<220> SKX_EXT_B_BGA1-IC,TBD    I50 @BASEBOARD_FAB2_LIB.BASEBOARD_FAB2(SCH_1):PAGE71
  U2D1 BD75 VCCIN<221> SKX_EXT_B_BGA1-IC,TBD    I50 @BASEBOARD_FAB2_LIB.BASEBOARD_FAB2(SCH_1):PAGE71
  U2D1 BD73 VCCIN<222> SKX_EXT_B_BGA1-IC,TBD    I50 @BASEBOARD_FAB2_LIB.BASEBOARD_FAB2(SCH_1):PAGE71
  U2D1 BD61 VCCIN<223> SKX_EXT_B_BGA1-IC,TBD    I50 @BASEBOARD_FAB2_LIB.BASEBOARD_FAB2(SCH_1):PAGE71
  U2D1 BC84 VCCIN<224> SKX_EXT_B_BGA1-IC,TBD    I50 @BASEBOARD_FAB2_LIB.BASEBOARD_FAB2(SCH_1):PAGE71
  U2D1 BC62 VCCIN<225> SKX_EXT_B_BGA1-IC,TBD    I50 @BASEBOARD_FAB2_LIB.BASEBOARD_FAB2(SCH_1):PAGE71
  U2D1 BC60 VCCIN<226> SKX_EXT_B_BGA1-IC,TBD    I50 @BASEBOARD_FAB2_LIB.BASEBOARD_FAB2(SCH_1):PAGE71
  U2D1 BB85 VCCIN<227> SKX_EXT_B_BGA1-IC,TBD    I50 @BASEBOARD_FAB2_LIB.BASEBOARD_FAB2(SCH_1):PAGE71
  U2D1 BB61 VCCIN<228> SKX_EXT_B_BGA1-IC,TBD    I50 @BASEBOARD_FAB2_LIB.BASEBOARD_FAB2(SCH_1):PAGE71
  U2D1 BA60 VCCIN<229> SKX_EXT_B_BGA1-IC,TBD    I50 @BASEBOARD_FAB2_LIB.BASEBOARD_FAB2(SCH_1):PAGE71
  U2D1 AY61 VCCIN<230> SKX_EXT_B_BGA1-IC,TBD    I50 @BASEBOARD_FAB2_LIB.BASEBOARD_FAB2(SCH_1):PAGE71
  U2D1 AW60 VCCIN<231> SKX_EXT_B_BGA1-IC,TBD    I50 @BASEBOARD_FAB2_LIB.BASEBOARD_FAB2(SCH_1):PAGE71
  U2D1 AV61 VCCIN<232> SKX_EXT_B_BGA1-IC,TBD    I50 @BASEBOARD_FAB2_LIB.BASEBOARD_FAB2(SCH_1):PAGE71
  U2D1 AV59 VCCIN<233> SKX_EXT_B_BGA1-IC,TBD    I50 @BASEBOARD_FAB2_LIB.BASEBOARD_FAB2(SCH_1):PAGE71
  U2D1 AU60 VCCIN<234> SKX_EXT_B_BGA1-IC,TBD    I50 @BASEBOARD_FAB2_LIB.BASEBOARD_FAB2(SCH_1):PAGE71
  U2D1 AU58 VCCIN<235> SKX_EXT_B_BGA1-IC,TBD    I50 @BASEBOARD_FAB2_LIB.BASEBOARD_FAB2(SCH_1):PAGE71
  U2D1 AT59 VCCIN<236> SKX_EXT_B_BGA1-IC,TBD    I50 @BASEBOARD_FAB2_LIB.BASEBOARD_FAB2(SCH_1):PAGE71
  U2D1 AT57 VCCIN<237> SKX_EXT_B_BGA1-IC,TBD    I50 @BASEBOARD_FAB2_LIB.BASEBOARD_FAB2(SCH_1):PAGE71
  U2D1 AR58 VCCIN<238> SKX_EXT_B_BGA1-IC,TBD    I50 @BASEBOARD_FAB2_LIB.BASEBOARD_FAB2(SCH_1):PAGE71
  U2D1 AR56 VCCIN<239> SKX_EXT_B_BGA1-IC,TBD    I50 @BASEBOARD_FAB2_LIB.BASEBOARD_FAB2(SCH_1):PAGE71
  U2D1 AP57 VCCIN<240> SKX_EXT_B_BGA1-IC,TBD    I50 @BASEBOARD_FAB2_LIB.BASEBOARD_FAB2(SCH_1):PAGE71
  U2D1 AP55 VCCIN<241> SKX_EXT_B_BGA1-IC,TBD    I50 @BASEBOARD_FAB2_LIB.BASEBOARD_FAB2(SCH_1):PAGE71
  U2D1 AN56 VCCIN<242> SKX_EXT_B_BGA1-IC,TBD    I50 @BASEBOARD_FAB2_LIB.BASEBOARD_FAB2(SCH_1):PAGE71
  U2D1 AN54 VCCIN<243> SKX_EXT_B_BGA1-IC,TBD    I50 @BASEBOARD_FAB2_LIB.BASEBOARD_FAB2(SCH_1):PAGE71
  U2D1 AN32 VCCIN<244> SKX_EXT_B_BGA1-IC,TBD    I50 @BASEBOARD_FAB2_LIB.BASEBOARD_FAB2(SCH_1):PAGE71
  U2D1 AM55 VCCIN<245> SKX_EXT_B_BGA1-IC,TBD    I50 @BASEBOARD_FAB2_LIB.BASEBOARD_FAB2(SCH_1):PAGE71
  U2D1 AM53 VCCIN<246> SKX_EXT_B_BGA1-IC,TBD    I50 @BASEBOARD_FAB2_LIB.BASEBOARD_FAB2(SCH_1):PAGE71
  U2D1 AM33 VCCIN<247> SKX_EXT_B_BGA1-IC,TBD    I50 @BASEBOARD_FAB2_LIB.BASEBOARD_FAB2(SCH_1):PAGE71
  U2D1 AL54 VCCIN<248> SKX_EXT_B_BGA1-IC,TBD    I50 @BASEBOARD_FAB2_LIB.BASEBOARD_FAB2(SCH_1):PAGE71
  U2D1 AL52 VCCIN<249> SKX_EXT_B_BGA1-IC,TBD    I50 @BASEBOARD_FAB2_LIB.BASEBOARD_FAB2(SCH_1):PAGE71
  U2D1 AL50 VCCIN<250> SKX_EXT_B_BGA1-IC,TBD    I50 @BASEBOARD_FAB2_LIB.BASEBOARD_FAB2(SCH_1):PAGE71
  U2D1 AL48 VCCIN<251> SKX_EXT_B_BGA1-IC,TBD    I50 @BASEBOARD_FAB2_LIB.BASEBOARD_FAB2(SCH_1):PAGE71
  U2D1 AL46 VCCIN<252> SKX_EXT_B_BGA1-IC,TBD    I50 @BASEBOARD_FAB2_LIB.BASEBOARD_FAB2(SCH_1):PAGE71
  U2D1 AL34 VCCIN<253> SKX_EXT_B_BGA1-IC,TBD    I50 @BASEBOARD_FAB2_LIB.BASEBOARD_FAB2(SCH_1):PAGE71
  U2D1 AK53 VCCIN<254> SKX_EXT_B_BGA1-IC,TBD    I50 @BASEBOARD_FAB2_LIB.BASEBOARD_FAB2(SCH_1):PAGE71
  U2D1 AK51 VCCIN<255> SKX_EXT_B_BGA1-IC,TBD    I50 @BASEBOARD_FAB2_LIB.BASEBOARD_FAB2(SCH_1):PAGE71
  U2D1 AK49 VCCIN<256> SKX_EXT_B_BGA1-IC,TBD    I50 @BASEBOARD_FAB2_LIB.BASEBOARD_FAB2(SCH_1):PAGE71
  U2D1 AK47 VCCIN<257> SKX_EXT_B_BGA1-IC,TBD    I50 @BASEBOARD_FAB2_LIB.BASEBOARD_FAB2(SCH_1):PAGE71
  U2D1 AK45 VCCIN<258> SKX_EXT_B_BGA1-IC,TBD    I50 @BASEBOARD_FAB2_LIB.BASEBOARD_FAB2(SCH_1):PAGE71
  U2D1 AK35 VCCIN<259> SKX_EXT_B_BGA1-IC,TBD    I50 @BASEBOARD_FAB2_LIB.BASEBOARD_FAB2(SCH_1):PAGE71
  U2D1 AJ36 VCCIN<260> SKX_EXT_B_BGA1-IC,TBD    I50 @BASEBOARD_FAB2_LIB.BASEBOARD_FAB2(SCH_1):PAGE71
  U2D1 AH41 VCCIN<261> SKX_EXT_B_BGA1-IC,TBD    I50 @BASEBOARD_FAB2_LIB.BASEBOARD_FAB2(SCH_1):PAGE71
  U2D1 AH39 VCCIN<262> SKX_EXT_B_BGA1-IC,TBD    I50 @BASEBOARD_FAB2_LIB.BASEBOARD_FAB2(SCH_1):PAGE71
  U2D1 AH37 VCCIN<263> SKX_EXT_B_BGA1-IC,TBD    I50 @BASEBOARD_FAB2_LIB.BASEBOARD_FAB2(SCH_1):PAGE71
  U2D1 AG42 VCCIN<264> SKX_EXT_B_BGA1-IC,TBD    I50 @BASEBOARD_FAB2_LIB.BASEBOARD_FAB2(SCH_1):PAGE71
  U2D1 AG40 VCCIN<265> SKX_EXT_B_BGA1-IC,TBD    I50 @BASEBOARD_FAB2_LIB.BASEBOARD_FAB2(SCH_1):PAGE71
  U2D1 AG38 VCCIN<266> SKX_EXT_B_BGA1-IC,TBD    I50 @BASEBOARD_FAB2_LIB.BASEBOARD_FAB2(SCH_1):PAGE71
  U2D1 AF43 VCCIN<267> SKX_EXT_B_BGA1-IC,TBD    I50 @BASEBOARD_FAB2_LIB.BASEBOARD_FAB2(SCH_1):PAGE71
  U2D1 CY49 VCCIN<0> SKX_EXT_B_BGA1-IC,TBD    I51 @BASEBOARD_FAB2_LIB.BASEBOARD_FAB2(SCH_1):PAGE71
  U2D1 CY47 VCCIN<1> SKX_EXT_B_BGA1-IC,TBD    I51 @BASEBOARD_FAB2_LIB.BASEBOARD_FAB2(SCH_1):PAGE71
  U2D1 CW50 VCCIN<2> SKX_EXT_B_BGA1-IC,TBD    I51 @BASEBOARD_FAB2_LIB.BASEBOARD_FAB2(SCH_1):PAGE71
  U2D1 CW48 VCCIN<3> SKX_EXT_B_BGA1-IC,TBD    I51 @BASEBOARD_FAB2_LIB.BASEBOARD_FAB2(SCH_1):PAGE71
  U2D1 CW46 VCCIN<4> SKX_EXT_B_BGA1-IC,TBD    I51 @BASEBOARD_FAB2_LIB.BASEBOARD_FAB2(SCH_1):PAGE71
  U2D1 CV51 VCCIN<5> SKX_EXT_B_BGA1-IC,TBD    I51 @BASEBOARD_FAB2_LIB.BASEBOARD_FAB2(SCH_1):PAGE71
  U2D1 CU54 VCCIN<6> SKX_EXT_B_BGA1-IC,TBD    I51 @BASEBOARD_FAB2_LIB.BASEBOARD_FAB2(SCH_1):PAGE71
  U2D1 CU52 VCCIN<7> SKX_EXT_B_BGA1-IC,TBD    I51 @BASEBOARD_FAB2_LIB.BASEBOARD_FAB2(SCH_1):PAGE71
  U2D1 CU42 VCCIN<8> SKX_EXT_B_BGA1-IC,TBD    I51 @BASEBOARD_FAB2_LIB.BASEBOARD_FAB2(SCH_1):PAGE71
  U2D1 CU40 VCCIN<9> SKX_EXT_B_BGA1-IC,TBD    I51 @BASEBOARD_FAB2_LIB.BASEBOARD_FAB2(SCH_1):PAGE71
  U2D1 CU38 VCCIN<10> SKX_EXT_B_BGA1-IC,TBD    I51 @BASEBOARD_FAB2_LIB.BASEBOARD_FAB2(SCH_1):PAGE71
  U2D1 CT55 VCCIN<11> SKX_EXT_B_BGA1-IC,TBD    I51 @BASEBOARD_FAB2_LIB.BASEBOARD_FAB2(SCH_1):PAGE71
  U2D1 CT53 VCCIN<12> SKX_EXT_B_BGA1-IC,TBD    I51 @BASEBOARD_FAB2_LIB.BASEBOARD_FAB2(SCH_1):PAGE71
  U2D1 CT41 VCCIN<13> SKX_EXT_B_BGA1-IC,TBD    I51 @BASEBOARD_FAB2_LIB.BASEBOARD_FAB2(SCH_1):PAGE71
  U2D1 CT39 VCCIN<14> SKX_EXT_B_BGA1-IC,TBD    I51 @BASEBOARD_FAB2_LIB.BASEBOARD_FAB2(SCH_1):PAGE71
  U2D1 CT37 VCCIN<15> SKX_EXT_B_BGA1-IC,TBD    I51 @BASEBOARD_FAB2_LIB.BASEBOARD_FAB2(SCH_1):PAGE71
  U2D1 CR56 VCCIN<16> SKX_EXT_B_BGA1-IC,TBD    I51 @BASEBOARD_FAB2_LIB.BASEBOARD_FAB2(SCH_1):PAGE71
  U2D1 CR54 VCCIN<17> SKX_EXT_B_BGA1-IC,TBD    I51 @BASEBOARD_FAB2_LIB.BASEBOARD_FAB2(SCH_1):PAGE71
  U2D1 CR34 VCCIN<18> SKX_EXT_B_BGA1-IC,TBD    I51 @BASEBOARD_FAB2_LIB.BASEBOARD_FAB2(SCH_1):PAGE71
  U2D1 CP57 VCCIN<19> SKX_EXT_B_BGA1-IC,TBD    I51 @BASEBOARD_FAB2_LIB.BASEBOARD_FAB2(SCH_1):PAGE71
  U2D1 CP55 VCCIN<20> SKX_EXT_B_BGA1-IC,TBD    I51 @BASEBOARD_FAB2_LIB.BASEBOARD_FAB2(SCH_1):PAGE71
  U2D1 CP33 VCCIN<21> SKX_EXT_B_BGA1-IC,TBD    I51 @BASEBOARD_FAB2_LIB.BASEBOARD_FAB2(SCH_1):PAGE71
  U2D1 CN58 VCCIN<22> SKX_EXT_B_BGA1-IC,TBD    I51 @BASEBOARD_FAB2_LIB.BASEBOARD_FAB2(SCH_1):PAGE71
  U2D1 CN56 VCCIN<23> SKX_EXT_B_BGA1-IC,TBD    I51 @BASEBOARD_FAB2_LIB.BASEBOARD_FAB2(SCH_1):PAGE71
  U2D1 CM59 VCCIN<24> SKX_EXT_B_BGA1-IC,TBD    I51 @BASEBOARD_FAB2_LIB.BASEBOARD_FAB2(SCH_1):PAGE71
  U2D1 CM57 VCCIN<25> SKX_EXT_B_BGA1-IC,TBD    I51 @BASEBOARD_FAB2_LIB.BASEBOARD_FAB2(SCH_1):PAGE71
  U2D1 CL60 VCCIN<26> SKX_EXT_B_BGA1-IC,TBD    I51 @BASEBOARD_FAB2_LIB.BASEBOARD_FAB2(SCH_1):PAGE71
  U2D1 CL58 VCCIN<27> SKX_EXT_B_BGA1-IC,TBD    I51 @BASEBOARD_FAB2_LIB.BASEBOARD_FAB2(SCH_1):PAGE71
  U2D1 CK61 VCCIN<28> SKX_EXT_B_BGA1-IC,TBD    I51 @BASEBOARD_FAB2_LIB.BASEBOARD_FAB2(SCH_1):PAGE71
  U2D1 CK59 VCCIN<29> SKX_EXT_B_BGA1-IC,TBD    I51 @BASEBOARD_FAB2_LIB.BASEBOARD_FAB2(SCH_1):PAGE71
  U2D1 CJ60 VCCIN<30> SKX_EXT_B_BGA1-IC,TBD    I51 @BASEBOARD_FAB2_LIB.BASEBOARD_FAB2(SCH_1):PAGE71
  U2D1 CH85 VCCIN<31> SKX_EXT_B_BGA1-IC,TBD    I51 @BASEBOARD_FAB2_LIB.BASEBOARD_FAB2(SCH_1):PAGE71
  U2D1 CH61 VCCIN<32> SKX_EXT_B_BGA1-IC,TBD    I51 @BASEBOARD_FAB2_LIB.BASEBOARD_FAB2(SCH_1):PAGE71
  U2D1 CG84 VCCIN<33> SKX_EXT_B_BGA1-IC,TBD    I51 @BASEBOARD_FAB2_LIB.BASEBOARD_FAB2(SCH_1):PAGE71
  U2D1 CG60 VCCIN<34> SKX_EXT_B_BGA1-IC,TBD    I51 @BASEBOARD_FAB2_LIB.BASEBOARD_FAB2(SCH_1):PAGE71
  U2D1 CF85 VCCIN<35> SKX_EXT_B_BGA1-IC,TBD    I51 @BASEBOARD_FAB2_LIB.BASEBOARD_FAB2(SCH_1):PAGE71
  U2D1 CF61 VCCIN<36> SKX_EXT_B_BGA1-IC,TBD    I51 @BASEBOARD_FAB2_LIB.BASEBOARD_FAB2(SCH_1):PAGE71
  U2D1 CE84 VCCIN<37> SKX_EXT_B_BGA1-IC,TBD    I51 @BASEBOARD_FAB2_LIB.BASEBOARD_FAB2(SCH_1):PAGE71
  U2D1 CE60 VCCIN<38> SKX_EXT_B_BGA1-IC,TBD    I51 @BASEBOARD_FAB2_LIB.BASEBOARD_FAB2(SCH_1):PAGE71
  U2D1 CD85 VCCIN<39> SKX_EXT_B_BGA1-IC,TBD    I51 @BASEBOARD_FAB2_LIB.BASEBOARD_FAB2(SCH_1):PAGE71
  U2D1 CD83 VCCIN<40> SKX_EXT_B_BGA1-IC,TBD    I51 @BASEBOARD_FAB2_LIB.BASEBOARD_FAB2(SCH_1):PAGE71
  U2D1 CD61 VCCIN<41> SKX_EXT_B_BGA1-IC,TBD    I51 @BASEBOARD_FAB2_LIB.BASEBOARD_FAB2(SCH_1):PAGE71
  U2D1 CC84 VCCIN<42> SKX_EXT_B_BGA1-IC,TBD    I51 @BASEBOARD_FAB2_LIB.BASEBOARD_FAB2(SCH_1):PAGE71
  U2D1 CC62 VCCIN<43> SKX_EXT_B_BGA1-IC,TBD    I51 @BASEBOARD_FAB2_LIB.BASEBOARD_FAB2(SCH_1):PAGE71
  U2D1 CC60 VCCIN<44> SKX_EXT_B_BGA1-IC,TBD    I51 @BASEBOARD_FAB2_LIB.BASEBOARD_FAB2(SCH_1):PAGE71
  U2D1 CB83 VCCIN<45> SKX_EXT_B_BGA1-IC,TBD    I51 @BASEBOARD_FAB2_LIB.BASEBOARD_FAB2(SCH_1):PAGE71
  U2D1 CB81 VCCIN<46> SKX_EXT_B_BGA1-IC,TBD    I51 @BASEBOARD_FAB2_LIB.BASEBOARD_FAB2(SCH_1):PAGE71
  U2D1 CB79 VCCIN<47> SKX_EXT_B_BGA1-IC,TBD    I51 @BASEBOARD_FAB2_LIB.BASEBOARD_FAB2(SCH_1):PAGE71
  U2D1 CB77 VCCIN<48> SKX_EXT_B_BGA1-IC,TBD    I51 @BASEBOARD_FAB2_LIB.BASEBOARD_FAB2(SCH_1):PAGE71
  U2D1 CB75 VCCIN<49> SKX_EXT_B_BGA1-IC,TBD    I51 @BASEBOARD_FAB2_LIB.BASEBOARD_FAB2(SCH_1):PAGE71
  U2D1 CB73 VCCIN<50> SKX_EXT_B_BGA1-IC,TBD    I51 @BASEBOARD_FAB2_LIB.BASEBOARD_FAB2(SCH_1):PAGE71
  U2D1 CB61 VCCIN<51> SKX_EXT_B_BGA1-IC,TBD    I51 @BASEBOARD_FAB2_LIB.BASEBOARD_FAB2(SCH_1):PAGE71
  U2D1 CA84 VCCIN<52> SKX_EXT_B_BGA1-IC,TBD    I51 @BASEBOARD_FAB2_LIB.BASEBOARD_FAB2(SCH_1):PAGE71
  U2D1 CA82 VCCIN<53> SKX_EXT_B_BGA1-IC,TBD    I51 @BASEBOARD_FAB2_LIB.BASEBOARD_FAB2(SCH_1):PAGE71
  U2D1 CA80 VCCIN<54> SKX_EXT_B_BGA1-IC,TBD    I51 @BASEBOARD_FAB2_LIB.BASEBOARD_FAB2(SCH_1):PAGE71
  U2D1 CA78 VCCIN<55> SKX_EXT_B_BGA1-IC,TBD    I51 @BASEBOARD_FAB2_LIB.BASEBOARD_FAB2(SCH_1):PAGE71
  U2D1 CA76 VCCIN<56> SKX_EXT_B_BGA1-IC,TBD    I51 @BASEBOARD_FAB2_LIB.BASEBOARD_FAB2(SCH_1):PAGE71
  U2D1 CA74 VCCIN<57> SKX_EXT_B_BGA1-IC,TBD    I51 @BASEBOARD_FAB2_LIB.BASEBOARD_FAB2(SCH_1):PAGE71
  U2D1 CA72 VCCIN<58> SKX_EXT_B_BGA1-IC,TBD    I51 @BASEBOARD_FAB2_LIB.BASEBOARD_FAB2(SCH_1):PAGE71
  U2D1 CA62 VCCIN<59> SKX_EXT_B_BGA1-IC,TBD    I51 @BASEBOARD_FAB2_LIB.BASEBOARD_FAB2(SCH_1):PAGE71
  U2D1 CA60 VCCIN<60> SKX_EXT_B_BGA1-IC,TBD    I51 @BASEBOARD_FAB2_LIB.BASEBOARD_FAB2(SCH_1):PAGE71
  U2D1 BY83 VCCIN<61> SKX_EXT_B_BGA1-IC,TBD    I51 @BASEBOARD_FAB2_LIB.BASEBOARD_FAB2(SCH_1):PAGE71
  U2D1 BY81 VCCIN<62> SKX_EXT_B_BGA1-IC,TBD    I51 @BASEBOARD_FAB2_LIB.BASEBOARD_FAB2(SCH_1):PAGE71
  U2D1 BY79 VCCIN<63> SKX_EXT_B_BGA1-IC,TBD    I51 @BASEBOARD_FAB2_LIB.BASEBOARD_FAB2(SCH_1):PAGE71
  U2D1 BY77 VCCIN<64> SKX_EXT_B_BGA1-IC,TBD    I51 @BASEBOARD_FAB2_LIB.BASEBOARD_FAB2(SCH_1):PAGE71
  U2D1 BY75 VCCIN<65> SKX_EXT_B_BGA1-IC,TBD    I51 @BASEBOARD_FAB2_LIB.BASEBOARD_FAB2(SCH_1):PAGE71
  U2D1 BY73 VCCIN<66> SKX_EXT_B_BGA1-IC,TBD    I51 @BASEBOARD_FAB2_LIB.BASEBOARD_FAB2(SCH_1):PAGE71
  U2D1 BY61 VCCIN<67> SKX_EXT_B_BGA1-IC,TBD    I51 @BASEBOARD_FAB2_LIB.BASEBOARD_FAB2(SCH_1):PAGE71
  U2D1 BW84 VCCIN<68> SKX_EXT_B_BGA1-IC,TBD    I51 @BASEBOARD_FAB2_LIB.BASEBOARD_FAB2(SCH_1):PAGE71
  U2D1 BW70 VCCIN<69> SKX_EXT_B_BGA1-IC,TBD    I51 @BASEBOARD_FAB2_LIB.BASEBOARD_FAB2(SCH_1):PAGE71
  U2D1 BW68 VCCIN<70> SKX_EXT_B_BGA1-IC,TBD    I51 @BASEBOARD_FAB2_LIB.BASEBOARD_FAB2(SCH_1):PAGE71
  U2D1 BW66 VCCIN<71> SKX_EXT_B_BGA1-IC,TBD    I51 @BASEBOARD_FAB2_LIB.BASEBOARD_FAB2(SCH_1):PAGE71
  U2D1 BW64 VCCIN<72> SKX_EXT_B_BGA1-IC,TBD    I51 @BASEBOARD_FAB2_LIB.BASEBOARD_FAB2(SCH_1):PAGE71
  U2D1 BW62 VCCIN<73> SKX_EXT_B_BGA1-IC,TBD    I51 @BASEBOARD_FAB2_LIB.BASEBOARD_FAB2(SCH_1):PAGE71
  U2D1 BW60 VCCIN<74> SKX_EXT_B_BGA1-IC,TBD    I51 @BASEBOARD_FAB2_LIB.BASEBOARD_FAB2(SCH_1):PAGE71
  U2D1 BV83 VCCIN<75> SKX_EXT_B_BGA1-IC,TBD    I51 @BASEBOARD_FAB2_LIB.BASEBOARD_FAB2(SCH_1):PAGE71
  U2D1 BV81 VCCIN<76> SKX_EXT_B_BGA1-IC,TBD    I51 @BASEBOARD_FAB2_LIB.BASEBOARD_FAB2(SCH_1):PAGE71
  U2D1 BV79 VCCIN<77> SKX_EXT_B_BGA1-IC,TBD    I51 @BASEBOARD_FAB2_LIB.BASEBOARD_FAB2(SCH_1):PAGE71
  U2D1 BV77 VCCIN<78> SKX_EXT_B_BGA1-IC,TBD    I51 @BASEBOARD_FAB2_LIB.BASEBOARD_FAB2(SCH_1):PAGE71
  U2D1 BV75 VCCIN<79> SKX_EXT_B_BGA1-IC,TBD    I51 @BASEBOARD_FAB2_LIB.BASEBOARD_FAB2(SCH_1):PAGE71
  U2D1 BV73 VCCIN<80> SKX_EXT_B_BGA1-IC,TBD    I51 @BASEBOARD_FAB2_LIB.BASEBOARD_FAB2(SCH_1):PAGE71
  U2D1 BV71 VCCIN<81> SKX_EXT_B_BGA1-IC,TBD    I51 @BASEBOARD_FAB2_LIB.BASEBOARD_FAB2(SCH_1):PAGE71
  U2D1 BV69 VCCIN<82> SKX_EXT_B_BGA1-IC,TBD    I51 @BASEBOARD_FAB2_LIB.BASEBOARD_FAB2(SCH_1):PAGE71
  U2D1 BV67 VCCIN<83> SKX_EXT_B_BGA1-IC,TBD    I51 @BASEBOARD_FAB2_LIB.BASEBOARD_FAB2(SCH_1):PAGE71
  U2D1 BV65 VCCIN<84> SKX_EXT_B_BGA1-IC,TBD    I51 @BASEBOARD_FAB2_LIB.BASEBOARD_FAB2(SCH_1):PAGE71
  U2D1 BV63 VCCIN<85> SKX_EXT_B_BGA1-IC,TBD    I51 @BASEBOARD_FAB2_LIB.BASEBOARD_FAB2(SCH_1):PAGE71
  U2D1 BV61 VCCIN<86> SKX_EXT_B_BGA1-IC,TBD    I51 @BASEBOARD_FAB2_LIB.BASEBOARD_FAB2(SCH_1):PAGE71
  U2D1 BU84 VCCIN<87> SKX_EXT_B_BGA1-IC,TBD    I51 @BASEBOARD_FAB2_LIB.BASEBOARD_FAB2(SCH_1):PAGE71
  U2D1 BU82 VCCIN<88> SKX_EXT_B_BGA1-IC,TBD    I51 @BASEBOARD_FAB2_LIB.BASEBOARD_FAB2(SCH_1):PAGE71
  U2D1 BU80 VCCIN<89> SKX_EXT_B_BGA1-IC,TBD    I51 @BASEBOARD_FAB2_LIB.BASEBOARD_FAB2(SCH_1):PAGE71
  U2D1 BU78 VCCIN<90> SKX_EXT_B_BGA1-IC,TBD    I51 @BASEBOARD_FAB2_LIB.BASEBOARD_FAB2(SCH_1):PAGE71
  U2D1 BU76 VCCIN<91> SKX_EXT_B_BGA1-IC,TBD    I51 @BASEBOARD_FAB2_LIB.BASEBOARD_FAB2(SCH_1):PAGE71
  U2D1 BU74 VCCIN<92> SKX_EXT_B_BGA1-IC,TBD    I51 @BASEBOARD_FAB2_LIB.BASEBOARD_FAB2(SCH_1):PAGE71
  U2D1 BU72 VCCIN<93> SKX_EXT_B_BGA1-IC,TBD    I51 @BASEBOARD_FAB2_LIB.BASEBOARD_FAB2(SCH_1):PAGE71
  U2D1 BU70 VCCIN<94> SKX_EXT_B_BGA1-IC,TBD    I51 @BASEBOARD_FAB2_LIB.BASEBOARD_FAB2(SCH_1):PAGE71
  U2D1 BU68 VCCIN<95> SKX_EXT_B_BGA1-IC,TBD    I51 @BASEBOARD_FAB2_LIB.BASEBOARD_FAB2(SCH_1):PAGE71
  U2D1 BU66 VCCIN<96> SKX_EXT_B_BGA1-IC,TBD    I51 @BASEBOARD_FAB2_LIB.BASEBOARD_FAB2(SCH_1):PAGE71
  U2D1 BU64 VCCIN<97> SKX_EXT_B_BGA1-IC,TBD    I51 @BASEBOARD_FAB2_LIB.BASEBOARD_FAB2(SCH_1):PAGE71
  U2D1 BU62 VCCIN<98> SKX_EXT_B_BGA1-IC,TBD    I51 @BASEBOARD_FAB2_LIB.BASEBOARD_FAB2(SCH_1):PAGE71
  U2D1 BU60 VCCIN<99> SKX_EXT_B_BGA1-IC,TBD    I51 @BASEBOARD_FAB2_LIB.BASEBOARD_FAB2(SCH_1):PAGE71
  U2D1 BT83 VCCIN<100> SKX_EXT_B_BGA1-IC,TBD    I51 @BASEBOARD_FAB2_LIB.BASEBOARD_FAB2(SCH_1):PAGE71
  U2D1 BT81 VCCIN<101> SKX_EXT_B_BGA1-IC,TBD    I51 @BASEBOARD_FAB2_LIB.BASEBOARD_FAB2(SCH_1):PAGE71
  U2D1 BT79 VCCIN<102> SKX_EXT_B_BGA1-IC,TBD    I51 @BASEBOARD_FAB2_LIB.BASEBOARD_FAB2(SCH_1):PAGE71
  U2D1 BT77 VCCIN<103> SKX_EXT_B_BGA1-IC,TBD    I51 @BASEBOARD_FAB2_LIB.BASEBOARD_FAB2(SCH_1):PAGE71
  U2D1 BT75 VCCIN<104> SKX_EXT_B_BGA1-IC,TBD    I51 @BASEBOARD_FAB2_LIB.BASEBOARD_FAB2(SCH_1):PAGE71
  U2D1 BT73 VCCIN<105> SKX_EXT_B_BGA1-IC,TBD    I51 @BASEBOARD_FAB2_LIB.BASEBOARD_FAB2(SCH_1):PAGE71
  U2D1 BT71 VCCIN<106> SKX_EXT_B_BGA1-IC,TBD    I51 @BASEBOARD_FAB2_LIB.BASEBOARD_FAB2(SCH_1):PAGE71
  U2D1 BT69 VCCIN<107> SKX_EXT_B_BGA1-IC,TBD    I51 @BASEBOARD_FAB2_LIB.BASEBOARD_FAB2(SCH_1):PAGE71
  U2D1 BT67 VCCIN<108> SKX_EXT_B_BGA1-IC,TBD    I51 @BASEBOARD_FAB2_LIB.BASEBOARD_FAB2(SCH_1):PAGE71
  U2D1 BT65 VCCIN<109> SKX_EXT_B_BGA1-IC,TBD    I51 @BASEBOARD_FAB2_LIB.BASEBOARD_FAB2(SCH_1):PAGE71
  U2D1 BT63 VCCIN<110> SKX_EXT_B_BGA1-IC,TBD    I51 @BASEBOARD_FAB2_LIB.BASEBOARD_FAB2(SCH_1):PAGE71
  U2D1 BT61 VCCIN<111> SKX_EXT_B_BGA1-IC,TBD    I51 @BASEBOARD_FAB2_LIB.BASEBOARD_FAB2(SCH_1):PAGE71
  U2D1 BR84 VCCIN<112> SKX_EXT_B_BGA1-IC,TBD    I51 @BASEBOARD_FAB2_LIB.BASEBOARD_FAB2(SCH_1):PAGE71
  U2D1 BR62 VCCIN<113> SKX_EXT_B_BGA1-IC,TBD    I51 @BASEBOARD_FAB2_LIB.BASEBOARD_FAB2(SCH_1):PAGE71
  U2D1 BR60 VCCIN<114> SKX_EXT_B_BGA1-IC,TBD    I51 @BASEBOARD_FAB2_LIB.BASEBOARD_FAB2(SCH_1):PAGE71
  U2D1 BP83 VCCIN<115> SKX_EXT_B_BGA1-IC,TBD    I51 @BASEBOARD_FAB2_LIB.BASEBOARD_FAB2(SCH_1):PAGE71
  U2D1 BP81 VCCIN<116> SKX_EXT_B_BGA1-IC,TBD    I51 @BASEBOARD_FAB2_LIB.BASEBOARD_FAB2(SCH_1):PAGE71
  U2D1 BP79 VCCIN<117> SKX_EXT_B_BGA1-IC,TBD    I51 @BASEBOARD_FAB2_LIB.BASEBOARD_FAB2(SCH_1):PAGE71
  U2D1 BP77 VCCIN<118> SKX_EXT_B_BGA1-IC,TBD    I51 @BASEBOARD_FAB2_LIB.BASEBOARD_FAB2(SCH_1):PAGE71
  U2D1 BP75 VCCIN<119> SKX_EXT_B_BGA1-IC,TBD    I51 @BASEBOARD_FAB2_LIB.BASEBOARD_FAB2(SCH_1):PAGE71
  U2D1 BP73 VCCIN<120> SKX_EXT_B_BGA1-IC,TBD    I51 @BASEBOARD_FAB2_LIB.BASEBOARD_FAB2(SCH_1):PAGE71
  U2D1 BP71 VCCIN<121> SKX_EXT_B_BGA1-IC,TBD    I51 @BASEBOARD_FAB2_LIB.BASEBOARD_FAB2(SCH_1):PAGE71
  U2D1 BP69 VCCIN<122> SKX_EXT_B_BGA1-IC,TBD    I51 @BASEBOARD_FAB2_LIB.BASEBOARD_FAB2(SCH_1):PAGE71
  U2D1 BP67 VCCIN<123> SKX_EXT_B_BGA1-IC,TBD    I51 @BASEBOARD_FAB2_LIB.BASEBOARD_FAB2(SCH_1):PAGE71
  U2D1 BP65 VCCIN<124> SKX_EXT_B_BGA1-IC,TBD    I51 @BASEBOARD_FAB2_LIB.BASEBOARD_FAB2(SCH_1):PAGE71
  U2D1 BP63 VCCIN<125> SKX_EXT_B_BGA1-IC,TBD    I51 @BASEBOARD_FAB2_LIB.BASEBOARD_FAB2(SCH_1):PAGE71
  U2D1 BP61 VCCIN<126> SKX_EXT_B_BGA1-IC,TBD    I51 @BASEBOARD_FAB2_LIB.BASEBOARD_FAB2(SCH_1):PAGE71
  U2D1 BN84 VCCIN<127> SKX_EXT_B_BGA1-IC,TBD    I51 @BASEBOARD_FAB2_LIB.BASEBOARD_FAB2(SCH_1):PAGE71
  U2D1 BN82 VCCIN<128> SKX_EXT_B_BGA1-IC,TBD    I51 @BASEBOARD_FAB2_LIB.BASEBOARD_FAB2(SCH_1):PAGE71
  U2D1 BN80 VCCIN<129> SKX_EXT_B_BGA1-IC,TBD    I51 @BASEBOARD_FAB2_LIB.BASEBOARD_FAB2(SCH_1):PAGE71
 C2D12    1      A CAP_A_0603V-22.0UF,4V,20%,X6S,A    I59 @BASEBOARD_FAB2_LIB.BASEBOARD_FAB2(SCH_1):PAGE76
 C2D22    1      A CAP_A_0603V-22.0UF,4V,20%,X6S,A    I61 @BASEBOARD_FAB2_LIB.BASEBOARD_FAB2(SCH_1):PAGE76
 C2D31    1      A CAP_A_0603V-22.0UF,4V,20%,X6S,A    I63 @BASEBOARD_FAB2_LIB.BASEBOARD_FAB2(SCH_1):PAGE76
 C2D21    1      A CAP_A_0603V-22.0UF,4V,20%,X6S,A    I65 @BASEBOARD_FAB2_LIB.BASEBOARD_FAB2(SCH_1):PAGE76
 C2D27    1      A CAP_A_0603V-22.0UF,4V,20%,X6S,A    I66 @BASEBOARD_FAB2_LIB.BASEBOARD_FAB2(SCH_1):PAGE76
  C3D2    1      A CAP_A_0603V-22.0UF,4V,20%,X6S,A    I69 @BASEBOARD_FAB2_LIB.BASEBOARD_FAB2(SCH_1):PAGE76
 C2D36    1      A CAP_A_0603V-22.0UF,4V,20%,X6S,A    I70 @BASEBOARD_FAB2_LIB.BASEBOARD_FAB2(SCH_1):PAGE76
 C2D13    1      A CAP_A_0603V-22.0UF,4V,20%,X6S,A    I73 @BASEBOARD_FAB2_LIB.BASEBOARD_FAB2(SCH_1):PAGE76
 C2D19    1      A CAP_A_0603V-22.0UF,4V,20%,X6S,A    I75 @BASEBOARD_FAB2_LIB.BASEBOARD_FAB2(SCH_1):PAGE76
 C2D14    1      A CAP_A_0603V-22.0UF,4V,20%,X6S,A    I76 @BASEBOARD_FAB2_LIB.BASEBOARD_FAB2(SCH_1):PAGE76
 C2D20    1      A CAP_A_0603V-22.0UF,4V,20%,X6S,A    I79 @BASEBOARD_FAB2_LIB.BASEBOARD_FAB2(SCH_1):PAGE76
 C2D24    1      A CAP_A_0603V-22.0UF,4V,20%,X6S,A    I80 @BASEBOARD_FAB2_LIB.BASEBOARD_FAB2(SCH_1):PAGE76
 C2D25    1      A CAP_A_0603V-22.0UF,4V,20%,X6S,A    I82 @BASEBOARD_FAB2_LIB.BASEBOARD_FAB2(SCH_1):PAGE76
 C2D30    1      A CAP_A_0603V-22.0UF,4V,20%,X6S,A    I83 @BASEBOARD_FAB2_LIB.BASEBOARD_FAB2(SCH_1):PAGE76
 C2D33    1      A CAP_A_0603V-22.0UF,4V,20%,X6S,A    I85 @BASEBOARD_FAB2_LIB.BASEBOARD_FAB2(SCH_1):PAGE76
 C8P20    1      A CAP_0805-47UF,4V,20%,X6S,C9533A    I89 @BASEBOARD_FAB2_LIB.BASEBOARD_FAB2(SCH_1):PAGE76
 C2D32    1      A CAP_A_0603V-22.0UF,4V,20%,X6S,A    I90 @BASEBOARD_FAB2_LIB.BASEBOARD_FAB2(SCH_1):PAGE76
 C8P18    1      A CAP_0805-47UF,4V,20%,X6S,C9533A    I92 @BASEBOARD_FAB2_LIB.BASEBOARD_FAB2(SCH_1):PAGE76
 C8P19    1      A CAP_0805-47UF,4V,20%,X6S,C9533A   I103 @BASEBOARD_FAB2_LIB.BASEBOARD_FAB2(SCH_1):PAGE76
 C8P12    1      A CAP_0805-47UF,4V,20%,X6S,C9533A   I107 @BASEBOARD_FAB2_LIB.BASEBOARD_FAB2(SCH_1):PAGE76
 C2D26    1      A CAP_A_0603V-22.0UF,4V,20%,X6S,A   I108 @BASEBOARD_FAB2_LIB.BASEBOARD_FAB2(SCH_1):PAGE76
 C2D23    1      A CAP_A_0603V-22.0UF,4V,20%,X6S,A   I112 @BASEBOARD_FAB2_LIB.BASEBOARD_FAB2(SCH_1):PAGE76
 C2D17    1      A CAP_A_0603V-22.0UF,4V,20%,X6S,A   I114 @BASEBOARD_FAB2_LIB.BASEBOARD_FAB2(SCH_1):PAGE76
 C8P26    1      A CAP_0805-47UF,4V,20%,X6S,C9533A   I118 @BASEBOARD_FAB2_LIB.BASEBOARD_FAB2(SCH_1):PAGE76
 C2D37    1      A CAP_A_0603V-22.0UF,4V,20%,X6S,A   I119 @BASEBOARD_FAB2_LIB.BASEBOARD_FAB2(SCH_1):PAGE76
 C2D34    1      A CAP_A_0603V-22.0UF,4V,20%,X6S,A   I122 @BASEBOARD_FAB2_LIB.BASEBOARD_FAB2(SCH_1):PAGE76
 C2D16    1      A CAP_A_0603V-22.0UF,4V,20%,X6S,A   I124 @BASEBOARD_FAB2_LIB.BASEBOARD_FAB2(SCH_1):PAGE76
 C8P29    1      A CAP_0805-47UF,4V,20%,X6S,C9533A   I125 @BASEBOARD_FAB2_LIB.BASEBOARD_FAB2(SCH_1):PAGE76
 C8P10    1      A CAP_0805-47UF,4V,20%,X6S,C9533A   I127 @BASEBOARD_FAB2_LIB.BASEBOARD_FAB2(SCH_1):PAGE76
 C8P16    1      A CAP_0805-47UF,4V,20%,X6S,C9533A   I129 @BASEBOARD_FAB2_LIB.BASEBOARD_FAB2(SCH_1):PAGE76
 C8P13    1      A CAP_0805-47UF,4V,20%,X6S,C9533A   I132 @BASEBOARD_FAB2_LIB.BASEBOARD_FAB2(SCH_1):PAGE76
 C8P28    1      A CAP_0805-47UF,4V,20%,X6S,C9533A   I137 @BASEBOARD_FAB2_LIB.BASEBOARD_FAB2(SCH_1):PAGE76
 C8P11    1      A CAP_0805-47UF,4V,20%,X6S,C9533A   I139 @BASEBOARD_FAB2_LIB.BASEBOARD_FAB2(SCH_1):PAGE76
 C2D15    1      A CAP_A_0603V-22.0UF,4V,20%,X6S,A   I159 @BASEBOARD_FAB2_LIB.BASEBOARD_FAB2(SCH_1):PAGE76
 C2D38    1      A CAP_A_0603V-22.0UF,4V,20%,X6S,A   I160 @BASEBOARD_FAB2_LIB.BASEBOARD_FAB2(SCH_1):PAGE76
 C2D35    1      A CAP_A_0603V-22.0UF,4V,20%,X6S,A   I161 @BASEBOARD_FAB2_LIB.BASEBOARD_FAB2(SCH_1):PAGE76
 C7P19    1      A CAP_0805-47UF,4V,20%,X6S,C9533A   I215 @BASEBOARD_FAB2_LIB.BASEBOARD_FAB2(SCH_1):PAGE76
 C8P24    1      A CAP_0805-47UF,4V,20%,X6S,C9533A   I217 @BASEBOARD_FAB2_LIB.BASEBOARD_FAB2(SCH_1):PAGE76
  C9R8    1      A CAP_A_0603V-22.0UF,4V,20%,X6S,A     I8 @BASEBOARD_FAB2_LIB.BASEBOARD_FAB2(SCH_1):PAGE207
  C1E3    1      A CAP_A_0603V-22.0UF,4V,20%,X6S,A    I18 @BASEBOARD_FAB2_LIB.BASEBOARD_FAB2(SCH_1):PAGE207
 EU1E2    1    VOS IR354XX_SM-IR35411,IC,H73688-0A    I20 @BASEBOARD_FAB2_LIB.BASEBOARD_FAB2(SCH_1):PAGE207
  C1E9    1      A CAP_A_0603V-22.0UF,4V,20%,X6S,A    I58 @BASEBOARD_FAB2_LIB.BASEBOARD_FAB2(SCH_1):PAGE207
  C9P3    1      A CAP_A_0603V-22.0UF,4V,20%,X6S,A    I59 @BASEBOARD_FAB2_LIB.BASEBOARD_FAB2(SCH_1):PAGE207
  R1E3    1      A RES_0603-100.0,1%,1/10W,CHIP,GA     I7 @BASEBOARD_FAB2_LIB.BASEBOARD_FAB2(SCH_1):PAGE208
 C1D14    1      A CAP_A_0603V-22.0UF,4V,20%,X6S,A     I9 @BASEBOARD_FAB2_LIB.BASEBOARD_FAB2(SCH_1):PAGE208
  C9P8    1      A CAPP_3018-470UF,2.5V,20%,ALUM,A    I12 @BASEBOARD_FAB2_LIB.BASEBOARD_FAB2(SCH_1):PAGE208
  C9P5    1      A CAPP_3018-470UF,2.5V,20%,ALUM,A    I14 @BASEBOARD_FAB2_LIB.BASEBOARD_FAB2(SCH_1):PAGE208
  C1D3    1      A CAP_A_0603V-22.0UF,4V,20%,X6S,A    I22 @BASEBOARD_FAB2_LIB.BASEBOARD_FAB2(SCH_1):PAGE208
 C9N24    1      A CAPP_3018-470UF,2.5V,20%,ALUM,A    I24 @BASEBOARD_FAB2_LIB.BASEBOARD_FAB2(SCH_1):PAGE208
  C9R9    1      A CAPP_3018-470UF,2.5V,20%,ALUM,A    I25 @BASEBOARD_FAB2_LIB.BASEBOARD_FAB2(SCH_1):PAGE208
  C9R3    1      A CAPP_3018-470UF,2.5V,20%,ALUM,A    I26 @BASEBOARD_FAB2_LIB.BASEBOARD_FAB2(SCH_1):PAGE208
 EU1D3    1    VOS IR354XX_SM-IR35411,IC,H73688-0A    I27 @BASEBOARD_FAB2_LIB.BASEBOARD_FAB2(SCH_1):PAGE208
 C9P23    1      A CAPP_3018-470UF,2.5V,20%,ALUM,A    I28 @BASEBOARD_FAB2_LIB.BASEBOARD_FAB2(SCH_1):PAGE208
 C9P18    1      A CAPP_3018-470UF,2.5V,20%,ALUM,A    I30 @BASEBOARD_FAB2_LIB.BASEBOARD_FAB2(SCH_1):PAGE208
 C9P10    1      A CAP_A_0603V-22.0UF,4V,20%,X6S,A    I66 @BASEBOARD_FAB2_LIB.BASEBOARD_FAB2(SCH_1):PAGE208
  C9R2    1      A CAP_A_0603V-22.0UF,4V,20%,X6S,A    I67 @BASEBOARD_FAB2_LIB.BASEBOARD_FAB2(SCH_1):PAGE208
 EU1D1    1    VOS IR354XX_SM-IR35411,IC,H73688-0A    I71 @BASEBOARD_FAB2_LIB.BASEBOARD_FAB2(SCH_1):PAGE208
  R1E4    2      B RES_0402-100.0,1%,1/16W,CHIP,GA    I15 @BASEBOARD_FAB2_LIB.BASEBOARD_FAB2(SCH_1):PAGE209
 C1D24    1      A CAP_A_0603V-22.0UF,4V,20%,X6S,A    I42 @BASEBOARD_FAB2_LIB.BASEBOARD_FAB2(SCH_1):PAGE209
 C9P20    1      A CAP_A_0603V-22.0UF,4V,20%,X6S,A    I55 @BASEBOARD_FAB2_LIB.BASEBOARD_FAB2(SCH_1):PAGE209
 EU1C3    1    VOS IR354XX_SM-IR35411,IC,H73688-0A    I56 @BASEBOARD_FAB2_LIB.BASEBOARD_FAB2(SCH_1):PAGE209
  L1E1    2      F IND-120NH-30-GP_DISCRET-GB2-INA   I107 @BASEBOARD_FAB2_LIB.BASEBOARD_FAB2(SCH_1):PAGE207
  L1D3    2      F IND-120NH-30-GP_DISCRET-GB2-INA   I108 @BASEBOARD_FAB2_LIB.BASEBOARD_FAB2(SCH_1):PAGE207
  L1D2    2      F IND-120NH-30-GP_DISCRET-GB2-INA   I116 @BASEBOARD_FAB2_LIB.BASEBOARD_FAB2(SCH_1):PAGE208
  L1D1    2      F IND-120NH-30-GP_DISCRET-GB2-INA   I117 @BASEBOARD_FAB2_LIB.BASEBOARD_FAB2(SCH_1):PAGE208
  L1C2    2      F IND-120NH-30-GP_DISCRET-GB2-INA    I80 @BASEBOARD_FAB2_LIB.BASEBOARD_FAB2(SCH_1):PAGE209
  C8W4    1      A CAP_0805-100UF,4V,20%,X5R,6024A   I245 @BASEBOARD_FAB2_LIB.BASEBOARD_FAB2(SCH_1):PAGE76
 C8P21    1      A CAP_0805-47UF,4V,20%,X6S,C9533A   I249 @BASEBOARD_FAB2_LIB.BASEBOARD_FAB2(SCH_1):PAGE76
 C8P27    1      A CAP_0805-47UF,4V,20%,X6S,C9533A   I250 @BASEBOARD_FAB2_LIB.BASEBOARD_FAB2(SCH_1):PAGE76
 C8P25    1      A CAP_0805-47UF,4V,20%,X6S,C9533A   I251 @BASEBOARD_FAB2_LIB.BASEBOARD_FAB2(SCH_1):PAGE76
 C8P17    1      A CAP_0805-47UF,4V,20%,X6S,C9533A   I252 @BASEBOARD_FAB2_LIB.BASEBOARD_FAB2(SCH_1):PAGE76
 EU1D4    1    VOS IR354XX_SM-IR35411,IC,H73688-0A   I113 @BASEBOARD_FAB2_LIB.BASEBOARD_FAB2(SCH_1):PAGE207

PVCCIOMCP_CPU0 @BASEBOARD_FAB2_LIB.BASEBOARD_FAB2(SCH_1):PVCCIOMCP_CPU0
  U5D1 BU18 RSVD<129> SKX_EXT_B_BGA1-IC,TBD    I15 @BASEBOARD_FAB2_LIB.BASEBOARD_FAB2(SCH_1):PAGE36
  U5D1 BP17 RSVD<133> SKX_EXT_B_BGA1-IC,TBD    I15 @BASEBOARD_FAB2_LIB.BASEBOARD_FAB2(SCH_1):PAGE36
  U5D1 BN18 RSVD<134> SKX_EXT_B_BGA1-IC,TBD    I15 @BASEBOARD_FAB2_LIB.BASEBOARD_FAB2(SCH_1):PAGE36
  U5D1 BM17 RSVD<136> SKX_EXT_B_BGA1-IC,TBD    I15 @BASEBOARD_FAB2_LIB.BASEBOARD_FAB2(SCH_1):PAGE36
  U5D1 BL18 RSVD<138> SKX_EXT_B_BGA1-IC,TBD    I15 @BASEBOARD_FAB2_LIB.BASEBOARD_FAB2(SCH_1):PAGE36
  U5D1 BV15 CD_VCCP<0> SKX_EXT_B_BGA1-IC,TBD    I34 @BASEBOARD_FAB2_LIB.BASEBOARD_FAB2(SCH_1):PAGE38
  U5D1 BV13 CD_VCCP<1> SKX_EXT_B_BGA1-IC,TBD    I34 @BASEBOARD_FAB2_LIB.BASEBOARD_FAB2(SCH_1):PAGE38
  U5D1 BV11 CD_VCCP<2> SKX_EXT_B_BGA1-IC,TBD    I34 @BASEBOARD_FAB2_LIB.BASEBOARD_FAB2(SCH_1):PAGE38
  U5D1 BU14 CD_VCCP<3> SKX_EXT_B_BGA1-IC,TBD    I34 @BASEBOARD_FAB2_LIB.BASEBOARD_FAB2(SCH_1):PAGE38
  U5D1 BU12 CD_VCCP<4> SKX_EXT_B_BGA1-IC,TBD    I34 @BASEBOARD_FAB2_LIB.BASEBOARD_FAB2(SCH_1):PAGE38
  U5D1 BT15 CD_VCCP<5> SKX_EXT_B_BGA1-IC,TBD    I34 @BASEBOARD_FAB2_LIB.BASEBOARD_FAB2(SCH_1):PAGE38
  U5D1 BT13 CD_VCCP<6> SKX_EXT_B_BGA1-IC,TBD    I34 @BASEBOARD_FAB2_LIB.BASEBOARD_FAB2(SCH_1):PAGE38
  U5D1 BT11 CD_VCCP<7> SKX_EXT_B_BGA1-IC,TBD    I34 @BASEBOARD_FAB2_LIB.BASEBOARD_FAB2(SCH_1):PAGE38
  U5D1 BR14 CD_VCCP<8> SKX_EXT_B_BGA1-IC,TBD    I34 @BASEBOARD_FAB2_LIB.BASEBOARD_FAB2(SCH_1):PAGE38
  U5D1 BR12 CD_VCCP<9> SKX_EXT_B_BGA1-IC,TBD    I34 @BASEBOARD_FAB2_LIB.BASEBOARD_FAB2(SCH_1):PAGE38
  U5D1 BP15 CD_VCCP<10> SKX_EXT_B_BGA1-IC,TBD    I34 @BASEBOARD_FAB2_LIB.BASEBOARD_FAB2(SCH_1):PAGE38
  U5D1 BP13 CD_VCCP<11> SKX_EXT_B_BGA1-IC,TBD    I34 @BASEBOARD_FAB2_LIB.BASEBOARD_FAB2(SCH_1):PAGE38
  U5D1 BP11 CD_VCCP<12> SKX_EXT_B_BGA1-IC,TBD    I34 @BASEBOARD_FAB2_LIB.BASEBOARD_FAB2(SCH_1):PAGE38
  U5D1 BN14 CD_VCCP<13> SKX_EXT_B_BGA1-IC,TBD    I34 @BASEBOARD_FAB2_LIB.BASEBOARD_FAB2(SCH_1):PAGE38
  U5D1 BN12 CD_VCCP<14> SKX_EXT_B_BGA1-IC,TBD    I34 @BASEBOARD_FAB2_LIB.BASEBOARD_FAB2(SCH_1):PAGE38
  U5D1 BM11 CD_VCCP<15> SKX_EXT_B_BGA1-IC,TBD    I34 @BASEBOARD_FAB2_LIB.BASEBOARD_FAB2(SCH_1):PAGE38
  J6B1  C17  IOC17 SCONN120_H61426002_SM-CONN,H61A    I56 @BASEBOARD_FAB2_LIB.BASEBOARD_FAB2(SCH_1):PAGE194
  J6B1  C18  IOC18 SCONN120_H61426002_SM-CONN,H61A    I56 @BASEBOARD_FAB2_LIB.BASEBOARD_FAB2(SCH_1):PAGE194
  J6B1  C19  IOC19 SCONN120_H61426002_SM-CONN,H61A    I56 @BASEBOARD_FAB2_LIB.BASEBOARD_FAB2(SCH_1):PAGE194
  J6B1  D17  IOD17 SCONN120_H61426002_SM-CONN,H61A    I56 @BASEBOARD_FAB2_LIB.BASEBOARD_FAB2(SCH_1):PAGE194
  J6B1  D18  IOD18 SCONN120_H61426002_SM-CONN,H61A    I56 @BASEBOARD_FAB2_LIB.BASEBOARD_FAB2(SCH_1):PAGE194
  J6B1  D19  IOD19 SCONN120_H61426002_SM-CONN,H61A    I56 @BASEBOARD_FAB2_LIB.BASEBOARD_FAB2(SCH_1):PAGE194
  J6B1  E15  IOE15 SCONN120_H61426002_SM-CONN,H61A    I56 @BASEBOARD_FAB2_LIB.BASEBOARD_FAB2(SCH_1):PAGE194
  J6B1  E16  IOE16 SCONN120_H61426002_SM-CONN,H61A    I56 @BASEBOARD_FAB2_LIB.BASEBOARD_FAB2(SCH_1):PAGE194
  J6B1  E17  IOE17 SCONN120_H61426002_SM-CONN,H61A    I56 @BASEBOARD_FAB2_LIB.BASEBOARD_FAB2(SCH_1):PAGE194
  J6B1  E18  IOE18 SCONN120_H61426002_SM-CONN,H61A    I56 @BASEBOARD_FAB2_LIB.BASEBOARD_FAB2(SCH_1):PAGE194
  J6B1  E19  IOE19 SCONN120_H61426002_SM-CONN,H61A    I56 @BASEBOARD_FAB2_LIB.BASEBOARD_FAB2(SCH_1):PAGE194
  J6B1  F15  IOF15 SCONN120_H61426002_SM-CONN,H61A    I56 @BASEBOARD_FAB2_LIB.BASEBOARD_FAB2(SCH_1):PAGE194
  J6B1  F16  IOF16 SCONN120_H61426002_SM-CONN,H61A    I56 @BASEBOARD_FAB2_LIB.BASEBOARD_FAB2(SCH_1):PAGE194
  J6B1  F17  IOF17 SCONN120_H61426002_SM-CONN,H61A    I56 @BASEBOARD_FAB2_LIB.BASEBOARD_FAB2(SCH_1):PAGE194
  J6B1  F18  IOF18 SCONN120_H61426002_SM-CONN,H61A    I56 @BASEBOARD_FAB2_LIB.BASEBOARD_FAB2(SCH_1):PAGE194
  J6B1  F19  IOF19 SCONN120_H61426002_SM-CONN,H61A    I56 @BASEBOARD_FAB2_LIB.BASEBOARD_FAB2(SCH_1):PAGE194
 C3N40    1      A CAP_A_0402V-1.0UF,6.3V,10%,X6SA    I86 @BASEBOARD_FAB2_LIB.BASEBOARD_FAB2(SCH_1):PAGE194
 C3M46    1      A CAP_A_0402V-1.0UF,6.3V,10%,X6SA    I99 @BASEBOARD_FAB2_LIB.BASEBOARD_FAB2(SCH_1):PAGE194
 C3N14    1      A CAPP_3018-470UF,2.5V,20%,ALUM,A   I101 @BASEBOARD_FAB2_LIB.BASEBOARD_FAB2(SCH_1):PAGE194

PVCCIOMCP_CPU1 @BASEBOARD_FAB2_LIB.BASEBOARD_FAB2(SCH_1):PVCCIOMCP_CPU1
  U2D1 BU18 RSVD<129> SKX_EXT_B_BGA1-IC,TBD     I9 @BASEBOARD_FAB2_LIB.BASEBOARD_FAB2(SCH_1):PAGE70
  U2D1 BP17 RSVD<133> SKX_EXT_B_BGA1-IC,TBD     I9 @BASEBOARD_FAB2_LIB.BASEBOARD_FAB2(SCH_1):PAGE70
  U2D1 BN18 RSVD<134> SKX_EXT_B_BGA1-IC,TBD     I9 @BASEBOARD_FAB2_LIB.BASEBOARD_FAB2(SCH_1):PAGE70
  U2D1 BM17 RSVD<136> SKX_EXT_B_BGA1-IC,TBD     I9 @BASEBOARD_FAB2_LIB.BASEBOARD_FAB2(SCH_1):PAGE70
  U2D1 BL18 RSVD<138> SKX_EXT_B_BGA1-IC,TBD     I9 @BASEBOARD_FAB2_LIB.BASEBOARD_FAB2(SCH_1):PAGE70
  U2D1 BV15 CD_VCCP<0> SKX_EXT_B_BGA1-IC,TBD    I33 @BASEBOARD_FAB2_LIB.BASEBOARD_FAB2(SCH_1):PAGE72
  U2D1 BV13 CD_VCCP<1> SKX_EXT_B_BGA1-IC,TBD    I33 @BASEBOARD_FAB2_LIB.BASEBOARD_FAB2(SCH_1):PAGE72
  U2D1 BV11 CD_VCCP<2> SKX_EXT_B_BGA1-IC,TBD    I33 @BASEBOARD_FAB2_LIB.BASEBOARD_FAB2(SCH_1):PAGE72
  U2D1 BU14 CD_VCCP<3> SKX_EXT_B_BGA1-IC,TBD    I33 @BASEBOARD_FAB2_LIB.BASEBOARD_FAB2(SCH_1):PAGE72
  U2D1 BU12 CD_VCCP<4> SKX_EXT_B_BGA1-IC,TBD    I33 @BASEBOARD_FAB2_LIB.BASEBOARD_FAB2(SCH_1):PAGE72
  U2D1 BT15 CD_VCCP<5> SKX_EXT_B_BGA1-IC,TBD    I33 @BASEBOARD_FAB2_LIB.BASEBOARD_FAB2(SCH_1):PAGE72
  U2D1 BT13 CD_VCCP<6> SKX_EXT_B_BGA1-IC,TBD    I33 @BASEBOARD_FAB2_LIB.BASEBOARD_FAB2(SCH_1):PAGE72
  U2D1 BT11 CD_VCCP<7> SKX_EXT_B_BGA1-IC,TBD    I33 @BASEBOARD_FAB2_LIB.BASEBOARD_FAB2(SCH_1):PAGE72
  U2D1 BR14 CD_VCCP<8> SKX_EXT_B_BGA1-IC,TBD    I33 @BASEBOARD_FAB2_LIB.BASEBOARD_FAB2(SCH_1):PAGE72
  U2D1 BR12 CD_VCCP<9> SKX_EXT_B_BGA1-IC,TBD    I33 @BASEBOARD_FAB2_LIB.BASEBOARD_FAB2(SCH_1):PAGE72
  U2D1 BP15 CD_VCCP<10> SKX_EXT_B_BGA1-IC,TBD    I33 @BASEBOARD_FAB2_LIB.BASEBOARD_FAB2(SCH_1):PAGE72
  U2D1 BP13 CD_VCCP<11> SKX_EXT_B_BGA1-IC,TBD    I33 @BASEBOARD_FAB2_LIB.BASEBOARD_FAB2(SCH_1):PAGE72
  U2D1 BP11 CD_VCCP<12> SKX_EXT_B_BGA1-IC,TBD    I33 @BASEBOARD_FAB2_LIB.BASEBOARD_FAB2(SCH_1):PAGE72
  U2D1 BN14 CD_VCCP<13> SKX_EXT_B_BGA1-IC,TBD    I33 @BASEBOARD_FAB2_LIB.BASEBOARD_FAB2(SCH_1):PAGE72
  U2D1 BN12 CD_VCCP<14> SKX_EXT_B_BGA1-IC,TBD    I33 @BASEBOARD_FAB2_LIB.BASEBOARD_FAB2(SCH_1):PAGE72
  U2D1 BM11 CD_VCCP<15> SKX_EXT_B_BGA1-IC,TBD    I33 @BASEBOARD_FAB2_LIB.BASEBOARD_FAB2(SCH_1):PAGE72
  C4C1    1      A CAPP_3018-470UF,2.5V,20%,ALUM,A    I29 @BASEBOARD_FAB2_LIB.BASEBOARD_FAB2(SCH_1):PAGE193
  C3C2    1      A CAP_A_0402V-1.0UF,6.3V,10%,X6SA    I31 @BASEBOARD_FAB2_LIB.BASEBOARD_FAB2(SCH_1):PAGE193
  C3C1    1      A CAP_A_0402V-1.0UF,6.3V,10%,X6SA    I38 @BASEBOARD_FAB2_LIB.BASEBOARD_FAB2(SCH_1):PAGE193
  J4B2  C17  IOC17 SCONN120_H61426002_SM-CONN,H61A    I46 @BASEBOARD_FAB2_LIB.BASEBOARD_FAB2(SCH_1):PAGE193
  J4B2  C18  IOC18 SCONN120_H61426002_SM-CONN,H61A    I46 @BASEBOARD_FAB2_LIB.BASEBOARD_FAB2(SCH_1):PAGE193
  J4B2  C19  IOC19 SCONN120_H61426002_SM-CONN,H61A    I46 @BASEBOARD_FAB2_LIB.BASEBOARD_FAB2(SCH_1):PAGE193
  J4B2  D17  IOD17 SCONN120_H61426002_SM-CONN,H61A    I46 @BASEBOARD_FAB2_LIB.BASEBOARD_FAB2(SCH_1):PAGE193
  J4B2  D18  IOD18 SCONN120_H61426002_SM-CONN,H61A    I46 @BASEBOARD_FAB2_LIB.BASEBOARD_FAB2(SCH_1):PAGE193
  J4B2  D19  IOD19 SCONN120_H61426002_SM-CONN,H61A    I46 @BASEBOARD_FAB2_LIB.BASEBOARD_FAB2(SCH_1):PAGE193
  J4B2  E15  IOE15 SCONN120_H61426002_SM-CONN,H61A    I46 @BASEBOARD_FAB2_LIB.BASEBOARD_FAB2(SCH_1):PAGE193
  J4B2  E16  IOE16 SCONN120_H61426002_SM-CONN,H61A    I46 @BASEBOARD_FAB2_LIB.BASEBOARD_FAB2(SCH_1):PAGE193
  J4B2  E17  IOE17 SCONN120_H61426002_SM-CONN,H61A    I46 @BASEBOARD_FAB2_LIB.BASEBOARD_FAB2(SCH_1):PAGE193
  J4B2  E18  IOE18 SCONN120_H61426002_SM-CONN,H61A    I46 @BASEBOARD_FAB2_LIB.BASEBOARD_FAB2(SCH_1):PAGE193
  J4B2  E19  IOE19 SCONN120_H61426002_SM-CONN,H61A    I46 @BASEBOARD_FAB2_LIB.BASEBOARD_FAB2(SCH_1):PAGE193
  J4B2  F15  IOF15 SCONN120_H61426002_SM-CONN,H61A    I46 @BASEBOARD_FAB2_LIB.BASEBOARD_FAB2(SCH_1):PAGE193
  J4B2  F16  IOF16 SCONN120_H61426002_SM-CONN,H61A    I46 @BASEBOARD_FAB2_LIB.BASEBOARD_FAB2(SCH_1):PAGE193
  J4B2  F17  IOF17 SCONN120_H61426002_SM-CONN,H61A    I46 @BASEBOARD_FAB2_LIB.BASEBOARD_FAB2(SCH_1):PAGE193
  J4B2  F18  IOF18 SCONN120_H61426002_SM-CONN,H61A    I46 @BASEBOARD_FAB2_LIB.BASEBOARD_FAB2(SCH_1):PAGE193
  J4B2  F19  IOF19 SCONN120_H61426002_SM-CONN,H61A    I46 @BASEBOARD_FAB2_LIB.BASEBOARD_FAB2(SCH_1):PAGE193

PVCCIO_CPU0 @BASEBOARD_FAB2_LIB.BASEBOARD_FAB2(SCH_1):PVCCIO_CPU0
  R6B2    1      A RES_0402-100.0,1%,1/16W,CHIP,GA   I159 @BASEBOARD_FAB2_LIB.BASEBOARD_FAB2(SCH_1):PAGE21
  R6B1    1      A RES_0402-49.9,1%,1/16W,CHIP,G2A   I161 @BASEBOARD_FAB2_LIB.BASEBOARD_FAB2(SCH_1):PAGE21
  R6N2    2      B RES_0402-100.0,1%,1/16W,CHIP,GA   I163 @BASEBOARD_FAB2_LIB.BASEBOARD_FAB2(SCH_1):PAGE21
  R6N1    2      B RES_0402-49.9,1%,1/16W,CHIP,G2A   I164 @BASEBOARD_FAB2_LIB.BASEBOARD_FAB2(SCH_1):PAGE21
  R5D6    1      A RES_0402-10.0,1%,1/16W,EMPTY,GA   I312 @BASEBOARD_FAB2_LIB.BASEBOARD_FAB2(SCH_1):PAGE37
  U5D1 CM15 VCCIO<20> SKX_EXT_B_BGA1-IC,TBD    I34 @BASEBOARD_FAB2_LIB.BASEBOARD_FAB2(SCH_1):PAGE38
  U5D1 CL12 VCCIO<21> SKX_EXT_B_BGA1-IC,TBD    I34 @BASEBOARD_FAB2_LIB.BASEBOARD_FAB2(SCH_1):PAGE38
  U5D1  CK5 VCCIO<22> SKX_EXT_B_BGA1-IC,TBD    I34 @BASEBOARD_FAB2_LIB.BASEBOARD_FAB2(SCH_1):PAGE38
  U5D1  CV7 VCCIO<23> SKX_EXT_B_BGA1-IC,TBD    I34 @BASEBOARD_FAB2_LIB.BASEBOARD_FAB2(SCH_1):PAGE38
  U5D1  CH9 VCCIO<24> SKX_EXT_B_BGA1-IC,TBD    I34 @BASEBOARD_FAB2_LIB.BASEBOARD_FAB2(SCH_1):PAGE38
  U5D1   D7 VCCIO<25> SKX_EXT_B_BGA1-IC,TBD    I34 @BASEBOARD_FAB2_LIB.BASEBOARD_FAB2(SCH_1):PAGE38
  U5D1 CE18 VCCIO<26> SKX_EXT_B_BGA1-IC,TBD    I34 @BASEBOARD_FAB2_LIB.BASEBOARD_FAB2(SCH_1):PAGE38
  U5D1  CD9 VCCIO<27> SKX_EXT_B_BGA1-IC,TBD    I34 @BASEBOARD_FAB2_LIB.BASEBOARD_FAB2(SCH_1):PAGE38
  U5D1 CB17 VCCIO<28> SKX_EXT_B_BGA1-IC,TBD    I34 @BASEBOARD_FAB2_LIB.BASEBOARD_FAB2(SCH_1):PAGE38
  U5D1 CB13 VCCIO<29> SKX_EXT_B_BGA1-IC,TBD    I34 @BASEBOARD_FAB2_LIB.BASEBOARD_FAB2(SCH_1):PAGE38
  U5D1 BP25 VCCIO<30> SKX_EXT_B_BGA1-IC,TBD    I34 @BASEBOARD_FAB2_LIB.BASEBOARD_FAB2(SCH_1):PAGE38
  U5D1 BJ24 VCCIO<31> SKX_EXT_B_BGA1-IC,TBD    I34 @BASEBOARD_FAB2_LIB.BASEBOARD_FAB2(SCH_1):PAGE38
  U5D1 BF23 VCCIO<32> SKX_EXT_B_BGA1-IC,TBD    I34 @BASEBOARD_FAB2_LIB.BASEBOARD_FAB2(SCH_1):PAGE38
  U5D1 DA14 VCCIO<33> SKX_EXT_B_BGA1-IC,TBD    I34 @BASEBOARD_FAB2_LIB.BASEBOARD_FAB2(SCH_1):PAGE38
  U5D1  BB5 VCCIO<34> SKX_EXT_B_BGA1-IC,TBD    I34 @BASEBOARD_FAB2_LIB.BASEBOARD_FAB2(SCH_1):PAGE38
  U5D1 BA24 VCCIO<35> SKX_EXT_B_BGA1-IC,TBD    I34 @BASEBOARD_FAB2_LIB.BASEBOARD_FAB2(SCH_1):PAGE38
  U5D1 AY11 VCCIO<36> SKX_EXT_B_BGA1-IC,TBD    I34 @BASEBOARD_FAB2_LIB.BASEBOARD_FAB2(SCH_1):PAGE38
  U5D1  AW6 VCCIO<37> SKX_EXT_B_BGA1-IC,TBD    I34 @BASEBOARD_FAB2_LIB.BASEBOARD_FAB2(SCH_1):PAGE38
  U5D1 AT11 VCCIO<38> SKX_EXT_B_BGA1-IC,TBD    I34 @BASEBOARD_FAB2_LIB.BASEBOARD_FAB2(SCH_1):PAGE38
  U5D1  DD7 VCCIO<39> SKX_EXT_B_BGA1-IC,TBD    I34 @BASEBOARD_FAB2_LIB.BASEBOARD_FAB2(SCH_1):PAGE38
  U5D1 AN10 VCCIO<40> SKX_EXT_B_BGA1-IC,TBD    I34 @BASEBOARD_FAB2_LIB.BASEBOARD_FAB2(SCH_1):PAGE38
  U5D1 DF13 VCCIO<41> SKX_EXT_B_BGA1-IC,TBD    I34 @BASEBOARD_FAB2_LIB.BASEBOARD_FAB2(SCH_1):PAGE38
  U5D1  AH9 VCCIO<42> SKX_EXT_B_BGA1-IC,TBD    I34 @BASEBOARD_FAB2_LIB.BASEBOARD_FAB2(SCH_1):PAGE38
  U5D1  AC4 VCCIO<43> SKX_EXT_B_BGA1-IC,TBD    I34 @BASEBOARD_FAB2_LIB.BASEBOARD_FAB2(SCH_1):PAGE38
  U5D1 AC20 VCCIO<44> SKX_EXT_B_BGA1-IC,TBD    I34 @BASEBOARD_FAB2_LIB.BASEBOARD_FAB2(SCH_1):PAGE38
  U5D1 AA10 VCCIO<45> SKX_EXT_B_BGA1-IC,TBD    I34 @BASEBOARD_FAB2_LIB.BASEBOARD_FAB2(SCH_1):PAGE38
  U5D1   W6 VCCIO<46> SKX_EXT_B_BGA1-IC,TBD    I34 @BASEBOARD_FAB2_LIB.BASEBOARD_FAB2(SCH_1):PAGE38
  U5D1   W4 VCCIO<47> SKX_EXT_B_BGA1-IC,TBD    I34 @BASEBOARD_FAB2_LIB.BASEBOARD_FAB2(SCH_1):PAGE38
  U5D1 DF21 VCCIO<48> SKX_EXT_B_BGA1-IC,TBD    I34 @BASEBOARD_FAB2_LIB.BASEBOARD_FAB2(SCH_1):PAGE38
  U5D1  U14 VCCIO<49> SKX_EXT_B_BGA1-IC,TBD    I34 @BASEBOARD_FAB2_LIB.BASEBOARD_FAB2(SCH_1):PAGE38
  U5D1   T3 VCCIO<50> SKX_EXT_B_BGA1-IC,TBD    I34 @BASEBOARD_FAB2_LIB.BASEBOARD_FAB2(SCH_1):PAGE38
  U5D1   P5 VCCIO<51> SKX_EXT_B_BGA1-IC,TBD    I34 @BASEBOARD_FAB2_LIB.BASEBOARD_FAB2(SCH_1):PAGE38
  U5D1  M21 VCCIO<52> SKX_EXT_B_BGA1-IC,TBD    I34 @BASEBOARD_FAB2_LIB.BASEBOARD_FAB2(SCH_1):PAGE38
  U5D1  M11 VCCIO<53> SKX_EXT_B_BGA1-IC,TBD    I34 @BASEBOARD_FAB2_LIB.BASEBOARD_FAB2(SCH_1):PAGE38
  U5D1  DG8 VCCIO<54> SKX_EXT_B_BGA1-IC,TBD    I34 @BASEBOARD_FAB2_LIB.BASEBOARD_FAB2(SCH_1):PAGE38
  U5D1  DH7 VCCIO<55> SKX_EXT_B_BGA1-IC,TBD    I34 @BASEBOARD_FAB2_LIB.BASEBOARD_FAB2(SCH_1):PAGE38
  U5D1  L16 VCCIO<56> SKX_EXT_B_BGA1-IC,TBD    I34 @BASEBOARD_FAB2_LIB.BASEBOARD_FAB2(SCH_1):PAGE38
  U5D1  L14 VCCIO<57> SKX_EXT_B_BGA1-IC,TBD    I34 @BASEBOARD_FAB2_LIB.BASEBOARD_FAB2(SCH_1):PAGE38
  U5D1  J10 VCCIO<58> SKX_EXT_B_BGA1-IC,TBD    I34 @BASEBOARD_FAB2_LIB.BASEBOARD_FAB2(SCH_1):PAGE38
  U5D1  H13 VCCIO<59> SKX_EXT_B_BGA1-IC,TBD    I34 @BASEBOARD_FAB2_LIB.BASEBOARD_FAB2(SCH_1):PAGE38
  U5D1 DJ16 VCCIO<60> SKX_EXT_B_BGA1-IC,TBD    I34 @BASEBOARD_FAB2_LIB.BASEBOARD_FAB2(SCH_1):PAGE38
  U5D1 DM17 VCCIO<61> SKX_EXT_B_BGA1-IC,TBD    I34 @BASEBOARD_FAB2_LIB.BASEBOARD_FAB2(SCH_1):PAGE38
  U5D1  DN8 VCCIO<62> SKX_EXT_B_BGA1-IC,TBD    I34 @BASEBOARD_FAB2_LIB.BASEBOARD_FAB2(SCH_1):PAGE38
  U5D1 DP19 VCCIO<63> SKX_EXT_B_BGA1-IC,TBD    I34 @BASEBOARD_FAB2_LIB.BASEBOARD_FAB2(SCH_1):PAGE38
  U5D1 DR10 VCCIO<64> SKX_EXT_B_BGA1-IC,TBD    I34 @BASEBOARD_FAB2_LIB.BASEBOARD_FAB2(SCH_1):PAGE38
  U5D1  DR2 VCCIO<65> SKX_EXT_B_BGA1-IC,TBD    I34 @BASEBOARD_FAB2_LIB.BASEBOARD_FAB2(SCH_1):PAGE38
  U5D1 DU20 VCCIO<66> SKX_EXT_B_BGA1-IC,TBD    I34 @BASEBOARD_FAB2_LIB.BASEBOARD_FAB2(SCH_1):PAGE38
  U5D1 EA12 VCCIO<67> SKX_EXT_B_BGA1-IC,TBD    I34 @BASEBOARD_FAB2_LIB.BASEBOARD_FAB2(SCH_1):PAGE38
  U5D1 EB15 VCCIO<68> SKX_EXT_B_BGA1-IC,TBD    I34 @BASEBOARD_FAB2_LIB.BASEBOARD_FAB2(SCH_1):PAGE38
  U5D1   J2 VCCIO<69> SKX_EXT_B_BGA1-IC,TBD    I34 @BASEBOARD_FAB2_LIB.BASEBOARD_FAB2(SCH_1):PAGE38
  U5D1  K15 VCCIO<70> SKX_EXT_B_BGA1-IC,TBD    I34 @BASEBOARD_FAB2_LIB.BASEBOARD_FAB2(SCH_1):PAGE38
  U5D1   M7 VCCIO<71> SKX_EXT_B_BGA1-IC,TBD    I34 @BASEBOARD_FAB2_LIB.BASEBOARD_FAB2(SCH_1):PAGE38
  U5D1   M9 VCCIO<72> SKX_EXT_B_BGA1-IC,TBD    I34 @BASEBOARD_FAB2_LIB.BASEBOARD_FAB2(SCH_1):PAGE38
  U5D1  N18 VCCIO<73> SKX_EXT_B_BGA1-IC,TBD    I34 @BASEBOARD_FAB2_LIB.BASEBOARD_FAB2(SCH_1):PAGE38
  U5D1  W10 VCCIO<74> SKX_EXT_B_BGA1-IC,TBD    I34 @BASEBOARD_FAB2_LIB.BASEBOARD_FAB2(SCH_1):PAGE38
  U5D1 BC26 VCCIO<75> SKX_EXT_B_BGA1-IC,TBD    I34 @BASEBOARD_FAB2_LIB.BASEBOARD_FAB2(SCH_1):PAGE38
  U5D1 BB27 VCCIO<76> SKX_EXT_B_BGA1-IC,TBD    I34 @BASEBOARD_FAB2_LIB.BASEBOARD_FAB2(SCH_1):PAGE38
  U5D1 BA26 VCCIO<77> SKX_EXT_B_BGA1-IC,TBD    I34 @BASEBOARD_FAB2_LIB.BASEBOARD_FAB2(SCH_1):PAGE38
  U5D1 AY27 VCCIO<78> SKX_EXT_B_BGA1-IC,TBD    I34 @BASEBOARD_FAB2_LIB.BASEBOARD_FAB2(SCH_1):PAGE38
  U5D1 AW26 VCCIO<79> SKX_EXT_B_BGA1-IC,TBD    I34 @BASEBOARD_FAB2_LIB.BASEBOARD_FAB2(SCH_1):PAGE38
  U5D1 AV27 VCCIO<80> SKX_EXT_B_BGA1-IC,TBD    I34 @BASEBOARD_FAB2_LIB.BASEBOARD_FAB2(SCH_1):PAGE38
  U5D1 CF27 VCCIO<81> SKX_EXT_B_BGA1-IC,TBD    I34 @BASEBOARD_FAB2_LIB.BASEBOARD_FAB2(SCH_1):PAGE38
  U5D1 CD27 VCCIO<82> SKX_EXT_B_BGA1-IC,TBD    I34 @BASEBOARD_FAB2_LIB.BASEBOARD_FAB2(SCH_1):PAGE38
  U5D1 CC26 VCCIO<83> SKX_EXT_B_BGA1-IC,TBD    I34 @BASEBOARD_FAB2_LIB.BASEBOARD_FAB2(SCH_1):PAGE38
  U5D1 CJ28 VCCIO<84> SKX_EXT_B_BGA1-IC,TBD    I34 @BASEBOARD_FAB2_LIB.BASEBOARD_FAB2(SCH_1):PAGE38
  U5D1 CH27 VCCIO<85> SKX_EXT_B_BGA1-IC,TBD    I34 @BASEBOARD_FAB2_LIB.BASEBOARD_FAB2(SCH_1):PAGE38
  U5D1 BM27 VCCIO<86> SKX_EXT_B_BGA1-IC,TBD    I34 @BASEBOARD_FAB2_LIB.BASEBOARD_FAB2(SCH_1):PAGE38
  U5D1 BL26 VCCIO<87> SKX_EXT_B_BGA1-IC,TBD    I34 @BASEBOARD_FAB2_LIB.BASEBOARD_FAB2(SCH_1):PAGE38
  U5D1 BK27 VCCIO<88> SKX_EXT_B_BGA1-IC,TBD    I34 @BASEBOARD_FAB2_LIB.BASEBOARD_FAB2(SCH_1):PAGE38
  U5D1 BK25 VCCIO<89> SKX_EXT_B_BGA1-IC,TBD    I34 @BASEBOARD_FAB2_LIB.BASEBOARD_FAB2(SCH_1):PAGE38
  U5D1 BJ26 VCCIO<90> SKX_EXT_B_BGA1-IC,TBD    I34 @BASEBOARD_FAB2_LIB.BASEBOARD_FAB2(SCH_1):PAGE38
  U5D1 BH27 VCCIO<91> SKX_EXT_B_BGA1-IC,TBD    I34 @BASEBOARD_FAB2_LIB.BASEBOARD_FAB2(SCH_1):PAGE38
  U5D1 BH25 VCCIO<92> SKX_EXT_B_BGA1-IC,TBD    I34 @BASEBOARD_FAB2_LIB.BASEBOARD_FAB2(SCH_1):PAGE38
  U5D1 BG26 VCCIO<93> SKX_EXT_B_BGA1-IC,TBD    I34 @BASEBOARD_FAB2_LIB.BASEBOARD_FAB2(SCH_1):PAGE38
  U5D1 BF27 VCCIO<94> SKX_EXT_B_BGA1-IC,TBD    I34 @BASEBOARD_FAB2_LIB.BASEBOARD_FAB2(SCH_1):PAGE38
  U5D1 AE36 VCCIO<95> SKX_EXT_B_BGA1-IC,TBD    I34 @BASEBOARD_FAB2_LIB.BASEBOARD_FAB2(SCH_1):PAGE38
  U5D1 AD37 VCCIO<96> SKX_EXT_B_BGA1-IC,TBD    I34 @BASEBOARD_FAB2_LIB.BASEBOARD_FAB2(SCH_1):PAGE38
  U5D1 AC36 VCCIO<97> SKX_EXT_B_BGA1-IC,TBD    I34 @BASEBOARD_FAB2_LIB.BASEBOARD_FAB2(SCH_1):PAGE38
  U5D1 AF35 VCCIO<98> SKX_EXT_B_BGA1-IC,TBD    I34 @BASEBOARD_FAB2_LIB.BASEBOARD_FAB2(SCH_1):PAGE38
  U5D1 AD35 VCCIO<99> SKX_EXT_B_BGA1-IC,TBD    I34 @BASEBOARD_FAB2_LIB.BASEBOARD_FAB2(SCH_1):PAGE38
  U5D1 AE34 VCCIO<100> SKX_EXT_B_BGA1-IC,TBD    I34 @BASEBOARD_FAB2_LIB.BASEBOARD_FAB2(SCH_1):PAGE38
  U5D1 AG34 VCCIO<101> SKX_EXT_B_BGA1-IC,TBD    I34 @BASEBOARD_FAB2_LIB.BASEBOARD_FAB2(SCH_1):PAGE38
  U5D1 AM29 VCCIO<102> SKX_EXT_B_BGA1-IC,TBD    I34 @BASEBOARD_FAB2_LIB.BASEBOARD_FAB2(SCH_1):PAGE38
  U5D1 AL28 VCCIO<103> SKX_EXT_B_BGA1-IC,TBD    I34 @BASEBOARD_FAB2_LIB.BASEBOARD_FAB2(SCH_1):PAGE38
  U5D1 AR28 VCCIO<104> SKX_EXT_B_BGA1-IC,TBD    I34 @BASEBOARD_FAB2_LIB.BASEBOARD_FAB2(SCH_1):PAGE38
  U5D1 EE10 VCCIO<0> SKX_EXT_B_BGA1-IC,TBD   I127 @BASEBOARD_FAB2_LIB.BASEBOARD_FAB2(SCH_1):PAGE39
  U5D1 AE10 VCCIO<1> SKX_EXT_B_BGA1-IC,TBD   I127 @BASEBOARD_FAB2_LIB.BASEBOARD_FAB2(SCH_1):PAGE39
  U5D1  AF5 VCCIO<2> SKX_EXT_B_BGA1-IC,TBD   I127 @BASEBOARD_FAB2_LIB.BASEBOARD_FAB2(SCH_1):PAGE39
  U5D1 DV11 VCCIO<3> SKX_EXT_B_BGA1-IC,TBD   I127 @BASEBOARD_FAB2_LIB.BASEBOARD_FAB2(SCH_1):PAGE39
  U5D1  AM5 VCCIO<4> SKX_EXT_B_BGA1-IC,TBD   I127 @BASEBOARD_FAB2_LIB.BASEBOARD_FAB2(SCH_1):PAGE39
  U5D1  AT5 VCCIO<5> SKX_EXT_B_BGA1-IC,TBD   I127 @BASEBOARD_FAB2_LIB.BASEBOARD_FAB2(SCH_1):PAGE39
  U5D1  AT7 VCCIO<6> SKX_EXT_B_BGA1-IC,TBD   I127 @BASEBOARD_FAB2_LIB.BASEBOARD_FAB2(SCH_1):PAGE39
  U5D1 BE24 VCCIO<7> SKX_EXT_B_BGA1-IC,TBD   I127 @BASEBOARD_FAB2_LIB.BASEBOARD_FAB2(SCH_1):PAGE39
  U5D1 DK21 VCCIO<8> SKX_EXT_B_BGA1-IC,TBD   I127 @BASEBOARD_FAB2_LIB.BASEBOARD_FAB2(SCH_1):PAGE39
  U5D1  CF5 VCCIO<9> SKX_EXT_B_BGA1-IC,TBD   I127 @BASEBOARD_FAB2_LIB.BASEBOARD_FAB2(SCH_1):PAGE39
  U5D1 CG14 VCCIO<10> SKX_EXT_B_BGA1-IC,TBD   I127 @BASEBOARD_FAB2_LIB.BASEBOARD_FAB2(SCH_1):PAGE39
  U5D1 CL20 VCCIO<11> SKX_EXT_B_BGA1-IC,TBD   I127 @BASEBOARD_FAB2_LIB.BASEBOARD_FAB2(SCH_1):PAGE39
  U5D1 CP13 VCCIO<12> SKX_EXT_B_BGA1-IC,TBD   I127 @BASEBOARD_FAB2_LIB.BASEBOARD_FAB2(SCH_1):PAGE39
  U5D1 DE14 VCCIO<13> SKX_EXT_B_BGA1-IC,TBD   I127 @BASEBOARD_FAB2_LIB.BASEBOARD_FAB2(SCH_1):PAGE39
  U5D1 DC18 VCCIO<14> SKX_EXT_B_BGA1-IC,TBD   I127 @BASEBOARD_FAB2_LIB.BASEBOARD_FAB2(SCH_1):PAGE39
  U5D1 CY17 VCCIO<15> SKX_EXT_B_BGA1-IC,TBD   I127 @BASEBOARD_FAB2_LIB.BASEBOARD_FAB2(SCH_1):PAGE39
  U5D1 CU18 VCCIO<16> SKX_EXT_B_BGA1-IC,TBD   I127 @BASEBOARD_FAB2_LIB.BASEBOARD_FAB2(SCH_1):PAGE39
  U5D1 CV21 VCCIO<17> SKX_EXT_B_BGA1-IC,TBD   I127 @BASEBOARD_FAB2_LIB.BASEBOARD_FAB2(SCH_1):PAGE39
  U5D1 CU12 VCCIO<18> SKX_EXT_B_BGA1-IC,TBD   I127 @BASEBOARD_FAB2_LIB.BASEBOARD_FAB2(SCH_1):PAGE39
  U5D1  CN6 VCCIO<19> SKX_EXT_B_BGA1-IC,TBD   I127 @BASEBOARD_FAB2_LIB.BASEBOARD_FAB2(SCH_1):PAGE39
  C4P1    1      A CAP_0805-47UF,4V,20%,X6S,C9533A    I10 @BASEBOARD_FAB2_LIB.BASEBOARD_FAB2(SCH_1):PAGE42
  C4P9    1      A CAP_0805-47UF,4V,20%,X6S,C9533A    I12 @BASEBOARD_FAB2_LIB.BASEBOARD_FAB2(SCH_1):PAGE42
 C4P10    1      A CAP_0805-47UF,4V,20%,X6S,C9533A    I17 @BASEBOARD_FAB2_LIB.BASEBOARD_FAB2(SCH_1):PAGE42
  C6D7    1      A CAP_A_0603V-22.0UF,4V,20%,X6S,A    I72 @BASEBOARD_FAB2_LIB.BASEBOARD_FAB2(SCH_1):PAGE42
  C6D4    1      A CAP_A_0603V-22.0UF,4V,20%,X6S,A    I74 @BASEBOARD_FAB2_LIB.BASEBOARD_FAB2(SCH_1):PAGE42
  C6D3    1      A CAP_A_0603V-22.0UF,4V,20%,X6S,A    I80 @BASEBOARD_FAB2_LIB.BASEBOARD_FAB2(SCH_1):PAGE42
  C6D6    1      A CAP_A_0603V-22.0UF,4V,20%,X6S,A    I81 @BASEBOARD_FAB2_LIB.BASEBOARD_FAB2(SCH_1):PAGE42
  C6D9    1      A CAP_A_0603V-22.0UF,4V,20%,X6S,A   I145 @BASEBOARD_FAB2_LIB.BASEBOARD_FAB2(SCH_1):PAGE42
 C6D10    1      A CAP_A_0603V-22.0UF,4V,20%,X6S,A   I147 @BASEBOARD_FAB2_LIB.BASEBOARD_FAB2(SCH_1):PAGE42
  C4P6    1      A CAP_A_0603V-22.0UF,4V,20%,X6S,A   I164 @BASEBOARD_FAB2_LIB.BASEBOARD_FAB2(SCH_1):PAGE42
  C4P8    1      A CAP_A_0603V-22.0UF,4V,20%,X6S,A   I178 @BASEBOARD_FAB2_LIB.BASEBOARD_FAB2(SCH_1):PAGE42
  R5D3    1      A RES_0402-240,1.0%,1/16W,CHIP,GA    I29 @BASEBOARD_FAB2_LIB.BASEBOARD_FAB2(SCH_1):PAGE90
  R6D7    1      A RES_0402-240,1.0%,1/16W,EMPTY,A    I31 @BASEBOARD_FAB2_LIB.BASEBOARD_FAB2(SCH_1):PAGE90
 R6D13    1      A RES_0402-240,1.0%,1/16W,EMPTY,A    I33 @BASEBOARD_FAB2_LIB.BASEBOARD_FAB2(SCH_1):PAGE90
 R6D15    1      A RES_0402-240,1.0%,1/16W,EMPTY,A    I48 @BASEBOARD_FAB2_LIB.BASEBOARD_FAB2(SCH_1):PAGE90
 R6D10    1      A RES_0402-240,1.0%,1/16W,EMPTY,A    I49 @BASEBOARD_FAB2_LIB.BASEBOARD_FAB2(SCH_1):PAGE90
 R4P14    1      A RES_0402-240,1.0%,1/16W,CHIP,GA    I53 @BASEBOARD_FAB2_LIB.BASEBOARD_FAB2(SCH_1):PAGE90
  R7E2    1      A RES_0402-75,1.0%,1/16W,CHIP,G2A    I19 @BASEBOARD_FAB2_LIB.BASEBOARD_FAB2(SCH_1):PAGE92
  R6D9    1      A RES_0402-150.0,1%,1/16W,CHIP,GA    I64 @BASEBOARD_FAB2_LIB.BASEBOARD_FAB2(SCH_1):PAGE92
 R7P27    1      A RES_0402-150.0,1%,1/16W,CHIP,GA    I65 @BASEBOARD_FAB2_LIB.BASEBOARD_FAB2(SCH_1):PAGE92
 R2T37    1      A RES_0402-200.0,1%,1/16W,CHIP,GA    I94 @BASEBOARD_FAB2_LIB.BASEBOARD_FAB2(SCH_1):PAGE92
 R7P18    1      A RES_0402-150.0,1%,1/16W,CHIP,GA   I100 @BASEBOARD_FAB2_LIB.BASEBOARD_FAB2(SCH_1):PAGE92
  R4R2    1      A RES_0402-150.0,1%,1/16W,CHIP,GA   I101 @BASEBOARD_FAB2_LIB.BASEBOARD_FAB2(SCH_1):PAGE92
 R2T19    1      A RES_0402-200.0,1%,1/16W,CHIP,GA    I63 @BASEBOARD_FAB2_LIB.BASEBOARD_FAB2(SCH_1):PAGE93
  R4R3    1      A RES_0402-150.0,1%,1/16W,CHIP,GA    I79 @BASEBOARD_FAB2_LIB.BASEBOARD_FAB2(SCH_1):PAGE93
 R2T26    1      A RES_0402-200.0,1%,1/16W,CHIP,GA    I87 @BASEBOARD_FAB2_LIB.BASEBOARD_FAB2(SCH_1):PAGE93
 R2T72    1      A RES_0402-150.0,1%,1/16W,CHIP,GA   I143 @BASEBOARD_FAB2_LIB.BASEBOARD_FAB2(SCH_1):PAGE93
 R6D12    1      A RES_0402-49.9,1%,1/16W,CHIP,G2A     I2 @BASEBOARD_FAB2_LIB.BASEBOARD_FAB2(SCH_1):PAGE96
  R6D8    1      A RES_0402-49.9,1%,1/16W,CHIP,G2A     I3 @BASEBOARD_FAB2_LIB.BASEBOARD_FAB2(SCH_1):PAGE96
  R4R4    1      A RES_0402-150.0,1%,1/16W,CHIP,GA    I42 @BASEBOARD_FAB2_LIB.BASEBOARD_FAB2(SCH_1):PAGE97
 R7P20    1      A RES_0402-150.0,1%,1/16W,CHIP,GA    I44 @BASEBOARD_FAB2_LIB.BASEBOARD_FAB2(SCH_1):PAGE97
 R4P21    1      A RES_0402-240,1.0%,1/16W,CHIP,GA    I72 @BASEBOARD_FAB2_LIB.BASEBOARD_FAB2(SCH_1):PAGE97
  C6F2    1      A CAP_A_0402V-0.1UF,16V,10%,X7R,A     I2 @BASEBOARD_FAB2_LIB.BASEBOARD_FAB2(SCH_1):PAGE99
  U6F1    1   VCCA PCA9617_SSOP-IC,G81764-001-GNDA    I15 @BASEBOARD_FAB2_LIB.BASEBOARD_FAB2(SCH_1):PAGE99
  R4T6    1      A RES_0402-240,1.0%,1/16W,CHIP,GA    I17 @BASEBOARD_FAB2_LIB.BASEBOARD_FAB2(SCH_1):PAGE99
  R4T5    1      A RES_0402-240,1.0%,1/16W,CHIP,GA    I19 @BASEBOARD_FAB2_LIB.BASEBOARD_FAB2(SCH_1):PAGE99
  C7E1    1      A CAP_A_0402V-0.1UF,16V,10%,X7R,A    I23 @BASEBOARD_FAB2_LIB.BASEBOARD_FAB2(SCH_1):PAGE99
  U7E1    1   VCCA PCA9617_SSOP-IC,G81764-001-GNDA    I61 @BASEBOARD_FAB2_LIB.BASEBOARD_FAB2(SCH_1):PAGE99
 R3R13    1      A RES_0402-240,1.0%,1/16W,CHIP,GA    I65 @BASEBOARD_FAB2_LIB.BASEBOARD_FAB2(SCH_1):PAGE99
 R3P60    1      A RES_0402-240,1.0%,1/16W,CHIP,GA    I67 @BASEBOARD_FAB2_LIB.BASEBOARD_FAB2(SCH_1):PAGE99
  R9A4    2      B RES_0402-475.0,1%,1/16W,CHIP,GA    I55 @BASEBOARD_FAB2_LIB.BASEBOARD_FAB2(SCH_1):PAGE111
 R1L17    2      B RES_0402-150.0,1%,1/16W,CHIP,GA    I56 @BASEBOARD_FAB2_LIB.BASEBOARD_FAB2(SCH_1):PAGE111
 R6P46    1      A RES_0402-100.0,1%,1/16W,CHIP,GA    I49 @BASEBOARD_FAB2_LIB.BASEBOARD_FAB2(SCH_1):PAGE112
 R7P30    1      A RES_0402-100.0,1%,1/16W,CHIP,GA    I50 @BASEBOARD_FAB2_LIB.BASEBOARD_FAB2(SCH_1):PAGE112
  R1M3    1      A RES_0402-100.0,1%,1/16W,CHIP,GA    I51 @BASEBOARD_FAB2_LIB.BASEBOARD_FAB2(SCH_1):PAGE112
 R4P15    1      A RES_0402-100.0,1%,1/16W,CHIP,GA    I53 @BASEBOARD_FAB2_LIB.BASEBOARD_FAB2(SCH_1):PAGE112
  R1M4    1      A RES_0402-100.0,1%,1/16W,CHIP,GA    I54 @BASEBOARD_FAB2_LIB.BASEBOARD_FAB2(SCH_1):PAGE112
 R4P12    1      A RES_0402-100.0,1%,1/16W,CHIP,GA    I57 @BASEBOARD_FAB2_LIB.BASEBOARD_FAB2(SCH_1):PAGE112
 R4P23    1      A RES_0402-150.0,1%,1/16W,CHIP,GA    I58 @BASEBOARD_FAB2_LIB.BASEBOARD_FAB2(SCH_1):PAGE112
 R4P24    1      A RES_0402-150.0,1%,1/16W,CHIP,GA    I59 @BASEBOARD_FAB2_LIB.BASEBOARD_FAB2(SCH_1):PAGE112
 R1L15    1      A RES_0402-150.0,1%,1/16W,CHIP,GA    I60 @BASEBOARD_FAB2_LIB.BASEBOARD_FAB2(SCH_1):PAGE112
  R6T9    1      A RES_0402-100.0,1%,1/16W,CHIP,GA   I120 @BASEBOARD_FAB2_LIB.BASEBOARD_FAB2(SCH_1):PAGE112
  R6T8    1      A RES_0402-100.0,1%,1/16W,CHIP,GA   I121 @BASEBOARD_FAB2_LIB.BASEBOARD_FAB2(SCH_1):PAGE112
 R2U40    1      A RES_0402-150.0,1%,1/16W,CHIP,GA    I53 @BASEBOARD_FAB2_LIB.BASEBOARD_FAB2(SCH_1):PAGE152
 R2U41    1      A RES_0402-150.0,1%,1/16W,CHIP,GA    I54 @BASEBOARD_FAB2_LIB.BASEBOARD_FAB2(SCH_1):PAGE152
 R4P17    2      B RES_0402-150.0,1%,1/16W,CHIP,GA    I58 @BASEBOARD_FAB2_LIB.BASEBOARD_FAB2(SCH_1):PAGE152
 R4P20    2      B RES_0402-150.0,1%,1/16W,CHIP,GA    I59 @BASEBOARD_FAB2_LIB.BASEBOARD_FAB2(SCH_1):PAGE152
 R7C17    1      A RES_0402-4.75K,1%,1/16W,CHIP,GA    I28 @BASEBOARD_FAB2_LIB.BASEBOARD_FAB2(SCH_1):PAGE166
  J6B1   F1   IOF1 SCONN120_H61426002_SM-CONN,H61A    I56 @BASEBOARD_FAB2_LIB.BASEBOARD_FAB2(SCH_1):PAGE194
 R6P16    1      A RES_0402-1.00K,1%,1/16W,CHIP,GA   I132 @BASEBOARD_FAB2_LIB.BASEBOARD_FAB2(SCH_1):PAGE201
 C3N35    1      A CAPP_3018-470UF,2.5V,20%,ALUM,A    I18 @BASEBOARD_FAB2_LIB.BASEBOARD_FAB2(SCH_1):PAGE212
  C7C6    1      A CAP_A_0603V-22.0UF,4V,20%,X6S,A    I23 @BASEBOARD_FAB2_LIB.BASEBOARD_FAB2(SCH_1):PAGE212
 R3N21    2      B RES_0402-100.0,1%,1/16W,CHIP,GA    I74 @BASEBOARD_FAB2_LIB.BASEBOARD_FAB2(SCH_1):PAGE212
 C7C10    1      A CAP_A_0603V-22.0UF,4V,20%,X6S,A    I77 @BASEBOARD_FAB2_LIB.BASEBOARD_FAB2(SCH_1):PAGE212
  R7C3    1      A RES_0402-51.1,1.0%,1/16W,CHIP,A    I78 @BASEBOARD_FAB2_LIB.BASEBOARD_FAB2(SCH_1):PAGE212
 EU7C1    1    VOS IR354XX_SM-IR35412,IC,H73684-0A   I101 @BASEBOARD_FAB2_LIB.BASEBOARD_FAB2(SCH_1):PAGE212
 C1T21    1      A CAP_A_0402V-1.0UF,6.3V,10%,X6SA    I20 @BASEBOARD_FAB2_LIB.BASEBOARD_FAB2(SCH_1):PAGE148
 R9W19    1      A RES_0402-240,1.0%,1/16W,CHIP,GA    I26 @BASEBOARD_FAB2_LIB.BASEBOARD_FAB2(SCH_1):PAGE248
 R9W18    1      A RES_0402-240,1.0%,1/16W,CHIP,GA    I27 @BASEBOARD_FAB2_LIB.BASEBOARD_FAB2(SCH_1):PAGE248
  C9W8    1      A CAP_A_0402V-0.1UF,16V,10%,X7R,A    I30 @BASEBOARD_FAB2_LIB.BASEBOARD_FAB2(SCH_1):PAGE248
  U1W2    1   VCCA TCA9517DGKR-GP_DISCRET-G8-TCA9A    I49 @BASEBOARD_FAB2_LIB.BASEBOARD_FAB2(SCH_1):PAGE248
  R5D4    1      A RES_0402-240,1.0%,1/16W,CHIP,GA    I96 @BASEBOARD_FAB2_LIB.BASEBOARD_FAB2(SCH_1):PAGE90
  L7C2    2      F IND-150NH-56-GP_DISCRET-GA1-INA   I141 @BASEBOARD_FAB2_LIB.BASEBOARD_FAB2(SCH_1):PAGE212
  R3U2    1      A RES_0402-100.0,1%,1/16W,CHIP,GA    I58 @BASEBOARD_FAB2_LIB.BASEBOARD_FAB2(SCH_1):PAGE215
 R3L11    1      A RES_0402-100.0,1%,1/16W,EMPTY,A    I67 @BASEBOARD_FAB2_LIB.BASEBOARD_FAB2(SCH_1):PAGE218
R25W155    1      A RES_0402-0.0,5%,1/16W,CHIP,G21A    I29 @BASEBOARD_FAB2_LIB.BASEBOARD_FAB2(SCH_1):PAGE148
  R4E9    1      A RES_0402-49.9,1%,1/16W,EMPTY,GA   I189 @BASEBOARD_FAB2_LIB.BASEBOARD_FAB2(SCH_1):PAGE201
 R4E10    1      A RES_0402-100.0,1%,1/16W,EMPTY,A   I190 @BASEBOARD_FAB2_LIB.BASEBOARD_FAB2(SCH_1):PAGE201
 R3P17    1      A RES_0402-49.9,1%,1/16W,CHIP,G2A    I99 @BASEBOARD_FAB2_LIB.BASEBOARD_FAB2(SCH_1):PAGE211
 R3P13    1      A RES_0402-100.0,1%,1/16W,CHIP,GA   I100 @BASEBOARD_FAB2_LIB.BASEBOARD_FAB2(SCH_1):PAGE211
 R3T11    1      A RES_0402-49.9,1%,1/16W,CHIP,G2A    I70 @BASEBOARD_FAB2_LIB.BASEBOARD_FAB2(SCH_1):PAGE215
 R3L13    1      A RES_0402-49.9,1%,1/16W,EMPTY,GA    I70 @BASEBOARD_FAB2_LIB.BASEBOARD_FAB2(SCH_1):PAGE218
  R7W4    1      A RES_0402-49.9,1%,1/16W,EMPTY,GA   I106 @BASEBOARD_FAB2_LIB.BASEBOARD_FAB2(SCH_1):PAGE92
 R3W10    1      A RES_0402-49.9,1%,1/16W,EMPTY,GA   I108 @BASEBOARD_FAB2_LIB.BASEBOARD_FAB2(SCH_1):PAGE92
  R2W2    1      A RES_0402-49.9,1%,1/16W,EMPTY,GA   I147 @BASEBOARD_FAB2_LIB.BASEBOARD_FAB2(SCH_1):PAGE93
 R1W35    1      A RES_0402-49.9,1%,1/16W,EMPTY,GA   I105 @BASEBOARD_FAB2_LIB.BASEBOARD_FAB2(SCH_1):PAGE152
 C3N26    1      A CAPP_3018-470UF,2.5V,20%,ALUM,A   I145 @BASEBOARD_FAB2_LIB.BASEBOARD_FAB2(SCH_1):PAGE212
 C3N38    1      A CAPP_3018-470UF,2.5V,20%,ALUM,A   I146 @BASEBOARD_FAB2_LIB.BASEBOARD_FAB2(SCH_1):PAGE212

PVCCIO_CPU0_R @BASEBOARD_FAB2_LIB.BASEBOARD_FAB2(SCH_1):PVCCIO_CPU0_R
 U25W4 AA17 PECIVDD AST2520A1-GP-GP_ASIC2-GB1-AST2A    I28 @BASEBOARD_FAB2_LIB.BASEBOARD_FAB2(SCH_1):PAGE148
R25W155    2      B RES_0402-0.0,5%,1/16W,CHIP,G21A    I29 @BASEBOARD_FAB2_LIB.BASEBOARD_FAB2(SCH_1):PAGE148

PVCCIO_CPU1 @BASEBOARD_FAB2_LIB.BASEBOARD_FAB2(SCH_1):PVCCIO_CPU1
  R9N1    1      A RES_0402-49.9,1%,1/16W,CHIP,G2A     I4 @BASEBOARD_FAB2_LIB.BASEBOARD_FAB2(SCH_1):PAGE55
  R9N2    1      A RES_0402-100.0,1%,1/16W,CHIP,GA     I7 @BASEBOARD_FAB2_LIB.BASEBOARD_FAB2(SCH_1):PAGE55
  R3B2    2      B RES_0402-49.9,1%,1/16W,CHIP,G2A    I19 @BASEBOARD_FAB2_LIB.BASEBOARD_FAB2(SCH_1):PAGE55
  R3B4    2      B RES_0402-100.0,1%,1/16W,CHIP,GA    I21 @BASEBOARD_FAB2_LIB.BASEBOARD_FAB2(SCH_1):PAGE55
 R3D32    1      A RES_0402-10.0,1%,1/16W,EMPTY,GA    I53 @BASEBOARD_FAB2_LIB.BASEBOARD_FAB2(SCH_1):PAGE71
  U2D1 CM15 VCCIO<20> SKX_EXT_B_BGA1-IC,TBD    I33 @BASEBOARD_FAB2_LIB.BASEBOARD_FAB2(SCH_1):PAGE72
  U2D1 CL12 VCCIO<21> SKX_EXT_B_BGA1-IC,TBD    I33 @BASEBOARD_FAB2_LIB.BASEBOARD_FAB2(SCH_1):PAGE72
  U2D1  CK5 VCCIO<22> SKX_EXT_B_BGA1-IC,TBD    I33 @BASEBOARD_FAB2_LIB.BASEBOARD_FAB2(SCH_1):PAGE72
  U2D1  CV7 VCCIO<23> SKX_EXT_B_BGA1-IC,TBD    I33 @BASEBOARD_FAB2_LIB.BASEBOARD_FAB2(SCH_1):PAGE72
  U2D1  CH9 VCCIO<24> SKX_EXT_B_BGA1-IC,TBD    I33 @BASEBOARD_FAB2_LIB.BASEBOARD_FAB2(SCH_1):PAGE72
  U2D1   D7 VCCIO<25> SKX_EXT_B_BGA1-IC,TBD    I33 @BASEBOARD_FAB2_LIB.BASEBOARD_FAB2(SCH_1):PAGE72
  U2D1 CE18 VCCIO<26> SKX_EXT_B_BGA1-IC,TBD    I33 @BASEBOARD_FAB2_LIB.BASEBOARD_FAB2(SCH_1):PAGE72
  U2D1  CD9 VCCIO<27> SKX_EXT_B_BGA1-IC,TBD    I33 @BASEBOARD_FAB2_LIB.BASEBOARD_FAB2(SCH_1):PAGE72
  U2D1 CB17 VCCIO<28> SKX_EXT_B_BGA1-IC,TBD    I33 @BASEBOARD_FAB2_LIB.BASEBOARD_FAB2(SCH_1):PAGE72
  U2D1 CB13 VCCIO<29> SKX_EXT_B_BGA1-IC,TBD    I33 @BASEBOARD_FAB2_LIB.BASEBOARD_FAB2(SCH_1):PAGE72
  U2D1 BP25 VCCIO<30> SKX_EXT_B_BGA1-IC,TBD    I33 @BASEBOARD_FAB2_LIB.BASEBOARD_FAB2(SCH_1):PAGE72
  U2D1 BJ24 VCCIO<31> SKX_EXT_B_BGA1-IC,TBD    I33 @BASEBOARD_FAB2_LIB.BASEBOARD_FAB2(SCH_1):PAGE72
  U2D1 BF23 VCCIO<32> SKX_EXT_B_BGA1-IC,TBD    I33 @BASEBOARD_FAB2_LIB.BASEBOARD_FAB2(SCH_1):PAGE72
  U2D1 DA14 VCCIO<33> SKX_EXT_B_BGA1-IC,TBD    I33 @BASEBOARD_FAB2_LIB.BASEBOARD_FAB2(SCH_1):PAGE72
  U2D1  BB5 VCCIO<34> SKX_EXT_B_BGA1-IC,TBD    I33 @BASEBOARD_FAB2_LIB.BASEBOARD_FAB2(SCH_1):PAGE72
  U2D1 BA24 VCCIO<35> SKX_EXT_B_BGA1-IC,TBD    I33 @BASEBOARD_FAB2_LIB.BASEBOARD_FAB2(SCH_1):PAGE72
  U2D1 AY11 VCCIO<36> SKX_EXT_B_BGA1-IC,TBD    I33 @BASEBOARD_FAB2_LIB.BASEBOARD_FAB2(SCH_1):PAGE72
  U2D1  AW6 VCCIO<37> SKX_EXT_B_BGA1-IC,TBD    I33 @BASEBOARD_FAB2_LIB.BASEBOARD_FAB2(SCH_1):PAGE72
  U2D1 AT11 VCCIO<38> SKX_EXT_B_BGA1-IC,TBD    I33 @BASEBOARD_FAB2_LIB.BASEBOARD_FAB2(SCH_1):PAGE72
  U2D1  DD7 VCCIO<39> SKX_EXT_B_BGA1-IC,TBD    I33 @BASEBOARD_FAB2_LIB.BASEBOARD_FAB2(SCH_1):PAGE72
  U2D1 AN10 VCCIO<40> SKX_EXT_B_BGA1-IC,TBD    I33 @BASEBOARD_FAB2_LIB.BASEBOARD_FAB2(SCH_1):PAGE72
  U2D1 DF13 VCCIO<41> SKX_EXT_B_BGA1-IC,TBD    I33 @BASEBOARD_FAB2_LIB.BASEBOARD_FAB2(SCH_1):PAGE72
  U2D1  AH9 VCCIO<42> SKX_EXT_B_BGA1-IC,TBD    I33 @BASEBOARD_FAB2_LIB.BASEBOARD_FAB2(SCH_1):PAGE72
  U2D1  AC4 VCCIO<43> SKX_EXT_B_BGA1-IC,TBD    I33 @BASEBOARD_FAB2_LIB.BASEBOARD_FAB2(SCH_1):PAGE72
  U2D1 AC20 VCCIO<44> SKX_EXT_B_BGA1-IC,TBD    I33 @BASEBOARD_FAB2_LIB.BASEBOARD_FAB2(SCH_1):PAGE72
  U2D1 AA10 VCCIO<45> SKX_EXT_B_BGA1-IC,TBD    I33 @BASEBOARD_FAB2_LIB.BASEBOARD_FAB2(SCH_1):PAGE72
  U2D1   W6 VCCIO<46> SKX_EXT_B_BGA1-IC,TBD    I33 @BASEBOARD_FAB2_LIB.BASEBOARD_FAB2(SCH_1):PAGE72
  U2D1   W4 VCCIO<47> SKX_EXT_B_BGA1-IC,TBD    I33 @BASEBOARD_FAB2_LIB.BASEBOARD_FAB2(SCH_1):PAGE72
  U2D1 DF21 VCCIO<48> SKX_EXT_B_BGA1-IC,TBD    I33 @BASEBOARD_FAB2_LIB.BASEBOARD_FAB2(SCH_1):PAGE72
  U2D1  U14 VCCIO<49> SKX_EXT_B_BGA1-IC,TBD    I33 @BASEBOARD_FAB2_LIB.BASEBOARD_FAB2(SCH_1):PAGE72
  U2D1   T3 VCCIO<50> SKX_EXT_B_BGA1-IC,TBD    I33 @BASEBOARD_FAB2_LIB.BASEBOARD_FAB2(SCH_1):PAGE72
  U2D1   P5 VCCIO<51> SKX_EXT_B_BGA1-IC,TBD    I33 @BASEBOARD_FAB2_LIB.BASEBOARD_FAB2(SCH_1):PAGE72
  U2D1  M21 VCCIO<52> SKX_EXT_B_BGA1-IC,TBD    I33 @BASEBOARD_FAB2_LIB.BASEBOARD_FAB2(SCH_1):PAGE72
  U2D1  M11 VCCIO<53> SKX_EXT_B_BGA1-IC,TBD    I33 @BASEBOARD_FAB2_LIB.BASEBOARD_FAB2(SCH_1):PAGE72
  U2D1  DG8 VCCIO<54> SKX_EXT_B_BGA1-IC,TBD    I33 @BASEBOARD_FAB2_LIB.BASEBOARD_FAB2(SCH_1):PAGE72
  U2D1  DH7 VCCIO<55> SKX_EXT_B_BGA1-IC,TBD    I33 @BASEBOARD_FAB2_LIB.BASEBOARD_FAB2(SCH_1):PAGE72
  U2D1  L16 VCCIO<56> SKX_EXT_B_BGA1-IC,TBD    I33 @BASEBOARD_FAB2_LIB.BASEBOARD_FAB2(SCH_1):PAGE72
  U2D1  L14 VCCIO<57> SKX_EXT_B_BGA1-IC,TBD    I33 @BASEBOARD_FAB2_LIB.BASEBOARD_FAB2(SCH_1):PAGE72
  U2D1  J10 VCCIO<58> SKX_EXT_B_BGA1-IC,TBD    I33 @BASEBOARD_FAB2_LIB.BASEBOARD_FAB2(SCH_1):PAGE72
  U2D1  H13 VCCIO<59> SKX_EXT_B_BGA1-IC,TBD    I33 @BASEBOARD_FAB2_LIB.BASEBOARD_FAB2(SCH_1):PAGE72
  U2D1 DJ16 VCCIO<60> SKX_EXT_B_BGA1-IC,TBD    I33 @BASEBOARD_FAB2_LIB.BASEBOARD_FAB2(SCH_1):PAGE72
  U2D1 DM17 VCCIO<61> SKX_EXT_B_BGA1-IC,TBD    I33 @BASEBOARD_FAB2_LIB.BASEBOARD_FAB2(SCH_1):PAGE72
  U2D1  DN8 VCCIO<62> SKX_EXT_B_BGA1-IC,TBD    I33 @BASEBOARD_FAB2_LIB.BASEBOARD_FAB2(SCH_1):PAGE72
  U2D1 DP19 VCCIO<63> SKX_EXT_B_BGA1-IC,TBD    I33 @BASEBOARD_FAB2_LIB.BASEBOARD_FAB2(SCH_1):PAGE72
  U2D1 DR10 VCCIO<64> SKX_EXT_B_BGA1-IC,TBD    I33 @BASEBOARD_FAB2_LIB.BASEBOARD_FAB2(SCH_1):PAGE72
  U2D1  DR2 VCCIO<65> SKX_EXT_B_BGA1-IC,TBD    I33 @BASEBOARD_FAB2_LIB.BASEBOARD_FAB2(SCH_1):PAGE72
  U2D1 DU20 VCCIO<66> SKX_EXT_B_BGA1-IC,TBD    I33 @BASEBOARD_FAB2_LIB.BASEBOARD_FAB2(SCH_1):PAGE72
  U2D1 EA12 VCCIO<67> SKX_EXT_B_BGA1-IC,TBD    I33 @BASEBOARD_FAB2_LIB.BASEBOARD_FAB2(SCH_1):PAGE72
  U2D1 EB15 VCCIO<68> SKX_EXT_B_BGA1-IC,TBD    I33 @BASEBOARD_FAB2_LIB.BASEBOARD_FAB2(SCH_1):PAGE72
  U2D1   J2 VCCIO<69> SKX_EXT_B_BGA1-IC,TBD    I33 @BASEBOARD_FAB2_LIB.BASEBOARD_FAB2(SCH_1):PAGE72
  U2D1  K15 VCCIO<70> SKX_EXT_B_BGA1-IC,TBD    I33 @BASEBOARD_FAB2_LIB.BASEBOARD_FAB2(SCH_1):PAGE72
  U2D1   M7 VCCIO<71> SKX_EXT_B_BGA1-IC,TBD    I33 @BASEBOARD_FAB2_LIB.BASEBOARD_FAB2(SCH_1):PAGE72
  U2D1   M9 VCCIO<72> SKX_EXT_B_BGA1-IC,TBD    I33 @BASEBOARD_FAB2_LIB.BASEBOARD_FAB2(SCH_1):PAGE72
  U2D1  N18 VCCIO<73> SKX_EXT_B_BGA1-IC,TBD    I33 @BASEBOARD_FAB2_LIB.BASEBOARD_FAB2(SCH_1):PAGE72
  U2D1  W10 VCCIO<74> SKX_EXT_B_BGA1-IC,TBD    I33 @BASEBOARD_FAB2_LIB.BASEBOARD_FAB2(SCH_1):PAGE72
  U2D1 BC26 VCCIO<75> SKX_EXT_B_BGA1-IC,TBD    I33 @BASEBOARD_FAB2_LIB.BASEBOARD_FAB2(SCH_1):PAGE72
  U2D1 BB27 VCCIO<76> SKX_EXT_B_BGA1-IC,TBD    I33 @BASEBOARD_FAB2_LIB.BASEBOARD_FAB2(SCH_1):PAGE72
  U2D1 BA26 VCCIO<77> SKX_EXT_B_BGA1-IC,TBD    I33 @BASEBOARD_FAB2_LIB.BASEBOARD_FAB2(SCH_1):PAGE72
  U2D1 AY27 VCCIO<78> SKX_EXT_B_BGA1-IC,TBD    I33 @BASEBOARD_FAB2_LIB.BASEBOARD_FAB2(SCH_1):PAGE72
  U2D1 AW26 VCCIO<79> SKX_EXT_B_BGA1-IC,TBD    I33 @BASEBOARD_FAB2_LIB.BASEBOARD_FAB2(SCH_1):PAGE72
  U2D1 AV27 VCCIO<80> SKX_EXT_B_BGA1-IC,TBD    I33 @BASEBOARD_FAB2_LIB.BASEBOARD_FAB2(SCH_1):PAGE72
  U2D1 CF27 VCCIO<81> SKX_EXT_B_BGA1-IC,TBD    I33 @BASEBOARD_FAB2_LIB.BASEBOARD_FAB2(SCH_1):PAGE72
  U2D1 CD27 VCCIO<82> SKX_EXT_B_BGA1-IC,TBD    I33 @BASEBOARD_FAB2_LIB.BASEBOARD_FAB2(SCH_1):PAGE72
  U2D1 CC26 VCCIO<83> SKX_EXT_B_BGA1-IC,TBD    I33 @BASEBOARD_FAB2_LIB.BASEBOARD_FAB2(SCH_1):PAGE72
  U2D1 CJ28 VCCIO<84> SKX_EXT_B_BGA1-IC,TBD    I33 @BASEBOARD_FAB2_LIB.BASEBOARD_FAB2(SCH_1):PAGE72
  U2D1 CH27 VCCIO<85> SKX_EXT_B_BGA1-IC,TBD    I33 @BASEBOARD_FAB2_LIB.BASEBOARD_FAB2(SCH_1):PAGE72
  U2D1 BM27 VCCIO<86> SKX_EXT_B_BGA1-IC,TBD    I33 @BASEBOARD_FAB2_LIB.BASEBOARD_FAB2(SCH_1):PAGE72
  U2D1 BL26 VCCIO<87> SKX_EXT_B_BGA1-IC,TBD    I33 @BASEBOARD_FAB2_LIB.BASEBOARD_FAB2(SCH_1):PAGE72
  U2D1 BK27 VCCIO<88> SKX_EXT_B_BGA1-IC,TBD    I33 @BASEBOARD_FAB2_LIB.BASEBOARD_FAB2(SCH_1):PAGE72
  U2D1 BK25 VCCIO<89> SKX_EXT_B_BGA1-IC,TBD    I33 @BASEBOARD_FAB2_LIB.BASEBOARD_FAB2(SCH_1):PAGE72
  U2D1 BJ26 VCCIO<90> SKX_EXT_B_BGA1-IC,TBD    I33 @BASEBOARD_FAB2_LIB.BASEBOARD_FAB2(SCH_1):PAGE72
  U2D1 BH27 VCCIO<91> SKX_EXT_B_BGA1-IC,TBD    I33 @BASEBOARD_FAB2_LIB.BASEBOARD_FAB2(SCH_1):PAGE72
  U2D1 BH25 VCCIO<92> SKX_EXT_B_BGA1-IC,TBD    I33 @BASEBOARD_FAB2_LIB.BASEBOARD_FAB2(SCH_1):PAGE72
  U2D1 BG26 VCCIO<93> SKX_EXT_B_BGA1-IC,TBD    I33 @BASEBOARD_FAB2_LIB.BASEBOARD_FAB2(SCH_1):PAGE72
  U2D1 BF27 VCCIO<94> SKX_EXT_B_BGA1-IC,TBD    I33 @BASEBOARD_FAB2_LIB.BASEBOARD_FAB2(SCH_1):PAGE72
  U2D1 AE36 VCCIO<95> SKX_EXT_B_BGA1-IC,TBD    I33 @BASEBOARD_FAB2_LIB.BASEBOARD_FAB2(SCH_1):PAGE72
  U2D1 AD37 VCCIO<96> SKX_EXT_B_BGA1-IC,TBD    I33 @BASEBOARD_FAB2_LIB.BASEBOARD_FAB2(SCH_1):PAGE72
  U2D1 AC36 VCCIO<97> SKX_EXT_B_BGA1-IC,TBD    I33 @BASEBOARD_FAB2_LIB.BASEBOARD_FAB2(SCH_1):PAGE72
  U2D1 AF35 VCCIO<98> SKX_EXT_B_BGA1-IC,TBD    I33 @BASEBOARD_FAB2_LIB.BASEBOARD_FAB2(SCH_1):PAGE72
  U2D1 AD35 VCCIO<99> SKX_EXT_B_BGA1-IC,TBD    I33 @BASEBOARD_FAB2_LIB.BASEBOARD_FAB2(SCH_1):PAGE72
  U2D1 AE34 VCCIO<100> SKX_EXT_B_BGA1-IC,TBD    I33 @BASEBOARD_FAB2_LIB.BASEBOARD_FAB2(SCH_1):PAGE72
  U2D1 AG34 VCCIO<101> SKX_EXT_B_BGA1-IC,TBD    I33 @BASEBOARD_FAB2_LIB.BASEBOARD_FAB2(SCH_1):PAGE72
  U2D1 AM29 VCCIO<102> SKX_EXT_B_BGA1-IC,TBD    I33 @BASEBOARD_FAB2_LIB.BASEBOARD_FAB2(SCH_1):PAGE72
  U2D1 AL28 VCCIO<103> SKX_EXT_B_BGA1-IC,TBD    I33 @BASEBOARD_FAB2_LIB.BASEBOARD_FAB2(SCH_1):PAGE72
  U2D1 AR28 VCCIO<104> SKX_EXT_B_BGA1-IC,TBD    I33 @BASEBOARD_FAB2_LIB.BASEBOARD_FAB2(SCH_1):PAGE72
  U2D1 EE10 VCCIO<0> SKX_EXT_B_BGA1-IC,TBD   I107 @BASEBOARD_FAB2_LIB.BASEBOARD_FAB2(SCH_1):PAGE73
  U2D1 AE10 VCCIO<1> SKX_EXT_B_BGA1-IC,TBD   I107 @BASEBOARD_FAB2_LIB.BASEBOARD_FAB2(SCH_1):PAGE73
  U2D1  AF5 VCCIO<2> SKX_EXT_B_BGA1-IC,TBD   I107 @BASEBOARD_FAB2_LIB.BASEBOARD_FAB2(SCH_1):PAGE73
  U2D1 DV11 VCCIO<3> SKX_EXT_B_BGA1-IC,TBD   I107 @BASEBOARD_FAB2_LIB.BASEBOARD_FAB2(SCH_1):PAGE73
  U2D1  AM5 VCCIO<4> SKX_EXT_B_BGA1-IC,TBD   I107 @BASEBOARD_FAB2_LIB.BASEBOARD_FAB2(SCH_1):PAGE73
  U2D1  AT5 VCCIO<5> SKX_EXT_B_BGA1-IC,TBD   I107 @BASEBOARD_FAB2_LIB.BASEBOARD_FAB2(SCH_1):PAGE73
  U2D1  AT7 VCCIO<6> SKX_EXT_B_BGA1-IC,TBD   I107 @BASEBOARD_FAB2_LIB.BASEBOARD_FAB2(SCH_1):PAGE73
  U2D1 BE24 VCCIO<7> SKX_EXT_B_BGA1-IC,TBD   I107 @BASEBOARD_FAB2_LIB.BASEBOARD_FAB2(SCH_1):PAGE73
  U2D1 DK21 VCCIO<8> SKX_EXT_B_BGA1-IC,TBD   I107 @BASEBOARD_FAB2_LIB.BASEBOARD_FAB2(SCH_1):PAGE73
  U2D1  CF5 VCCIO<9> SKX_EXT_B_BGA1-IC,TBD   I107 @BASEBOARD_FAB2_LIB.BASEBOARD_FAB2(SCH_1):PAGE73
  U2D1 CG14 VCCIO<10> SKX_EXT_B_BGA1-IC,TBD   I107 @BASEBOARD_FAB2_LIB.BASEBOARD_FAB2(SCH_1):PAGE73
  U2D1 CL20 VCCIO<11> SKX_EXT_B_BGA1-IC,TBD   I107 @BASEBOARD_FAB2_LIB.BASEBOARD_FAB2(SCH_1):PAGE73
  U2D1 CP13 VCCIO<12> SKX_EXT_B_BGA1-IC,TBD   I107 @BASEBOARD_FAB2_LIB.BASEBOARD_FAB2(SCH_1):PAGE73
  U2D1 DE14 VCCIO<13> SKX_EXT_B_BGA1-IC,TBD   I107 @BASEBOARD_FAB2_LIB.BASEBOARD_FAB2(SCH_1):PAGE73
  U2D1 DC18 VCCIO<14> SKX_EXT_B_BGA1-IC,TBD   I107 @BASEBOARD_FAB2_LIB.BASEBOARD_FAB2(SCH_1):PAGE73
  U2D1 CY17 VCCIO<15> SKX_EXT_B_BGA1-IC,TBD   I107 @BASEBOARD_FAB2_LIB.BASEBOARD_FAB2(SCH_1):PAGE73
  U2D1 CU18 VCCIO<16> SKX_EXT_B_BGA1-IC,TBD   I107 @BASEBOARD_FAB2_LIB.BASEBOARD_FAB2(SCH_1):PAGE73
  U2D1 CV21 VCCIO<17> SKX_EXT_B_BGA1-IC,TBD   I107 @BASEBOARD_FAB2_LIB.BASEBOARD_FAB2(SCH_1):PAGE73
  U2D1 CU12 VCCIO<18> SKX_EXT_B_BGA1-IC,TBD   I107 @BASEBOARD_FAB2_LIB.BASEBOARD_FAB2(SCH_1):PAGE73
  U2D1  CN6 VCCIO<19> SKX_EXT_B_BGA1-IC,TBD   I107 @BASEBOARD_FAB2_LIB.BASEBOARD_FAB2(SCH_1):PAGE73
  C3D9    1      A CAP_A_0603V-22.0UF,4V,20%,X6S,A    I15 @BASEBOARD_FAB2_LIB.BASEBOARD_FAB2(SCH_1):PAGE76
  C3D8    1      A CAP_A_0603V-22.0UF,4V,20%,X6S,A    I18 @BASEBOARD_FAB2_LIB.BASEBOARD_FAB2(SCH_1):PAGE76
 C7P17    1      A CAP_0805-47UF,4V,20%,X6S,C9533A    I29 @BASEBOARD_FAB2_LIB.BASEBOARD_FAB2(SCH_1):PAGE76
 C7P18    1      A CAP_0805-47UF,4V,20%,X6S,C9533A    I51 @BASEBOARD_FAB2_LIB.BASEBOARD_FAB2(SCH_1):PAGE76
  C7P3    1      A CAP_0805-47UF,4V,20%,X6S,C9533A    I52 @BASEBOARD_FAB2_LIB.BASEBOARD_FAB2(SCH_1):PAGE76
 C3D23    1      A CAP_A_0603V-22.0UF,4V,20%,X6S,A   I172 @BASEBOARD_FAB2_LIB.BASEBOARD_FAB2(SCH_1):PAGE76
 C3D15    1      A CAP_A_0603V-22.0UF,4V,20%,X6S,A   I174 @BASEBOARD_FAB2_LIB.BASEBOARD_FAB2(SCH_1):PAGE76
 C3D24    1      A CAP_A_0603V-22.0UF,4V,20%,X6S,A   I175 @BASEBOARD_FAB2_LIB.BASEBOARD_FAB2(SCH_1):PAGE76
 C3D16    1      A CAP_A_0603V-22.0UF,4V,20%,X6S,A   I176 @BASEBOARD_FAB2_LIB.BASEBOARD_FAB2(SCH_1):PAGE76
 C7P12    1      A CAP_A_0603V-22.0UF,4V,20%,X6S,A   I179 @BASEBOARD_FAB2_LIB.BASEBOARD_FAB2(SCH_1):PAGE76
 C7P16    1      A CAP_A_0603V-22.0UF,4V,20%,X6S,A   I206 @BASEBOARD_FAB2_LIB.BASEBOARD_FAB2(SCH_1):PAGE76
 R3D22    1      A RES_0402-240,1.0%,1/16W,EMPTY,A    I17 @BASEBOARD_FAB2_LIB.BASEBOARD_FAB2(SCH_1):PAGE90
 R3D16    1      A RES_0402-240,1.0%,1/16W,EMPTY,A    I24 @BASEBOARD_FAB2_LIB.BASEBOARD_FAB2(SCH_1):PAGE90
 R3D23    1      A RES_0402-240,1.0%,1/16W,EMPTY,A    I25 @BASEBOARD_FAB2_LIB.BASEBOARD_FAB2(SCH_1):PAGE90
 R3D26    1      A RES_0402-240,1.0%,1/16W,EMPTY,A    I28 @BASEBOARD_FAB2_LIB.BASEBOARD_FAB2(SCH_1):PAGE90
 R3D24    1      A RES_0402-240,1.0%,1/16W,CHIP,GA    I59 @BASEBOARD_FAB2_LIB.BASEBOARD_FAB2(SCH_1):PAGE90
 R3D17    1      A RES_0402-240,1.0%,1/16W,EMPTY,A    I60 @BASEBOARD_FAB2_LIB.BASEBOARD_FAB2(SCH_1):PAGE90
 R7P22    1      A RES_0402-240,1.0%,1/16W,EMPTY,A    I76 @BASEBOARD_FAB2_LIB.BASEBOARD_FAB2(SCH_1):PAGE90
 R3P41    1      A RES_0402-75,1.0%,1/16W,CHIP,G2A     I9 @BASEBOARD_FAB2_LIB.BASEBOARD_FAB2(SCH_1):PAGE92
 R7P28    1      A RES_0402-150.0,1%,1/16W,CHIP,GA   I106 @BASEBOARD_FAB2_LIB.BASEBOARD_FAB2(SCH_1):PAGE93
 R2T73    1      A RES_0402-150.0,1%,1/16W,CHIP,GA   I144 @BASEBOARD_FAB2_LIB.BASEBOARD_FAB2(SCH_1):PAGE93
 R3D20    1      A RES_0402-49.9,1%,1/16W,CHIP,G2A    I25 @BASEBOARD_FAB2_LIB.BASEBOARD_FAB2(SCH_1):PAGE96
 R3D15    1      A RES_0402-49.9,1%,1/16W,CHIP,G2A    I26 @BASEBOARD_FAB2_LIB.BASEBOARD_FAB2(SCH_1):PAGE96
 R4C10    1      A RES_0402-240,1.0%,1/16W,CHIP,GA    I76 @BASEBOARD_FAB2_LIB.BASEBOARD_FAB2(SCH_1):PAGE97
 C4G22    1      A CAP_A_0402V-0.1UF,16V,10%,X7R,A    I27 @BASEBOARD_FAB2_LIB.BASEBOARD_FAB2(SCH_1):PAGE99
  C3B4    1      A CAP_A_0402V-0.1UF,16V,10%,X7R,A    I47 @BASEBOARD_FAB2_LIB.BASEBOARD_FAB2(SCH_1):PAGE99
  U4G1    1   VCCA PCA9617_SSOP-IC,G81764-001-GNDA    I63 @BASEBOARD_FAB2_LIB.BASEBOARD_FAB2(SCH_1):PAGE99
  R6T1    1      A RES_0402-240,1.0%,1/16W,CHIP,GA    I70 @BASEBOARD_FAB2_LIB.BASEBOARD_FAB2(SCH_1):PAGE99
  R6T2    1      A RES_0402-240,1.0%,1/16W,CHIP,GA    I72 @BASEBOARD_FAB2_LIB.BASEBOARD_FAB2(SCH_1):PAGE99
  U3B1    1   VCCA PCA9617_SSOP-IC,G81764-001-GNDA    I75 @BASEBOARD_FAB2_LIB.BASEBOARD_FAB2(SCH_1):PAGE99
  R7M7    1      A RES_0402-240,1.0%,1/16W,CHIP,GA    I77 @BASEBOARD_FAB2_LIB.BASEBOARD_FAB2(SCH_1):PAGE99
  R7M2    1      A RES_0402-240,1.0%,1/16W,CHIP,GA    I79 @BASEBOARD_FAB2_LIB.BASEBOARD_FAB2(SCH_1):PAGE99
  R6T7    1      A RES_0402-150.0,1%,1/16W,CHIP,GA    I55 @BASEBOARD_FAB2_LIB.BASEBOARD_FAB2(SCH_1):PAGE112
  R6T6    1      A RES_0402-150.0,1%,1/16W,CHIP,GA    I56 @BASEBOARD_FAB2_LIB.BASEBOARD_FAB2(SCH_1):PAGE112
 R1U41    1      A RES_0402-150.0,1%,1/16W,CHIP,GA    I56 @BASEBOARD_FAB2_LIB.BASEBOARD_FAB2(SCH_1):PAGE152
 R1U35    1      A RES_0402-150.0,1%,1/16W,CHIP,GA    I57 @BASEBOARD_FAB2_LIB.BASEBOARD_FAB2(SCH_1):PAGE152
  R7P5    2      B RES_0402-150.0,1%,1/16W,CHIP,GA    I61 @BASEBOARD_FAB2_LIB.BASEBOARD_FAB2(SCH_1):PAGE152
 R7P21    2      B RES_0402-150.0,1%,1/16W,CHIP,GA    I62 @BASEBOARD_FAB2_LIB.BASEBOARD_FAB2(SCH_1):PAGE152
 R9M18    1      A RES_0402-240,1.0%,1/16W,CHIP,GA     I6 @BASEBOARD_FAB2_LIB.BASEBOARD_FAB2(SCH_1):PAGE163
 R9M19    1      A RES_0402-240,1.0%,1/16W,CHIP,GA     I7 @BASEBOARD_FAB2_LIB.BASEBOARD_FAB2(SCH_1):PAGE163
  C9M8    1      A CAP_A_0402V-0.1UF,16V,10%,X7R,A    I10 @BASEBOARD_FAB2_LIB.BASEBOARD_FAB2(SCH_1):PAGE163
  J4B2   F1   IOF1 SCONN120_H61426002_SM-CONN,H61A    I46 @BASEBOARD_FAB2_LIB.BASEBOARD_FAB2(SCH_1):PAGE193
  R9P1    1      A RES_0402-100.0,1%,1/16W,CHIP,GA     I4 @BASEBOARD_FAB2_LIB.BASEBOARD_FAB2(SCH_1):PAGE206
  R9P2    1      A RES_0402-49.9,1%,1/16W,CHIP,G2A    I53 @BASEBOARD_FAB2_LIB.BASEBOARD_FAB2(SCH_1):PAGE206
 R9N14    1      A RES_0402-1.00K,1%,1/16W,CHIP,GA   I120 @BASEBOARD_FAB2_LIB.BASEBOARD_FAB2(SCH_1):PAGE206
 R6P35    1      A RES_0402-100.0,1%,1/16W,EMPTY,A    I27 @BASEBOARD_FAB2_LIB.BASEBOARD_FAB2(SCH_1):PAGE213
 R6P33    1      A RES_0402-110,1%,1/16W,EMPTY,G2A    I30 @BASEBOARD_FAB2_LIB.BASEBOARD_FAB2(SCH_1):PAGE213
  C6R5    1      A CAPP_3018-470UF,2.5V,20%,ALUM,A    I24 @BASEBOARD_FAB2_LIB.BASEBOARD_FAB2(SCH_1):PAGE214
  C7R1    1      A CAP_A_0603V-22.0UF,4V,20%,X6S,A    I65 @BASEBOARD_FAB2_LIB.BASEBOARD_FAB2(SCH_1):PAGE214
  R3E1    2      B RES_0402-100.0,1%,1/16W,CHIP,GA   I105 @BASEBOARD_FAB2_LIB.BASEBOARD_FAB2(SCH_1):PAGE214
  C3E1    1      A CAP_A_0603V-22.0UF,4V,20%,X6S,A   I108 @BASEBOARD_FAB2_LIB.BASEBOARD_FAB2(SCH_1):PAGE214
  R7R1    1      A RES_0402-51.1,1.0%,1/16W,CHIP,A   I109 @BASEBOARD_FAB2_LIB.BASEBOARD_FAB2(SCH_1):PAGE214
 EU4E2    1    VOS IR354XX_SM-IR35412,IC,H73684-0A   I126 @BASEBOARD_FAB2_LIB.BASEBOARD_FAB2(SCH_1):PAGE214
  U1B2    1   VCCA TCA9517DGKR-GP_DISCRET-G8-TCA9A    I28 @BASEBOARD_FAB2_LIB.BASEBOARD_FAB2(SCH_1):PAGE163
  L4E2    2      F IND-150NH-56-GP_DISCRET-GA1-INA   I174 @BASEBOARD_FAB2_LIB.BASEBOARD_FAB2(SCH_1):PAGE214
  R9U3    1      A RES_0402-100.0,1%,1/16W,CHIP,GA    I57 @BASEBOARD_FAB2_LIB.BASEBOARD_FAB2(SCH_1):PAGE223
  R9M7    1      A RES_0402-100.0,1%,1/16W,EMPTY,A    I57 @BASEBOARD_FAB2_LIB.BASEBOARD_FAB2(SCH_1):PAGE226
  R9M6    1      A RES_0402-49.9,1%,1/16W,EMPTY,GA    I70 @BASEBOARD_FAB2_LIB.BASEBOARD_FAB2(SCH_1):PAGE226
  R9U4    1      A RES_0402-49.9,1%,1/16W,CHIP,G2A    I70 @BASEBOARD_FAB2_LIB.BASEBOARD_FAB2(SCH_1):PAGE223
 C6R12    1      A CAPP_3018-470UF,2.5V,20%,ALUM,A   I177 @BASEBOARD_FAB2_LIB.BASEBOARD_FAB2(SCH_1):PAGE214
  C4E7    1      A CAPP_3018-470UF,2.5V,20%,ALUM,A   I178 @BASEBOARD_FAB2_LIB.BASEBOARD_FAB2(SCH_1):PAGE214

PVCCMCP_CPU0 @BASEBOARD_FAB2_LIB.BASEBOARD_FAB2(SCH_1):PVCCMCP_CPU0
  U5D1 AP25 RSVD<196> SKX_EXT_B_BGA1-IC,TBD   I204 @BASEBOARD_FAB2_LIB.BASEBOARD_FAB2(SCH_1):PAGE22
  U5D1 AP23 RSVD<197> SKX_EXT_B_BGA1-IC,TBD   I204 @BASEBOARD_FAB2_LIB.BASEBOARD_FAB2(SCH_1):PAGE22
  U5D1 AN26 RSVD<200> SKX_EXT_B_BGA1-IC,TBD   I204 @BASEBOARD_FAB2_LIB.BASEBOARD_FAB2(SCH_1):PAGE22
  U5D1 AN24 RSVD<201> SKX_EXT_B_BGA1-IC,TBD   I204 @BASEBOARD_FAB2_LIB.BASEBOARD_FAB2(SCH_1):PAGE22
  U5D1 AN22 RSVD<202> SKX_EXT_B_BGA1-IC,TBD   I204 @BASEBOARD_FAB2_LIB.BASEBOARD_FAB2(SCH_1):PAGE22
  U5D1 AN18 RSVD<203> SKX_EXT_B_BGA1-IC,TBD   I204 @BASEBOARD_FAB2_LIB.BASEBOARD_FAB2(SCH_1):PAGE22
  U5D1 AM25 RSVD<207> SKX_EXT_B_BGA1-IC,TBD   I204 @BASEBOARD_FAB2_LIB.BASEBOARD_FAB2(SCH_1):PAGE22
  U5D1 AM21 RSVD<209> SKX_EXT_B_BGA1-IC,TBD   I204 @BASEBOARD_FAB2_LIB.BASEBOARD_FAB2(SCH_1):PAGE22
  U5D1 AT25 RSVD<187> SKX_EXT_B_BGA1-IC,TBD    I61 @BASEBOARD_FAB2_LIB.BASEBOARD_FAB2(SCH_1):PAGE29
  U5D1 AT23 RSVD<188> SKX_EXT_B_BGA1-IC,TBD    I61 @BASEBOARD_FAB2_LIB.BASEBOARD_FAB2(SCH_1):PAGE29
  U5D1 AR26 RSVD<191> SKX_EXT_B_BGA1-IC,TBD    I61 @BASEBOARD_FAB2_LIB.BASEBOARD_FAB2(SCH_1):PAGE29
  U5D1 AR22 RSVD<192> SKX_EXT_B_BGA1-IC,TBD    I61 @BASEBOARD_FAB2_LIB.BASEBOARD_FAB2(SCH_1):PAGE29
  U5D1 AR20 RSVD<193> SKX_EXT_B_BGA1-IC,TBD    I61 @BASEBOARD_FAB2_LIB.BASEBOARD_FAB2(SCH_1):PAGE29
  U5D1 CH23 RSVD<92> SKX_EXT_B_BGA1-IC,TBD    I15 @BASEBOARD_FAB2_LIB.BASEBOARD_FAB2(SCH_1):PAGE36
  U5D1 CH21 RSVD<93> SKX_EXT_B_BGA1-IC,TBD    I15 @BASEBOARD_FAB2_LIB.BASEBOARD_FAB2(SCH_1):PAGE36
  U5D1 CG26 RSVD<96> SKX_EXT_B_BGA1-IC,TBD    I15 @BASEBOARD_FAB2_LIB.BASEBOARD_FAB2(SCH_1):PAGE36
  U5D1 CG20 RSVD<98> SKX_EXT_B_BGA1-IC,TBD    I15 @BASEBOARD_FAB2_LIB.BASEBOARD_FAB2(SCH_1):PAGE36
  U5D1 CF23 RSVD<102> SKX_EXT_B_BGA1-IC,TBD    I15 @BASEBOARD_FAB2_LIB.BASEBOARD_FAB2(SCH_1):PAGE36
  U5D1 CF21 RSVD<103> SKX_EXT_B_BGA1-IC,TBD    I15 @BASEBOARD_FAB2_LIB.BASEBOARD_FAB2(SCH_1):PAGE36
  U5D1 CF19 RSVD<104> SKX_EXT_B_BGA1-IC,TBD    I15 @BASEBOARD_FAB2_LIB.BASEBOARD_FAB2(SCH_1):PAGE36
  U5D1 CE22 RSVD<107> SKX_EXT_B_BGA1-IC,TBD    I15 @BASEBOARD_FAB2_LIB.BASEBOARD_FAB2(SCH_1):PAGE36
  U5D1 CD21 RSVD<109> SKX_EXT_B_BGA1-IC,TBD    I15 @BASEBOARD_FAB2_LIB.BASEBOARD_FAB2(SCH_1):PAGE36
  U5D1 CD19 RSVD<110> SKX_EXT_B_BGA1-IC,TBD    I15 @BASEBOARD_FAB2_LIB.BASEBOARD_FAB2(SCH_1):PAGE36
  U5D1 CC20 RSVD<112> SKX_EXT_B_BGA1-IC,TBD    I15 @BASEBOARD_FAB2_LIB.BASEBOARD_FAB2(SCH_1):PAGE36
  U5D1 CB21 RSVD<115> SKX_EXT_B_BGA1-IC,TBD    I15 @BASEBOARD_FAB2_LIB.BASEBOARD_FAB2(SCH_1):PAGE36
  U5D1 CB19 RSVD<116> SKX_EXT_B_BGA1-IC,TBD    I15 @BASEBOARD_FAB2_LIB.BASEBOARD_FAB2(SCH_1):PAGE36
  U5D1 CA22 RSVD<118> SKX_EXT_B_BGA1-IC,TBD    I15 @BASEBOARD_FAB2_LIB.BASEBOARD_FAB2(SCH_1):PAGE36
  U5D1 BY19 RSVD<120> SKX_EXT_B_BGA1-IC,TBD    I15 @BASEBOARD_FAB2_LIB.BASEBOARD_FAB2(SCH_1):PAGE36
  U5D1 BW20 RSVD<122> SKX_EXT_B_BGA1-IC,TBD    I15 @BASEBOARD_FAB2_LIB.BASEBOARD_FAB2(SCH_1):PAGE36
  U5D1 BV21 RSVD<125> SKX_EXT_B_BGA1-IC,TBD    I15 @BASEBOARD_FAB2_LIB.BASEBOARD_FAB2(SCH_1):PAGE36
  U5D1 BV19 RSVD<126> SKX_EXT_B_BGA1-IC,TBD    I15 @BASEBOARD_FAB2_LIB.BASEBOARD_FAB2(SCH_1):PAGE36
  U5D1 BU22 RSVD<127> SKX_EXT_B_BGA1-IC,TBD    I15 @BASEBOARD_FAB2_LIB.BASEBOARD_FAB2(SCH_1):PAGE36
  U5D1 BU20 RSVD<128> SKX_EXT_B_BGA1-IC,TBD    I15 @BASEBOARD_FAB2_LIB.BASEBOARD_FAB2(SCH_1):PAGE36
  U5D1 BR24 RSVD<130> SKX_EXT_B_BGA1-IC,TBD    I15 @BASEBOARD_FAB2_LIB.BASEBOARD_FAB2(SCH_1):PAGE36
  U5D1 BR22 RSVD<131> SKX_EXT_B_BGA1-IC,TBD    I15 @BASEBOARD_FAB2_LIB.BASEBOARD_FAB2(SCH_1):PAGE36
  U5D1 BP21 RSVD<132> SKX_EXT_B_BGA1-IC,TBD    I15 @BASEBOARD_FAB2_LIB.BASEBOARD_FAB2(SCH_1):PAGE36
  U5D1 BM19 RSVD<135> SKX_EXT_B_BGA1-IC,TBD    I15 @BASEBOARD_FAB2_LIB.BASEBOARD_FAB2(SCH_1):PAGE36
  U5D1 BL20 RSVD<137> SKX_EXT_B_BGA1-IC,TBD    I15 @BASEBOARD_FAB2_LIB.BASEBOARD_FAB2(SCH_1):PAGE36
  U5D1 BK17 RSVD<139> SKX_EXT_B_BGA1-IC,TBD    I15 @BASEBOARD_FAB2_LIB.BASEBOARD_FAB2(SCH_1):PAGE36
  U5D1 BJ20 RSVD<140> SKX_EXT_B_BGA1-IC,TBD    I15 @BASEBOARD_FAB2_LIB.BASEBOARD_FAB2(SCH_1):PAGE36
  U5D1 BJ18 RSVD<141> SKX_EXT_B_BGA1-IC,TBD    I15 @BASEBOARD_FAB2_LIB.BASEBOARD_FAB2(SCH_1):PAGE36
  U5D1 BJ16 RSVD<142> SKX_EXT_B_BGA1-IC,TBD    I15 @BASEBOARD_FAB2_LIB.BASEBOARD_FAB2(SCH_1):PAGE36
  U5D1 BH19 RSVD<143> SKX_EXT_B_BGA1-IC,TBD    I15 @BASEBOARD_FAB2_LIB.BASEBOARD_FAB2(SCH_1):PAGE36
  U5D1 CL24 RSVD<81> SKX_EXT_B_BGA1-IC,TBD    I16 @BASEBOARD_FAB2_LIB.BASEBOARD_FAB2(SCH_1):PAGE36
  U5D1 CK25 RSVD<83> SKX_EXT_B_BGA1-IC,TBD    I16 @BASEBOARD_FAB2_LIB.BASEBOARD_FAB2(SCH_1):PAGE36
  U5D1 CK23 RSVD<84> SKX_EXT_B_BGA1-IC,TBD    I16 @BASEBOARD_FAB2_LIB.BASEBOARD_FAB2(SCH_1):PAGE36
  U5D1 CJ26 RSVD<86> SKX_EXT_B_BGA1-IC,TBD    I16 @BASEBOARD_FAB2_LIB.BASEBOARD_FAB2(SCH_1):PAGE36
  U5D1 CJ24 RSVD<87> SKX_EXT_B_BGA1-IC,TBD    I16 @BASEBOARD_FAB2_LIB.BASEBOARD_FAB2(SCH_1):PAGE36
  U5D1 CJ22 RSVD<88> SKX_EXT_B_BGA1-IC,TBD    I16 @BASEBOARD_FAB2_LIB.BASEBOARD_FAB2(SCH_1):PAGE36
  U5D1 CJ20 RSVD<89> SKX_EXT_B_BGA1-IC,TBD    I16 @BASEBOARD_FAB2_LIB.BASEBOARD_FAB2(SCH_1):PAGE36
  U5D1 BL14 CD_VCC_CORE<0> SKX_EXT_B_BGA1-IC,TBD    I34 @BASEBOARD_FAB2_LIB.BASEBOARD_FAB2(SCH_1):PAGE38
  U5D1 BK15 CD_VCC_CORE<1> SKX_EXT_B_BGA1-IC,TBD    I34 @BASEBOARD_FAB2_LIB.BASEBOARD_FAB2(SCH_1):PAGE38
  U5D1 BK13 CD_VCC_CORE<2> SKX_EXT_B_BGA1-IC,TBD    I34 @BASEBOARD_FAB2_LIB.BASEBOARD_FAB2(SCH_1):PAGE38
  U5D1 BJ14 CD_VCC_CORE<3> SKX_EXT_B_BGA1-IC,TBD    I34 @BASEBOARD_FAB2_LIB.BASEBOARD_FAB2(SCH_1):PAGE38
  U5D1 BJ12 CD_VCC_CORE<4> SKX_EXT_B_BGA1-IC,TBD    I34 @BASEBOARD_FAB2_LIB.BASEBOARD_FAB2(SCH_1):PAGE38
  U5D1 BH13 CD_VCC_CORE<5> SKX_EXT_B_BGA1-IC,TBD    I34 @BASEBOARD_FAB2_LIB.BASEBOARD_FAB2(SCH_1):PAGE38
  U5D1 BG14 CD_VCC_CORE<6> SKX_EXT_B_BGA1-IC,TBD    I34 @BASEBOARD_FAB2_LIB.BASEBOARD_FAB2(SCH_1):PAGE38
  U5D1 BG12 CD_VCC_CORE<7> SKX_EXT_B_BGA1-IC,TBD    I34 @BASEBOARD_FAB2_LIB.BASEBOARD_FAB2(SCH_1):PAGE38
  U5D1 BF13 CD_VCC_CORE<8> SKX_EXT_B_BGA1-IC,TBD    I34 @BASEBOARD_FAB2_LIB.BASEBOARD_FAB2(SCH_1):PAGE38
  U5D1 BF11 CD_VCC_CORE<9> SKX_EXT_B_BGA1-IC,TBD    I34 @BASEBOARD_FAB2_LIB.BASEBOARD_FAB2(SCH_1):PAGE38
  U5D1 BE14 CD_VCC_CORE<10> SKX_EXT_B_BGA1-IC,TBD    I34 @BASEBOARD_FAB2_LIB.BASEBOARD_FAB2(SCH_1):PAGE38
  U5D1 BE12 CD_VCC_CORE<11> SKX_EXT_B_BGA1-IC,TBD    I34 @BASEBOARD_FAB2_LIB.BASEBOARD_FAB2(SCH_1):PAGE38
  U5D1 BD13 CD_VCC_CORE<12> SKX_EXT_B_BGA1-IC,TBD    I34 @BASEBOARD_FAB2_LIB.BASEBOARD_FAB2(SCH_1):PAGE38
  U5D1 DA24 RSVD<52> SKX_EXT_B_BGA1-IC,TBD   I127 @BASEBOARD_FAB2_LIB.BASEBOARD_FAB2(SCH_1):PAGE39
  U5D1 CY25 RSVD<58> SKX_EXT_B_BGA1-IC,TBD   I127 @BASEBOARD_FAB2_LIB.BASEBOARD_FAB2(SCH_1):PAGE39
  U5D1 CW24 RSVD<62> SKX_EXT_B_BGA1-IC,TBD   I127 @BASEBOARD_FAB2_LIB.BASEBOARD_FAB2(SCH_1):PAGE39
  U5D1 CV23 RSVD<65> SKX_EXT_B_BGA1-IC,TBD   I127 @BASEBOARD_FAB2_LIB.BASEBOARD_FAB2(SCH_1):PAGE39
  U5D1 CU24 RSVD<68> SKX_EXT_B_BGA1-IC,TBD   I127 @BASEBOARD_FAB2_LIB.BASEBOARD_FAB2(SCH_1):PAGE39
  U5D1 CT23 RSVD<71> SKX_EXT_B_BGA1-IC,TBD   I127 @BASEBOARD_FAB2_LIB.BASEBOARD_FAB2(SCH_1):PAGE39
  U5D1 CP23 RSVD<74> SKX_EXT_B_BGA1-IC,TBD   I127 @BASEBOARD_FAB2_LIB.BASEBOARD_FAB2(SCH_1):PAGE39
  U5D1 CN24 RSVD<76> SKX_EXT_B_BGA1-IC,TBD   I127 @BASEBOARD_FAB2_LIB.BASEBOARD_FAB2(SCH_1):PAGE39
  U5D1 CM25 RSVD<78> SKX_EXT_B_BGA1-IC,TBD   I127 @BASEBOARD_FAB2_LIB.BASEBOARD_FAB2(SCH_1):PAGE39
  U5D1 CM23 RSVD<79> SKX_EXT_B_BGA1-IC,TBD   I127 @BASEBOARD_FAB2_LIB.BASEBOARD_FAB2(SCH_1):PAGE39
  U5D1 CL26 RSVD<80> SKX_EXT_B_BGA1-IC,TBD   I127 @BASEBOARD_FAB2_LIB.BASEBOARD_FAB2(SCH_1):PAGE39
  C6D8    1      A CAP_A_0603V-22.0UF,4V,20%,X6S,A    I68 @BASEBOARD_FAB2_LIB.BASEBOARD_FAB2(SCH_1):PAGE42
 C5D38    1      A CAP_A_0603V-22.0UF,4V,20%,X6S,A    I69 @BASEBOARD_FAB2_LIB.BASEBOARD_FAB2(SCH_1):PAGE42
 C5D37    1      A CAP_A_0603V-22.0UF,4V,20%,X6S,A    I70 @BASEBOARD_FAB2_LIB.BASEBOARD_FAB2(SCH_1):PAGE42
  C6D5    1      A CAP_A_0603V-22.0UF,4V,20%,X6S,A    I75 @BASEBOARD_FAB2_LIB.BASEBOARD_FAB2(SCH_1):PAGE42
  C6D2    1      A CAP_A_0603V-22.0UF,4V,20%,X6S,A    I77 @BASEBOARD_FAB2_LIB.BASEBOARD_FAB2(SCH_1):PAGE42
 C5D51    1      A CAP_A_0603V-22.0UF,4V,20%,X6S,A    I83 @BASEBOARD_FAB2_LIB.BASEBOARD_FAB2(SCH_1):PAGE42
 C5D21    1      A CAP_A_0603V-22.0UF,4V,20%,X6S,A    I88 @BASEBOARD_FAB2_LIB.BASEBOARD_FAB2(SCH_1):PAGE42
 C5D50    1      A CAP_A_0603V-22.0UF,4V,20%,X6S,A    I89 @BASEBOARD_FAB2_LIB.BASEBOARD_FAB2(SCH_1):PAGE42
 C5D48    1      A CAP_A_0603V-22.0UF,4V,20%,X6S,A    I90 @BASEBOARD_FAB2_LIB.BASEBOARD_FAB2(SCH_1):PAGE42
 C5D23    1      A CAP_A_0603V-22.0UF,4V,20%,X6S,A    I98 @BASEBOARD_FAB2_LIB.BASEBOARD_FAB2(SCH_1):PAGE42
 C5D36    1      A CAP_A_0603V-22.0UF,4V,20%,X6S,A   I151 @BASEBOARD_FAB2_LIB.BASEBOARD_FAB2(SCH_1):PAGE42
 C5D49    1      A CAP_A_0603V-22.0UF,4V,20%,X6S,A   I152 @BASEBOARD_FAB2_LIB.BASEBOARD_FAB2(SCH_1):PAGE42
 C5D22    1      A CAP_A_0603V-22.0UF,4V,20%,X6S,A   I153 @BASEBOARD_FAB2_LIB.BASEBOARD_FAB2(SCH_1):PAGE42
 C5D20    1      A CAP_A_0603V-22.0UF,4V,20%,X6S,A   I173 @BASEBOARD_FAB2_LIB.BASEBOARD_FAB2(SCH_1):PAGE42
 C5D33    1      A CAP_A_0603V-22.0UF,4V,20%,X6S,A   I174 @BASEBOARD_FAB2_LIB.BASEBOARD_FAB2(SCH_1):PAGE42
 C5D34    1      A CAP_A_0603V-22.0UF,4V,20%,X6S,A   I175 @BASEBOARD_FAB2_LIB.BASEBOARD_FAB2(SCH_1):PAGE42
 C5D35    1      A CAP_A_0603V-22.0UF,4V,20%,X6S,A   I176 @BASEBOARD_FAB2_LIB.BASEBOARD_FAB2(SCH_1):PAGE42
 C5D53    1      A CAP_A_0603V-22.0UF,4V,20%,X6S,A   I179 @BASEBOARD_FAB2_LIB.BASEBOARD_FAB2(SCH_1):PAGE42
 C5D52    1      A CAP_A_0603V-22.0UF,4V,20%,X6S,A   I180 @BASEBOARD_FAB2_LIB.BASEBOARD_FAB2(SCH_1):PAGE42
  C4R1    1      A CAPP_3018-470UF,2.5V,20%,ALUM,A    I29 @BASEBOARD_FAB2_LIB.BASEBOARD_FAB2(SCH_1):PAGE194
  C3R4    1      A CAPP_3018-470UF,2.5V,20%,ALUM,A    I31 @BASEBOARD_FAB2_LIB.BASEBOARD_FAB2(SCH_1):PAGE194
  J6E1   A1   IOA1 SCONN120_H61426002_SM-CONN,H61A    I55 @BASEBOARD_FAB2_LIB.BASEBOARD_FAB2(SCH_1):PAGE194
  J6E1   A2   IOA2 SCONN120_H61426002_SM-CONN,H61A    I55 @BASEBOARD_FAB2_LIB.BASEBOARD_FAB2(SCH_1):PAGE194
  J6E1   A3   IOA3 SCONN120_H61426002_SM-CONN,H61A    I55 @BASEBOARD_FAB2_LIB.BASEBOARD_FAB2(SCH_1):PAGE194
  J6E1   A5   IOA5 SCONN120_H61426002_SM-CONN,H61A    I55 @BASEBOARD_FAB2_LIB.BASEBOARD_FAB2(SCH_1):PAGE194
  J6E1   A6   IOA6 SCONN120_H61426002_SM-CONN,H61A    I55 @BASEBOARD_FAB2_LIB.BASEBOARD_FAB2(SCH_1):PAGE194
  J6E1   A7   IOA7 SCONN120_H61426002_SM-CONN,H61A    I55 @BASEBOARD_FAB2_LIB.BASEBOARD_FAB2(SCH_1):PAGE194
  J6E1   A8   IOA8 SCONN120_H61426002_SM-CONN,H61A    I55 @BASEBOARD_FAB2_LIB.BASEBOARD_FAB2(SCH_1):PAGE194
  J6E1   A9   IOA9 SCONN120_H61426002_SM-CONN,H61A    I55 @BASEBOARD_FAB2_LIB.BASEBOARD_FAB2(SCH_1):PAGE194
  J6E1  A10  IOA10 SCONN120_H61426002_SM-CONN,H61A    I55 @BASEBOARD_FAB2_LIB.BASEBOARD_FAB2(SCH_1):PAGE194
  J6E1  A11  IOA11 SCONN120_H61426002_SM-CONN,H61A    I55 @BASEBOARD_FAB2_LIB.BASEBOARD_FAB2(SCH_1):PAGE194
  J6E1  A12  IOA12 SCONN120_H61426002_SM-CONN,H61A    I55 @BASEBOARD_FAB2_LIB.BASEBOARD_FAB2(SCH_1):PAGE194
  J6E1  A13  IOA13 SCONN120_H61426002_SM-CONN,H61A    I55 @BASEBOARD_FAB2_LIB.BASEBOARD_FAB2(SCH_1):PAGE194
  J6E1  A14  IOA14 SCONN120_H61426002_SM-CONN,H61A    I55 @BASEBOARD_FAB2_LIB.BASEBOARD_FAB2(SCH_1):PAGE194
  J6E1  A15  IOA15 SCONN120_H61426002_SM-CONN,H61A    I55 @BASEBOARD_FAB2_LIB.BASEBOARD_FAB2(SCH_1):PAGE194
  J6E1  A16  IOA16 SCONN120_H61426002_SM-CONN,H61A    I55 @BASEBOARD_FAB2_LIB.BASEBOARD_FAB2(SCH_1):PAGE194
  J6E1  A17  IOA17 SCONN120_H61426002_SM-CONN,H61A    I55 @BASEBOARD_FAB2_LIB.BASEBOARD_FAB2(SCH_1):PAGE194
  J6E1  A18  IOA18 SCONN120_H61426002_SM-CONN,H61A    I55 @BASEBOARD_FAB2_LIB.BASEBOARD_FAB2(SCH_1):PAGE194
  J6E1   B1   IOB1 SCONN120_H61426002_SM-CONN,H61A    I55 @BASEBOARD_FAB2_LIB.BASEBOARD_FAB2(SCH_1):PAGE194
  J6E1   B2   IOB2 SCONN120_H61426002_SM-CONN,H61A    I55 @BASEBOARD_FAB2_LIB.BASEBOARD_FAB2(SCH_1):PAGE194
  J6E1   B3   IOB3 SCONN120_H61426002_SM-CONN,H61A    I55 @BASEBOARD_FAB2_LIB.BASEBOARD_FAB2(SCH_1):PAGE194
  J6E1   B5   IOB5 SCONN120_H61426002_SM-CONN,H61A    I55 @BASEBOARD_FAB2_LIB.BASEBOARD_FAB2(SCH_1):PAGE194
  J6E1   B6   IOB6 SCONN120_H61426002_SM-CONN,H61A    I55 @BASEBOARD_FAB2_LIB.BASEBOARD_FAB2(SCH_1):PAGE194
  J6E1   B7   IOB7 SCONN120_H61426002_SM-CONN,H61A    I55 @BASEBOARD_FAB2_LIB.BASEBOARD_FAB2(SCH_1):PAGE194
  J6E1   B8   IOB8 SCONN120_H61426002_SM-CONN,H61A    I55 @BASEBOARD_FAB2_LIB.BASEBOARD_FAB2(SCH_1):PAGE194
  J6E1   B9   IOB9 SCONN120_H61426002_SM-CONN,H61A    I55 @BASEBOARD_FAB2_LIB.BASEBOARD_FAB2(SCH_1):PAGE194
  J6E1  B10  IOB10 SCONN120_H61426002_SM-CONN,H61A    I55 @BASEBOARD_FAB2_LIB.BASEBOARD_FAB2(SCH_1):PAGE194
  J6E1  B11  IOB11 SCONN120_H61426002_SM-CONN,H61A    I55 @BASEBOARD_FAB2_LIB.BASEBOARD_FAB2(SCH_1):PAGE194
  J6E1  B12  IOB12 SCONN120_H61426002_SM-CONN,H61A    I55 @BASEBOARD_FAB2_LIB.BASEBOARD_FAB2(SCH_1):PAGE194
  J6E1  B13  IOB13 SCONN120_H61426002_SM-CONN,H61A    I55 @BASEBOARD_FAB2_LIB.BASEBOARD_FAB2(SCH_1):PAGE194
  J6E1  B14  IOB14 SCONN120_H61426002_SM-CONN,H61A    I55 @BASEBOARD_FAB2_LIB.BASEBOARD_FAB2(SCH_1):PAGE194
  J6E1  B15  IOB15 SCONN120_H61426002_SM-CONN,H61A    I55 @BASEBOARD_FAB2_LIB.BASEBOARD_FAB2(SCH_1):PAGE194
  J6E1  B16  IOB16 SCONN120_H61426002_SM-CONN,H61A    I55 @BASEBOARD_FAB2_LIB.BASEBOARD_FAB2(SCH_1):PAGE194
  J6E1  B17  IOB17 SCONN120_H61426002_SM-CONN,H61A    I55 @BASEBOARD_FAB2_LIB.BASEBOARD_FAB2(SCH_1):PAGE194
  J6E1  B18  IOB18 SCONN120_H61426002_SM-CONN,H61A    I55 @BASEBOARD_FAB2_LIB.BASEBOARD_FAB2(SCH_1):PAGE194
  J6E1   C1   IOC1 SCONN120_H61426002_SM-CONN,H61A    I55 @BASEBOARD_FAB2_LIB.BASEBOARD_FAB2(SCH_1):PAGE194
  J6E1   C2   IOC2 SCONN120_H61426002_SM-CONN,H61A    I55 @BASEBOARD_FAB2_LIB.BASEBOARD_FAB2(SCH_1):PAGE194
  J6E1   C3   IOC3 SCONN120_H61426002_SM-CONN,H61A    I55 @BASEBOARD_FAB2_LIB.BASEBOARD_FAB2(SCH_1):PAGE194
  J6E1   C4   IOC4 SCONN120_H61426002_SM-CONN,H61A    I55 @BASEBOARD_FAB2_LIB.BASEBOARD_FAB2(SCH_1):PAGE194
  J6E1   C5   IOC5 SCONN120_H61426002_SM-CONN,H61A    I55 @BASEBOARD_FAB2_LIB.BASEBOARD_FAB2(SCH_1):PAGE194
  J6E1   C6   IOC6 SCONN120_H61426002_SM-CONN,H61A    I55 @BASEBOARD_FAB2_LIB.BASEBOARD_FAB2(SCH_1):PAGE194
  J6E1   C7   IOC7 SCONN120_H61426002_SM-CONN,H61A    I55 @BASEBOARD_FAB2_LIB.BASEBOARD_FAB2(SCH_1):PAGE194
  J6E1   C8   IOC8 SCONN120_H61426002_SM-CONN,H61A    I55 @BASEBOARD_FAB2_LIB.BASEBOARD_FAB2(SCH_1):PAGE194
  J6E1   C9   IOC9 SCONN120_H61426002_SM-CONN,H61A    I55 @BASEBOARD_FAB2_LIB.BASEBOARD_FAB2(SCH_1):PAGE194
  J6E1  C10  IOC10 SCONN120_H61426002_SM-CONN,H61A    I55 @BASEBOARD_FAB2_LIB.BASEBOARD_FAB2(SCH_1):PAGE194
  J6E1  C11  IOC11 SCONN120_H61426002_SM-CONN,H61A    I55 @BASEBOARD_FAB2_LIB.BASEBOARD_FAB2(SCH_1):PAGE194
  J6E1  C12  IOC12 SCONN120_H61426002_SM-CONN,H61A    I55 @BASEBOARD_FAB2_LIB.BASEBOARD_FAB2(SCH_1):PAGE194
  J6E1  C13  IOC13 SCONN120_H61426002_SM-CONN,H61A    I55 @BASEBOARD_FAB2_LIB.BASEBOARD_FAB2(SCH_1):PAGE194
  J6E1  C14  IOC14 SCONN120_H61426002_SM-CONN,H61A    I55 @BASEBOARD_FAB2_LIB.BASEBOARD_FAB2(SCH_1):PAGE194
  J6E1  C15  IOC15 SCONN120_H61426002_SM-CONN,H61A    I55 @BASEBOARD_FAB2_LIB.BASEBOARD_FAB2(SCH_1):PAGE194
  J6E1  C16  IOC16 SCONN120_H61426002_SM-CONN,H61A    I55 @BASEBOARD_FAB2_LIB.BASEBOARD_FAB2(SCH_1):PAGE194
  J6E1  C17  IOC17 SCONN120_H61426002_SM-CONN,H61A    I55 @BASEBOARD_FAB2_LIB.BASEBOARD_FAB2(SCH_1):PAGE194
  J6E1  C18  IOC18 SCONN120_H61426002_SM-CONN,H61A    I55 @BASEBOARD_FAB2_LIB.BASEBOARD_FAB2(SCH_1):PAGE194
  C5W1    1      A CAP_A_0603V-22.0UF,4V,20%,X6S,A   I217 @BASEBOARD_FAB2_LIB.BASEBOARD_FAB2(SCH_1):PAGE42
  C5W2    1      A CAP_A_0603V-22.0UF,4V,20%,X6S,A   I218 @BASEBOARD_FAB2_LIB.BASEBOARD_FAB2(SCH_1):PAGE42
 C5P29    1      A CAP_0805-100UF,4V,20%,X5R,6024A   I220 @BASEBOARD_FAB2_LIB.BASEBOARD_FAB2(SCH_1):PAGE42
 C5P30    1      A CAP_0805-100UF,4V,20%,X5R,6024A   I221 @BASEBOARD_FAB2_LIB.BASEBOARD_FAB2(SCH_1):PAGE42
 C5P19    1      A CAP_0805-100UF,4V,20%,X5R,6024A   I222 @BASEBOARD_FAB2_LIB.BASEBOARD_FAB2(SCH_1):PAGE42
  C4P4    1      A CAP_0805-100UF,4V,20%,X5R,6024A   I223 @BASEBOARD_FAB2_LIB.BASEBOARD_FAB2(SCH_1):PAGE42
  C4P7    1      A CAP_0805-100UF,4V,20%,X5R,6024A   I224 @BASEBOARD_FAB2_LIB.BASEBOARD_FAB2(SCH_1):PAGE42
  C4P3    1      A CAP_0805-100UF,4V,20%,X5R,6024A   I225 @BASEBOARD_FAB2_LIB.BASEBOARD_FAB2(SCH_1):PAGE42
 C5P10    1      A CAP_0805-100UF,4V,20%,X5R,6024A   I226 @BASEBOARD_FAB2_LIB.BASEBOARD_FAB2(SCH_1):PAGE42
 C5P11    1      A CAP_0805-100UF,4V,20%,X5R,6024A   I227 @BASEBOARD_FAB2_LIB.BASEBOARD_FAB2(SCH_1):PAGE42
 C5P18    1      A CAP_0805-100UF,4V,20%,X5R,6024A   I228 @BASEBOARD_FAB2_LIB.BASEBOARD_FAB2(SCH_1):PAGE42
 C5P28    1      A CAP_0805-100UF,4V,20%,X5R,6024A   I229 @BASEBOARD_FAB2_LIB.BASEBOARD_FAB2(SCH_1):PAGE42
  C4P2    1      A CAP_0805-100UF,4V,20%,X5R,6024A   I230 @BASEBOARD_FAB2_LIB.BASEBOARD_FAB2(SCH_1):PAGE42
 C5P31    1      A CAP_0805-100UF,4V,20%,X5R,6024A   I231 @BASEBOARD_FAB2_LIB.BASEBOARD_FAB2(SCH_1):PAGE42
 C5P13    1      A CAP_0805-100UF,4V,20%,X5R,6024A   I232 @BASEBOARD_FAB2_LIB.BASEBOARD_FAB2(SCH_1):PAGE42
  C4P5    1      A CAP_0805-100UF,4V,20%,X5R,6024A   I233 @BASEBOARD_FAB2_LIB.BASEBOARD_FAB2(SCH_1):PAGE42
 C5P20    1      A CAP_0805-100UF,4V,20%,X5R,6024A   I234 @BASEBOARD_FAB2_LIB.BASEBOARD_FAB2(SCH_1):PAGE42
 C5P21    1      A CAP_0805-100UF,4V,20%,X5R,6024A   I235 @BASEBOARD_FAB2_LIB.BASEBOARD_FAB2(SCH_1):PAGE42
 C5P12    1      A CAP_0805-100UF,4V,20%,X5R,6024A   I236 @BASEBOARD_FAB2_LIB.BASEBOARD_FAB2(SCH_1):PAGE42

PVCCMCP_CPU1 @BASEBOARD_FAB2_LIB.BASEBOARD_FAB2(SCH_1):PVCCMCP_CPU1
  U2D1 AP25 RSVD<196> SKX_EXT_B_BGA1-IC,TBD   I169 @BASEBOARD_FAB2_LIB.BASEBOARD_FAB2(SCH_1):PAGE56
  U2D1 AP23 RSVD<197> SKX_EXT_B_BGA1-IC,TBD   I169 @BASEBOARD_FAB2_LIB.BASEBOARD_FAB2(SCH_1):PAGE56
  U2D1 AN26 RSVD<200> SKX_EXT_B_BGA1-IC,TBD   I169 @BASEBOARD_FAB2_LIB.BASEBOARD_FAB2(SCH_1):PAGE56
  U2D1 AN24 RSVD<201> SKX_EXT_B_BGA1-IC,TBD   I169 @BASEBOARD_FAB2_LIB.BASEBOARD_FAB2(SCH_1):PAGE56
  U2D1 AN22 RSVD<202> SKX_EXT_B_BGA1-IC,TBD   I169 @BASEBOARD_FAB2_LIB.BASEBOARD_FAB2(SCH_1):PAGE56
  U2D1 AN18 RSVD<203> SKX_EXT_B_BGA1-IC,TBD   I169 @BASEBOARD_FAB2_LIB.BASEBOARD_FAB2(SCH_1):PAGE56
  U2D1 AM25 RSVD<207> SKX_EXT_B_BGA1-IC,TBD   I169 @BASEBOARD_FAB2_LIB.BASEBOARD_FAB2(SCH_1):PAGE56
  U2D1 AM21 RSVD<209> SKX_EXT_B_BGA1-IC,TBD   I169 @BASEBOARD_FAB2_LIB.BASEBOARD_FAB2(SCH_1):PAGE56
  U2D1 AT25 RSVD<187> SKX_EXT_B_BGA1-IC,TBD    I23 @BASEBOARD_FAB2_LIB.BASEBOARD_FAB2(SCH_1):PAGE63
  U2D1 AT23 RSVD<188> SKX_EXT_B_BGA1-IC,TBD    I23 @BASEBOARD_FAB2_LIB.BASEBOARD_FAB2(SCH_1):PAGE63
  U2D1 AR26 RSVD<191> SKX_EXT_B_BGA1-IC,TBD    I23 @BASEBOARD_FAB2_LIB.BASEBOARD_FAB2(SCH_1):PAGE63
  U2D1 AR22 RSVD<192> SKX_EXT_B_BGA1-IC,TBD    I23 @BASEBOARD_FAB2_LIB.BASEBOARD_FAB2(SCH_1):PAGE63
  U2D1 AR20 RSVD<193> SKX_EXT_B_BGA1-IC,TBD    I23 @BASEBOARD_FAB2_LIB.BASEBOARD_FAB2(SCH_1):PAGE63
  U2D1 CH23 RSVD<92> SKX_EXT_B_BGA1-IC,TBD     I9 @BASEBOARD_FAB2_LIB.BASEBOARD_FAB2(SCH_1):PAGE70
  U2D1 CH21 RSVD<93> SKX_EXT_B_BGA1-IC,TBD     I9 @BASEBOARD_FAB2_LIB.BASEBOARD_FAB2(SCH_1):PAGE70
  U2D1 CG26 RSVD<96> SKX_EXT_B_BGA1-IC,TBD     I9 @BASEBOARD_FAB2_LIB.BASEBOARD_FAB2(SCH_1):PAGE70
  U2D1 CG20 RSVD<98> SKX_EXT_B_BGA1-IC,TBD     I9 @BASEBOARD_FAB2_LIB.BASEBOARD_FAB2(SCH_1):PAGE70
  U2D1 CF23 RSVD<102> SKX_EXT_B_BGA1-IC,TBD     I9 @BASEBOARD_FAB2_LIB.BASEBOARD_FAB2(SCH_1):PAGE70
  U2D1 CF21 RSVD<103> SKX_EXT_B_BGA1-IC,TBD     I9 @BASEBOARD_FAB2_LIB.BASEBOARD_FAB2(SCH_1):PAGE70
  U2D1 CF19 RSVD<104> SKX_EXT_B_BGA1-IC,TBD     I9 @BASEBOARD_FAB2_LIB.BASEBOARD_FAB2(SCH_1):PAGE70
  U2D1 CE22 RSVD<107> SKX_EXT_B_BGA1-IC,TBD     I9 @BASEBOARD_FAB2_LIB.BASEBOARD_FAB2(SCH_1):PAGE70
  U2D1 CD21 RSVD<109> SKX_EXT_B_BGA1-IC,TBD     I9 @BASEBOARD_FAB2_LIB.BASEBOARD_FAB2(SCH_1):PAGE70
  U2D1 CD19 RSVD<110> SKX_EXT_B_BGA1-IC,TBD     I9 @BASEBOARD_FAB2_LIB.BASEBOARD_FAB2(SCH_1):PAGE70
  U2D1 CC20 RSVD<112> SKX_EXT_B_BGA1-IC,TBD     I9 @BASEBOARD_FAB2_LIB.BASEBOARD_FAB2(SCH_1):PAGE70
  U2D1 CB21 RSVD<115> SKX_EXT_B_BGA1-IC,TBD     I9 @BASEBOARD_FAB2_LIB.BASEBOARD_FAB2(SCH_1):PAGE70
  U2D1 CB19 RSVD<116> SKX_EXT_B_BGA1-IC,TBD     I9 @BASEBOARD_FAB2_LIB.BASEBOARD_FAB2(SCH_1):PAGE70
  U2D1 CA22 RSVD<118> SKX_EXT_B_BGA1-IC,TBD     I9 @BASEBOARD_FAB2_LIB.BASEBOARD_FAB2(SCH_1):PAGE70
  U2D1 BY19 RSVD<120> SKX_EXT_B_BGA1-IC,TBD     I9 @BASEBOARD_FAB2_LIB.BASEBOARD_FAB2(SCH_1):PAGE70
  U2D1 BW20 RSVD<122> SKX_EXT_B_BGA1-IC,TBD     I9 @BASEBOARD_FAB2_LIB.BASEBOARD_FAB2(SCH_1):PAGE70
  U2D1 BV21 RSVD<125> SKX_EXT_B_BGA1-IC,TBD     I9 @BASEBOARD_FAB2_LIB.BASEBOARD_FAB2(SCH_1):PAGE70
  U2D1 BV19 RSVD<126> SKX_EXT_B_BGA1-IC,TBD     I9 @BASEBOARD_FAB2_LIB.BASEBOARD_FAB2(SCH_1):PAGE70
  U2D1 BU22 RSVD<127> SKX_EXT_B_BGA1-IC,TBD     I9 @BASEBOARD_FAB2_LIB.BASEBOARD_FAB2(SCH_1):PAGE70
  U2D1 BU20 RSVD<128> SKX_EXT_B_BGA1-IC,TBD     I9 @BASEBOARD_FAB2_LIB.BASEBOARD_FAB2(SCH_1):PAGE70
  U2D1 BR24 RSVD<130> SKX_EXT_B_BGA1-IC,TBD     I9 @BASEBOARD_FAB2_LIB.BASEBOARD_FAB2(SCH_1):PAGE70
  U2D1 BR22 RSVD<131> SKX_EXT_B_BGA1-IC,TBD     I9 @BASEBOARD_FAB2_LIB.BASEBOARD_FAB2(SCH_1):PAGE70
  U2D1 BP21 RSVD<132> SKX_EXT_B_BGA1-IC,TBD     I9 @BASEBOARD_FAB2_LIB.BASEBOARD_FAB2(SCH_1):PAGE70
  U2D1 BM19 RSVD<135> SKX_EXT_B_BGA1-IC,TBD     I9 @BASEBOARD_FAB2_LIB.BASEBOARD_FAB2(SCH_1):PAGE70
  U2D1 BL20 RSVD<137> SKX_EXT_B_BGA1-IC,TBD     I9 @BASEBOARD_FAB2_LIB.BASEBOARD_FAB2(SCH_1):PAGE70
  U2D1 BK17 RSVD<139> SKX_EXT_B_BGA1-IC,TBD     I9 @BASEBOARD_FAB2_LIB.BASEBOARD_FAB2(SCH_1):PAGE70
  U2D1 BJ20 RSVD<140> SKX_EXT_B_BGA1-IC,TBD     I9 @BASEBOARD_FAB2_LIB.BASEBOARD_FAB2(SCH_1):PAGE70
  U2D1 BJ18 RSVD<141> SKX_EXT_B_BGA1-IC,TBD     I9 @BASEBOARD_FAB2_LIB.BASEBOARD_FAB2(SCH_1):PAGE70
  U2D1 BJ16 RSVD<142> SKX_EXT_B_BGA1-IC,TBD     I9 @BASEBOARD_FAB2_LIB.BASEBOARD_FAB2(SCH_1):PAGE70
  U2D1 BH19 RSVD<143> SKX_EXT_B_BGA1-IC,TBD     I9 @BASEBOARD_FAB2_LIB.BASEBOARD_FAB2(SCH_1):PAGE70
  U2D1 CL24 RSVD<81> SKX_EXT_B_BGA1-IC,TBD    I10 @BASEBOARD_FAB2_LIB.BASEBOARD_FAB2(SCH_1):PAGE70
  U2D1 CK25 RSVD<83> SKX_EXT_B_BGA1-IC,TBD    I10 @BASEBOARD_FAB2_LIB.BASEBOARD_FAB2(SCH_1):PAGE70
  U2D1 CK23 RSVD<84> SKX_EXT_B_BGA1-IC,TBD    I10 @BASEBOARD_FAB2_LIB.BASEBOARD_FAB2(SCH_1):PAGE70
  U2D1 CJ26 RSVD<86> SKX_EXT_B_BGA1-IC,TBD    I10 @BASEBOARD_FAB2_LIB.BASEBOARD_FAB2(SCH_1):PAGE70
  U2D1 CJ24 RSVD<87> SKX_EXT_B_BGA1-IC,TBD    I10 @BASEBOARD_FAB2_LIB.BASEBOARD_FAB2(SCH_1):PAGE70
  U2D1 CJ22 RSVD<88> SKX_EXT_B_BGA1-IC,TBD    I10 @BASEBOARD_FAB2_LIB.BASEBOARD_FAB2(SCH_1):PAGE70
  U2D1 CJ20 RSVD<89> SKX_EXT_B_BGA1-IC,TBD    I10 @BASEBOARD_FAB2_LIB.BASEBOARD_FAB2(SCH_1):PAGE70
  U2D1 BL14 CD_VCC_CORE<0> SKX_EXT_B_BGA1-IC,TBD    I33 @BASEBOARD_FAB2_LIB.BASEBOARD_FAB2(SCH_1):PAGE72
  U2D1 BK15 CD_VCC_CORE<1> SKX_EXT_B_BGA1-IC,TBD    I33 @BASEBOARD_FAB2_LIB.BASEBOARD_FAB2(SCH_1):PAGE72
  U2D1 BK13 CD_VCC_CORE<2> SKX_EXT_B_BGA1-IC,TBD    I33 @BASEBOARD_FAB2_LIB.BASEBOARD_FAB2(SCH_1):PAGE72
  U2D1 BJ14 CD_VCC_CORE<3> SKX_EXT_B_BGA1-IC,TBD    I33 @BASEBOARD_FAB2_LIB.BASEBOARD_FAB2(SCH_1):PAGE72
  U2D1 BJ12 CD_VCC_CORE<4> SKX_EXT_B_BGA1-IC,TBD    I33 @BASEBOARD_FAB2_LIB.BASEBOARD_FAB2(SCH_1):PAGE72
  U2D1 BH13 CD_VCC_CORE<5> SKX_EXT_B_BGA1-IC,TBD    I33 @BASEBOARD_FAB2_LIB.BASEBOARD_FAB2(SCH_1):PAGE72
  U2D1 BG14 CD_VCC_CORE<6> SKX_EXT_B_BGA1-IC,TBD    I33 @BASEBOARD_FAB2_LIB.BASEBOARD_FAB2(SCH_1):PAGE72
  U2D1 BG12 CD_VCC_CORE<7> SKX_EXT_B_BGA1-IC,TBD    I33 @BASEBOARD_FAB2_LIB.BASEBOARD_FAB2(SCH_1):PAGE72
  U2D1 BF13 CD_VCC_CORE<8> SKX_EXT_B_BGA1-IC,TBD    I33 @BASEBOARD_FAB2_LIB.BASEBOARD_FAB2(SCH_1):PAGE72
  U2D1 BF11 CD_VCC_CORE<9> SKX_EXT_B_BGA1-IC,TBD    I33 @BASEBOARD_FAB2_LIB.BASEBOARD_FAB2(SCH_1):PAGE72
  U2D1 BE14 CD_VCC_CORE<10> SKX_EXT_B_BGA1-IC,TBD    I33 @BASEBOARD_FAB2_LIB.BASEBOARD_FAB2(SCH_1):PAGE72
  U2D1 BE12 CD_VCC_CORE<11> SKX_EXT_B_BGA1-IC,TBD    I33 @BASEBOARD_FAB2_LIB.BASEBOARD_FAB2(SCH_1):PAGE72
  U2D1 BD13 CD_VCC_CORE<12> SKX_EXT_B_BGA1-IC,TBD    I33 @BASEBOARD_FAB2_LIB.BASEBOARD_FAB2(SCH_1):PAGE72
  U2D1 DA24 RSVD<52> SKX_EXT_B_BGA1-IC,TBD   I107 @BASEBOARD_FAB2_LIB.BASEBOARD_FAB2(SCH_1):PAGE73
  U2D1 CY25 RSVD<58> SKX_EXT_B_BGA1-IC,TBD   I107 @BASEBOARD_FAB2_LIB.BASEBOARD_FAB2(SCH_1):PAGE73
  U2D1 CW24 RSVD<62> SKX_EXT_B_BGA1-IC,TBD   I107 @BASEBOARD_FAB2_LIB.BASEBOARD_FAB2(SCH_1):PAGE73
  U2D1 CV23 RSVD<65> SKX_EXT_B_BGA1-IC,TBD   I107 @BASEBOARD_FAB2_LIB.BASEBOARD_FAB2(SCH_1):PAGE73
  U2D1 CU24 RSVD<68> SKX_EXT_B_BGA1-IC,TBD   I107 @BASEBOARD_FAB2_LIB.BASEBOARD_FAB2(SCH_1):PAGE73
  U2D1 CT23 RSVD<71> SKX_EXT_B_BGA1-IC,TBD   I107 @BASEBOARD_FAB2_LIB.BASEBOARD_FAB2(SCH_1):PAGE73
  U2D1 CP23 RSVD<74> SKX_EXT_B_BGA1-IC,TBD   I107 @BASEBOARD_FAB2_LIB.BASEBOARD_FAB2(SCH_1):PAGE73
  U2D1 CN24 RSVD<76> SKX_EXT_B_BGA1-IC,TBD   I107 @BASEBOARD_FAB2_LIB.BASEBOARD_FAB2(SCH_1):PAGE73
  U2D1 CM25 RSVD<78> SKX_EXT_B_BGA1-IC,TBD   I107 @BASEBOARD_FAB2_LIB.BASEBOARD_FAB2(SCH_1):PAGE73
  U2D1 CM23 RSVD<79> SKX_EXT_B_BGA1-IC,TBD   I107 @BASEBOARD_FAB2_LIB.BASEBOARD_FAB2(SCH_1):PAGE73
  U2D1 CL26 RSVD<80> SKX_EXT_B_BGA1-IC,TBD   I107 @BASEBOARD_FAB2_LIB.BASEBOARD_FAB2(SCH_1):PAGE73
 C3D21    1      A CAP_A_0603V-22.0UF,4V,20%,X6S,A     I1 @BASEBOARD_FAB2_LIB.BASEBOARD_FAB2(SCH_1):PAGE76
  C3D5    1      A CAP_A_0603V-22.0UF,4V,20%,X6S,A     I3 @BASEBOARD_FAB2_LIB.BASEBOARD_FAB2(SCH_1):PAGE76
 C3D12    1      A CAP_A_0603V-22.0UF,4V,20%,X6S,A     I4 @BASEBOARD_FAB2_LIB.BASEBOARD_FAB2(SCH_1):PAGE76
  C3D4    1      A CAP_A_0603V-22.0UF,4V,20%,X6S,A     I5 @BASEBOARD_FAB2_LIB.BASEBOARD_FAB2(SCH_1):PAGE76
 C3D11    1      A CAP_A_0603V-22.0UF,4V,20%,X6S,A     I7 @BASEBOARD_FAB2_LIB.BASEBOARD_FAB2(SCH_1):PAGE76
 C3D13    1      A CAP_A_0603V-22.0UF,4V,20%,X6S,A     I8 @BASEBOARD_FAB2_LIB.BASEBOARD_FAB2(SCH_1):PAGE76
 C2D40    1      A CAP_A_0603V-22.0UF,4V,20%,X6S,A    I10 @BASEBOARD_FAB2_LIB.BASEBOARD_FAB2(SCH_1):PAGE76
  C3D7    1      A CAP_A_0603V-22.0UF,4V,20%,X6S,A   I164 @BASEBOARD_FAB2_LIB.BASEBOARD_FAB2(SCH_1):PAGE76
 C2D39    1      A CAP_A_0603V-22.0UF,4V,20%,X6S,A   I165 @BASEBOARD_FAB2_LIB.BASEBOARD_FAB2(SCH_1):PAGE76
 C3D17    1      A CAP_A_0603V-22.0UF,4V,20%,X6S,A   I166 @BASEBOARD_FAB2_LIB.BASEBOARD_FAB2(SCH_1):PAGE76
 C3D18    1      A CAP_A_0603V-22.0UF,4V,20%,X6S,A   I169 @BASEBOARD_FAB2_LIB.BASEBOARD_FAB2(SCH_1):PAGE76
  C3D6    1      A CAP_A_0603V-22.0UF,4V,20%,X6S,A   I170 @BASEBOARD_FAB2_LIB.BASEBOARD_FAB2(SCH_1):PAGE76
 C3D14    1      A CAP_A_0603V-22.0UF,4V,20%,X6S,A   I171 @BASEBOARD_FAB2_LIB.BASEBOARD_FAB2(SCH_1):PAGE76
 C3D10    1      A CAP_A_0603V-22.0UF,4V,20%,X6S,A   I196 @BASEBOARD_FAB2_LIB.BASEBOARD_FAB2(SCH_1):PAGE76
 C2D18    1      A CAP_A_0603V-22.0UF,4V,20%,X6S,A   I197 @BASEBOARD_FAB2_LIB.BASEBOARD_FAB2(SCH_1):PAGE76
 C2D28    1      A CAP_A_0603V-22.0UF,4V,20%,X6S,A   I198 @BASEBOARD_FAB2_LIB.BASEBOARD_FAB2(SCH_1):PAGE76
 C2D29    1      A CAP_A_0603V-22.0UF,4V,20%,X6S,A   I199 @BASEBOARD_FAB2_LIB.BASEBOARD_FAB2(SCH_1):PAGE76
 C3D20    1      A CAP_A_0603V-22.0UF,4V,20%,X6S,A   I207 @BASEBOARD_FAB2_LIB.BASEBOARD_FAB2(SCH_1):PAGE76
 C3D19    1      A CAP_A_0603V-22.0UF,4V,20%,X6S,A   I208 @BASEBOARD_FAB2_LIB.BASEBOARD_FAB2(SCH_1):PAGE76
  J4E1   A1   IOA1 SCONN120_H61426002_SM-CONN,H61A    I45 @BASEBOARD_FAB2_LIB.BASEBOARD_FAB2(SCH_1):PAGE193
  J4E1   A2   IOA2 SCONN120_H61426002_SM-CONN,H61A    I45 @BASEBOARD_FAB2_LIB.BASEBOARD_FAB2(SCH_1):PAGE193
  J4E1   A3   IOA3 SCONN120_H61426002_SM-CONN,H61A    I45 @BASEBOARD_FAB2_LIB.BASEBOARD_FAB2(SCH_1):PAGE193
  J4E1   A5   IOA5 SCONN120_H61426002_SM-CONN,H61A    I45 @BASEBOARD_FAB2_LIB.BASEBOARD_FAB2(SCH_1):PAGE193
  J4E1   A6   IOA6 SCONN120_H61426002_SM-CONN,H61A    I45 @BASEBOARD_FAB2_LIB.BASEBOARD_FAB2(SCH_1):PAGE193
  J4E1   A7   IOA7 SCONN120_H61426002_SM-CONN,H61A    I45 @BASEBOARD_FAB2_LIB.BASEBOARD_FAB2(SCH_1):PAGE193
  J4E1   A8   IOA8 SCONN120_H61426002_SM-CONN,H61A    I45 @BASEBOARD_FAB2_LIB.BASEBOARD_FAB2(SCH_1):PAGE193
  J4E1   A9   IOA9 SCONN120_H61426002_SM-CONN,H61A    I45 @BASEBOARD_FAB2_LIB.BASEBOARD_FAB2(SCH_1):PAGE193
  J4E1  A10  IOA10 SCONN120_H61426002_SM-CONN,H61A    I45 @BASEBOARD_FAB2_LIB.BASEBOARD_FAB2(SCH_1):PAGE193
  J4E1  A11  IOA11 SCONN120_H61426002_SM-CONN,H61A    I45 @BASEBOARD_FAB2_LIB.BASEBOARD_FAB2(SCH_1):PAGE193
  J4E1  A12  IOA12 SCONN120_H61426002_SM-CONN,H61A    I45 @BASEBOARD_FAB2_LIB.BASEBOARD_FAB2(SCH_1):PAGE193
  J4E1  A13  IOA13 SCONN120_H61426002_SM-CONN,H61A    I45 @BASEBOARD_FAB2_LIB.BASEBOARD_FAB2(SCH_1):PAGE193
  J4E1  A14  IOA14 SCONN120_H61426002_SM-CONN,H61A    I45 @BASEBOARD_FAB2_LIB.BASEBOARD_FAB2(SCH_1):PAGE193
  J4E1  A15  IOA15 SCONN120_H61426002_SM-CONN,H61A    I45 @BASEBOARD_FAB2_LIB.BASEBOARD_FAB2(SCH_1):PAGE193
  J4E1  A16  IOA16 SCONN120_H61426002_SM-CONN,H61A    I45 @BASEBOARD_FAB2_LIB.BASEBOARD_FAB2(SCH_1):PAGE193
  J4E1  A17  IOA17 SCONN120_H61426002_SM-CONN,H61A    I45 @BASEBOARD_FAB2_LIB.BASEBOARD_FAB2(SCH_1):PAGE193
  J4E1  A18  IOA18 SCONN120_H61426002_SM-CONN,H61A    I45 @BASEBOARD_FAB2_LIB.BASEBOARD_FAB2(SCH_1):PAGE193
  J4E1   B1   IOB1 SCONN120_H61426002_SM-CONN,H61A    I45 @BASEBOARD_FAB2_LIB.BASEBOARD_FAB2(SCH_1):PAGE193
  J4E1   B2   IOB2 SCONN120_H61426002_SM-CONN,H61A    I45 @BASEBOARD_FAB2_LIB.BASEBOARD_FAB2(SCH_1):PAGE193
  J4E1   B3   IOB3 SCONN120_H61426002_SM-CONN,H61A    I45 @BASEBOARD_FAB2_LIB.BASEBOARD_FAB2(SCH_1):PAGE193
  J4E1   B5   IOB5 SCONN120_H61426002_SM-CONN,H61A    I45 @BASEBOARD_FAB2_LIB.BASEBOARD_FAB2(SCH_1):PAGE193
  J4E1   B6   IOB6 SCONN120_H61426002_SM-CONN,H61A    I45 @BASEBOARD_FAB2_LIB.BASEBOARD_FAB2(SCH_1):PAGE193
  J4E1   B7   IOB7 SCONN120_H61426002_SM-CONN,H61A    I45 @BASEBOARD_FAB2_LIB.BASEBOARD_FAB2(SCH_1):PAGE193
  J4E1   B8   IOB8 SCONN120_H61426002_SM-CONN,H61A    I45 @BASEBOARD_FAB2_LIB.BASEBOARD_FAB2(SCH_1):PAGE193
  J4E1   B9   IOB9 SCONN120_H61426002_SM-CONN,H61A    I45 @BASEBOARD_FAB2_LIB.BASEBOARD_FAB2(SCH_1):PAGE193
  J4E1  B10  IOB10 SCONN120_H61426002_SM-CONN,H61A    I45 @BASEBOARD_FAB2_LIB.BASEBOARD_FAB2(SCH_1):PAGE193
  J4E1  B11  IOB11 SCONN120_H61426002_SM-CONN,H61A    I45 @BASEBOARD_FAB2_LIB.BASEBOARD_FAB2(SCH_1):PAGE193
  J4E1  B12  IOB12 SCONN120_H61426002_SM-CONN,H61A    I45 @BASEBOARD_FAB2_LIB.BASEBOARD_FAB2(SCH_1):PAGE193
  J4E1  B13  IOB13 SCONN120_H61426002_SM-CONN,H61A    I45 @BASEBOARD_FAB2_LIB.BASEBOARD_FAB2(SCH_1):PAGE193
  J4E1  B14  IOB14 SCONN120_H61426002_SM-CONN,H61A    I45 @BASEBOARD_FAB2_LIB.BASEBOARD_FAB2(SCH_1):PAGE193
  J4E1  B15  IOB15 SCONN120_H61426002_SM-CONN,H61A    I45 @BASEBOARD_FAB2_LIB.BASEBOARD_FAB2(SCH_1):PAGE193
  J4E1  B16  IOB16 SCONN120_H61426002_SM-CONN,H61A    I45 @BASEBOARD_FAB2_LIB.BASEBOARD_FAB2(SCH_1):PAGE193
  J4E1  B17  IOB17 SCONN120_H61426002_SM-CONN,H61A    I45 @BASEBOARD_FAB2_LIB.BASEBOARD_FAB2(SCH_1):PAGE193
  J4E1  B18  IOB18 SCONN120_H61426002_SM-CONN,H61A    I45 @BASEBOARD_FAB2_LIB.BASEBOARD_FAB2(SCH_1):PAGE193
  J4E1   C1   IOC1 SCONN120_H61426002_SM-CONN,H61A    I45 @BASEBOARD_FAB2_LIB.BASEBOARD_FAB2(SCH_1):PAGE193
  J4E1   C2   IOC2 SCONN120_H61426002_SM-CONN,H61A    I45 @BASEBOARD_FAB2_LIB.BASEBOARD_FAB2(SCH_1):PAGE193
  J4E1   C3   IOC3 SCONN120_H61426002_SM-CONN,H61A    I45 @BASEBOARD_FAB2_LIB.BASEBOARD_FAB2(SCH_1):PAGE193
  J4E1   C4   IOC4 SCONN120_H61426002_SM-CONN,H61A    I45 @BASEBOARD_FAB2_LIB.BASEBOARD_FAB2(SCH_1):PAGE193
  J4E1   C5   IOC5 SCONN120_H61426002_SM-CONN,H61A    I45 @BASEBOARD_FAB2_LIB.BASEBOARD_FAB2(SCH_1):PAGE193
  J4E1   C6   IOC6 SCONN120_H61426002_SM-CONN,H61A    I45 @BASEBOARD_FAB2_LIB.BASEBOARD_FAB2(SCH_1):PAGE193
  J4E1   C7   IOC7 SCONN120_H61426002_SM-CONN,H61A    I45 @BASEBOARD_FAB2_LIB.BASEBOARD_FAB2(SCH_1):PAGE193
  J4E1   C8   IOC8 SCONN120_H61426002_SM-CONN,H61A    I45 @BASEBOARD_FAB2_LIB.BASEBOARD_FAB2(SCH_1):PAGE193
  J4E1   C9   IOC9 SCONN120_H61426002_SM-CONN,H61A    I45 @BASEBOARD_FAB2_LIB.BASEBOARD_FAB2(SCH_1):PAGE193
  J4E1  C10  IOC10 SCONN120_H61426002_SM-CONN,H61A    I45 @BASEBOARD_FAB2_LIB.BASEBOARD_FAB2(SCH_1):PAGE193
  J4E1  C11  IOC11 SCONN120_H61426002_SM-CONN,H61A    I45 @BASEBOARD_FAB2_LIB.BASEBOARD_FAB2(SCH_1):PAGE193
  J4E1  C12  IOC12 SCONN120_H61426002_SM-CONN,H61A    I45 @BASEBOARD_FAB2_LIB.BASEBOARD_FAB2(SCH_1):PAGE193
  J4E1  C13  IOC13 SCONN120_H61426002_SM-CONN,H61A    I45 @BASEBOARD_FAB2_LIB.BASEBOARD_FAB2(SCH_1):PAGE193
  J4E1  C14  IOC14 SCONN120_H61426002_SM-CONN,H61A    I45 @BASEBOARD_FAB2_LIB.BASEBOARD_FAB2(SCH_1):PAGE193
  J4E1  C15  IOC15 SCONN120_H61426002_SM-CONN,H61A    I45 @BASEBOARD_FAB2_LIB.BASEBOARD_FAB2(SCH_1):PAGE193
  J4E1  C16  IOC16 SCONN120_H61426002_SM-CONN,H61A    I45 @BASEBOARD_FAB2_LIB.BASEBOARD_FAB2(SCH_1):PAGE193
  J4E1  C17  IOC17 SCONN120_H61426002_SM-CONN,H61A    I45 @BASEBOARD_FAB2_LIB.BASEBOARD_FAB2(SCH_1):PAGE193
  J4E1  C18  IOC18 SCONN120_H61426002_SM-CONN,H61A    I45 @BASEBOARD_FAB2_LIB.BASEBOARD_FAB2(SCH_1):PAGE193
 C4E24    1      A CAPP_3018-470UF,2.5V,20%,ALUM,A    I61 @BASEBOARD_FAB2_LIB.BASEBOARD_FAB2(SCH_1):PAGE193
 C6R16    1      A CAPP_3018-470UF,2.5V,20%,ALUM,A    I62 @BASEBOARD_FAB2_LIB.BASEBOARD_FAB2(SCH_1):PAGE193
  C3W4    1      A CAP_A_0603V-22.0UF,4V,20%,X6S,A   I254 @BASEBOARD_FAB2_LIB.BASEBOARD_FAB2(SCH_1):PAGE76
  C3W3    1      A CAP_A_0603V-22.0UF,4V,20%,X6S,A   I256 @BASEBOARD_FAB2_LIB.BASEBOARD_FAB2(SCH_1):PAGE76
 C4E29    1      A CAPP_3018-470UF,2.5V,20%,ALUM,A   I175 @BASEBOARD_FAB2_LIB.BASEBOARD_FAB2(SCH_1):PAGE193
  C7P9    1      A CAP_0805-100UF,4V,20%,X5R,6024A   I258 @BASEBOARD_FAB2_LIB.BASEBOARD_FAB2(SCH_1):PAGE76
  C7P5    1      A CAP_0805-100UF,4V,20%,X5R,6024A   I259 @BASEBOARD_FAB2_LIB.BASEBOARD_FAB2(SCH_1):PAGE76
 C8P23    1      A CAP_0805-100UF,4V,20%,X5R,6024A   I260 @BASEBOARD_FAB2_LIB.BASEBOARD_FAB2(SCH_1):PAGE76
 C7P14    1      A CAP_0805-100UF,4V,20%,X5R,6024A   I261 @BASEBOARD_FAB2_LIB.BASEBOARD_FAB2(SCH_1):PAGE76
 C7P11    1      A CAP_0805-100UF,4V,20%,X5R,6024A   I262 @BASEBOARD_FAB2_LIB.BASEBOARD_FAB2(SCH_1):PAGE76
 C7P15    1      A CAP_0805-100UF,4V,20%,X5R,6024A   I263 @BASEBOARD_FAB2_LIB.BASEBOARD_FAB2(SCH_1):PAGE76
 C8P22    1      A CAP_0805-100UF,4V,20%,X5R,6024A   I264 @BASEBOARD_FAB2_LIB.BASEBOARD_FAB2(SCH_1):PAGE76
  C7P8    1      A CAP_0805-100UF,4V,20%,X5R,6024A   I265 @BASEBOARD_FAB2_LIB.BASEBOARD_FAB2(SCH_1):PAGE76
 C7P10    1      A CAP_0805-100UF,4V,20%,X5R,6024A   I266 @BASEBOARD_FAB2_LIB.BASEBOARD_FAB2(SCH_1):PAGE76
  C7P7    1      A CAP_0805-100UF,4V,20%,X5R,6024A   I267 @BASEBOARD_FAB2_LIB.BASEBOARD_FAB2(SCH_1):PAGE76
  C7P6    1      A CAP_0805-100UF,4V,20%,X5R,6024A   I268 @BASEBOARD_FAB2_LIB.BASEBOARD_FAB2(SCH_1):PAGE76
 C7P13    1      A CAP_0805-100UF,4V,20%,X5R,6024A   I269 @BASEBOARD_FAB2_LIB.BASEBOARD_FAB2(SCH_1):PAGE76
 C8P15    1      A CAP_0805-100UF,4V,20%,X5R,6024A   I270 @BASEBOARD_FAB2_LIB.BASEBOARD_FAB2(SCH_1):PAGE76
  C7P4    1      A CAP_0805-100UF,4V,20%,X5R,6024A   I271 @BASEBOARD_FAB2_LIB.BASEBOARD_FAB2(SCH_1):PAGE76
 C8P14    1      A CAP_0805-100UF,4V,20%,X5R,6024A   I272 @BASEBOARD_FAB2_LIB.BASEBOARD_FAB2(SCH_1):PAGE76
  C8P9    1      A CAP_0805-100UF,4V,20%,X5R,6024A   I273 @BASEBOARD_FAB2_LIB.BASEBOARD_FAB2(SCH_1):PAGE76
  C8P8    1      A CAP_0805-100UF,4V,20%,X5R,6024A   I274 @BASEBOARD_FAB2_LIB.BASEBOARD_FAB2(SCH_1):PAGE76

PVDDQ_ABC @BASEBOARD_FAB2_LIB.BASEBOARD_FAB2(SCH_1):PVDDQ_ABC
  U5D1  B49 VCCD012<0> SKX_EXT_B_BGA1-IC,TBD    I33 @BASEBOARD_FAB2_LIB.BASEBOARD_FAB2(SCH_1):PAGE38
  U5D1  B53 VCCD012<1> SKX_EXT_B_BGA1-IC,TBD    I33 @BASEBOARD_FAB2_LIB.BASEBOARD_FAB2(SCH_1):PAGE38
  U5D1  B59 VCCD012<2> SKX_EXT_B_BGA1-IC,TBD    I33 @BASEBOARD_FAB2_LIB.BASEBOARD_FAB2(SCH_1):PAGE38
  U5D1  E46 VCCD012<3> SKX_EXT_B_BGA1-IC,TBD    I33 @BASEBOARD_FAB2_LIB.BASEBOARD_FAB2(SCH_1):PAGE38
  U5D1  E48 VCCD012<4> SKX_EXT_B_BGA1-IC,TBD    I33 @BASEBOARD_FAB2_LIB.BASEBOARD_FAB2(SCH_1):PAGE38
  U5D1  E50 VCCD012<5> SKX_EXT_B_BGA1-IC,TBD    I33 @BASEBOARD_FAB2_LIB.BASEBOARD_FAB2(SCH_1):PAGE38
  U5D1  E52 VCCD012<6> SKX_EXT_B_BGA1-IC,TBD    I33 @BASEBOARD_FAB2_LIB.BASEBOARD_FAB2(SCH_1):PAGE38
  U5D1  E54 VCCD012<7> SKX_EXT_B_BGA1-IC,TBD    I33 @BASEBOARD_FAB2_LIB.BASEBOARD_FAB2(SCH_1):PAGE38
  U5D1  E56 VCCD012<8> SKX_EXT_B_BGA1-IC,TBD    I33 @BASEBOARD_FAB2_LIB.BASEBOARD_FAB2(SCH_1):PAGE38
  U5D1  E58 VCCD012<9> SKX_EXT_B_BGA1-IC,TBD    I33 @BASEBOARD_FAB2_LIB.BASEBOARD_FAB2(SCH_1):PAGE38
  U5D1  E60 VCCD012<10> SKX_EXT_B_BGA1-IC,TBD    I33 @BASEBOARD_FAB2_LIB.BASEBOARD_FAB2(SCH_1):PAGE38
  U5D1  E62 VCCD012<11> SKX_EXT_B_BGA1-IC,TBD    I33 @BASEBOARD_FAB2_LIB.BASEBOARD_FAB2(SCH_1):PAGE38
  U5D1  E64 VCCD012<12> SKX_EXT_B_BGA1-IC,TBD    I33 @BASEBOARD_FAB2_LIB.BASEBOARD_FAB2(SCH_1):PAGE38
  U5D1  L46 VCCD012<13> SKX_EXT_B_BGA1-IC,TBD    I33 @BASEBOARD_FAB2_LIB.BASEBOARD_FAB2(SCH_1):PAGE38
  U5D1  L48 VCCD012<14> SKX_EXT_B_BGA1-IC,TBD    I33 @BASEBOARD_FAB2_LIB.BASEBOARD_FAB2(SCH_1):PAGE38
  U5D1  L50 VCCD012<15> SKX_EXT_B_BGA1-IC,TBD    I33 @BASEBOARD_FAB2_LIB.BASEBOARD_FAB2(SCH_1):PAGE38
  U5D1  L52 VCCD012<16> SKX_EXT_B_BGA1-IC,TBD    I33 @BASEBOARD_FAB2_LIB.BASEBOARD_FAB2(SCH_1):PAGE38
  U5D1  L54 VCCD012<17> SKX_EXT_B_BGA1-IC,TBD    I33 @BASEBOARD_FAB2_LIB.BASEBOARD_FAB2(SCH_1):PAGE38
  U5D1  L56 VCCD012<18> SKX_EXT_B_BGA1-IC,TBD    I33 @BASEBOARD_FAB2_LIB.BASEBOARD_FAB2(SCH_1):PAGE38
  U5D1  L58 VCCD012<19> SKX_EXT_B_BGA1-IC,TBD    I33 @BASEBOARD_FAB2_LIB.BASEBOARD_FAB2(SCH_1):PAGE38
  U5D1  L60 VCCD012<20> SKX_EXT_B_BGA1-IC,TBD    I33 @BASEBOARD_FAB2_LIB.BASEBOARD_FAB2(SCH_1):PAGE38
  U5D1  L62 VCCD012<21> SKX_EXT_B_BGA1-IC,TBD    I33 @BASEBOARD_FAB2_LIB.BASEBOARD_FAB2(SCH_1):PAGE38
  U5D1  N64 VCCD012<22> SKX_EXT_B_BGA1-IC,TBD    I33 @BASEBOARD_FAB2_LIB.BASEBOARD_FAB2(SCH_1):PAGE38
  U5D1  U46 VCCD012<23> SKX_EXT_B_BGA1-IC,TBD    I33 @BASEBOARD_FAB2_LIB.BASEBOARD_FAB2(SCH_1):PAGE38
  U5D1  U48 VCCD012<24> SKX_EXT_B_BGA1-IC,TBD    I33 @BASEBOARD_FAB2_LIB.BASEBOARD_FAB2(SCH_1):PAGE38
  U5D1  U50 VCCD012<25> SKX_EXT_B_BGA1-IC,TBD    I33 @BASEBOARD_FAB2_LIB.BASEBOARD_FAB2(SCH_1):PAGE38
  U5D1  U52 VCCD012<26> SKX_EXT_B_BGA1-IC,TBD    I33 @BASEBOARD_FAB2_LIB.BASEBOARD_FAB2(SCH_1):PAGE38
  U5D1  U54 VCCD012<27> SKX_EXT_B_BGA1-IC,TBD    I33 @BASEBOARD_FAB2_LIB.BASEBOARD_FAB2(SCH_1):PAGE38
  U5D1  U56 VCCD012<28> SKX_EXT_B_BGA1-IC,TBD    I33 @BASEBOARD_FAB2_LIB.BASEBOARD_FAB2(SCH_1):PAGE38
  U5D1  U58 VCCD012<29> SKX_EXT_B_BGA1-IC,TBD    I33 @BASEBOARD_FAB2_LIB.BASEBOARD_FAB2(SCH_1):PAGE38
  U5D1  U60 VCCD012<30> SKX_EXT_B_BGA1-IC,TBD    I33 @BASEBOARD_FAB2_LIB.BASEBOARD_FAB2(SCH_1):PAGE38
  U5D1  U62 VCCD012<31> SKX_EXT_B_BGA1-IC,TBD    I33 @BASEBOARD_FAB2_LIB.BASEBOARD_FAB2(SCH_1):PAGE38
  U5D1  W64 VCCD012<32> SKX_EXT_B_BGA1-IC,TBD    I33 @BASEBOARD_FAB2_LIB.BASEBOARD_FAB2(SCH_1):PAGE38
  U5D1  Y45 VCCD012<33> SKX_EXT_B_BGA1-IC,TBD    I33 @BASEBOARD_FAB2_LIB.BASEBOARD_FAB2(SCH_1):PAGE38
  U5D1  Y47 VCCD012<34> SKX_EXT_B_BGA1-IC,TBD    I33 @BASEBOARD_FAB2_LIB.BASEBOARD_FAB2(SCH_1):PAGE38
  U5D1  Y49 VCCD012<35> SKX_EXT_B_BGA1-IC,TBD    I33 @BASEBOARD_FAB2_LIB.BASEBOARD_FAB2(SCH_1):PAGE38
  U5D1  Y51 VCCD012<36> SKX_EXT_B_BGA1-IC,TBD    I33 @BASEBOARD_FAB2_LIB.BASEBOARD_FAB2(SCH_1):PAGE38
  U5D1  Y53 VCCD012<37> SKX_EXT_B_BGA1-IC,TBD    I33 @BASEBOARD_FAB2_LIB.BASEBOARD_FAB2(SCH_1):PAGE38
  U5D1  Y55 VCCD012<38> SKX_EXT_B_BGA1-IC,TBD    I33 @BASEBOARD_FAB2_LIB.BASEBOARD_FAB2(SCH_1):PAGE38
  U5D1  Y57 VCCD012<39> SKX_EXT_B_BGA1-IC,TBD    I33 @BASEBOARD_FAB2_LIB.BASEBOARD_FAB2(SCH_1):PAGE38
  U5D1  Y59 VCCD012<40> SKX_EXT_B_BGA1-IC,TBD    I33 @BASEBOARD_FAB2_LIB.BASEBOARD_FAB2(SCH_1):PAGE38
  U5D1  Y61 VCCD012<41> SKX_EXT_B_BGA1-IC,TBD    I33 @BASEBOARD_FAB2_LIB.BASEBOARD_FAB2(SCH_1):PAGE38
  U5D1  Y63 VCCD012<42> SKX_EXT_B_BGA1-IC,TBD    I33 @BASEBOARD_FAB2_LIB.BASEBOARD_FAB2(SCH_1):PAGE38
  U5D1 AD45 VCCD012<43> SKX_EXT_B_BGA1-IC,TBD    I33 @BASEBOARD_FAB2_LIB.BASEBOARD_FAB2(SCH_1):PAGE38
  U5D1 AF55 VCCD012<44> SKX_EXT_B_BGA1-IC,TBD    I33 @BASEBOARD_FAB2_LIB.BASEBOARD_FAB2(SCH_1):PAGE38
  U5D1 AF57 VCCD012<45> SKX_EXT_B_BGA1-IC,TBD    I33 @BASEBOARD_FAB2_LIB.BASEBOARD_FAB2(SCH_1):PAGE38
  U5D1 AF59 VCCD012<46> SKX_EXT_B_BGA1-IC,TBD    I33 @BASEBOARD_FAB2_LIB.BASEBOARD_FAB2(SCH_1):PAGE38
  U5D1 AF61 VCCD012<47> SKX_EXT_B_BGA1-IC,TBD    I33 @BASEBOARD_FAB2_LIB.BASEBOARD_FAB2(SCH_1):PAGE38
  U5D1 AF63 VCCD012<48> SKX_EXT_B_BGA1-IC,TBD    I33 @BASEBOARD_FAB2_LIB.BASEBOARD_FAB2(SCH_1):PAGE38
  U5D1  D45 VCCD012<49> SKX_EXT_B_BGA1-IC,TBD    I33 @BASEBOARD_FAB2_LIB.BASEBOARD_FAB2(SCH_1):PAGE38
  U5D1  C46 VCCD012<50> SKX_EXT_B_BGA1-IC,TBD    I33 @BASEBOARD_FAB2_LIB.BASEBOARD_FAB2(SCH_1):PAGE38
  U5D1  B47 VCCD012<51> SKX_EXT_B_BGA1-IC,TBD    I33 @BASEBOARD_FAB2_LIB.BASEBOARD_FAB2(SCH_1):PAGE38
  J4G1  236 VDD<0> SCONN288_H44441004_PIP-SCONN,HA   I260 @BASEBOARD_FAB2_LIB.BASEBOARD_FAB2(SCH_1):PAGE43
  J4G1  233 VDD<1> SCONN288_H44441004_PIP-SCONN,HA   I260 @BASEBOARD_FAB2_LIB.BASEBOARD_FAB2(SCH_1):PAGE43
  J4G1  231 VDD<2> SCONN288_H44441004_PIP-SCONN,HA   I260 @BASEBOARD_FAB2_LIB.BASEBOARD_FAB2(SCH_1):PAGE43
  J4G1  229 VDD<3> SCONN288_H44441004_PIP-SCONN,HA   I260 @BASEBOARD_FAB2_LIB.BASEBOARD_FAB2(SCH_1):PAGE43
  J4G1  226 VDD<4> SCONN288_H44441004_PIP-SCONN,HA   I260 @BASEBOARD_FAB2_LIB.BASEBOARD_FAB2(SCH_1):PAGE43
  J4G1  223 VDD<5> SCONN288_H44441004_PIP-SCONN,HA   I260 @BASEBOARD_FAB2_LIB.BASEBOARD_FAB2(SCH_1):PAGE43
  J4G1  220 VDD<6> SCONN288_H44441004_PIP-SCONN,HA   I260 @BASEBOARD_FAB2_LIB.BASEBOARD_FAB2(SCH_1):PAGE43
  J4G1  217 VDD<7> SCONN288_H44441004_PIP-SCONN,HA   I260 @BASEBOARD_FAB2_LIB.BASEBOARD_FAB2(SCH_1):PAGE43
  J4G1  215 VDD<8> SCONN288_H44441004_PIP-SCONN,HA   I260 @BASEBOARD_FAB2_LIB.BASEBOARD_FAB2(SCH_1):PAGE43
  J4G1  212 VDD<9> SCONN288_H44441004_PIP-SCONN,HA   I260 @BASEBOARD_FAB2_LIB.BASEBOARD_FAB2(SCH_1):PAGE43
  J4G1  209 VDD<10> SCONN288_H44441004_PIP-SCONN,HA   I260 @BASEBOARD_FAB2_LIB.BASEBOARD_FAB2(SCH_1):PAGE43
  J4G1  206 VDD<11> SCONN288_H44441004_PIP-SCONN,HA   I260 @BASEBOARD_FAB2_LIB.BASEBOARD_FAB2(SCH_1):PAGE43
  J4G1  204 VDD<12> SCONN288_H44441004_PIP-SCONN,HA   I260 @BASEBOARD_FAB2_LIB.BASEBOARD_FAB2(SCH_1):PAGE43
  J4G1   92 VDD<13> SCONN288_H44441004_PIP-SCONN,HA   I260 @BASEBOARD_FAB2_LIB.BASEBOARD_FAB2(SCH_1):PAGE43
  J4G1   90 VDD<14> SCONN288_H44441004_PIP-SCONN,HA   I260 @BASEBOARD_FAB2_LIB.BASEBOARD_FAB2(SCH_1):PAGE43
  J4G1   88 VDD<15> SCONN288_H44441004_PIP-SCONN,HA   I260 @BASEBOARD_FAB2_LIB.BASEBOARD_FAB2(SCH_1):PAGE43
  J4G1   85 VDD<16> SCONN288_H44441004_PIP-SCONN,HA   I260 @BASEBOARD_FAB2_LIB.BASEBOARD_FAB2(SCH_1):PAGE43
  J4G1   83 VDD<17> SCONN288_H44441004_PIP-SCONN,HA   I260 @BASEBOARD_FAB2_LIB.BASEBOARD_FAB2(SCH_1):PAGE43
  J4G1   80 VDD<18> SCONN288_H44441004_PIP-SCONN,HA   I260 @BASEBOARD_FAB2_LIB.BASEBOARD_FAB2(SCH_1):PAGE43
  J4G1   76 VDD<19> SCONN288_H44441004_PIP-SCONN,HA   I260 @BASEBOARD_FAB2_LIB.BASEBOARD_FAB2(SCH_1):PAGE43
  J4G1   73 VDD<20> SCONN288_H44441004_PIP-SCONN,HA   I260 @BASEBOARD_FAB2_LIB.BASEBOARD_FAB2(SCH_1):PAGE43
  J4G1   70 VDD<21> SCONN288_H44441004_PIP-SCONN,HA   I260 @BASEBOARD_FAB2_LIB.BASEBOARD_FAB2(SCH_1):PAGE43
  J4G1   67 VDD<22> SCONN288_H44441004_PIP-SCONN,HA   I260 @BASEBOARD_FAB2_LIB.BASEBOARD_FAB2(SCH_1):PAGE43
  J4G1   64 VDD<23> SCONN288_H44441004_PIP-SCONN,HA   I260 @BASEBOARD_FAB2_LIB.BASEBOARD_FAB2(SCH_1):PAGE43
  J4G1   61 VDD<24> SCONN288_H44441004_PIP-SCONN,HA   I260 @BASEBOARD_FAB2_LIB.BASEBOARD_FAB2(SCH_1):PAGE43
  J4G1   59 VDD<25> SCONN288_H44441004_PIP-SCONN,HA   I260 @BASEBOARD_FAB2_LIB.BASEBOARD_FAB2(SCH_1):PAGE43
  J6T1  236 VDD<0> SCONN288_H44441003_PIP-SCONN,HA    I75 @BASEBOARD_FAB2_LIB.BASEBOARD_FAB2(SCH_1):PAGE44
  J6T1  233 VDD<1> SCONN288_H44441003_PIP-SCONN,HA    I75 @BASEBOARD_FAB2_LIB.BASEBOARD_FAB2(SCH_1):PAGE44
  J6T1  231 VDD<2> SCONN288_H44441003_PIP-SCONN,HA    I75 @BASEBOARD_FAB2_LIB.BASEBOARD_FAB2(SCH_1):PAGE44
  J6T1  229 VDD<3> SCONN288_H44441003_PIP-SCONN,HA    I75 @BASEBOARD_FAB2_LIB.BASEBOARD_FAB2(SCH_1):PAGE44
  J6T1  226 VDD<4> SCONN288_H44441003_PIP-SCONN,HA    I75 @BASEBOARD_FAB2_LIB.BASEBOARD_FAB2(SCH_1):PAGE44
  J6T1  223 VDD<5> SCONN288_H44441003_PIP-SCONN,HA    I75 @BASEBOARD_FAB2_LIB.BASEBOARD_FAB2(SCH_1):PAGE44
  J6T1  220 VDD<6> SCONN288_H44441003_PIP-SCONN,HA    I75 @BASEBOARD_FAB2_LIB.BASEBOARD_FAB2(SCH_1):PAGE44
  J6T1  217 VDD<7> SCONN288_H44441003_PIP-SCONN,HA    I75 @BASEBOARD_FAB2_LIB.BASEBOARD_FAB2(SCH_1):PAGE44
  J6T1  215 VDD<8> SCONN288_H44441003_PIP-SCONN,HA    I75 @BASEBOARD_FAB2_LIB.BASEBOARD_FAB2(SCH_1):PAGE44
  J6T1  212 VDD<9> SCONN288_H44441003_PIP-SCONN,HA    I75 @BASEBOARD_FAB2_LIB.BASEBOARD_FAB2(SCH_1):PAGE44
  J6T1  209 VDD<10> SCONN288_H44441003_PIP-SCONN,HA    I75 @BASEBOARD_FAB2_LIB.BASEBOARD_FAB2(SCH_1):PAGE44
  J6T1  206 VDD<11> SCONN288_H44441003_PIP-SCONN,HA    I75 @BASEBOARD_FAB2_LIB.BASEBOARD_FAB2(SCH_1):PAGE44
  J6T1  204 VDD<12> SCONN288_H44441003_PIP-SCONN,HA    I75 @BASEBOARD_FAB2_LIB.BASEBOARD_FAB2(SCH_1):PAGE44
  J6T1   92 VDD<13> SCONN288_H44441003_PIP-SCONN,HA    I75 @BASEBOARD_FAB2_LIB.BASEBOARD_FAB2(SCH_1):PAGE44
  J6T1   90 VDD<14> SCONN288_H44441003_PIP-SCONN,HA    I75 @BASEBOARD_FAB2_LIB.BASEBOARD_FAB2(SCH_1):PAGE44
  J6T1   88 VDD<15> SCONN288_H44441003_PIP-SCONN,HA    I75 @BASEBOARD_FAB2_LIB.BASEBOARD_FAB2(SCH_1):PAGE44
  J6T1   85 VDD<16> SCONN288_H44441003_PIP-SCONN,HA    I75 @BASEBOARD_FAB2_LIB.BASEBOARD_FAB2(SCH_1):PAGE44
  J6T1   83 VDD<17> SCONN288_H44441003_PIP-SCONN,HA    I75 @BASEBOARD_FAB2_LIB.BASEBOARD_FAB2(SCH_1):PAGE44
  J6T1   80 VDD<18> SCONN288_H44441003_PIP-SCONN,HA    I75 @BASEBOARD_FAB2_LIB.BASEBOARD_FAB2(SCH_1):PAGE44
  J6T1   76 VDD<19> SCONN288_H44441003_PIP-SCONN,HA    I75 @BASEBOARD_FAB2_LIB.BASEBOARD_FAB2(SCH_1):PAGE44
  J6T1   73 VDD<20> SCONN288_H44441003_PIP-SCONN,HA    I75 @BASEBOARD_FAB2_LIB.BASEBOARD_FAB2(SCH_1):PAGE44
  J6T1   70 VDD<21> SCONN288_H44441003_PIP-SCONN,HA    I75 @BASEBOARD_FAB2_LIB.BASEBOARD_FAB2(SCH_1):PAGE44
  J6T1   67 VDD<22> SCONN288_H44441003_PIP-SCONN,HA    I75 @BASEBOARD_FAB2_LIB.BASEBOARD_FAB2(SCH_1):PAGE44
  J6T1   64 VDD<23> SCONN288_H44441003_PIP-SCONN,HA    I75 @BASEBOARD_FAB2_LIB.BASEBOARD_FAB2(SCH_1):PAGE44
  J6T1   61 VDD<24> SCONN288_H44441003_PIP-SCONN,HA    I75 @BASEBOARD_FAB2_LIB.BASEBOARD_FAB2(SCH_1):PAGE44
  J6T1   59 VDD<25> SCONN288_H44441003_PIP-SCONN,HA    I75 @BASEBOARD_FAB2_LIB.BASEBOARD_FAB2(SCH_1):PAGE44
  J4G2  236 VDD<0> SCONN288_H44441004_PIP-SCONN,HA   I169 @BASEBOARD_FAB2_LIB.BASEBOARD_FAB2(SCH_1):PAGE45
  J4G2  233 VDD<1> SCONN288_H44441004_PIP-SCONN,HA   I169 @BASEBOARD_FAB2_LIB.BASEBOARD_FAB2(SCH_1):PAGE45
  J4G2  231 VDD<2> SCONN288_H44441004_PIP-SCONN,HA   I169 @BASEBOARD_FAB2_LIB.BASEBOARD_FAB2(SCH_1):PAGE45
  J4G2  229 VDD<3> SCONN288_H44441004_PIP-SCONN,HA   I169 @BASEBOARD_FAB2_LIB.BASEBOARD_FAB2(SCH_1):PAGE45
  J4G2  226 VDD<4> SCONN288_H44441004_PIP-SCONN,HA   I169 @BASEBOARD_FAB2_LIB.BASEBOARD_FAB2(SCH_1):PAGE45
  J4G2  223 VDD<5> SCONN288_H44441004_PIP-SCONN,HA   I169 @BASEBOARD_FAB2_LIB.BASEBOARD_FAB2(SCH_1):PAGE45
  J4G2  220 VDD<6> SCONN288_H44441004_PIP-SCONN,HA   I169 @BASEBOARD_FAB2_LIB.BASEBOARD_FAB2(SCH_1):PAGE45
  J4G2  217 VDD<7> SCONN288_H44441004_PIP-SCONN,HA   I169 @BASEBOARD_FAB2_LIB.BASEBOARD_FAB2(SCH_1):PAGE45
  J4G2  215 VDD<8> SCONN288_H44441004_PIP-SCONN,HA   I169 @BASEBOARD_FAB2_LIB.BASEBOARD_FAB2(SCH_1):PAGE45
  J4G2  212 VDD<9> SCONN288_H44441004_PIP-SCONN,HA   I169 @BASEBOARD_FAB2_LIB.BASEBOARD_FAB2(SCH_1):PAGE45
  J4G2  209 VDD<10> SCONN288_H44441004_PIP-SCONN,HA   I169 @BASEBOARD_FAB2_LIB.BASEBOARD_FAB2(SCH_1):PAGE45
  J4G2  206 VDD<11> SCONN288_H44441004_PIP-SCONN,HA   I169 @BASEBOARD_FAB2_LIB.BASEBOARD_FAB2(SCH_1):PAGE45
  J4G2  204 VDD<12> SCONN288_H44441004_PIP-SCONN,HA   I169 @BASEBOARD_FAB2_LIB.BASEBOARD_FAB2(SCH_1):PAGE45
  J4G2   92 VDD<13> SCONN288_H44441004_PIP-SCONN,HA   I169 @BASEBOARD_FAB2_LIB.BASEBOARD_FAB2(SCH_1):PAGE45
  J4G2   90 VDD<14> SCONN288_H44441004_PIP-SCONN,HA   I169 @BASEBOARD_FAB2_LIB.BASEBOARD_FAB2(SCH_1):PAGE45
  J4G2   88 VDD<15> SCONN288_H44441004_PIP-SCONN,HA   I169 @BASEBOARD_FAB2_LIB.BASEBOARD_FAB2(SCH_1):PAGE45
  J4G2   85 VDD<16> SCONN288_H44441004_PIP-SCONN,HA   I169 @BASEBOARD_FAB2_LIB.BASEBOARD_FAB2(SCH_1):PAGE45
  J4G2   83 VDD<17> SCONN288_H44441004_PIP-SCONN,HA   I169 @BASEBOARD_FAB2_LIB.BASEBOARD_FAB2(SCH_1):PAGE45
  J4G2   80 VDD<18> SCONN288_H44441004_PIP-SCONN,HA   I169 @BASEBOARD_FAB2_LIB.BASEBOARD_FAB2(SCH_1):PAGE45
  J4G2   76 VDD<19> SCONN288_H44441004_PIP-SCONN,HA   I169 @BASEBOARD_FAB2_LIB.BASEBOARD_FAB2(SCH_1):PAGE45
  J4G2   73 VDD<20> SCONN288_H44441004_PIP-SCONN,HA   I169 @BASEBOARD_FAB2_LIB.BASEBOARD_FAB2(SCH_1):PAGE45
  J4G2   70 VDD<21> SCONN288_H44441004_PIP-SCONN,HA   I169 @BASEBOARD_FAB2_LIB.BASEBOARD_FAB2(SCH_1):PAGE45
  J4G2   67 VDD<22> SCONN288_H44441004_PIP-SCONN,HA   I169 @BASEBOARD_FAB2_LIB.BASEBOARD_FAB2(SCH_1):PAGE45
  J4G2   64 VDD<23> SCONN288_H44441004_PIP-SCONN,HA   I169 @BASEBOARD_FAB2_LIB.BASEBOARD_FAB2(SCH_1):PAGE45
  J4G2   61 VDD<24> SCONN288_H44441004_PIP-SCONN,HA   I169 @BASEBOARD_FAB2_LIB.BASEBOARD_FAB2(SCH_1):PAGE45
  J4G2   59 VDD<25> SCONN288_H44441004_PIP-SCONN,HA   I169 @BASEBOARD_FAB2_LIB.BASEBOARD_FAB2(SCH_1):PAGE45
  J6U1  236 VDD<0> SCONN288_H44441003_PIP-SCONN,HA    I67 @BASEBOARD_FAB2_LIB.BASEBOARD_FAB2(SCH_1):PAGE46
  J6U1  233 VDD<1> SCONN288_H44441003_PIP-SCONN,HA    I67 @BASEBOARD_FAB2_LIB.BASEBOARD_FAB2(SCH_1):PAGE46
  J6U1  231 VDD<2> SCONN288_H44441003_PIP-SCONN,HA    I67 @BASEBOARD_FAB2_LIB.BASEBOARD_FAB2(SCH_1):PAGE46
  J6U1  229 VDD<3> SCONN288_H44441003_PIP-SCONN,HA    I67 @BASEBOARD_FAB2_LIB.BASEBOARD_FAB2(SCH_1):PAGE46
  J6U1  226 VDD<4> SCONN288_H44441003_PIP-SCONN,HA    I67 @BASEBOARD_FAB2_LIB.BASEBOARD_FAB2(SCH_1):PAGE46
  J6U1  223 VDD<5> SCONN288_H44441003_PIP-SCONN,HA    I67 @BASEBOARD_FAB2_LIB.BASEBOARD_FAB2(SCH_1):PAGE46
  J6U1  220 VDD<6> SCONN288_H44441003_PIP-SCONN,HA    I67 @BASEBOARD_FAB2_LIB.BASEBOARD_FAB2(SCH_1):PAGE46
  J6U1  217 VDD<7> SCONN288_H44441003_PIP-SCONN,HA    I67 @BASEBOARD_FAB2_LIB.BASEBOARD_FAB2(SCH_1):PAGE46
  J6U1  215 VDD<8> SCONN288_H44441003_PIP-SCONN,HA    I67 @BASEBOARD_FAB2_LIB.BASEBOARD_FAB2(SCH_1):PAGE46
  J6U1  212 VDD<9> SCONN288_H44441003_PIP-SCONN,HA    I67 @BASEBOARD_FAB2_LIB.BASEBOARD_FAB2(SCH_1):PAGE46
  J6U1  209 VDD<10> SCONN288_H44441003_PIP-SCONN,HA    I67 @BASEBOARD_FAB2_LIB.BASEBOARD_FAB2(SCH_1):PAGE46
  J6U1  206 VDD<11> SCONN288_H44441003_PIP-SCONN,HA    I67 @BASEBOARD_FAB2_LIB.BASEBOARD_FAB2(SCH_1):PAGE46
  J6U1  204 VDD<12> SCONN288_H44441003_PIP-SCONN,HA    I67 @BASEBOARD_FAB2_LIB.BASEBOARD_FAB2(SCH_1):PAGE46
  J6U1   92 VDD<13> SCONN288_H44441003_PIP-SCONN,HA    I67 @BASEBOARD_FAB2_LIB.BASEBOARD_FAB2(SCH_1):PAGE46
  J6U1   90 VDD<14> SCONN288_H44441003_PIP-SCONN,HA    I67 @BASEBOARD_FAB2_LIB.BASEBOARD_FAB2(SCH_1):PAGE46
  J6U1   88 VDD<15> SCONN288_H44441003_PIP-SCONN,HA    I67 @BASEBOARD_FAB2_LIB.BASEBOARD_FAB2(SCH_1):PAGE46
  J6U1   85 VDD<16> SCONN288_H44441003_PIP-SCONN,HA    I67 @BASEBOARD_FAB2_LIB.BASEBOARD_FAB2(SCH_1):PAGE46
  J6U1   83 VDD<17> SCONN288_H44441003_PIP-SCONN,HA    I67 @BASEBOARD_FAB2_LIB.BASEBOARD_FAB2(SCH_1):PAGE46
  J6U1   80 VDD<18> SCONN288_H44441003_PIP-SCONN,HA    I67 @BASEBOARD_FAB2_LIB.BASEBOARD_FAB2(SCH_1):PAGE46
  J6U1   76 VDD<19> SCONN288_H44441003_PIP-SCONN,HA    I67 @BASEBOARD_FAB2_LIB.BASEBOARD_FAB2(SCH_1):PAGE46
  J6U1   73 VDD<20> SCONN288_H44441003_PIP-SCONN,HA    I67 @BASEBOARD_FAB2_LIB.BASEBOARD_FAB2(SCH_1):PAGE46
  J6U1   70 VDD<21> SCONN288_H44441003_PIP-SCONN,HA    I67 @BASEBOARD_FAB2_LIB.BASEBOARD_FAB2(SCH_1):PAGE46
  J6U1   67 VDD<22> SCONN288_H44441003_PIP-SCONN,HA    I67 @BASEBOARD_FAB2_LIB.BASEBOARD_FAB2(SCH_1):PAGE46
  J6U1   64 VDD<23> SCONN288_H44441003_PIP-SCONN,HA    I67 @BASEBOARD_FAB2_LIB.BASEBOARD_FAB2(SCH_1):PAGE46
  J6U1   61 VDD<24> SCONN288_H44441003_PIP-SCONN,HA    I67 @BASEBOARD_FAB2_LIB.BASEBOARD_FAB2(SCH_1):PAGE46
  J6U1   59 VDD<25> SCONN288_H44441003_PIP-SCONN,HA    I67 @BASEBOARD_FAB2_LIB.BASEBOARD_FAB2(SCH_1):PAGE46
  J4G3  236 VDD<0> SCONN288_H44441004_PIP-SCONN,HA   I179 @BASEBOARD_FAB2_LIB.BASEBOARD_FAB2(SCH_1):PAGE47
  J4G3  233 VDD<1> SCONN288_H44441004_PIP-SCONN,HA   I179 @BASEBOARD_FAB2_LIB.BASEBOARD_FAB2(SCH_1):PAGE47
  J4G3  231 VDD<2> SCONN288_H44441004_PIP-SCONN,HA   I179 @BASEBOARD_FAB2_LIB.BASEBOARD_FAB2(SCH_1):PAGE47
  J4G3  229 VDD<3> SCONN288_H44441004_PIP-SCONN,HA   I179 @BASEBOARD_FAB2_LIB.BASEBOARD_FAB2(SCH_1):PAGE47
  J4G3  226 VDD<4> SCONN288_H44441004_PIP-SCONN,HA   I179 @BASEBOARD_FAB2_LIB.BASEBOARD_FAB2(SCH_1):PAGE47
  J4G3  223 VDD<5> SCONN288_H44441004_PIP-SCONN,HA   I179 @BASEBOARD_FAB2_LIB.BASEBOARD_FAB2(SCH_1):PAGE47
  J4G3  220 VDD<6> SCONN288_H44441004_PIP-SCONN,HA   I179 @BASEBOARD_FAB2_LIB.BASEBOARD_FAB2(SCH_1):PAGE47
  J4G3  217 VDD<7> SCONN288_H44441004_PIP-SCONN,HA   I179 @BASEBOARD_FAB2_LIB.BASEBOARD_FAB2(SCH_1):PAGE47
  J4G3  215 VDD<8> SCONN288_H44441004_PIP-SCONN,HA   I179 @BASEBOARD_FAB2_LIB.BASEBOARD_FAB2(SCH_1):PAGE47
  J4G3  212 VDD<9> SCONN288_H44441004_PIP-SCONN,HA   I179 @BASEBOARD_FAB2_LIB.BASEBOARD_FAB2(SCH_1):PAGE47
  J4G3  209 VDD<10> SCONN288_H44441004_PIP-SCONN,HA   I179 @BASEBOARD_FAB2_LIB.BASEBOARD_FAB2(SCH_1):PAGE47
  J4G3  206 VDD<11> SCONN288_H44441004_PIP-SCONN,HA   I179 @BASEBOARD_FAB2_LIB.BASEBOARD_FAB2(SCH_1):PAGE47
  J4G3  204 VDD<12> SCONN288_H44441004_PIP-SCONN,HA   I179 @BASEBOARD_FAB2_LIB.BASEBOARD_FAB2(SCH_1):PAGE47
  J4G3   92 VDD<13> SCONN288_H44441004_PIP-SCONN,HA   I179 @BASEBOARD_FAB2_LIB.BASEBOARD_FAB2(SCH_1):PAGE47
  J4G3   90 VDD<14> SCONN288_H44441004_PIP-SCONN,HA   I179 @BASEBOARD_FAB2_LIB.BASEBOARD_FAB2(SCH_1):PAGE47
  J4G3   88 VDD<15> SCONN288_H44441004_PIP-SCONN,HA   I179 @BASEBOARD_FAB2_LIB.BASEBOARD_FAB2(SCH_1):PAGE47
  J4G3   85 VDD<16> SCONN288_H44441004_PIP-SCONN,HA   I179 @BASEBOARD_FAB2_LIB.BASEBOARD_FAB2(SCH_1):PAGE47
  J4G3   83 VDD<17> SCONN288_H44441004_PIP-SCONN,HA   I179 @BASEBOARD_FAB2_LIB.BASEBOARD_FAB2(SCH_1):PAGE47
  J4G3   80 VDD<18> SCONN288_H44441004_PIP-SCONN,HA   I179 @BASEBOARD_FAB2_LIB.BASEBOARD_FAB2(SCH_1):PAGE47
  J4G3   76 VDD<19> SCONN288_H44441004_PIP-SCONN,HA   I179 @BASEBOARD_FAB2_LIB.BASEBOARD_FAB2(SCH_1):PAGE47
  J4G3   73 VDD<20> SCONN288_H44441004_PIP-SCONN,HA   I179 @BASEBOARD_FAB2_LIB.BASEBOARD_FAB2(SCH_1):PAGE47
  J4G3   70 VDD<21> SCONN288_H44441004_PIP-SCONN,HA   I179 @BASEBOARD_FAB2_LIB.BASEBOARD_FAB2(SCH_1):PAGE47
  J4G3   67 VDD<22> SCONN288_H44441004_PIP-SCONN,HA   I179 @BASEBOARD_FAB2_LIB.BASEBOARD_FAB2(SCH_1):PAGE47
  J4G3   64 VDD<23> SCONN288_H44441004_PIP-SCONN,HA   I179 @BASEBOARD_FAB2_LIB.BASEBOARD_FAB2(SCH_1):PAGE47
  J4G3   61 VDD<24> SCONN288_H44441004_PIP-SCONN,HA   I179 @BASEBOARD_FAB2_LIB.BASEBOARD_FAB2(SCH_1):PAGE47
  J4G3   59 VDD<25> SCONN288_H44441004_PIP-SCONN,HA   I179 @BASEBOARD_FAB2_LIB.BASEBOARD_FAB2(SCH_1):PAGE47
  J6U2  236 VDD<0> SCONN288_H44441003_PIP-SCONN,HA   I171 @BASEBOARD_FAB2_LIB.BASEBOARD_FAB2(SCH_1):PAGE48
  J6U2  233 VDD<1> SCONN288_H44441003_PIP-SCONN,HA   I171 @BASEBOARD_FAB2_LIB.BASEBOARD_FAB2(SCH_1):PAGE48
  J6U2  231 VDD<2> SCONN288_H44441003_PIP-SCONN,HA   I171 @BASEBOARD_FAB2_LIB.BASEBOARD_FAB2(SCH_1):PAGE48
  J6U2  229 VDD<3> SCONN288_H44441003_PIP-SCONN,HA   I171 @BASEBOARD_FAB2_LIB.BASEBOARD_FAB2(SCH_1):PAGE48
  J6U2  226 VDD<4> SCONN288_H44441003_PIP-SCONN,HA   I171 @BASEBOARD_FAB2_LIB.BASEBOARD_FAB2(SCH_1):PAGE48
  J6U2  223 VDD<5> SCONN288_H44441003_PIP-SCONN,HA   I171 @BASEBOARD_FAB2_LIB.BASEBOARD_FAB2(SCH_1):PAGE48
  J6U2  220 VDD<6> SCONN288_H44441003_PIP-SCONN,HA   I171 @BASEBOARD_FAB2_LIB.BASEBOARD_FAB2(SCH_1):PAGE48
  J6U2  217 VDD<7> SCONN288_H44441003_PIP-SCONN,HA   I171 @BASEBOARD_FAB2_LIB.BASEBOARD_FAB2(SCH_1):PAGE48
  J6U2  215 VDD<8> SCONN288_H44441003_PIP-SCONN,HA   I171 @BASEBOARD_FAB2_LIB.BASEBOARD_FAB2(SCH_1):PAGE48
  J6U2  212 VDD<9> SCONN288_H44441003_PIP-SCONN,HA   I171 @BASEBOARD_FAB2_LIB.BASEBOARD_FAB2(SCH_1):PAGE48
  J6U2  209 VDD<10> SCONN288_H44441003_PIP-SCONN,HA   I171 @BASEBOARD_FAB2_LIB.BASEBOARD_FAB2(SCH_1):PAGE48
  J6U2  206 VDD<11> SCONN288_H44441003_PIP-SCONN,HA   I171 @BASEBOARD_FAB2_LIB.BASEBOARD_FAB2(SCH_1):PAGE48
  J6U2  204 VDD<12> SCONN288_H44441003_PIP-SCONN,HA   I171 @BASEBOARD_FAB2_LIB.BASEBOARD_FAB2(SCH_1):PAGE48
  J6U2   92 VDD<13> SCONN288_H44441003_PIP-SCONN,HA   I171 @BASEBOARD_FAB2_LIB.BASEBOARD_FAB2(SCH_1):PAGE48
  J6U2   90 VDD<14> SCONN288_H44441003_PIP-SCONN,HA   I171 @BASEBOARD_FAB2_LIB.BASEBOARD_FAB2(SCH_1):PAGE48
  J6U2   88 VDD<15> SCONN288_H44441003_PIP-SCONN,HA   I171 @BASEBOARD_FAB2_LIB.BASEBOARD_FAB2(SCH_1):PAGE48
  J6U2   85 VDD<16> SCONN288_H44441003_PIP-SCONN,HA   I171 @BASEBOARD_FAB2_LIB.BASEBOARD_FAB2(SCH_1):PAGE48
  J6U2   83 VDD<17> SCONN288_H44441003_PIP-SCONN,HA   I171 @BASEBOARD_FAB2_LIB.BASEBOARD_FAB2(SCH_1):PAGE48
  J6U2   80 VDD<18> SCONN288_H44441003_PIP-SCONN,HA   I171 @BASEBOARD_FAB2_LIB.BASEBOARD_FAB2(SCH_1):PAGE48
  J6U2   76 VDD<19> SCONN288_H44441003_PIP-SCONN,HA   I171 @BASEBOARD_FAB2_LIB.BASEBOARD_FAB2(SCH_1):PAGE48
  J6U2   73 VDD<20> SCONN288_H44441003_PIP-SCONN,HA   I171 @BASEBOARD_FAB2_LIB.BASEBOARD_FAB2(SCH_1):PAGE48
  J6U2   70 VDD<21> SCONN288_H44441003_PIP-SCONN,HA   I171 @BASEBOARD_FAB2_LIB.BASEBOARD_FAB2(SCH_1):PAGE48
  J6U2   67 VDD<22> SCONN288_H44441003_PIP-SCONN,HA   I171 @BASEBOARD_FAB2_LIB.BASEBOARD_FAB2(SCH_1):PAGE48
  J6U2   64 VDD<23> SCONN288_H44441003_PIP-SCONN,HA   I171 @BASEBOARD_FAB2_LIB.BASEBOARD_FAB2(SCH_1):PAGE48
  J6U2   61 VDD<24> SCONN288_H44441003_PIP-SCONN,HA   I171 @BASEBOARD_FAB2_LIB.BASEBOARD_FAB2(SCH_1):PAGE48
  J6U2   59 VDD<25> SCONN288_H44441003_PIP-SCONN,HA   I171 @BASEBOARD_FAB2_LIB.BASEBOARD_FAB2(SCH_1):PAGE48
 R3P38    1      A RES_0402-64.9,1.0%,1/16W,CHIP,A     I7 @BASEBOARD_FAB2_LIB.BASEBOARD_FAB2(SCH_1):PAGE96
  R4F4    1      A RES_0402-1.00K,1%,1/16W,CHIP,GA    I36 @BASEBOARD_FAB2_LIB.BASEBOARD_FAB2(SCH_1):PAGE98
  R4G2    1      A RES_0402-1.00K,1%,1/16W,CHIP,GA    I38 @BASEBOARD_FAB2_LIB.BASEBOARD_FAB2(SCH_1):PAGE98
 R4G21    1      A RES_0402-1.00K,1%,1/16W,CHIP,GA    I46 @BASEBOARD_FAB2_LIB.BASEBOARD_FAB2(SCH_1):PAGE98
  C6G3    1      A CAP_0805LF-22UF,4V,20%,X6S,C95A     I6 @BASEBOARD_FAB2_LIB.BASEBOARD_FAB2(SCH_1):PAGE216
 C7G27    1      A CAP_0805LF-22UF,4V,20%,X6S,C95A    I68 @BASEBOARD_FAB2_LIB.BASEBOARD_FAB2(SCH_1):PAGE216
 EU7G2    1    VOS IR354XX_SM-IR35411,IC,H73688-0A   I102 @BASEBOARD_FAB2_LIB.BASEBOARD_FAB2(SCH_1):PAGE216
 EU7G3    1    VOS IR354XX_SM-IR35411,IC,H73688-0A   I103 @BASEBOARD_FAB2_LIB.BASEBOARD_FAB2(SCH_1):PAGE216
  R3U4    1      A RES_0603-120.0,1%,1/10W,CHIP,GA    I58 @BASEBOARD_FAB2_LIB.BASEBOARD_FAB2(SCH_1):PAGE217
 C7G28    1      A CAPP_3018-470UF,2.5V,20%,ALUM,A    I75 @BASEBOARD_FAB2_LIB.BASEBOARD_FAB2(SCH_1):PAGE217
  C3U1    1      A CAPP_3018-470UF,2.5V,20%,ALUM,A    I76 @BASEBOARD_FAB2_LIB.BASEBOARD_FAB2(SCH_1):PAGE217
  C3U5    1      A CAPP_3018-470UF,2.5V,20%,ALUM,A    I77 @BASEBOARD_FAB2_LIB.BASEBOARD_FAB2(SCH_1):PAGE217
  C3U8    1      A CAPP_3018-470UF,2.5V,20%,ALUM,A    I78 @BASEBOARD_FAB2_LIB.BASEBOARD_FAB2(SCH_1):PAGE217
  C5F2    1      A CAP_A_0603V-47UF,4V,20%,X5R,60A   I205 @BASEBOARD_FAB2_LIB.BASEBOARD_FAB2(SCH_1):PAGE217
  C5F1    1      A CAP_A_0603V-47UF,4V,20%,X5R,60A   I206 @BASEBOARD_FAB2_LIB.BASEBOARD_FAB2(SCH_1):PAGE217
 C5G10    1      A CAP_A_0603V-47UF,4V,20%,X5R,60A   I207 @BASEBOARD_FAB2_LIB.BASEBOARD_FAB2(SCH_1):PAGE217
  C5T2    1      A CAP_A_0603V-47UF,4V,20%,X5R,60A   I208 @BASEBOARD_FAB2_LIB.BASEBOARD_FAB2(SCH_1):PAGE217
 C5U11    1      A CAP_A_0603V-47UF,4V,20%,X5R,60A   I209 @BASEBOARD_FAB2_LIB.BASEBOARD_FAB2(SCH_1):PAGE217
 C5T13    1      A CAP_A_0603V-47UF,4V,20%,X5R,60A   I210 @BASEBOARD_FAB2_LIB.BASEBOARD_FAB2(SCH_1):PAGE217
  C5T4    1      A CAP_A_0603V-47UF,4V,20%,X5R,60A   I211 @BASEBOARD_FAB2_LIB.BASEBOARD_FAB2(SCH_1):PAGE217
  C5T1    1      A CAP_A_0603V-47UF,4V,20%,X5R,60A   I212 @BASEBOARD_FAB2_LIB.BASEBOARD_FAB2(SCH_1):PAGE217
 C5G19    1      A CAP_A_0603V-47UF,4V,20%,X5R,60A   I213 @BASEBOARD_FAB2_LIB.BASEBOARD_FAB2(SCH_1):PAGE217
 SH4U2    2      B SHUNT_SH0201-EMPTY,N_A   I260 @BASEBOARD_FAB2_LIB.BASEBOARD_FAB2(SCH_1):PAGE217
 C5G41    1      A CAP_A_0603V-22.0UF,4V,20%,X6S,A    I53 @BASEBOARD_FAB2_LIB.BASEBOARD_FAB2(SCH_1):PAGE242
 C5G42    1      A CAP_A_0603V-22.0UF,4V,20%,X6S,A    I54 @BASEBOARD_FAB2_LIB.BASEBOARD_FAB2(SCH_1):PAGE242
 C5G44    1      A CAP_A_0603V-22.0UF,4V,20%,X6S,A    I55 @BASEBOARD_FAB2_LIB.BASEBOARD_FAB2(SCH_1):PAGE242
 C5G43    1      A CAP_A_0603V-22.0UF,4V,20%,X6S,A    I56 @BASEBOARD_FAB2_LIB.BASEBOARD_FAB2(SCH_1):PAGE242
 C5G48    1      A CAP_A_0603V-22.0UF,4V,20%,X6S,A    I57 @BASEBOARD_FAB2_LIB.BASEBOARD_FAB2(SCH_1):PAGE242
 C5G47    1      A CAP_A_0603V-22.0UF,4V,20%,X6S,A    I58 @BASEBOARD_FAB2_LIB.BASEBOARD_FAB2(SCH_1):PAGE242
 C5G46    1      A CAP_A_0603V-22.0UF,4V,20%,X6S,A    I59 @BASEBOARD_FAB2_LIB.BASEBOARD_FAB2(SCH_1):PAGE242
 C5G45    1      A CAP_A_0603V-22.0UF,4V,20%,X6S,A    I60 @BASEBOARD_FAB2_LIB.BASEBOARD_FAB2(SCH_1):PAGE242
 C5G49    1      A CAP_A_0603V-22.0UF,4V,20%,X6S,A    I61 @BASEBOARD_FAB2_LIB.BASEBOARD_FAB2(SCH_1):PAGE242
 C5G54    1      A CAP_A_0603V-22.0UF,4V,20%,X6S,A    I62 @BASEBOARD_FAB2_LIB.BASEBOARD_FAB2(SCH_1):PAGE242
 C5G58    1      A CAP_A_0603V-22.0UF,4V,20%,X6S,A    I63 @BASEBOARD_FAB2_LIB.BASEBOARD_FAB2(SCH_1):PAGE242
 C5G57    1      A CAP_A_0603V-22.0UF,4V,20%,X6S,A    I64 @BASEBOARD_FAB2_LIB.BASEBOARD_FAB2(SCH_1):PAGE242
 C5G56    1      A CAP_A_0603V-22.0UF,4V,20%,X6S,A    I65 @BASEBOARD_FAB2_LIB.BASEBOARD_FAB2(SCH_1):PAGE242
 C5G55    1      A CAP_A_0603V-22.0UF,4V,20%,X6S,A    I66 @BASEBOARD_FAB2_LIB.BASEBOARD_FAB2(SCH_1):PAGE242
 C5G53    1      A CAP_A_0603V-22.0UF,4V,20%,X6S,A    I67 @BASEBOARD_FAB2_LIB.BASEBOARD_FAB2(SCH_1):PAGE242
 C5G52    1      A CAP_A_0603V-22.0UF,4V,20%,X6S,A    I68 @BASEBOARD_FAB2_LIB.BASEBOARD_FAB2(SCH_1):PAGE242
 C5G51    1      A CAP_A_0603V-22.0UF,4V,20%,X6S,A    I69 @BASEBOARD_FAB2_LIB.BASEBOARD_FAB2(SCH_1):PAGE242
 C5G50    1      A CAP_A_0603V-22.0UF,4V,20%,X6S,A    I70 @BASEBOARD_FAB2_LIB.BASEBOARD_FAB2(SCH_1):PAGE242
 C5G22    1      A CAP_0805-47UF,4V,20%,X6S,C9533A    I90 @BASEBOARD_FAB2_LIB.BASEBOARD_FAB2(SCH_1):PAGE242
 C5G21    1      A CAP_0805-47UF,4V,20%,X6S,C9533A    I92 @BASEBOARD_FAB2_LIB.BASEBOARD_FAB2(SCH_1):PAGE242
  R6U5    1      A RES_0402-0.0,5%,1/16W,CHIP,G21A     I6 @BASEBOARD_FAB2_LIB.BASEBOARD_FAB2(SCH_1):PAGE221
 C6U15    1      A CAP_0603LF-10UF,4V,20%,X6S,E15A    I18 @BASEBOARD_FAB2_LIB.BASEBOARD_FAB2(SCH_1):PAGE221
 C6U16    1      A CAP_0603LF-10UF,4V,20%,X6S,E15A    I19 @BASEBOARD_FAB2_LIB.BASEBOARD_FAB2(SCH_1):PAGE221
 EU4G3   10    VIN MIC5166_DFN-IC,H55101-001    I15 @BASEBOARD_FAB2_LIB.BASEBOARD_FAB2(SCH_1):PAGE221
 C5D58    1      A CAP_A_0603V-22.0UF,4V,20%,X6S,A   I269 @BASEBOARD_FAB2_LIB.BASEBOARD_FAB2(SCH_1):PAGE217
 C5D61    1      A CAP_A_0603V-22.0UF,4V,20%,X6S,A   I270 @BASEBOARD_FAB2_LIB.BASEBOARD_FAB2(SCH_1):PAGE217
 C5D59    1      A CAP_A_0603V-22.0UF,4V,20%,X6S,A   I271 @BASEBOARD_FAB2_LIB.BASEBOARD_FAB2(SCH_1):PAGE217
 C5D60    1      A CAP_A_0603V-22.0UF,4V,20%,X6S,A   I272 @BASEBOARD_FAB2_LIB.BASEBOARD_FAB2(SCH_1):PAGE217
 C5D54    1      A CAP_A_0603V-22.0UF,4V,20%,X6S,A   I279 @BASEBOARD_FAB2_LIB.BASEBOARD_FAB2(SCH_1):PAGE217
 C5D55    1      A CAP_A_0603V-22.0UF,4V,20%,X6S,A   I280 @BASEBOARD_FAB2_LIB.BASEBOARD_FAB2(SCH_1):PAGE217
 C5D56    1      A CAP_A_0603V-22.0UF,4V,20%,X6S,A   I281 @BASEBOARD_FAB2_LIB.BASEBOARD_FAB2(SCH_1):PAGE217
 C5D57    1      A CAP_A_0603V-22.0UF,4V,20%,X6S,A   I282 @BASEBOARD_FAB2_LIB.BASEBOARD_FAB2(SCH_1):PAGE217
  C5U2    1      A CAP_A_0603V-47UF,4V,20%,X5R,60A   I283 @BASEBOARD_FAB2_LIB.BASEBOARD_FAB2(SCH_1):PAGE217
  C5U3    1      A CAP_A_0603V-47UF,4V,20%,X5R,60A   I284 @BASEBOARD_FAB2_LIB.BASEBOARD_FAB2(SCH_1):PAGE217
  C5U4    1      A CAP_A_0603V-47UF,4V,20%,X5R,60A   I285 @BASEBOARD_FAB2_LIB.BASEBOARD_FAB2(SCH_1):PAGE217
  C5U5    1      A CAP_A_0603V-47UF,4V,20%,X5R,60A   I286 @BASEBOARD_FAB2_LIB.BASEBOARD_FAB2(SCH_1):PAGE217
  C5U6    1      A CAP_A_0603V-47UF,4V,20%,X5R,60A   I287 @BASEBOARD_FAB2_LIB.BASEBOARD_FAB2(SCH_1):PAGE217
  C5U7    1      A CAP_A_0603V-47UF,4V,20%,X5R,60A   I288 @BASEBOARD_FAB2_LIB.BASEBOARD_FAB2(SCH_1):PAGE217
  C5U8    1      A CAP_A_0603V-47UF,4V,20%,X5R,60A   I289 @BASEBOARD_FAB2_LIB.BASEBOARD_FAB2(SCH_1):PAGE217
  C5U9    1      A CAP_A_0603V-47UF,4V,20%,X5R,60A   I290 @BASEBOARD_FAB2_LIB.BASEBOARD_FAB2(SCH_1):PAGE217
 C5T12    1      A CAP_A_0603V-47UF,4V,20%,X5R,60A   I291 @BASEBOARD_FAB2_LIB.BASEBOARD_FAB2(SCH_1):PAGE217
 C5T11    1      A CAP_A_0603V-47UF,4V,20%,X5R,60A   I292 @BASEBOARD_FAB2_LIB.BASEBOARD_FAB2(SCH_1):PAGE217
 C5T10    1      A CAP_A_0603V-47UF,4V,20%,X5R,60A   I293 @BASEBOARD_FAB2_LIB.BASEBOARD_FAB2(SCH_1):PAGE217
  C5T9    1      A CAP_A_0603V-47UF,4V,20%,X5R,60A   I294 @BASEBOARD_FAB2_LIB.BASEBOARD_FAB2(SCH_1):PAGE217
  C5T8    1      A CAP_A_0603V-47UF,4V,20%,X5R,60A   I295 @BASEBOARD_FAB2_LIB.BASEBOARD_FAB2(SCH_1):PAGE217
  C5T7    1      A CAP_A_0603V-47UF,4V,20%,X5R,60A   I296 @BASEBOARD_FAB2_LIB.BASEBOARD_FAB2(SCH_1):PAGE217
  C5T6    1      A CAP_A_0603V-47UF,4V,20%,X5R,60A   I297 @BASEBOARD_FAB2_LIB.BASEBOARD_FAB2(SCH_1):PAGE217
  C5T5    1      A CAP_A_0603V-47UF,4V,20%,X5R,60A   I298 @BASEBOARD_FAB2_LIB.BASEBOARD_FAB2(SCH_1):PAGE217
 C5G11    1      A CAP_A_0603V-47UF,4V,20%,X5R,60A   I299 @BASEBOARD_FAB2_LIB.BASEBOARD_FAB2(SCH_1):PAGE217
 C5G12    1      A CAP_A_0603V-47UF,4V,20%,X5R,60A   I300 @BASEBOARD_FAB2_LIB.BASEBOARD_FAB2(SCH_1):PAGE217
  C5G2    1      A CAP_A_0603V-47UF,4V,20%,X5R,60A   I301 @BASEBOARD_FAB2_LIB.BASEBOARD_FAB2(SCH_1):PAGE217
  C5G4    1      A CAP_A_0603V-47UF,4V,20%,X5R,60A   I302 @BASEBOARD_FAB2_LIB.BASEBOARD_FAB2(SCH_1):PAGE217
 C5G13    1      A CAP_A_0603V-47UF,4V,20%,X5R,60A   I303 @BASEBOARD_FAB2_LIB.BASEBOARD_FAB2(SCH_1):PAGE217
  C5G6    1      A CAP_A_0603V-47UF,4V,20%,X5R,60A   I304 @BASEBOARD_FAB2_LIB.BASEBOARD_FAB2(SCH_1):PAGE217
  C5G5    1      A CAP_A_0603V-47UF,4V,20%,X5R,60A   I305 @BASEBOARD_FAB2_LIB.BASEBOARD_FAB2(SCH_1):PAGE217
  C5G7    1      A CAP_A_0603V-47UF,4V,20%,X5R,60A   I306 @BASEBOARD_FAB2_LIB.BASEBOARD_FAB2(SCH_1):PAGE217
  C5G1    1      A CAP_A_0603V-47UF,4V,20%,X5R,60A   I307 @BASEBOARD_FAB2_LIB.BASEBOARD_FAB2(SCH_1):PAGE217
  C5G8    1      A CAP_A_0603V-47UF,4V,20%,X5R,60A   I308 @BASEBOARD_FAB2_LIB.BASEBOARD_FAB2(SCH_1):PAGE217
 C5G18    1      A CAP_A_0603V-47UF,4V,20%,X5R,60A   I309 @BASEBOARD_FAB2_LIB.BASEBOARD_FAB2(SCH_1):PAGE217
 C5G17    1      A CAP_A_0603V-47UF,4V,20%,X5R,60A   I310 @BASEBOARD_FAB2_LIB.BASEBOARD_FAB2(SCH_1):PAGE217
 C5G14    1      A CAP_A_0603V-47UF,4V,20%,X5R,60A   I311 @BASEBOARD_FAB2_LIB.BASEBOARD_FAB2(SCH_1):PAGE217
 C5G16    1      A CAP_A_0603V-47UF,4V,20%,X5R,60A   I312 @BASEBOARD_FAB2_LIB.BASEBOARD_FAB2(SCH_1):PAGE217
 C5G15    1      A CAP_A_0603V-47UF,4V,20%,X5R,60A   I313 @BASEBOARD_FAB2_LIB.BASEBOARD_FAB2(SCH_1):PAGE217
  C5G3    1      A CAP_A_0603V-47UF,4V,20%,X5R,60A   I314 @BASEBOARD_FAB2_LIB.BASEBOARD_FAB2(SCH_1):PAGE217
  L7G1    2      F IND-120NH-30-GP_DISCRET-GB2-INA   I153 @BASEBOARD_FAB2_LIB.BASEBOARD_FAB2(SCH_1):PAGE216
  C5U1    1      A CAP_0805-100UF,4V,20%,X5R,6024A   I316 @BASEBOARD_FAB2_LIB.BASEBOARD_FAB2(SCH_1):PAGE217
 C5U10    1      A CAP_0805-100UF,4V,20%,X5R,6024A   I317 @BASEBOARD_FAB2_LIB.BASEBOARD_FAB2(SCH_1):PAGE217
  C5G9    1      A CAP_0805-100UF,4V,20%,X5R,6024A   I318 @BASEBOARD_FAB2_LIB.BASEBOARD_FAB2(SCH_1):PAGE217
  C4T4    1      A CAP_0805-100UF,4V,20%,X5R,6024A   I319 @BASEBOARD_FAB2_LIB.BASEBOARD_FAB2(SCH_1):PAGE217
 C5U15    1      A CAP_0805-100UF,4V,20%,X5R,6024A   I320 @BASEBOARD_FAB2_LIB.BASEBOARD_FAB2(SCH_1):PAGE217
 C5U13    1      A CAP_0805-100UF,4V,20%,X5R,6024A   I321 @BASEBOARD_FAB2_LIB.BASEBOARD_FAB2(SCH_1):PAGE217
 C5U14    1      A CAP_0805-100UF,4V,20%,X5R,6024A   I322 @BASEBOARD_FAB2_LIB.BASEBOARD_FAB2(SCH_1):PAGE217
 C5P41    1      A CAP_0805-100UF,4V,20%,X5R,6024A   I323 @BASEBOARD_FAB2_LIB.BASEBOARD_FAB2(SCH_1):PAGE217
 C5P44    1      A CAP_0805-100UF,4V,20%,X5R,6024A   I324 @BASEBOARD_FAB2_LIB.BASEBOARD_FAB2(SCH_1):PAGE217
 C5P42    1      A CAP_0805-100UF,4V,20%,X5R,6024A   I325 @BASEBOARD_FAB2_LIB.BASEBOARD_FAB2(SCH_1):PAGE217
 C5P43    1      A CAP_0805-100UF,4V,20%,X5R,6024A   I326 @BASEBOARD_FAB2_LIB.BASEBOARD_FAB2(SCH_1):PAGE217
 C5P38    1      A CAP_0805-100UF,4V,20%,X5R,6024A   I327 @BASEBOARD_FAB2_LIB.BASEBOARD_FAB2(SCH_1):PAGE217
 C5P39    1      A CAP_0805-100UF,4V,20%,X5R,6024A   I328 @BASEBOARD_FAB2_LIB.BASEBOARD_FAB2(SCH_1):PAGE217
 C5G20    1      A CAP_0805-100UF,4V,20%,X5R,6024A   I329 @BASEBOARD_FAB2_LIB.BASEBOARD_FAB2(SCH_1):PAGE217
  L7G2    2      F IND-120NH-30-GP_DISCRET-GB2-INA   I155 @BASEBOARD_FAB2_LIB.BASEBOARD_FAB2(SCH_1):PAGE216

PVDDQ_DEF @BASEBOARD_FAB2_LIB.BASEBOARD_FAB2(SCH_1):PVDDQ_DEF
  U5D1 EF59 VCCD345<0> SKX_EXT_B_BGA1-IC,TBD    I33 @BASEBOARD_FAB2_LIB.BASEBOARD_FAB2(SCH_1):PAGE38
  U5D1 EF53 VCCD345<1> SKX_EXT_B_BGA1-IC,TBD    I33 @BASEBOARD_FAB2_LIB.BASEBOARD_FAB2(SCH_1):PAGE38
  U5D1 EF49 VCCD345<2> SKX_EXT_B_BGA1-IC,TBD    I33 @BASEBOARD_FAB2_LIB.BASEBOARD_FAB2(SCH_1):PAGE38
  U5D1 EC62 VCCD345<3> SKX_EXT_B_BGA1-IC,TBD    I33 @BASEBOARD_FAB2_LIB.BASEBOARD_FAB2(SCH_1):PAGE38
  U5D1 EC60 VCCD345<4> SKX_EXT_B_BGA1-IC,TBD    I33 @BASEBOARD_FAB2_LIB.BASEBOARD_FAB2(SCH_1):PAGE38
  U5D1 EC58 VCCD345<5> SKX_EXT_B_BGA1-IC,TBD    I33 @BASEBOARD_FAB2_LIB.BASEBOARD_FAB2(SCH_1):PAGE38
  U5D1 EC56 VCCD345<6> SKX_EXT_B_BGA1-IC,TBD    I33 @BASEBOARD_FAB2_LIB.BASEBOARD_FAB2(SCH_1):PAGE38
  U5D1 EC54 VCCD345<7> SKX_EXT_B_BGA1-IC,TBD    I33 @BASEBOARD_FAB2_LIB.BASEBOARD_FAB2(SCH_1):PAGE38
  U5D1 EC52 VCCD345<8> SKX_EXT_B_BGA1-IC,TBD    I33 @BASEBOARD_FAB2_LIB.BASEBOARD_FAB2(SCH_1):PAGE38
  U5D1 EC50 VCCD345<9> SKX_EXT_B_BGA1-IC,TBD    I33 @BASEBOARD_FAB2_LIB.BASEBOARD_FAB2(SCH_1):PAGE38
  U5D1 EC48 VCCD345<10> SKX_EXT_B_BGA1-IC,TBD    I33 @BASEBOARD_FAB2_LIB.BASEBOARD_FAB2(SCH_1):PAGE38
  U5D1 EC46 VCCD345<11> SKX_EXT_B_BGA1-IC,TBD    I33 @BASEBOARD_FAB2_LIB.BASEBOARD_FAB2(SCH_1):PAGE38
  U5D1 DU64 VCCD345<12> SKX_EXT_B_BGA1-IC,TBD    I33 @BASEBOARD_FAB2_LIB.BASEBOARD_FAB2(SCH_1):PAGE38
  U5D1 DU62 VCCD345<13> SKX_EXT_B_BGA1-IC,TBD    I33 @BASEBOARD_FAB2_LIB.BASEBOARD_FAB2(SCH_1):PAGE38
  U5D1 DU60 VCCD345<14> SKX_EXT_B_BGA1-IC,TBD    I33 @BASEBOARD_FAB2_LIB.BASEBOARD_FAB2(SCH_1):PAGE38
  U5D1 DU58 VCCD345<15> SKX_EXT_B_BGA1-IC,TBD    I33 @BASEBOARD_FAB2_LIB.BASEBOARD_FAB2(SCH_1):PAGE38
  U5D1 DU56 VCCD345<16> SKX_EXT_B_BGA1-IC,TBD    I33 @BASEBOARD_FAB2_LIB.BASEBOARD_FAB2(SCH_1):PAGE38
  U5D1 DU54 VCCD345<17> SKX_EXT_B_BGA1-IC,TBD    I33 @BASEBOARD_FAB2_LIB.BASEBOARD_FAB2(SCH_1):PAGE38
  U5D1 DU52 VCCD345<18> SKX_EXT_B_BGA1-IC,TBD    I33 @BASEBOARD_FAB2_LIB.BASEBOARD_FAB2(SCH_1):PAGE38
  U5D1 DU50 VCCD345<19> SKX_EXT_B_BGA1-IC,TBD    I33 @BASEBOARD_FAB2_LIB.BASEBOARD_FAB2(SCH_1):PAGE38
  U5D1 DU48 VCCD345<20> SKX_EXT_B_BGA1-IC,TBD    I33 @BASEBOARD_FAB2_LIB.BASEBOARD_FAB2(SCH_1):PAGE38
  U5D1 DU46 VCCD345<21> SKX_EXT_B_BGA1-IC,TBD    I33 @BASEBOARD_FAB2_LIB.BASEBOARD_FAB2(SCH_1):PAGE38
  U5D1 DL62 VCCD345<22> SKX_EXT_B_BGA1-IC,TBD    I33 @BASEBOARD_FAB2_LIB.BASEBOARD_FAB2(SCH_1):PAGE38
  U5D1 DL60 VCCD345<23> SKX_EXT_B_BGA1-IC,TBD    I33 @BASEBOARD_FAB2_LIB.BASEBOARD_FAB2(SCH_1):PAGE38
  U5D1 DL58 VCCD345<24> SKX_EXT_B_BGA1-IC,TBD    I33 @BASEBOARD_FAB2_LIB.BASEBOARD_FAB2(SCH_1):PAGE38
  U5D1 DL56 VCCD345<25> SKX_EXT_B_BGA1-IC,TBD    I33 @BASEBOARD_FAB2_LIB.BASEBOARD_FAB2(SCH_1):PAGE38
  U5D1 DL54 VCCD345<26> SKX_EXT_B_BGA1-IC,TBD    I33 @BASEBOARD_FAB2_LIB.BASEBOARD_FAB2(SCH_1):PAGE38
  U5D1 DL52 VCCD345<27> SKX_EXT_B_BGA1-IC,TBD    I33 @BASEBOARD_FAB2_LIB.BASEBOARD_FAB2(SCH_1):PAGE38
  U5D1 DL50 VCCD345<28> SKX_EXT_B_BGA1-IC,TBD    I33 @BASEBOARD_FAB2_LIB.BASEBOARD_FAB2(SCH_1):PAGE38
  U5D1 DL48 VCCD345<29> SKX_EXT_B_BGA1-IC,TBD    I33 @BASEBOARD_FAB2_LIB.BASEBOARD_FAB2(SCH_1):PAGE38
  U5D1 DL46 VCCD345<30> SKX_EXT_B_BGA1-IC,TBD    I33 @BASEBOARD_FAB2_LIB.BASEBOARD_FAB2(SCH_1):PAGE38
  U5D1 DJ64 VCCD345<31> SKX_EXT_B_BGA1-IC,TBD    I33 @BASEBOARD_FAB2_LIB.BASEBOARD_FAB2(SCH_1):PAGE38
  U5D1 DH63 VCCD345<32> SKX_EXT_B_BGA1-IC,TBD    I33 @BASEBOARD_FAB2_LIB.BASEBOARD_FAB2(SCH_1):PAGE38
  U5D1 DH61 VCCD345<33> SKX_EXT_B_BGA1-IC,TBD    I33 @BASEBOARD_FAB2_LIB.BASEBOARD_FAB2(SCH_1):PAGE38
  U5D1 DH59 VCCD345<34> SKX_EXT_B_BGA1-IC,TBD    I33 @BASEBOARD_FAB2_LIB.BASEBOARD_FAB2(SCH_1):PAGE38
  U5D1 DH57 VCCD345<35> SKX_EXT_B_BGA1-IC,TBD    I33 @BASEBOARD_FAB2_LIB.BASEBOARD_FAB2(SCH_1):PAGE38
  U5D1 DH55 VCCD345<36> SKX_EXT_B_BGA1-IC,TBD    I33 @BASEBOARD_FAB2_LIB.BASEBOARD_FAB2(SCH_1):PAGE38
  U5D1 DH53 VCCD345<37> SKX_EXT_B_BGA1-IC,TBD    I33 @BASEBOARD_FAB2_LIB.BASEBOARD_FAB2(SCH_1):PAGE38
  U5D1 DH51 VCCD345<38> SKX_EXT_B_BGA1-IC,TBD    I33 @BASEBOARD_FAB2_LIB.BASEBOARD_FAB2(SCH_1):PAGE38
  U5D1 DH49 VCCD345<39> SKX_EXT_B_BGA1-IC,TBD    I33 @BASEBOARD_FAB2_LIB.BASEBOARD_FAB2(SCH_1):PAGE38
  U5D1 DH47 VCCD345<40> SKX_EXT_B_BGA1-IC,TBD    I33 @BASEBOARD_FAB2_LIB.BASEBOARD_FAB2(SCH_1):PAGE38
  U5D1 DH45 VCCD345<41> SKX_EXT_B_BGA1-IC,TBD    I33 @BASEBOARD_FAB2_LIB.BASEBOARD_FAB2(SCH_1):PAGE38
  U5D1 DD45 VCCD345<42> SKX_EXT_B_BGA1-IC,TBD    I33 @BASEBOARD_FAB2_LIB.BASEBOARD_FAB2(SCH_1):PAGE38
  U5D1 DB63 VCCD345<43> SKX_EXT_B_BGA1-IC,TBD    I33 @BASEBOARD_FAB2_LIB.BASEBOARD_FAB2(SCH_1):PAGE38
  U5D1 DB61 VCCD345<44> SKX_EXT_B_BGA1-IC,TBD    I33 @BASEBOARD_FAB2_LIB.BASEBOARD_FAB2(SCH_1):PAGE38
  U5D1 DB59 VCCD345<45> SKX_EXT_B_BGA1-IC,TBD    I33 @BASEBOARD_FAB2_LIB.BASEBOARD_FAB2(SCH_1):PAGE38
  U5D1 DB57 VCCD345<46> SKX_EXT_B_BGA1-IC,TBD    I33 @BASEBOARD_FAB2_LIB.BASEBOARD_FAB2(SCH_1):PAGE38
  U5D1 DB55 VCCD345<47> SKX_EXT_B_BGA1-IC,TBD    I33 @BASEBOARD_FAB2_LIB.BASEBOARD_FAB2(SCH_1):PAGE38
  U5D1 DB53 VCCD345<48> SKX_EXT_B_BGA1-IC,TBD    I33 @BASEBOARD_FAB2_LIB.BASEBOARD_FAB2(SCH_1):PAGE38
  U5D1 EF45 VCCD345<49> SKX_EXT_B_BGA1-IC,TBD    I33 @BASEBOARD_FAB2_LIB.BASEBOARD_FAB2(SCH_1):PAGE38
  U5D1 EE44 VCCD345<50> SKX_EXT_B_BGA1-IC,TBD    I33 @BASEBOARD_FAB2_LIB.BASEBOARD_FAB2(SCH_1):PAGE38
  J4B1  236 VDD<0> SCONN288_H44441004_PIP-SCONN,HA   I169 @BASEBOARD_FAB2_LIB.BASEBOARD_FAB2(SCH_1):PAGE49
  J4B1  233 VDD<1> SCONN288_H44441004_PIP-SCONN,HA   I169 @BASEBOARD_FAB2_LIB.BASEBOARD_FAB2(SCH_1):PAGE49
  J4B1  231 VDD<2> SCONN288_H44441004_PIP-SCONN,HA   I169 @BASEBOARD_FAB2_LIB.BASEBOARD_FAB2(SCH_1):PAGE49
  J4B1  229 VDD<3> SCONN288_H44441004_PIP-SCONN,HA   I169 @BASEBOARD_FAB2_LIB.BASEBOARD_FAB2(SCH_1):PAGE49
  J4B1  226 VDD<4> SCONN288_H44441004_PIP-SCONN,HA   I169 @BASEBOARD_FAB2_LIB.BASEBOARD_FAB2(SCH_1):PAGE49
  J4B1  223 VDD<5> SCONN288_H44441004_PIP-SCONN,HA   I169 @BASEBOARD_FAB2_LIB.BASEBOARD_FAB2(SCH_1):PAGE49
  J4B1  220 VDD<6> SCONN288_H44441004_PIP-SCONN,HA   I169 @BASEBOARD_FAB2_LIB.BASEBOARD_FAB2(SCH_1):PAGE49
  J4B1  217 VDD<7> SCONN288_H44441004_PIP-SCONN,HA   I169 @BASEBOARD_FAB2_LIB.BASEBOARD_FAB2(SCH_1):PAGE49
  J4B1  215 VDD<8> SCONN288_H44441004_PIP-SCONN,HA   I169 @BASEBOARD_FAB2_LIB.BASEBOARD_FAB2(SCH_1):PAGE49
  J4B1  212 VDD<9> SCONN288_H44441004_PIP-SCONN,HA   I169 @BASEBOARD_FAB2_LIB.BASEBOARD_FAB2(SCH_1):PAGE49
  J4B1  209 VDD<10> SCONN288_H44441004_PIP-SCONN,HA   I169 @BASEBOARD_FAB2_LIB.BASEBOARD_FAB2(SCH_1):PAGE49
  J4B1  206 VDD<11> SCONN288_H44441004_PIP-SCONN,HA   I169 @BASEBOARD_FAB2_LIB.BASEBOARD_FAB2(SCH_1):PAGE49
  J4B1  204 VDD<12> SCONN288_H44441004_PIP-SCONN,HA   I169 @BASEBOARD_FAB2_LIB.BASEBOARD_FAB2(SCH_1):PAGE49
  J4B1   92 VDD<13> SCONN288_H44441004_PIP-SCONN,HA   I169 @BASEBOARD_FAB2_LIB.BASEBOARD_FAB2(SCH_1):PAGE49
  J4B1   90 VDD<14> SCONN288_H44441004_PIP-SCONN,HA   I169 @BASEBOARD_FAB2_LIB.BASEBOARD_FAB2(SCH_1):PAGE49
  J4B1   88 VDD<15> SCONN288_H44441004_PIP-SCONN,HA   I169 @BASEBOARD_FAB2_LIB.BASEBOARD_FAB2(SCH_1):PAGE49
  J4B1   85 VDD<16> SCONN288_H44441004_PIP-SCONN,HA   I169 @BASEBOARD_FAB2_LIB.BASEBOARD_FAB2(SCH_1):PAGE49
  J4B1   83 VDD<17> SCONN288_H44441004_PIP-SCONN,HA   I169 @BASEBOARD_FAB2_LIB.BASEBOARD_FAB2(SCH_1):PAGE49
  J4B1   80 VDD<18> SCONN288_H44441004_PIP-SCONN,HA   I169 @BASEBOARD_FAB2_LIB.BASEBOARD_FAB2(SCH_1):PAGE49
  J4B1   76 VDD<19> SCONN288_H44441004_PIP-SCONN,HA   I169 @BASEBOARD_FAB2_LIB.BASEBOARD_FAB2(SCH_1):PAGE49
  J4B1   73 VDD<20> SCONN288_H44441004_PIP-SCONN,HA   I169 @BASEBOARD_FAB2_LIB.BASEBOARD_FAB2(SCH_1):PAGE49
  J4B1   70 VDD<21> SCONN288_H44441004_PIP-SCONN,HA   I169 @BASEBOARD_FAB2_LIB.BASEBOARD_FAB2(SCH_1):PAGE49
  J4B1   67 VDD<22> SCONN288_H44441004_PIP-SCONN,HA   I169 @BASEBOARD_FAB2_LIB.BASEBOARD_FAB2(SCH_1):PAGE49
  J4B1   64 VDD<23> SCONN288_H44441004_PIP-SCONN,HA   I169 @BASEBOARD_FAB2_LIB.BASEBOARD_FAB2(SCH_1):PAGE49
  J4B1   61 VDD<24> SCONN288_H44441004_PIP-SCONN,HA   I169 @BASEBOARD_FAB2_LIB.BASEBOARD_FAB2(SCH_1):PAGE49
  J4B1   59 VDD<25> SCONN288_H44441004_PIP-SCONN,HA   I169 @BASEBOARD_FAB2_LIB.BASEBOARD_FAB2(SCH_1):PAGE49
  J6M1  236 VDD<0> SCONN288_H44441003_PIP-SCONN,HA    I50 @BASEBOARD_FAB2_LIB.BASEBOARD_FAB2(SCH_1):PAGE50
  J6M1  233 VDD<1> SCONN288_H44441003_PIP-SCONN,HA    I50 @BASEBOARD_FAB2_LIB.BASEBOARD_FAB2(SCH_1):PAGE50
  J6M1  231 VDD<2> SCONN288_H44441003_PIP-SCONN,HA    I50 @BASEBOARD_FAB2_LIB.BASEBOARD_FAB2(SCH_1):PAGE50
  J6M1  229 VDD<3> SCONN288_H44441003_PIP-SCONN,HA    I50 @BASEBOARD_FAB2_LIB.BASEBOARD_FAB2(SCH_1):PAGE50
  J6M1  226 VDD<4> SCONN288_H44441003_PIP-SCONN,HA    I50 @BASEBOARD_FAB2_LIB.BASEBOARD_FAB2(SCH_1):PAGE50
  J6M1  223 VDD<5> SCONN288_H44441003_PIP-SCONN,HA    I50 @BASEBOARD_FAB2_LIB.BASEBOARD_FAB2(SCH_1):PAGE50
  J6M1  220 VDD<6> SCONN288_H44441003_PIP-SCONN,HA    I50 @BASEBOARD_FAB2_LIB.BASEBOARD_FAB2(SCH_1):PAGE50
  J6M1  217 VDD<7> SCONN288_H44441003_PIP-SCONN,HA    I50 @BASEBOARD_FAB2_LIB.BASEBOARD_FAB2(SCH_1):PAGE50
  J6M1  215 VDD<8> SCONN288_H44441003_PIP-SCONN,HA    I50 @BASEBOARD_FAB2_LIB.BASEBOARD_FAB2(SCH_1):PAGE50
  J6M1  212 VDD<9> SCONN288_H44441003_PIP-SCONN,HA    I50 @BASEBOARD_FAB2_LIB.BASEBOARD_FAB2(SCH_1):PAGE50
  J6M1  209 VDD<10> SCONN288_H44441003_PIP-SCONN,HA    I50 @BASEBOARD_FAB2_LIB.BASEBOARD_FAB2(SCH_1):PAGE50
  J6M1  206 VDD<11> SCONN288_H44441003_PIP-SCONN,HA    I50 @BASEBOARD_FAB2_LIB.BASEBOARD_FAB2(SCH_1):PAGE50
  J6M1  204 VDD<12> SCONN288_H44441003_PIP-SCONN,HA    I50 @BASEBOARD_FAB2_LIB.BASEBOARD_FAB2(SCH_1):PAGE50
  J6M1   92 VDD<13> SCONN288_H44441003_PIP-SCONN,HA    I50 @BASEBOARD_FAB2_LIB.BASEBOARD_FAB2(SCH_1):PAGE50
  J6M1   90 VDD<14> SCONN288_H44441003_PIP-SCONN,HA    I50 @BASEBOARD_FAB2_LIB.BASEBOARD_FAB2(SCH_1):PAGE50
  J6M1   88 VDD<15> SCONN288_H44441003_PIP-SCONN,HA    I50 @BASEBOARD_FAB2_LIB.BASEBOARD_FAB2(SCH_1):PAGE50
  J6M1   85 VDD<16> SCONN288_H44441003_PIP-SCONN,HA    I50 @BASEBOARD_FAB2_LIB.BASEBOARD_FAB2(SCH_1):PAGE50
  J6M1   83 VDD<17> SCONN288_H44441003_PIP-SCONN,HA    I50 @BASEBOARD_FAB2_LIB.BASEBOARD_FAB2(SCH_1):PAGE50
  J6M1   80 VDD<18> SCONN288_H44441003_PIP-SCONN,HA    I50 @BASEBOARD_FAB2_LIB.BASEBOARD_FAB2(SCH_1):PAGE50
  J6M1   76 VDD<19> SCONN288_H44441003_PIP-SCONN,HA    I50 @BASEBOARD_FAB2_LIB.BASEBOARD_FAB2(SCH_1):PAGE50
  J6M1   73 VDD<20> SCONN288_H44441003_PIP-SCONN,HA    I50 @BASEBOARD_FAB2_LIB.BASEBOARD_FAB2(SCH_1):PAGE50
  J6M1   70 VDD<21> SCONN288_H44441003_PIP-SCONN,HA    I50 @BASEBOARD_FAB2_LIB.BASEBOARD_FAB2(SCH_1):PAGE50
  J6M1   67 VDD<22> SCONN288_H44441003_PIP-SCONN,HA    I50 @BASEBOARD_FAB2_LIB.BASEBOARD_FAB2(SCH_1):PAGE50
  J6M1   64 VDD<23> SCONN288_H44441003_PIP-SCONN,HA    I50 @BASEBOARD_FAB2_LIB.BASEBOARD_FAB2(SCH_1):PAGE50
  J6M1   61 VDD<24> SCONN288_H44441003_PIP-SCONN,HA    I50 @BASEBOARD_FAB2_LIB.BASEBOARD_FAB2(SCH_1):PAGE50
  J6M1   59 VDD<25> SCONN288_H44441003_PIP-SCONN,HA    I50 @BASEBOARD_FAB2_LIB.BASEBOARD_FAB2(SCH_1):PAGE50
  J4A2  236 VDD<0> SCONN288_H44441004_PIP-SCONN,HA   I167 @BASEBOARD_FAB2_LIB.BASEBOARD_FAB2(SCH_1):PAGE51
  J4A2  233 VDD<1> SCONN288_H44441004_PIP-SCONN,HA   I167 @BASEBOARD_FAB2_LIB.BASEBOARD_FAB2(SCH_1):PAGE51
  J4A2  231 VDD<2> SCONN288_H44441004_PIP-SCONN,HA   I167 @BASEBOARD_FAB2_LIB.BASEBOARD_FAB2(SCH_1):PAGE51
  J4A2  229 VDD<3> SCONN288_H44441004_PIP-SCONN,HA   I167 @BASEBOARD_FAB2_LIB.BASEBOARD_FAB2(SCH_1):PAGE51
  J4A2  226 VDD<4> SCONN288_H44441004_PIP-SCONN,HA   I167 @BASEBOARD_FAB2_LIB.BASEBOARD_FAB2(SCH_1):PAGE51
  J4A2  223 VDD<5> SCONN288_H44441004_PIP-SCONN,HA   I167 @BASEBOARD_FAB2_LIB.BASEBOARD_FAB2(SCH_1):PAGE51
  J4A2  220 VDD<6> SCONN288_H44441004_PIP-SCONN,HA   I167 @BASEBOARD_FAB2_LIB.BASEBOARD_FAB2(SCH_1):PAGE51
  J4A2  217 VDD<7> SCONN288_H44441004_PIP-SCONN,HA   I167 @BASEBOARD_FAB2_LIB.BASEBOARD_FAB2(SCH_1):PAGE51
  J4A2  215 VDD<8> SCONN288_H44441004_PIP-SCONN,HA   I167 @BASEBOARD_FAB2_LIB.BASEBOARD_FAB2(SCH_1):PAGE51
  J4A2  212 VDD<9> SCONN288_H44441004_PIP-SCONN,HA   I167 @BASEBOARD_FAB2_LIB.BASEBOARD_FAB2(SCH_1):PAGE51
  J4A2  209 VDD<10> SCONN288_H44441004_PIP-SCONN,HA   I167 @BASEBOARD_FAB2_LIB.BASEBOARD_FAB2(SCH_1):PAGE51
  J4A2  206 VDD<11> SCONN288_H44441004_PIP-SCONN,HA   I167 @BASEBOARD_FAB2_LIB.BASEBOARD_FAB2(SCH_1):PAGE51
  J4A2  204 VDD<12> SCONN288_H44441004_PIP-SCONN,HA   I167 @BASEBOARD_FAB2_LIB.BASEBOARD_FAB2(SCH_1):PAGE51
  J4A2   92 VDD<13> SCONN288_H44441004_PIP-SCONN,HA   I167 @BASEBOARD_FAB2_LIB.BASEBOARD_FAB2(SCH_1):PAGE51
  J4A2   90 VDD<14> SCONN288_H44441004_PIP-SCONN,HA   I167 @BASEBOARD_FAB2_LIB.BASEBOARD_FAB2(SCH_1):PAGE51
  J4A2   88 VDD<15> SCONN288_H44441004_PIP-SCONN,HA   I167 @BASEBOARD_FAB2_LIB.BASEBOARD_FAB2(SCH_1):PAGE51
  J4A2   85 VDD<16> SCONN288_H44441004_PIP-SCONN,HA   I167 @BASEBOARD_FAB2_LIB.BASEBOARD_FAB2(SCH_1):PAGE51
  J4A2   83 VDD<17> SCONN288_H44441004_PIP-SCONN,HA   I167 @BASEBOARD_FAB2_LIB.BASEBOARD_FAB2(SCH_1):PAGE51
  J4A2   80 VDD<18> SCONN288_H44441004_PIP-SCONN,HA   I167 @BASEBOARD_FAB2_LIB.BASEBOARD_FAB2(SCH_1):PAGE51
  J4A2   76 VDD<19> SCONN288_H44441004_PIP-SCONN,HA   I167 @BASEBOARD_FAB2_LIB.BASEBOARD_FAB2(SCH_1):PAGE51
  J4A2   73 VDD<20> SCONN288_H44441004_PIP-SCONN,HA   I167 @BASEBOARD_FAB2_LIB.BASEBOARD_FAB2(SCH_1):PAGE51
  J4A2   70 VDD<21> SCONN288_H44441004_PIP-SCONN,HA   I167 @BASEBOARD_FAB2_LIB.BASEBOARD_FAB2(SCH_1):PAGE51
  J4A2   67 VDD<22> SCONN288_H44441004_PIP-SCONN,HA   I167 @BASEBOARD_FAB2_LIB.BASEBOARD_FAB2(SCH_1):PAGE51
  J4A2   64 VDD<23> SCONN288_H44441004_PIP-SCONN,HA   I167 @BASEBOARD_FAB2_LIB.BASEBOARD_FAB2(SCH_1):PAGE51
  J4A2   61 VDD<24> SCONN288_H44441004_PIP-SCONN,HA   I167 @BASEBOARD_FAB2_LIB.BASEBOARD_FAB2(SCH_1):PAGE51
  J4A2   59 VDD<25> SCONN288_H44441004_PIP-SCONN,HA   I167 @BASEBOARD_FAB2_LIB.BASEBOARD_FAB2(SCH_1):PAGE51
  J6L2  236 VDD<0> SCONN288_H44441003_PIP-SCONN,HA    I55 @BASEBOARD_FAB2_LIB.BASEBOARD_FAB2(SCH_1):PAGE52
  J6L2  233 VDD<1> SCONN288_H44441003_PIP-SCONN,HA    I55 @BASEBOARD_FAB2_LIB.BASEBOARD_FAB2(SCH_1):PAGE52
  J6L2  231 VDD<2> SCONN288_H44441003_PIP-SCONN,HA    I55 @BASEBOARD_FAB2_LIB.BASEBOARD_FAB2(SCH_1):PAGE52
  J6L2  229 VDD<3> SCONN288_H44441003_PIP-SCONN,HA    I55 @BASEBOARD_FAB2_LIB.BASEBOARD_FAB2(SCH_1):PAGE52
  J6L2  226 VDD<4> SCONN288_H44441003_PIP-SCONN,HA    I55 @BASEBOARD_FAB2_LIB.BASEBOARD_FAB2(SCH_1):PAGE52
  J6L2  223 VDD<5> SCONN288_H44441003_PIP-SCONN,HA    I55 @BASEBOARD_FAB2_LIB.BASEBOARD_FAB2(SCH_1):PAGE52
  J6L2  220 VDD<6> SCONN288_H44441003_PIP-SCONN,HA    I55 @BASEBOARD_FAB2_LIB.BASEBOARD_FAB2(SCH_1):PAGE52
  J6L2  217 VDD<7> SCONN288_H44441003_PIP-SCONN,HA    I55 @BASEBOARD_FAB2_LIB.BASEBOARD_FAB2(SCH_1):PAGE52
  J6L2  215 VDD<8> SCONN288_H44441003_PIP-SCONN,HA    I55 @BASEBOARD_FAB2_LIB.BASEBOARD_FAB2(SCH_1):PAGE52
  J6L2  212 VDD<9> SCONN288_H44441003_PIP-SCONN,HA    I55 @BASEBOARD_FAB2_LIB.BASEBOARD_FAB2(SCH_1):PAGE52
  J6L2  209 VDD<10> SCONN288_H44441003_PIP-SCONN,HA    I55 @BASEBOARD_FAB2_LIB.BASEBOARD_FAB2(SCH_1):PAGE52
  J6L2  206 VDD<11> SCONN288_H44441003_PIP-SCONN,HA    I55 @BASEBOARD_FAB2_LIB.BASEBOARD_FAB2(SCH_1):PAGE52
  J6L2  204 VDD<12> SCONN288_H44441003_PIP-SCONN,HA    I55 @BASEBOARD_FAB2_LIB.BASEBOARD_FAB2(SCH_1):PAGE52
  J6L2   92 VDD<13> SCONN288_H44441003_PIP-SCONN,HA    I55 @BASEBOARD_FAB2_LIB.BASEBOARD_FAB2(SCH_1):PAGE52
  J6L2   90 VDD<14> SCONN288_H44441003_PIP-SCONN,HA    I55 @BASEBOARD_FAB2_LIB.BASEBOARD_FAB2(SCH_1):PAGE52
  J6L2   88 VDD<15> SCONN288_H44441003_PIP-SCONN,HA    I55 @BASEBOARD_FAB2_LIB.BASEBOARD_FAB2(SCH_1):PAGE52
  J6L2   85 VDD<16> SCONN288_H44441003_PIP-SCONN,HA    I55 @BASEBOARD_FAB2_LIB.BASEBOARD_FAB2(SCH_1):PAGE52
  J6L2   83 VDD<17> SCONN288_H44441003_PIP-SCONN,HA    I55 @BASEBOARD_FAB2_LIB.BASEBOARD_FAB2(SCH_1):PAGE52
  J6L2   80 VDD<18> SCONN288_H44441003_PIP-SCONN,HA    I55 @BASEBOARD_FAB2_LIB.BASEBOARD_FAB2(SCH_1):PAGE52
  J6L2   76 VDD<19> SCONN288_H44441003_PIP-SCONN,HA    I55 @BASEBOARD_FAB2_LIB.BASEBOARD_FAB2(SCH_1):PAGE52
  J6L2   73 VDD<20> SCONN288_H44441003_PIP-SCONN,HA    I55 @BASEBOARD_FAB2_LIB.BASEBOARD_FAB2(SCH_1):PAGE52
  J6L2   70 VDD<21> SCONN288_H44441003_PIP-SCONN,HA    I55 @BASEBOARD_FAB2_LIB.BASEBOARD_FAB2(SCH_1):PAGE52
  J6L2   67 VDD<22> SCONN288_H44441003_PIP-SCONN,HA    I55 @BASEBOARD_FAB2_LIB.BASEBOARD_FAB2(SCH_1):PAGE52
  J6L2   64 VDD<23> SCONN288_H44441003_PIP-SCONN,HA    I55 @BASEBOARD_FAB2_LIB.BASEBOARD_FAB2(SCH_1):PAGE52
  J6L2   61 VDD<24> SCONN288_H44441003_PIP-SCONN,HA    I55 @BASEBOARD_FAB2_LIB.BASEBOARD_FAB2(SCH_1):PAGE52
  J6L2   59 VDD<25> SCONN288_H44441003_PIP-SCONN,HA    I55 @BASEBOARD_FAB2_LIB.BASEBOARD_FAB2(SCH_1):PAGE52
  J4A1  236 VDD<0> SCONN288_H44441004_PIP-SCONN,HA   I171 @BASEBOARD_FAB2_LIB.BASEBOARD_FAB2(SCH_1):PAGE53
  J4A1  233 VDD<1> SCONN288_H44441004_PIP-SCONN,HA   I171 @BASEBOARD_FAB2_LIB.BASEBOARD_FAB2(SCH_1):PAGE53
  J4A1  231 VDD<2> SCONN288_H44441004_PIP-SCONN,HA   I171 @BASEBOARD_FAB2_LIB.BASEBOARD_FAB2(SCH_1):PAGE53
  J4A1  229 VDD<3> SCONN288_H44441004_PIP-SCONN,HA   I171 @BASEBOARD_FAB2_LIB.BASEBOARD_FAB2(SCH_1):PAGE53
  J4A1  226 VDD<4> SCONN288_H44441004_PIP-SCONN,HA   I171 @BASEBOARD_FAB2_LIB.BASEBOARD_FAB2(SCH_1):PAGE53
  J4A1  223 VDD<5> SCONN288_H44441004_PIP-SCONN,HA   I171 @BASEBOARD_FAB2_LIB.BASEBOARD_FAB2(SCH_1):PAGE53
  J4A1  220 VDD<6> SCONN288_H44441004_PIP-SCONN,HA   I171 @BASEBOARD_FAB2_LIB.BASEBOARD_FAB2(SCH_1):PAGE53
  J4A1  217 VDD<7> SCONN288_H44441004_PIP-SCONN,HA   I171 @BASEBOARD_FAB2_LIB.BASEBOARD_FAB2(SCH_1):PAGE53
  J4A1  215 VDD<8> SCONN288_H44441004_PIP-SCONN,HA   I171 @BASEBOARD_FAB2_LIB.BASEBOARD_FAB2(SCH_1):PAGE53
  J4A1  212 VDD<9> SCONN288_H44441004_PIP-SCONN,HA   I171 @BASEBOARD_FAB2_LIB.BASEBOARD_FAB2(SCH_1):PAGE53
  J4A1  209 VDD<10> SCONN288_H44441004_PIP-SCONN,HA   I171 @BASEBOARD_FAB2_LIB.BASEBOARD_FAB2(SCH_1):PAGE53
  J4A1  206 VDD<11> SCONN288_H44441004_PIP-SCONN,HA   I171 @BASEBOARD_FAB2_LIB.BASEBOARD_FAB2(SCH_1):PAGE53
  J4A1  204 VDD<12> SCONN288_H44441004_PIP-SCONN,HA   I171 @BASEBOARD_FAB2_LIB.BASEBOARD_FAB2(SCH_1):PAGE53
  J4A1   92 VDD<13> SCONN288_H44441004_PIP-SCONN,HA   I171 @BASEBOARD_FAB2_LIB.BASEBOARD_FAB2(SCH_1):PAGE53
  J4A1   90 VDD<14> SCONN288_H44441004_PIP-SCONN,HA   I171 @BASEBOARD_FAB2_LIB.BASEBOARD_FAB2(SCH_1):PAGE53
  J4A1   88 VDD<15> SCONN288_H44441004_PIP-SCONN,HA   I171 @BASEBOARD_FAB2_LIB.BASEBOARD_FAB2(SCH_1):PAGE53
  J4A1   85 VDD<16> SCONN288_H44441004_PIP-SCONN,HA   I171 @BASEBOARD_FAB2_LIB.BASEBOARD_FAB2(SCH_1):PAGE53
  J4A1   83 VDD<17> SCONN288_H44441004_PIP-SCONN,HA   I171 @BASEBOARD_FAB2_LIB.BASEBOARD_FAB2(SCH_1):PAGE53
  J4A1   80 VDD<18> SCONN288_H44441004_PIP-SCONN,HA   I171 @BASEBOARD_FAB2_LIB.BASEBOARD_FAB2(SCH_1):PAGE53
  J4A1   76 VDD<19> SCONN288_H44441004_PIP-SCONN,HA   I171 @BASEBOARD_FAB2_LIB.BASEBOARD_FAB2(SCH_1):PAGE53
  J4A1   73 VDD<20> SCONN288_H44441004_PIP-SCONN,HA   I171 @BASEBOARD_FAB2_LIB.BASEBOARD_FAB2(SCH_1):PAGE53
  J4A1   70 VDD<21> SCONN288_H44441004_PIP-SCONN,HA   I171 @BASEBOARD_FAB2_LIB.BASEBOARD_FAB2(SCH_1):PAGE53
  J4A1   67 VDD<22> SCONN288_H44441004_PIP-SCONN,HA   I171 @BASEBOARD_FAB2_LIB.BASEBOARD_FAB2(SCH_1):PAGE53
  J4A1   64 VDD<23> SCONN288_H44441004_PIP-SCONN,HA   I171 @BASEBOARD_FAB2_LIB.BASEBOARD_FAB2(SCH_1):PAGE53
  J4A1   61 VDD<24> SCONN288_H44441004_PIP-SCONN,HA   I171 @BASEBOARD_FAB2_LIB.BASEBOARD_FAB2(SCH_1):PAGE53
  J4A1   59 VDD<25> SCONN288_H44441004_PIP-SCONN,HA   I171 @BASEBOARD_FAB2_LIB.BASEBOARD_FAB2(SCH_1):PAGE53
  J6L1  236 VDD<0> SCONN288_H44441003_PIP-SCONN,HA   I170 @BASEBOARD_FAB2_LIB.BASEBOARD_FAB2(SCH_1):PAGE54
  J6L1  233 VDD<1> SCONN288_H44441003_PIP-SCONN,HA   I170 @BASEBOARD_FAB2_LIB.BASEBOARD_FAB2(SCH_1):PAGE54
  J6L1  231 VDD<2> SCONN288_H44441003_PIP-SCONN,HA   I170 @BASEBOARD_FAB2_LIB.BASEBOARD_FAB2(SCH_1):PAGE54
  J6L1  229 VDD<3> SCONN288_H44441003_PIP-SCONN,HA   I170 @BASEBOARD_FAB2_LIB.BASEBOARD_FAB2(SCH_1):PAGE54
  J6L1  226 VDD<4> SCONN288_H44441003_PIP-SCONN,HA   I170 @BASEBOARD_FAB2_LIB.BASEBOARD_FAB2(SCH_1):PAGE54
  J6L1  223 VDD<5> SCONN288_H44441003_PIP-SCONN,HA   I170 @BASEBOARD_FAB2_LIB.BASEBOARD_FAB2(SCH_1):PAGE54
  J6L1  220 VDD<6> SCONN288_H44441003_PIP-SCONN,HA   I170 @BASEBOARD_FAB2_LIB.BASEBOARD_FAB2(SCH_1):PAGE54
  J6L1  217 VDD<7> SCONN288_H44441003_PIP-SCONN,HA   I170 @BASEBOARD_FAB2_LIB.BASEBOARD_FAB2(SCH_1):PAGE54
  J6L1  215 VDD<8> SCONN288_H44441003_PIP-SCONN,HA   I170 @BASEBOARD_FAB2_LIB.BASEBOARD_FAB2(SCH_1):PAGE54
  J6L1  212 VDD<9> SCONN288_H44441003_PIP-SCONN,HA   I170 @BASEBOARD_FAB2_LIB.BASEBOARD_FAB2(SCH_1):PAGE54
  J6L1  209 VDD<10> SCONN288_H44441003_PIP-SCONN,HA   I170 @BASEBOARD_FAB2_LIB.BASEBOARD_FAB2(SCH_1):PAGE54
  J6L1  206 VDD<11> SCONN288_H44441003_PIP-SCONN,HA   I170 @BASEBOARD_FAB2_LIB.BASEBOARD_FAB2(SCH_1):PAGE54
  J6L1  204 VDD<12> SCONN288_H44441003_PIP-SCONN,HA   I170 @BASEBOARD_FAB2_LIB.BASEBOARD_FAB2(SCH_1):PAGE54
  J6L1   92 VDD<13> SCONN288_H44441003_PIP-SCONN,HA   I170 @BASEBOARD_FAB2_LIB.BASEBOARD_FAB2(SCH_1):PAGE54
  J6L1   90 VDD<14> SCONN288_H44441003_PIP-SCONN,HA   I170 @BASEBOARD_FAB2_LIB.BASEBOARD_FAB2(SCH_1):PAGE54
  J6L1   88 VDD<15> SCONN288_H44441003_PIP-SCONN,HA   I170 @BASEBOARD_FAB2_LIB.BASEBOARD_FAB2(SCH_1):PAGE54
  J6L1   85 VDD<16> SCONN288_H44441003_PIP-SCONN,HA   I170 @BASEBOARD_FAB2_LIB.BASEBOARD_FAB2(SCH_1):PAGE54
  J6L1   83 VDD<17> SCONN288_H44441003_PIP-SCONN,HA   I170 @BASEBOARD_FAB2_LIB.BASEBOARD_FAB2(SCH_1):PAGE54
  J6L1   80 VDD<18> SCONN288_H44441003_PIP-SCONN,HA   I170 @BASEBOARD_FAB2_LIB.BASEBOARD_FAB2(SCH_1):PAGE54
  J6L1   76 VDD<19> SCONN288_H44441003_PIP-SCONN,HA   I170 @BASEBOARD_FAB2_LIB.BASEBOARD_FAB2(SCH_1):PAGE54
  J6L1   73 VDD<20> SCONN288_H44441003_PIP-SCONN,HA   I170 @BASEBOARD_FAB2_LIB.BASEBOARD_FAB2(SCH_1):PAGE54
  J6L1   70 VDD<21> SCONN288_H44441003_PIP-SCONN,HA   I170 @BASEBOARD_FAB2_LIB.BASEBOARD_FAB2(SCH_1):PAGE54
  J6L1   67 VDD<22> SCONN288_H44441003_PIP-SCONN,HA   I170 @BASEBOARD_FAB2_LIB.BASEBOARD_FAB2(SCH_1):PAGE54
  J6L1   64 VDD<23> SCONN288_H44441003_PIP-SCONN,HA   I170 @BASEBOARD_FAB2_LIB.BASEBOARD_FAB2(SCH_1):PAGE54
  J6L1   61 VDD<24> SCONN288_H44441003_PIP-SCONN,HA   I170 @BASEBOARD_FAB2_LIB.BASEBOARD_FAB2(SCH_1):PAGE54
  J6L1   59 VDD<25> SCONN288_H44441003_PIP-SCONN,HA   I170 @BASEBOARD_FAB2_LIB.BASEBOARD_FAB2(SCH_1):PAGE54
 R3P29    1      A RES_0402-64.9,1.0%,1/16W,CHIP,A     I5 @BASEBOARD_FAB2_LIB.BASEBOARD_FAB2(SCH_1):PAGE96
  R6M1    1      A RES_0402-1.00K,1%,1/16W,CHIP,GA     I9 @BASEBOARD_FAB2_LIB.BASEBOARD_FAB2(SCH_1):PAGE98
 R6L13    1      A RES_0402-1.00K,1%,1/16W,CHIP,GA    I54 @BASEBOARD_FAB2_LIB.BASEBOARD_FAB2(SCH_1):PAGE98
  R6L2    1      A RES_0402-1.00K,1%,1/16W,CHIP,GA    I62 @BASEBOARD_FAB2_LIB.BASEBOARD_FAB2(SCH_1):PAGE98
  C6A4    1      A CAP_0805LF-22UF,4V,20%,X6S,C95A    I68 @BASEBOARD_FAB2_LIB.BASEBOARD_FAB2(SCH_1):PAGE219
  C6A1    1      A CAP_0805LF-22UF,4V,20%,X6S,C95A    I87 @BASEBOARD_FAB2_LIB.BASEBOARD_FAB2(SCH_1):PAGE219
 EU7A1    1    VOS IR354XX_SM-IR35411,IC,H73688-0A   I106 @BASEBOARD_FAB2_LIB.BASEBOARD_FAB2(SCH_1):PAGE219
 EU7A4    1    VOS IR354XX_SM-IR35411,IC,H73688-0A   I107 @BASEBOARD_FAB2_LIB.BASEBOARD_FAB2(SCH_1):PAGE219
  R4L4    1      A RES_0603-120.0,1%,1/10W,CHIP,GA    I58 @BASEBOARD_FAB2_LIB.BASEBOARD_FAB2(SCH_1):PAGE220
  C3L6    1      A CAPP_3018-470UF,2.5V,20%,ALUM,A    I75 @BASEBOARD_FAB2_LIB.BASEBOARD_FAB2(SCH_1):PAGE220
 C3L14    1      A CAPP_3018-470UF,2.5V,20%,ALUM,A    I76 @BASEBOARD_FAB2_LIB.BASEBOARD_FAB2(SCH_1):PAGE220
  C6A5    1      A CAPP_3018-470UF,2.5V,20%,ALUM,A    I77 @BASEBOARD_FAB2_LIB.BASEBOARD_FAB2(SCH_1):PAGE220
  C4L5    1      A CAPP_3018-470UF,2.5V,20%,ALUM,A    I78 @BASEBOARD_FAB2_LIB.BASEBOARD_FAB2(SCH_1):PAGE220
 C5L15    1      A CAP_A_0603V-47UF,4V,20%,X5R,60A   I192 @BASEBOARD_FAB2_LIB.BASEBOARD_FAB2(SCH_1):PAGE220
  C5A5    1      A CAP_A_0603V-47UF,4V,20%,X5R,60A   I193 @BASEBOARD_FAB2_LIB.BASEBOARD_FAB2(SCH_1):PAGE220
  C5B1    1      A CAP_A_0603V-47UF,4V,20%,X5R,60A   I194 @BASEBOARD_FAB2_LIB.BASEBOARD_FAB2(SCH_1):PAGE220
  C5M9    1      A CAP_A_0603V-47UF,4V,20%,X5R,60A   I195 @BASEBOARD_FAB2_LIB.BASEBOARD_FAB2(SCH_1):PAGE220
  C4M5    1      A CAP_A_0603V-47UF,4V,20%,X5R,60A   I196 @BASEBOARD_FAB2_LIB.BASEBOARD_FAB2(SCH_1):PAGE220
  C5B2    1      A CAP_A_0603V-47UF,4V,20%,X5R,60A   I197 @BASEBOARD_FAB2_LIB.BASEBOARD_FAB2(SCH_1):PAGE220
 C5M10    1      A CAP_A_0603V-47UF,4V,20%,X5R,60A   I198 @BASEBOARD_FAB2_LIB.BASEBOARD_FAB2(SCH_1):PAGE220
  C5M3    1      A CAP_A_0603V-47UF,4V,20%,X5R,60A   I199 @BASEBOARD_FAB2_LIB.BASEBOARD_FAB2(SCH_1):PAGE220
 C5M11    1      A CAP_A_0603V-47UF,4V,20%,X5R,60A   I200 @BASEBOARD_FAB2_LIB.BASEBOARD_FAB2(SCH_1):PAGE220
 SH4L2    2      B SHUNT_SH0201-EMPTY,N_A   I239 @BASEBOARD_FAB2_LIB.BASEBOARD_FAB2(SCH_1):PAGE220
 C5G67    1      A CAP_A_0603V-22.0UF,4V,20%,X6S,A    I71 @BASEBOARD_FAB2_LIB.BASEBOARD_FAB2(SCH_1):PAGE242
 C5G66    1      A CAP_A_0603V-22.0UF,4V,20%,X6S,A    I72 @BASEBOARD_FAB2_LIB.BASEBOARD_FAB2(SCH_1):PAGE242
 C5G65    1      A CAP_A_0603V-22.0UF,4V,20%,X6S,A    I73 @BASEBOARD_FAB2_LIB.BASEBOARD_FAB2(SCH_1):PAGE242
 C5G64    1      A CAP_A_0603V-22.0UF,4V,20%,X6S,A    I74 @BASEBOARD_FAB2_LIB.BASEBOARD_FAB2(SCH_1):PAGE242
 C5G63    1      A CAP_A_0603V-22.0UF,4V,20%,X6S,A    I75 @BASEBOARD_FAB2_LIB.BASEBOARD_FAB2(SCH_1):PAGE242
 C5G62    1      A CAP_A_0603V-22.0UF,4V,20%,X6S,A    I76 @BASEBOARD_FAB2_LIB.BASEBOARD_FAB2(SCH_1):PAGE242
 C5G61    1      A CAP_A_0603V-22.0UF,4V,20%,X6S,A    I77 @BASEBOARD_FAB2_LIB.BASEBOARD_FAB2(SCH_1):PAGE242
 C5G60    1      A CAP_A_0603V-22.0UF,4V,20%,X6S,A    I78 @BASEBOARD_FAB2_LIB.BASEBOARD_FAB2(SCH_1):PAGE242
 C5G59    1      A CAP_A_0603V-22.0UF,4V,20%,X6S,A    I79 @BASEBOARD_FAB2_LIB.BASEBOARD_FAB2(SCH_1):PAGE242
 C5G76    1      A CAP_A_0603V-22.0UF,4V,20%,X6S,A    I80 @BASEBOARD_FAB2_LIB.BASEBOARD_FAB2(SCH_1):PAGE242
 C5G75    1      A CAP_A_0603V-22.0UF,4V,20%,X6S,A    I81 @BASEBOARD_FAB2_LIB.BASEBOARD_FAB2(SCH_1):PAGE242
 C5G74    1      A CAP_A_0603V-22.0UF,4V,20%,X6S,A    I82 @BASEBOARD_FAB2_LIB.BASEBOARD_FAB2(SCH_1):PAGE242
 C5G73    1      A CAP_A_0603V-22.0UF,4V,20%,X6S,A    I83 @BASEBOARD_FAB2_LIB.BASEBOARD_FAB2(SCH_1):PAGE242
 C5G72    1      A CAP_A_0603V-22.0UF,4V,20%,X6S,A    I84 @BASEBOARD_FAB2_LIB.BASEBOARD_FAB2(SCH_1):PAGE242
 C5G71    1      A CAP_A_0603V-22.0UF,4V,20%,X6S,A    I85 @BASEBOARD_FAB2_LIB.BASEBOARD_FAB2(SCH_1):PAGE242
 C5G70    1      A CAP_A_0603V-22.0UF,4V,20%,X6S,A    I86 @BASEBOARD_FAB2_LIB.BASEBOARD_FAB2(SCH_1):PAGE242
 C5G69    1      A CAP_A_0603V-22.0UF,4V,20%,X6S,A    I87 @BASEBOARD_FAB2_LIB.BASEBOARD_FAB2(SCH_1):PAGE242
 C5G68    1      A CAP_A_0603V-22.0UF,4V,20%,X6S,A    I88 @BASEBOARD_FAB2_LIB.BASEBOARD_FAB2(SCH_1):PAGE242
 C5G77    1      A CAP_0805-47UF,4V,20%,X6S,C9533A    I89 @BASEBOARD_FAB2_LIB.BASEBOARD_FAB2(SCH_1):PAGE242
 C5G78    1      A CAP_0805-47UF,4V,20%,X6S,C9533A    I91 @BASEBOARD_FAB2_LIB.BASEBOARD_FAB2(SCH_1):PAGE242
 R6L10    1      A RES_0402-0.0,5%,1/16W,CHIP,G21A     I6 @BASEBOARD_FAB2_LIB.BASEBOARD_FAB2(SCH_1):PAGE222
 EU4A1   10    VIN MIC5166_DFN-IC,H55101-001    I13 @BASEBOARD_FAB2_LIB.BASEBOARD_FAB2(SCH_1):PAGE222
  C6L4    1      A CAP_0603LF-10UF,4V,20%,X6S,E15A    I15 @BASEBOARD_FAB2_LIB.BASEBOARD_FAB2(SCH_1):PAGE222
  C6L3    1      A CAP_0603LF-10UF,4V,20%,X6S,E15A    I17 @BASEBOARD_FAB2_LIB.BASEBOARD_FAB2(SCH_1):PAGE222
  C5D4    1      A CAP_A_0603V-22.0UF,4V,20%,X6S,A   I249 @BASEBOARD_FAB2_LIB.BASEBOARD_FAB2(SCH_1):PAGE220
  C5D3    1      A CAP_A_0603V-22.0UF,4V,20%,X6S,A   I250 @BASEBOARD_FAB2_LIB.BASEBOARD_FAB2(SCH_1):PAGE220
  C5D2    1      A CAP_A_0603V-22.0UF,4V,20%,X6S,A   I251 @BASEBOARD_FAB2_LIB.BASEBOARD_FAB2(SCH_1):PAGE220
  C5D1    1      A CAP_A_0603V-22.0UF,4V,20%,X6S,A   I252 @BASEBOARD_FAB2_LIB.BASEBOARD_FAB2(SCH_1):PAGE220
  C5D9    1      A CAP_A_0603V-22.0UF,4V,20%,X6S,A   I258 @BASEBOARD_FAB2_LIB.BASEBOARD_FAB2(SCH_1):PAGE220
  C5D6    1      A CAP_A_0603V-22.0UF,4V,20%,X6S,A   I259 @BASEBOARD_FAB2_LIB.BASEBOARD_FAB2(SCH_1):PAGE220
  C5D7    1      A CAP_A_0603V-22.0UF,4V,20%,X6S,A   I260 @BASEBOARD_FAB2_LIB.BASEBOARD_FAB2(SCH_1):PAGE220
  C5D8    1      A CAP_A_0603V-22.0UF,4V,20%,X6S,A   I261 @BASEBOARD_FAB2_LIB.BASEBOARD_FAB2(SCH_1):PAGE220
  C5A1    1      A CAP_A_0603V-47UF,4V,20%,X5R,60A   I262 @BASEBOARD_FAB2_LIB.BASEBOARD_FAB2(SCH_1):PAGE220
 C5A15    1      A CAP_A_0603V-47UF,4V,20%,X5R,60A   I263 @BASEBOARD_FAB2_LIB.BASEBOARD_FAB2(SCH_1):PAGE220
 C5A12    1      A CAP_A_0603V-47UF,4V,20%,X5R,60A   I264 @BASEBOARD_FAB2_LIB.BASEBOARD_FAB2(SCH_1):PAGE220
 C5A13    1      A CAP_A_0603V-47UF,4V,20%,X5R,60A   I265 @BASEBOARD_FAB2_LIB.BASEBOARD_FAB2(SCH_1):PAGE220
  C5A2    1      A CAP_A_0603V-47UF,4V,20%,X5R,60A   I266 @BASEBOARD_FAB2_LIB.BASEBOARD_FAB2(SCH_1):PAGE220
 C5A14    1      A CAP_A_0603V-47UF,4V,20%,X5R,60A   I267 @BASEBOARD_FAB2_LIB.BASEBOARD_FAB2(SCH_1):PAGE220
  C5A6    1      A CAP_A_0603V-47UF,4V,20%,X5R,60A   I268 @BASEBOARD_FAB2_LIB.BASEBOARD_FAB2(SCH_1):PAGE220
  C5A7    1      A CAP_A_0603V-47UF,4V,20%,X5R,60A   I269 @BASEBOARD_FAB2_LIB.BASEBOARD_FAB2(SCH_1):PAGE220
  C5A3    1      A CAP_A_0603V-47UF,4V,20%,X5R,60A   I270 @BASEBOARD_FAB2_LIB.BASEBOARD_FAB2(SCH_1):PAGE220
  C5A8    1      A CAP_A_0603V-47UF,4V,20%,X5R,60A   I271 @BASEBOARD_FAB2_LIB.BASEBOARD_FAB2(SCH_1):PAGE220
  C5A9    1      A CAP_A_0603V-47UF,4V,20%,X5R,60A   I272 @BASEBOARD_FAB2_LIB.BASEBOARD_FAB2(SCH_1):PAGE220
 C5A16    1      A CAP_A_0603V-47UF,4V,20%,X5R,60A   I273 @BASEBOARD_FAB2_LIB.BASEBOARD_FAB2(SCH_1):PAGE220
  C5A4    1      A CAP_A_0603V-47UF,4V,20%,X5R,60A   I274 @BASEBOARD_FAB2_LIB.BASEBOARD_FAB2(SCH_1):PAGE220
 C5A17    1      A CAP_A_0603V-47UF,4V,20%,X5R,60A   I275 @BASEBOARD_FAB2_LIB.BASEBOARD_FAB2(SCH_1):PAGE220
 C5A18    1      A CAP_A_0603V-47UF,4V,20%,X5R,60A   I276 @BASEBOARD_FAB2_LIB.BASEBOARD_FAB2(SCH_1):PAGE220
 C5A19    1      A CAP_A_0603V-47UF,4V,20%,X5R,60A   I277 @BASEBOARD_FAB2_LIB.BASEBOARD_FAB2(SCH_1):PAGE220
  C5L6    1      A CAP_A_0603V-47UF,4V,20%,X5R,60A   I278 @BASEBOARD_FAB2_LIB.BASEBOARD_FAB2(SCH_1):PAGE220
  C5L7    1      A CAP_A_0603V-47UF,4V,20%,X5R,60A   I279 @BASEBOARD_FAB2_LIB.BASEBOARD_FAB2(SCH_1):PAGE220
  C5L8    1      A CAP_A_0603V-47UF,4V,20%,X5R,60A   I280 @BASEBOARD_FAB2_LIB.BASEBOARD_FAB2(SCH_1):PAGE220
  C5L9    1      A CAP_A_0603V-47UF,4V,20%,X5R,60A   I281 @BASEBOARD_FAB2_LIB.BASEBOARD_FAB2(SCH_1):PAGE220
 C5L10    1      A CAP_A_0603V-47UF,4V,20%,X5R,60A   I282 @BASEBOARD_FAB2_LIB.BASEBOARD_FAB2(SCH_1):PAGE220
 C5L11    1      A CAP_A_0603V-47UF,4V,20%,X5R,60A   I283 @BASEBOARD_FAB2_LIB.BASEBOARD_FAB2(SCH_1):PAGE220
 C5L12    1      A CAP_A_0603V-47UF,4V,20%,X5R,60A   I284 @BASEBOARD_FAB2_LIB.BASEBOARD_FAB2(SCH_1):PAGE220
 C5L13    1      A CAP_A_0603V-47UF,4V,20%,X5R,60A   I285 @BASEBOARD_FAB2_LIB.BASEBOARD_FAB2(SCH_1):PAGE220
  C5M7    1      A CAP_A_0603V-47UF,4V,20%,X5R,60A   I286 @BASEBOARD_FAB2_LIB.BASEBOARD_FAB2(SCH_1):PAGE220
  C5M6    1      A CAP_A_0603V-47UF,4V,20%,X5R,60A   I287 @BASEBOARD_FAB2_LIB.BASEBOARD_FAB2(SCH_1):PAGE220
  C5M5    1      A CAP_A_0603V-47UF,4V,20%,X5R,60A   I288 @BASEBOARD_FAB2_LIB.BASEBOARD_FAB2(SCH_1):PAGE220
  C5M4    1      A CAP_A_0603V-47UF,4V,20%,X5R,60A   I289 @BASEBOARD_FAB2_LIB.BASEBOARD_FAB2(SCH_1):PAGE220
  C5M2    1      A CAP_A_0603V-47UF,4V,20%,X5R,60A   I290 @BASEBOARD_FAB2_LIB.BASEBOARD_FAB2(SCH_1):PAGE220
  C5M1    1      A CAP_A_0603V-47UF,4V,20%,X5R,60A   I291 @BASEBOARD_FAB2_LIB.BASEBOARD_FAB2(SCH_1):PAGE220
  C4M2    1      A CAP_A_0603V-47UF,4V,20%,X5R,60A   I292 @BASEBOARD_FAB2_LIB.BASEBOARD_FAB2(SCH_1):PAGE220
 C5A11    1      A CAP_A_0603V-47UF,4V,20%,X5R,60A   I293 @BASEBOARD_FAB2_LIB.BASEBOARD_FAB2(SCH_1):PAGE220
 C5A20    1      A CAP_0805-100UF,4V,20%,X5R,6024A   I308 @BASEBOARD_FAB2_LIB.BASEBOARD_FAB2(SCH_1):PAGE220
  C5L1    1      A CAP_0805-100UF,4V,20%,X5R,6024A   I309 @BASEBOARD_FAB2_LIB.BASEBOARD_FAB2(SCH_1):PAGE220
  C5L3    1      A CAP_0805-100UF,4V,20%,X5R,6024A   I310 @BASEBOARD_FAB2_LIB.BASEBOARD_FAB2(SCH_1):PAGE220
  C5L2    1      A CAP_0805-100UF,4V,20%,X5R,6024A   I311 @BASEBOARD_FAB2_LIB.BASEBOARD_FAB2(SCH_1):PAGE220
 C5M12    1      A CAP_0805-100UF,4V,20%,X5R,6024A   I312 @BASEBOARD_FAB2_LIB.BASEBOARD_FAB2(SCH_1):PAGE220
 C5L14    1      A CAP_0805-100UF,4V,20%,X5R,6024A   I313 @BASEBOARD_FAB2_LIB.BASEBOARD_FAB2(SCH_1):PAGE220
  C5M8    1      A CAP_0805-100UF,4V,20%,X5R,6024A   I314 @BASEBOARD_FAB2_LIB.BASEBOARD_FAB2(SCH_1):PAGE220
  C5P3    1      A CAP_0805-100UF,4V,20%,X5R,6024A   I315 @BASEBOARD_FAB2_LIB.BASEBOARD_FAB2(SCH_1):PAGE220
  C5P6    1      A CAP_0805-100UF,4V,20%,X5R,6024A   I316 @BASEBOARD_FAB2_LIB.BASEBOARD_FAB2(SCH_1):PAGE220
  C5P5    1      A CAP_0805-100UF,4V,20%,X5R,6024A   I317 @BASEBOARD_FAB2_LIB.BASEBOARD_FAB2(SCH_1):PAGE220
  C5P4    1      A CAP_0805-100UF,4V,20%,X5R,6024A   I318 @BASEBOARD_FAB2_LIB.BASEBOARD_FAB2(SCH_1):PAGE220
  C5P2    1      A CAP_0805-100UF,4V,20%,X5R,6024A   I319 @BASEBOARD_FAB2_LIB.BASEBOARD_FAB2(SCH_1):PAGE220
  C5P1    1      A CAP_0805-100UF,4V,20%,X5R,6024A   I320 @BASEBOARD_FAB2_LIB.BASEBOARD_FAB2(SCH_1):PAGE220
 C5A10    1      A CAP_0805-100UF,4V,20%,X5R,6024A   I321 @BASEBOARD_FAB2_LIB.BASEBOARD_FAB2(SCH_1):PAGE220
  L7A1    2      F IND-120NH-30-GP_DISCRET-GB2-INA   I157 @BASEBOARD_FAB2_LIB.BASEBOARD_FAB2(SCH_1):PAGE219
  L7A3    2      F IND-120NH-30-GP_DISCRET-GB2-INA   I158 @BASEBOARD_FAB2_LIB.BASEBOARD_FAB2(SCH_1):PAGE219

PVDDQ_GHJ @BASEBOARD_FAB2_LIB.BASEBOARD_FAB2(SCH_1):PVDDQ_GHJ
  U2D1  B49 VCCD012<0> SKX_EXT_B_BGA1-IC,TBD    I32 @BASEBOARD_FAB2_LIB.BASEBOARD_FAB2(SCH_1):PAGE72
  U2D1  B53 VCCD012<1> SKX_EXT_B_BGA1-IC,TBD    I32 @BASEBOARD_FAB2_LIB.BASEBOARD_FAB2(SCH_1):PAGE72
  U2D1  B59 VCCD012<2> SKX_EXT_B_BGA1-IC,TBD    I32 @BASEBOARD_FAB2_LIB.BASEBOARD_FAB2(SCH_1):PAGE72
  U2D1  E46 VCCD012<3> SKX_EXT_B_BGA1-IC,TBD    I32 @BASEBOARD_FAB2_LIB.BASEBOARD_FAB2(SCH_1):PAGE72
  U2D1  E48 VCCD012<4> SKX_EXT_B_BGA1-IC,TBD    I32 @BASEBOARD_FAB2_LIB.BASEBOARD_FAB2(SCH_1):PAGE72
  U2D1  E50 VCCD012<5> SKX_EXT_B_BGA1-IC,TBD    I32 @BASEBOARD_FAB2_LIB.BASEBOARD_FAB2(SCH_1):PAGE72
  U2D1  E52 VCCD012<6> SKX_EXT_B_BGA1-IC,TBD    I32 @BASEBOARD_FAB2_LIB.BASEBOARD_FAB2(SCH_1):PAGE72
  U2D1  E54 VCCD012<7> SKX_EXT_B_BGA1-IC,TBD    I32 @BASEBOARD_FAB2_LIB.BASEBOARD_FAB2(SCH_1):PAGE72
  U2D1  E56 VCCD012<8> SKX_EXT_B_BGA1-IC,TBD    I32 @BASEBOARD_FAB2_LIB.BASEBOARD_FAB2(SCH_1):PAGE72
  U2D1  E58 VCCD012<9> SKX_EXT_B_BGA1-IC,TBD    I32 @BASEBOARD_FAB2_LIB.BASEBOARD_FAB2(SCH_1):PAGE72
  U2D1  E60 VCCD012<10> SKX_EXT_B_BGA1-IC,TBD    I32 @BASEBOARD_FAB2_LIB.BASEBOARD_FAB2(SCH_1):PAGE72
  U2D1  E62 VCCD012<11> SKX_EXT_B_BGA1-IC,TBD    I32 @BASEBOARD_FAB2_LIB.BASEBOARD_FAB2(SCH_1):PAGE72
  U2D1  E64 VCCD012<12> SKX_EXT_B_BGA1-IC,TBD    I32 @BASEBOARD_FAB2_LIB.BASEBOARD_FAB2(SCH_1):PAGE72
  U2D1  L46 VCCD012<13> SKX_EXT_B_BGA1-IC,TBD    I32 @BASEBOARD_FAB2_LIB.BASEBOARD_FAB2(SCH_1):PAGE72
  U2D1  L48 VCCD012<14> SKX_EXT_B_BGA1-IC,TBD    I32 @BASEBOARD_FAB2_LIB.BASEBOARD_FAB2(SCH_1):PAGE72
  U2D1  L50 VCCD012<15> SKX_EXT_B_BGA1-IC,TBD    I32 @BASEBOARD_FAB2_LIB.BASEBOARD_FAB2(SCH_1):PAGE72
  U2D1  L52 VCCD012<16> SKX_EXT_B_BGA1-IC,TBD    I32 @BASEBOARD_FAB2_LIB.BASEBOARD_FAB2(SCH_1):PAGE72
  U2D1  L54 VCCD012<17> SKX_EXT_B_BGA1-IC,TBD    I32 @BASEBOARD_FAB2_LIB.BASEBOARD_FAB2(SCH_1):PAGE72
  U2D1  L56 VCCD012<18> SKX_EXT_B_BGA1-IC,TBD    I32 @BASEBOARD_FAB2_LIB.BASEBOARD_FAB2(SCH_1):PAGE72
  U2D1  L58 VCCD012<19> SKX_EXT_B_BGA1-IC,TBD    I32 @BASEBOARD_FAB2_LIB.BASEBOARD_FAB2(SCH_1):PAGE72
  U2D1  L60 VCCD012<20> SKX_EXT_B_BGA1-IC,TBD    I32 @BASEBOARD_FAB2_LIB.BASEBOARD_FAB2(SCH_1):PAGE72
  U2D1  L62 VCCD012<21> SKX_EXT_B_BGA1-IC,TBD    I32 @BASEBOARD_FAB2_LIB.BASEBOARD_FAB2(SCH_1):PAGE72
  U2D1  N64 VCCD012<22> SKX_EXT_B_BGA1-IC,TBD    I32 @BASEBOARD_FAB2_LIB.BASEBOARD_FAB2(SCH_1):PAGE72
  U2D1  U46 VCCD012<23> SKX_EXT_B_BGA1-IC,TBD    I32 @BASEBOARD_FAB2_LIB.BASEBOARD_FAB2(SCH_1):PAGE72
  U2D1  U48 VCCD012<24> SKX_EXT_B_BGA1-IC,TBD    I32 @BASEBOARD_FAB2_LIB.BASEBOARD_FAB2(SCH_1):PAGE72
  U2D1  U50 VCCD012<25> SKX_EXT_B_BGA1-IC,TBD    I32 @BASEBOARD_FAB2_LIB.BASEBOARD_FAB2(SCH_1):PAGE72
  U2D1  U52 VCCD012<26> SKX_EXT_B_BGA1-IC,TBD    I32 @BASEBOARD_FAB2_LIB.BASEBOARD_FAB2(SCH_1):PAGE72
  U2D1  U54 VCCD012<27> SKX_EXT_B_BGA1-IC,TBD    I32 @BASEBOARD_FAB2_LIB.BASEBOARD_FAB2(SCH_1):PAGE72
  U2D1  U56 VCCD012<28> SKX_EXT_B_BGA1-IC,TBD    I32 @BASEBOARD_FAB2_LIB.BASEBOARD_FAB2(SCH_1):PAGE72
  U2D1  U58 VCCD012<29> SKX_EXT_B_BGA1-IC,TBD    I32 @BASEBOARD_FAB2_LIB.BASEBOARD_FAB2(SCH_1):PAGE72
  U2D1  U60 VCCD012<30> SKX_EXT_B_BGA1-IC,TBD    I32 @BASEBOARD_FAB2_LIB.BASEBOARD_FAB2(SCH_1):PAGE72
  U2D1  U62 VCCD012<31> SKX_EXT_B_BGA1-IC,TBD    I32 @BASEBOARD_FAB2_LIB.BASEBOARD_FAB2(SCH_1):PAGE72
  U2D1  W64 VCCD012<32> SKX_EXT_B_BGA1-IC,TBD    I32 @BASEBOARD_FAB2_LIB.BASEBOARD_FAB2(SCH_1):PAGE72
  U2D1  Y45 VCCD012<33> SKX_EXT_B_BGA1-IC,TBD    I32 @BASEBOARD_FAB2_LIB.BASEBOARD_FAB2(SCH_1):PAGE72
  U2D1  Y47 VCCD012<34> SKX_EXT_B_BGA1-IC,TBD    I32 @BASEBOARD_FAB2_LIB.BASEBOARD_FAB2(SCH_1):PAGE72
  U2D1  Y49 VCCD012<35> SKX_EXT_B_BGA1-IC,TBD    I32 @BASEBOARD_FAB2_LIB.BASEBOARD_FAB2(SCH_1):PAGE72
  U2D1  Y51 VCCD012<36> SKX_EXT_B_BGA1-IC,TBD    I32 @BASEBOARD_FAB2_LIB.BASEBOARD_FAB2(SCH_1):PAGE72
  U2D1  Y53 VCCD012<37> SKX_EXT_B_BGA1-IC,TBD    I32 @BASEBOARD_FAB2_LIB.BASEBOARD_FAB2(SCH_1):PAGE72
  U2D1  Y55 VCCD012<38> SKX_EXT_B_BGA1-IC,TBD    I32 @BASEBOARD_FAB2_LIB.BASEBOARD_FAB2(SCH_1):PAGE72
  U2D1  Y57 VCCD012<39> SKX_EXT_B_BGA1-IC,TBD    I32 @BASEBOARD_FAB2_LIB.BASEBOARD_FAB2(SCH_1):PAGE72
  U2D1  Y59 VCCD012<40> SKX_EXT_B_BGA1-IC,TBD    I32 @BASEBOARD_FAB2_LIB.BASEBOARD_FAB2(SCH_1):PAGE72
  U2D1  Y61 VCCD012<41> SKX_EXT_B_BGA1-IC,TBD    I32 @BASEBOARD_FAB2_LIB.BASEBOARD_FAB2(SCH_1):PAGE72
  U2D1  Y63 VCCD012<42> SKX_EXT_B_BGA1-IC,TBD    I32 @BASEBOARD_FAB2_LIB.BASEBOARD_FAB2(SCH_1):PAGE72
  U2D1 AD45 VCCD012<43> SKX_EXT_B_BGA1-IC,TBD    I32 @BASEBOARD_FAB2_LIB.BASEBOARD_FAB2(SCH_1):PAGE72
  U2D1 AF55 VCCD012<44> SKX_EXT_B_BGA1-IC,TBD    I32 @BASEBOARD_FAB2_LIB.BASEBOARD_FAB2(SCH_1):PAGE72
  U2D1 AF57 VCCD012<45> SKX_EXT_B_BGA1-IC,TBD    I32 @BASEBOARD_FAB2_LIB.BASEBOARD_FAB2(SCH_1):PAGE72
  U2D1 AF59 VCCD012<46> SKX_EXT_B_BGA1-IC,TBD    I32 @BASEBOARD_FAB2_LIB.BASEBOARD_FAB2(SCH_1):PAGE72
  U2D1 AF61 VCCD012<47> SKX_EXT_B_BGA1-IC,TBD    I32 @BASEBOARD_FAB2_LIB.BASEBOARD_FAB2(SCH_1):PAGE72
  U2D1 AF63 VCCD012<48> SKX_EXT_B_BGA1-IC,TBD    I32 @BASEBOARD_FAB2_LIB.BASEBOARD_FAB2(SCH_1):PAGE72
  U2D1  D45 VCCD012<49> SKX_EXT_B_BGA1-IC,TBD    I32 @BASEBOARD_FAB2_LIB.BASEBOARD_FAB2(SCH_1):PAGE72
  U2D1  C46 VCCD012<50> SKX_EXT_B_BGA1-IC,TBD    I32 @BASEBOARD_FAB2_LIB.BASEBOARD_FAB2(SCH_1):PAGE72
  U2D1  B47 VCCD012<51> SKX_EXT_B_BGA1-IC,TBD    I32 @BASEBOARD_FAB2_LIB.BASEBOARD_FAB2(SCH_1):PAGE72
  J1G1  236 VDD<0> SCONN288_H44441004_PIP-SCONN,HA   I171 @BASEBOARD_FAB2_LIB.BASEBOARD_FAB2(SCH_1):PAGE77
  J1G1  233 VDD<1> SCONN288_H44441004_PIP-SCONN,HA   I171 @BASEBOARD_FAB2_LIB.BASEBOARD_FAB2(SCH_1):PAGE77
  J1G1  231 VDD<2> SCONN288_H44441004_PIP-SCONN,HA   I171 @BASEBOARD_FAB2_LIB.BASEBOARD_FAB2(SCH_1):PAGE77
  J1G1  229 VDD<3> SCONN288_H44441004_PIP-SCONN,HA   I171 @BASEBOARD_FAB2_LIB.BASEBOARD_FAB2(SCH_1):PAGE77
  J1G1  226 VDD<4> SCONN288_H44441004_PIP-SCONN,HA   I171 @BASEBOARD_FAB2_LIB.BASEBOARD_FAB2(SCH_1):PAGE77
  J1G1  223 VDD<5> SCONN288_H44441004_PIP-SCONN,HA   I171 @BASEBOARD_FAB2_LIB.BASEBOARD_FAB2(SCH_1):PAGE77
  J1G1  220 VDD<6> SCONN288_H44441004_PIP-SCONN,HA   I171 @BASEBOARD_FAB2_LIB.BASEBOARD_FAB2(SCH_1):PAGE77
  J1G1  217 VDD<7> SCONN288_H44441004_PIP-SCONN,HA   I171 @BASEBOARD_FAB2_LIB.BASEBOARD_FAB2(SCH_1):PAGE77
  J1G1  215 VDD<8> SCONN288_H44441004_PIP-SCONN,HA   I171 @BASEBOARD_FAB2_LIB.BASEBOARD_FAB2(SCH_1):PAGE77
  J1G1  212 VDD<9> SCONN288_H44441004_PIP-SCONN,HA   I171 @BASEBOARD_FAB2_LIB.BASEBOARD_FAB2(SCH_1):PAGE77
  J1G1  209 VDD<10> SCONN288_H44441004_PIP-SCONN,HA   I171 @BASEBOARD_FAB2_LIB.BASEBOARD_FAB2(SCH_1):PAGE77
  J1G1  206 VDD<11> SCONN288_H44441004_PIP-SCONN,HA   I171 @BASEBOARD_FAB2_LIB.BASEBOARD_FAB2(SCH_1):PAGE77
  J1G1  204 VDD<12> SCONN288_H44441004_PIP-SCONN,HA   I171 @BASEBOARD_FAB2_LIB.BASEBOARD_FAB2(SCH_1):PAGE77
  J1G1   92 VDD<13> SCONN288_H44441004_PIP-SCONN,HA   I171 @BASEBOARD_FAB2_LIB.BASEBOARD_FAB2(SCH_1):PAGE77
  J1G1   90 VDD<14> SCONN288_H44441004_PIP-SCONN,HA   I171 @BASEBOARD_FAB2_LIB.BASEBOARD_FAB2(SCH_1):PAGE77
  J1G1   88 VDD<15> SCONN288_H44441004_PIP-SCONN,HA   I171 @BASEBOARD_FAB2_LIB.BASEBOARD_FAB2(SCH_1):PAGE77
  J1G1   85 VDD<16> SCONN288_H44441004_PIP-SCONN,HA   I171 @BASEBOARD_FAB2_LIB.BASEBOARD_FAB2(SCH_1):PAGE77
  J1G1   83 VDD<17> SCONN288_H44441004_PIP-SCONN,HA   I171 @BASEBOARD_FAB2_LIB.BASEBOARD_FAB2(SCH_1):PAGE77
  J1G1   80 VDD<18> SCONN288_H44441004_PIP-SCONN,HA   I171 @BASEBOARD_FAB2_LIB.BASEBOARD_FAB2(SCH_1):PAGE77
  J1G1   76 VDD<19> SCONN288_H44441004_PIP-SCONN,HA   I171 @BASEBOARD_FAB2_LIB.BASEBOARD_FAB2(SCH_1):PAGE77
  J1G1   73 VDD<20> SCONN288_H44441004_PIP-SCONN,HA   I171 @BASEBOARD_FAB2_LIB.BASEBOARD_FAB2(SCH_1):PAGE77
  J1G1   70 VDD<21> SCONN288_H44441004_PIP-SCONN,HA   I171 @BASEBOARD_FAB2_LIB.BASEBOARD_FAB2(SCH_1):PAGE77
  J1G1   67 VDD<22> SCONN288_H44441004_PIP-SCONN,HA   I171 @BASEBOARD_FAB2_LIB.BASEBOARD_FAB2(SCH_1):PAGE77
  J1G1   64 VDD<23> SCONN288_H44441004_PIP-SCONN,HA   I171 @BASEBOARD_FAB2_LIB.BASEBOARD_FAB2(SCH_1):PAGE77
  J1G1   61 VDD<24> SCONN288_H44441004_PIP-SCONN,HA   I171 @BASEBOARD_FAB2_LIB.BASEBOARD_FAB2(SCH_1):PAGE77
  J1G1   59 VDD<25> SCONN288_H44441004_PIP-SCONN,HA   I171 @BASEBOARD_FAB2_LIB.BASEBOARD_FAB2(SCH_1):PAGE77
  J9T1  236 VDD<0> SCONN288_H44441003_PIP-SCONN,HA    I75 @BASEBOARD_FAB2_LIB.BASEBOARD_FAB2(SCH_1):PAGE78
  J9T1  233 VDD<1> SCONN288_H44441003_PIP-SCONN,HA    I75 @BASEBOARD_FAB2_LIB.BASEBOARD_FAB2(SCH_1):PAGE78
  J9T1  231 VDD<2> SCONN288_H44441003_PIP-SCONN,HA    I75 @BASEBOARD_FAB2_LIB.BASEBOARD_FAB2(SCH_1):PAGE78
  J9T1  229 VDD<3> SCONN288_H44441003_PIP-SCONN,HA    I75 @BASEBOARD_FAB2_LIB.BASEBOARD_FAB2(SCH_1):PAGE78
  J9T1  226 VDD<4> SCONN288_H44441003_PIP-SCONN,HA    I75 @BASEBOARD_FAB2_LIB.BASEBOARD_FAB2(SCH_1):PAGE78
  J9T1  223 VDD<5> SCONN288_H44441003_PIP-SCONN,HA    I75 @BASEBOARD_FAB2_LIB.BASEBOARD_FAB2(SCH_1):PAGE78
  J9T1  220 VDD<6> SCONN288_H44441003_PIP-SCONN,HA    I75 @BASEBOARD_FAB2_LIB.BASEBOARD_FAB2(SCH_1):PAGE78
  J9T1  217 VDD<7> SCONN288_H44441003_PIP-SCONN,HA    I75 @BASEBOARD_FAB2_LIB.BASEBOARD_FAB2(SCH_1):PAGE78
  J9T1  215 VDD<8> SCONN288_H44441003_PIP-SCONN,HA    I75 @BASEBOARD_FAB2_LIB.BASEBOARD_FAB2(SCH_1):PAGE78
  J9T1  212 VDD<9> SCONN288_H44441003_PIP-SCONN,HA    I75 @BASEBOARD_FAB2_LIB.BASEBOARD_FAB2(SCH_1):PAGE78
  J9T1  209 VDD<10> SCONN288_H44441003_PIP-SCONN,HA    I75 @BASEBOARD_FAB2_LIB.BASEBOARD_FAB2(SCH_1):PAGE78
  J9T1  206 VDD<11> SCONN288_H44441003_PIP-SCONN,HA    I75 @BASEBOARD_FAB2_LIB.BASEBOARD_FAB2(SCH_1):PAGE78
  J9T1  204 VDD<12> SCONN288_H44441003_PIP-SCONN,HA    I75 @BASEBOARD_FAB2_LIB.BASEBOARD_FAB2(SCH_1):PAGE78
  J9T1   92 VDD<13> SCONN288_H44441003_PIP-SCONN,HA    I75 @BASEBOARD_FAB2_LIB.BASEBOARD_FAB2(SCH_1):PAGE78
  J9T1   90 VDD<14> SCONN288_H44441003_PIP-SCONN,HA    I75 @BASEBOARD_FAB2_LIB.BASEBOARD_FAB2(SCH_1):PAGE78
  J9T1   88 VDD<15> SCONN288_H44441003_PIP-SCONN,HA    I75 @BASEBOARD_FAB2_LIB.BASEBOARD_FAB2(SCH_1):PAGE78
  J9T1   85 VDD<16> SCONN288_H44441003_PIP-SCONN,HA    I75 @BASEBOARD_FAB2_LIB.BASEBOARD_FAB2(SCH_1):PAGE78
  J9T1   83 VDD<17> SCONN288_H44441003_PIP-SCONN,HA    I75 @BASEBOARD_FAB2_LIB.BASEBOARD_FAB2(SCH_1):PAGE78
  J9T1   80 VDD<18> SCONN288_H44441003_PIP-SCONN,HA    I75 @BASEBOARD_FAB2_LIB.BASEBOARD_FAB2(SCH_1):PAGE78
  J9T1   76 VDD<19> SCONN288_H44441003_PIP-SCONN,HA    I75 @BASEBOARD_FAB2_LIB.BASEBOARD_FAB2(SCH_1):PAGE78
  J9T1   73 VDD<20> SCONN288_H44441003_PIP-SCONN,HA    I75 @BASEBOARD_FAB2_LIB.BASEBOARD_FAB2(SCH_1):PAGE78
  J9T1   70 VDD<21> SCONN288_H44441003_PIP-SCONN,HA    I75 @BASEBOARD_FAB2_LIB.BASEBOARD_FAB2(SCH_1):PAGE78
  J9T1   67 VDD<22> SCONN288_H44441003_PIP-SCONN,HA    I75 @BASEBOARD_FAB2_LIB.BASEBOARD_FAB2(SCH_1):PAGE78
  J9T1   64 VDD<23> SCONN288_H44441003_PIP-SCONN,HA    I75 @BASEBOARD_FAB2_LIB.BASEBOARD_FAB2(SCH_1):PAGE78
  J9T1   61 VDD<24> SCONN288_H44441003_PIP-SCONN,HA    I75 @BASEBOARD_FAB2_LIB.BASEBOARD_FAB2(SCH_1):PAGE78
  J9T1   59 VDD<25> SCONN288_H44441003_PIP-SCONN,HA    I75 @BASEBOARD_FAB2_LIB.BASEBOARD_FAB2(SCH_1):PAGE78
  J1G2  236 VDD<0> SCONN288_H44441004_PIP-SCONN,HA   I169 @BASEBOARD_FAB2_LIB.BASEBOARD_FAB2(SCH_1):PAGE79
  J1G2  233 VDD<1> SCONN288_H44441004_PIP-SCONN,HA   I169 @BASEBOARD_FAB2_LIB.BASEBOARD_FAB2(SCH_1):PAGE79
  J1G2  231 VDD<2> SCONN288_H44441004_PIP-SCONN,HA   I169 @BASEBOARD_FAB2_LIB.BASEBOARD_FAB2(SCH_1):PAGE79
  J1G2  229 VDD<3> SCONN288_H44441004_PIP-SCONN,HA   I169 @BASEBOARD_FAB2_LIB.BASEBOARD_FAB2(SCH_1):PAGE79
  J1G2  226 VDD<4> SCONN288_H44441004_PIP-SCONN,HA   I169 @BASEBOARD_FAB2_LIB.BASEBOARD_FAB2(SCH_1):PAGE79
  J1G2  223 VDD<5> SCONN288_H44441004_PIP-SCONN,HA   I169 @BASEBOARD_FAB2_LIB.BASEBOARD_FAB2(SCH_1):PAGE79
  J1G2  220 VDD<6> SCONN288_H44441004_PIP-SCONN,HA   I169 @BASEBOARD_FAB2_LIB.BASEBOARD_FAB2(SCH_1):PAGE79
  J1G2  217 VDD<7> SCONN288_H44441004_PIP-SCONN,HA   I169 @BASEBOARD_FAB2_LIB.BASEBOARD_FAB2(SCH_1):PAGE79
  J1G2  215 VDD<8> SCONN288_H44441004_PIP-SCONN,HA   I169 @BASEBOARD_FAB2_LIB.BASEBOARD_FAB2(SCH_1):PAGE79
  J1G2  212 VDD<9> SCONN288_H44441004_PIP-SCONN,HA   I169 @BASEBOARD_FAB2_LIB.BASEBOARD_FAB2(SCH_1):PAGE79
  J1G2  209 VDD<10> SCONN288_H44441004_PIP-SCONN,HA   I169 @BASEBOARD_FAB2_LIB.BASEBOARD_FAB2(SCH_1):PAGE79
  J1G2  206 VDD<11> SCONN288_H44441004_PIP-SCONN,HA   I169 @BASEBOARD_FAB2_LIB.BASEBOARD_FAB2(SCH_1):PAGE79
  J1G2  204 VDD<12> SCONN288_H44441004_PIP-SCONN,HA   I169 @BASEBOARD_FAB2_LIB.BASEBOARD_FAB2(SCH_1):PAGE79
  J1G2   92 VDD<13> SCONN288_H44441004_PIP-SCONN,HA   I169 @BASEBOARD_FAB2_LIB.BASEBOARD_FAB2(SCH_1):PAGE79
  J1G2   90 VDD<14> SCONN288_H44441004_PIP-SCONN,HA   I169 @BASEBOARD_FAB2_LIB.BASEBOARD_FAB2(SCH_1):PAGE79
  J1G2   88 VDD<15> SCONN288_H44441004_PIP-SCONN,HA   I169 @BASEBOARD_FAB2_LIB.BASEBOARD_FAB2(SCH_1):PAGE79
  J1G2   85 VDD<16> SCONN288_H44441004_PIP-SCONN,HA   I169 @BASEBOARD_FAB2_LIB.BASEBOARD_FAB2(SCH_1):PAGE79
  J1G2   83 VDD<17> SCONN288_H44441004_PIP-SCONN,HA   I169 @BASEBOARD_FAB2_LIB.BASEBOARD_FAB2(SCH_1):PAGE79
  J1G2   80 VDD<18> SCONN288_H44441004_PIP-SCONN,HA   I169 @BASEBOARD_FAB2_LIB.BASEBOARD_FAB2(SCH_1):PAGE79
  J1G2   76 VDD<19> SCONN288_H44441004_PIP-SCONN,HA   I169 @BASEBOARD_FAB2_LIB.BASEBOARD_FAB2(SCH_1):PAGE79
  J1G2   73 VDD<20> SCONN288_H44441004_PIP-SCONN,HA   I169 @BASEBOARD_FAB2_LIB.BASEBOARD_FAB2(SCH_1):PAGE79
  J1G2   70 VDD<21> SCONN288_H44441004_PIP-SCONN,HA   I169 @BASEBOARD_FAB2_LIB.BASEBOARD_FAB2(SCH_1):PAGE79
  J1G2   67 VDD<22> SCONN288_H44441004_PIP-SCONN,HA   I169 @BASEBOARD_FAB2_LIB.BASEBOARD_FAB2(SCH_1):PAGE79
  J1G2   64 VDD<23> SCONN288_H44441004_PIP-SCONN,HA   I169 @BASEBOARD_FAB2_LIB.BASEBOARD_FAB2(SCH_1):PAGE79
  J1G2   61 VDD<24> SCONN288_H44441004_PIP-SCONN,HA   I169 @BASEBOARD_FAB2_LIB.BASEBOARD_FAB2(SCH_1):PAGE79
  J1G2   59 VDD<25> SCONN288_H44441004_PIP-SCONN,HA   I169 @BASEBOARD_FAB2_LIB.BASEBOARD_FAB2(SCH_1):PAGE79
  J9U1  236 VDD<0> SCONN288_H44441003_PIP-SCONN,HA    I56 @BASEBOARD_FAB2_LIB.BASEBOARD_FAB2(SCH_1):PAGE80
  J9U1  233 VDD<1> SCONN288_H44441003_PIP-SCONN,HA    I56 @BASEBOARD_FAB2_LIB.BASEBOARD_FAB2(SCH_1):PAGE80
  J9U1  231 VDD<2> SCONN288_H44441003_PIP-SCONN,HA    I56 @BASEBOARD_FAB2_LIB.BASEBOARD_FAB2(SCH_1):PAGE80
  J9U1  229 VDD<3> SCONN288_H44441003_PIP-SCONN,HA    I56 @BASEBOARD_FAB2_LIB.BASEBOARD_FAB2(SCH_1):PAGE80
  J9U1  226 VDD<4> SCONN288_H44441003_PIP-SCONN,HA    I56 @BASEBOARD_FAB2_LIB.BASEBOARD_FAB2(SCH_1):PAGE80
  J9U1  223 VDD<5> SCONN288_H44441003_PIP-SCONN,HA    I56 @BASEBOARD_FAB2_LIB.BASEBOARD_FAB2(SCH_1):PAGE80
  J9U1  220 VDD<6> SCONN288_H44441003_PIP-SCONN,HA    I56 @BASEBOARD_FAB2_LIB.BASEBOARD_FAB2(SCH_1):PAGE80
  J9U1  217 VDD<7> SCONN288_H44441003_PIP-SCONN,HA    I56 @BASEBOARD_FAB2_LIB.BASEBOARD_FAB2(SCH_1):PAGE80
  J9U1  215 VDD<8> SCONN288_H44441003_PIP-SCONN,HA    I56 @BASEBOARD_FAB2_LIB.BASEBOARD_FAB2(SCH_1):PAGE80
  J9U1  212 VDD<9> SCONN288_H44441003_PIP-SCONN,HA    I56 @BASEBOARD_FAB2_LIB.BASEBOARD_FAB2(SCH_1):PAGE80
  J9U1  209 VDD<10> SCONN288_H44441003_PIP-SCONN,HA    I56 @BASEBOARD_FAB2_LIB.BASEBOARD_FAB2(SCH_1):PAGE80
  J9U1  206 VDD<11> SCONN288_H44441003_PIP-SCONN,HA    I56 @BASEBOARD_FAB2_LIB.BASEBOARD_FAB2(SCH_1):PAGE80
  J9U1  204 VDD<12> SCONN288_H44441003_PIP-SCONN,HA    I56 @BASEBOARD_FAB2_LIB.BASEBOARD_FAB2(SCH_1):PAGE80
  J9U1   92 VDD<13> SCONN288_H44441003_PIP-SCONN,HA    I56 @BASEBOARD_FAB2_LIB.BASEBOARD_FAB2(SCH_1):PAGE80
  J9U1   90 VDD<14> SCONN288_H44441003_PIP-SCONN,HA    I56 @BASEBOARD_FAB2_LIB.BASEBOARD_FAB2(SCH_1):PAGE80
  J9U1   88 VDD<15> SCONN288_H44441003_PIP-SCONN,HA    I56 @BASEBOARD_FAB2_LIB.BASEBOARD_FAB2(SCH_1):PAGE80
  J9U1   85 VDD<16> SCONN288_H44441003_PIP-SCONN,HA    I56 @BASEBOARD_FAB2_LIB.BASEBOARD_FAB2(SCH_1):PAGE80
  J9U1   83 VDD<17> SCONN288_H44441003_PIP-SCONN,HA    I56 @BASEBOARD_FAB2_LIB.BASEBOARD_FAB2(SCH_1):PAGE80
  J9U1   80 VDD<18> SCONN288_H44441003_PIP-SCONN,HA    I56 @BASEBOARD_FAB2_LIB.BASEBOARD_FAB2(SCH_1):PAGE80
  J9U1   76 VDD<19> SCONN288_H44441003_PIP-SCONN,HA    I56 @BASEBOARD_FAB2_LIB.BASEBOARD_FAB2(SCH_1):PAGE80
  J9U1   73 VDD<20> SCONN288_H44441003_PIP-SCONN,HA    I56 @BASEBOARD_FAB2_LIB.BASEBOARD_FAB2(SCH_1):PAGE80
  J9U1   70 VDD<21> SCONN288_H44441003_PIP-SCONN,HA    I56 @BASEBOARD_FAB2_LIB.BASEBOARD_FAB2(SCH_1):PAGE80
  J9U1   67 VDD<22> SCONN288_H44441003_PIP-SCONN,HA    I56 @BASEBOARD_FAB2_LIB.BASEBOARD_FAB2(SCH_1):PAGE80
  J9U1   64 VDD<23> SCONN288_H44441003_PIP-SCONN,HA    I56 @BASEBOARD_FAB2_LIB.BASEBOARD_FAB2(SCH_1):PAGE80
  J9U1   61 VDD<24> SCONN288_H44441003_PIP-SCONN,HA    I56 @BASEBOARD_FAB2_LIB.BASEBOARD_FAB2(SCH_1):PAGE80
  J9U1   59 VDD<25> SCONN288_H44441003_PIP-SCONN,HA    I56 @BASEBOARD_FAB2_LIB.BASEBOARD_FAB2(SCH_1):PAGE80
  J1G3  236 VDD<0> SCONN288_H44441004_PIP-SCONN,HA   I169 @BASEBOARD_FAB2_LIB.BASEBOARD_FAB2(SCH_1):PAGE81
  J1G3  233 VDD<1> SCONN288_H44441004_PIP-SCONN,HA   I169 @BASEBOARD_FAB2_LIB.BASEBOARD_FAB2(SCH_1):PAGE81
  J1G3  231 VDD<2> SCONN288_H44441004_PIP-SCONN,HA   I169 @BASEBOARD_FAB2_LIB.BASEBOARD_FAB2(SCH_1):PAGE81
  J1G3  229 VDD<3> SCONN288_H44441004_PIP-SCONN,HA   I169 @BASEBOARD_FAB2_LIB.BASEBOARD_FAB2(SCH_1):PAGE81
  J1G3  226 VDD<4> SCONN288_H44441004_PIP-SCONN,HA   I169 @BASEBOARD_FAB2_LIB.BASEBOARD_FAB2(SCH_1):PAGE81
  J1G3  223 VDD<5> SCONN288_H44441004_PIP-SCONN,HA   I169 @BASEBOARD_FAB2_LIB.BASEBOARD_FAB2(SCH_1):PAGE81
  J1G3  220 VDD<6> SCONN288_H44441004_PIP-SCONN,HA   I169 @BASEBOARD_FAB2_LIB.BASEBOARD_FAB2(SCH_1):PAGE81
  J1G3  217 VDD<7> SCONN288_H44441004_PIP-SCONN,HA   I169 @BASEBOARD_FAB2_LIB.BASEBOARD_FAB2(SCH_1):PAGE81
  J1G3  215 VDD<8> SCONN288_H44441004_PIP-SCONN,HA   I169 @BASEBOARD_FAB2_LIB.BASEBOARD_FAB2(SCH_1):PAGE81
  J1G3  212 VDD<9> SCONN288_H44441004_PIP-SCONN,HA   I169 @BASEBOARD_FAB2_LIB.BASEBOARD_FAB2(SCH_1):PAGE81
  J1G3  209 VDD<10> SCONN288_H44441004_PIP-SCONN,HA   I169 @BASEBOARD_FAB2_LIB.BASEBOARD_FAB2(SCH_1):PAGE81
  J1G3  206 VDD<11> SCONN288_H44441004_PIP-SCONN,HA   I169 @BASEBOARD_FAB2_LIB.BASEBOARD_FAB2(SCH_1):PAGE81
  J1G3  204 VDD<12> SCONN288_H44441004_PIP-SCONN,HA   I169 @BASEBOARD_FAB2_LIB.BASEBOARD_FAB2(SCH_1):PAGE81
  J1G3   92 VDD<13> SCONN288_H44441004_PIP-SCONN,HA   I169 @BASEBOARD_FAB2_LIB.BASEBOARD_FAB2(SCH_1):PAGE81
  J1G3   90 VDD<14> SCONN288_H44441004_PIP-SCONN,HA   I169 @BASEBOARD_FAB2_LIB.BASEBOARD_FAB2(SCH_1):PAGE81
  J1G3   88 VDD<15> SCONN288_H44441004_PIP-SCONN,HA   I169 @BASEBOARD_FAB2_LIB.BASEBOARD_FAB2(SCH_1):PAGE81
  J1G3   85 VDD<16> SCONN288_H44441004_PIP-SCONN,HA   I169 @BASEBOARD_FAB2_LIB.BASEBOARD_FAB2(SCH_1):PAGE81
  J1G3   83 VDD<17> SCONN288_H44441004_PIP-SCONN,HA   I169 @BASEBOARD_FAB2_LIB.BASEBOARD_FAB2(SCH_1):PAGE81
  J1G3   80 VDD<18> SCONN288_H44441004_PIP-SCONN,HA   I169 @BASEBOARD_FAB2_LIB.BASEBOARD_FAB2(SCH_1):PAGE81
  J1G3   76 VDD<19> SCONN288_H44441004_PIP-SCONN,HA   I169 @BASEBOARD_FAB2_LIB.BASEBOARD_FAB2(SCH_1):PAGE81
  J1G3   73 VDD<20> SCONN288_H44441004_PIP-SCONN,HA   I169 @BASEBOARD_FAB2_LIB.BASEBOARD_FAB2(SCH_1):PAGE81
  J1G3   70 VDD<21> SCONN288_H44441004_PIP-SCONN,HA   I169 @BASEBOARD_FAB2_LIB.BASEBOARD_FAB2(SCH_1):PAGE81
  J1G3   67 VDD<22> SCONN288_H44441004_PIP-SCONN,HA   I169 @BASEBOARD_FAB2_LIB.BASEBOARD_FAB2(SCH_1):PAGE81
  J1G3   64 VDD<23> SCONN288_H44441004_PIP-SCONN,HA   I169 @BASEBOARD_FAB2_LIB.BASEBOARD_FAB2(SCH_1):PAGE81
  J1G3   61 VDD<24> SCONN288_H44441004_PIP-SCONN,HA   I169 @BASEBOARD_FAB2_LIB.BASEBOARD_FAB2(SCH_1):PAGE81
  J1G3   59 VDD<25> SCONN288_H44441004_PIP-SCONN,HA   I169 @BASEBOARD_FAB2_LIB.BASEBOARD_FAB2(SCH_1):PAGE81
  J9U2  236 VDD<0> SCONN288_H44441003_PIP-SCONN,HA   I171 @BASEBOARD_FAB2_LIB.BASEBOARD_FAB2(SCH_1):PAGE82
  J9U2  233 VDD<1> SCONN288_H44441003_PIP-SCONN,HA   I171 @BASEBOARD_FAB2_LIB.BASEBOARD_FAB2(SCH_1):PAGE82
  J9U2  231 VDD<2> SCONN288_H44441003_PIP-SCONN,HA   I171 @BASEBOARD_FAB2_LIB.BASEBOARD_FAB2(SCH_1):PAGE82
  J9U2  229 VDD<3> SCONN288_H44441003_PIP-SCONN,HA   I171 @BASEBOARD_FAB2_LIB.BASEBOARD_FAB2(SCH_1):PAGE82
  J9U2  226 VDD<4> SCONN288_H44441003_PIP-SCONN,HA   I171 @BASEBOARD_FAB2_LIB.BASEBOARD_FAB2(SCH_1):PAGE82
  J9U2  223 VDD<5> SCONN288_H44441003_PIP-SCONN,HA   I171 @BASEBOARD_FAB2_LIB.BASEBOARD_FAB2(SCH_1):PAGE82
  J9U2  220 VDD<6> SCONN288_H44441003_PIP-SCONN,HA   I171 @BASEBOARD_FAB2_LIB.BASEBOARD_FAB2(SCH_1):PAGE82
  J9U2  217 VDD<7> SCONN288_H44441003_PIP-SCONN,HA   I171 @BASEBOARD_FAB2_LIB.BASEBOARD_FAB2(SCH_1):PAGE82
  J9U2  215 VDD<8> SCONN288_H44441003_PIP-SCONN,HA   I171 @BASEBOARD_FAB2_LIB.BASEBOARD_FAB2(SCH_1):PAGE82
  J9U2  212 VDD<9> SCONN288_H44441003_PIP-SCONN,HA   I171 @BASEBOARD_FAB2_LIB.BASEBOARD_FAB2(SCH_1):PAGE82
  J9U2  209 VDD<10> SCONN288_H44441003_PIP-SCONN,HA   I171 @BASEBOARD_FAB2_LIB.BASEBOARD_FAB2(SCH_1):PAGE82
  J9U2  206 VDD<11> SCONN288_H44441003_PIP-SCONN,HA   I171 @BASEBOARD_FAB2_LIB.BASEBOARD_FAB2(SCH_1):PAGE82
  J9U2  204 VDD<12> SCONN288_H44441003_PIP-SCONN,HA   I171 @BASEBOARD_FAB2_LIB.BASEBOARD_FAB2(SCH_1):PAGE82
  J9U2   92 VDD<13> SCONN288_H44441003_PIP-SCONN,HA   I171 @BASEBOARD_FAB2_LIB.BASEBOARD_FAB2(SCH_1):PAGE82
  J9U2   90 VDD<14> SCONN288_H44441003_PIP-SCONN,HA   I171 @BASEBOARD_FAB2_LIB.BASEBOARD_FAB2(SCH_1):PAGE82
  J9U2   88 VDD<15> SCONN288_H44441003_PIP-SCONN,HA   I171 @BASEBOARD_FAB2_LIB.BASEBOARD_FAB2(SCH_1):PAGE82
  J9U2   85 VDD<16> SCONN288_H44441003_PIP-SCONN,HA   I171 @BASEBOARD_FAB2_LIB.BASEBOARD_FAB2(SCH_1):PAGE82
  J9U2   83 VDD<17> SCONN288_H44441003_PIP-SCONN,HA   I171 @BASEBOARD_FAB2_LIB.BASEBOARD_FAB2(SCH_1):PAGE82
  J9U2   80 VDD<18> SCONN288_H44441003_PIP-SCONN,HA   I171 @BASEBOARD_FAB2_LIB.BASEBOARD_FAB2(SCH_1):PAGE82
  J9U2   76 VDD<19> SCONN288_H44441003_PIP-SCONN,HA   I171 @BASEBOARD_FAB2_LIB.BASEBOARD_FAB2(SCH_1):PAGE82
  J9U2   73 VDD<20> SCONN288_H44441003_PIP-SCONN,HA   I171 @BASEBOARD_FAB2_LIB.BASEBOARD_FAB2(SCH_1):PAGE82
  J9U2   70 VDD<21> SCONN288_H44441003_PIP-SCONN,HA   I171 @BASEBOARD_FAB2_LIB.BASEBOARD_FAB2(SCH_1):PAGE82
  J9U2   67 VDD<22> SCONN288_H44441003_PIP-SCONN,HA   I171 @BASEBOARD_FAB2_LIB.BASEBOARD_FAB2(SCH_1):PAGE82
  J9U2   64 VDD<23> SCONN288_H44441003_PIP-SCONN,HA   I171 @BASEBOARD_FAB2_LIB.BASEBOARD_FAB2(SCH_1):PAGE82
  J9U2   61 VDD<24> SCONN288_H44441003_PIP-SCONN,HA   I171 @BASEBOARD_FAB2_LIB.BASEBOARD_FAB2(SCH_1):PAGE82
  J9U2   59 VDD<25> SCONN288_H44441003_PIP-SCONN,HA   I171 @BASEBOARD_FAB2_LIB.BASEBOARD_FAB2(SCH_1):PAGE82
 R3D21    1      A RES_0402-64.9,1.0%,1/16W,CHIP,A    I30 @BASEBOARD_FAB2_LIB.BASEBOARD_FAB2(SCH_1):PAGE96
  R1F5    1      A RES_0402-1.00K,1%,1/16W,CHIP,GA     I6 @BASEBOARD_FAB2_LIB.BASEBOARD_FAB2(SCH_1):PAGE100
  R1G2    1      A RES_0402-1.00K,1%,1/16W,CHIP,GA    I19 @BASEBOARD_FAB2_LIB.BASEBOARD_FAB2(SCH_1):PAGE100
 R1G15    1      A RES_0402-1.00K,1%,1/16W,CHIP,GA    I35 @BASEBOARD_FAB2_LIB.BASEBOARD_FAB2(SCH_1):PAGE100
 C1G17    1      A CAP_0805LF-22UF,4V,20%,X6S,C95A     I6 @BASEBOARD_FAB2_LIB.BASEBOARD_FAB2(SCH_1):PAGE224
 C1G20    1      A CAP_0805LF-22UF,4V,20%,X6S,C95A    I68 @BASEBOARD_FAB2_LIB.BASEBOARD_FAB2(SCH_1):PAGE224
 EU1G1    1    VOS IR354XX_SM-IR35411,IC,H73688-0A   I110 @BASEBOARD_FAB2_LIB.BASEBOARD_FAB2(SCH_1):PAGE224
 EU1F1    1    VOS IR354XX_SM-IR35411,IC,H73688-0A   I111 @BASEBOARD_FAB2_LIB.BASEBOARD_FAB2(SCH_1):PAGE224
 R1G20    1      A RES_0603-120.0,1%,1/10W,CHIP,GA    I58 @BASEBOARD_FAB2_LIB.BASEBOARD_FAB2(SCH_1):PAGE225
  C9T5    1      A CAPP_3018-470UF,2.5V,20%,ALUM,A    I75 @BASEBOARD_FAB2_LIB.BASEBOARD_FAB2(SCH_1):PAGE225
  C9U2    1      A CAPP_3018-470UF,2.5V,20%,ALUM,A    I76 @BASEBOARD_FAB2_LIB.BASEBOARD_FAB2(SCH_1):PAGE225
  C9U9    1      A CAPP_3018-470UF,2.5V,20%,ALUM,A    I77 @BASEBOARD_FAB2_LIB.BASEBOARD_FAB2(SCH_1):PAGE225
  C9U5    1      A CAPP_3018-470UF,2.5V,20%,ALUM,A    I78 @BASEBOARD_FAB2_LIB.BASEBOARD_FAB2(SCH_1):PAGE225
  C8T4    1      A CAP_A_0603V-47UF,4V,20%,X5R,60A   I196 @BASEBOARD_FAB2_LIB.BASEBOARD_FAB2(SCH_1):PAGE225
  C2G8    1      A CAP_A_0603V-47UF,4V,20%,X5R,60A   I197 @BASEBOARD_FAB2_LIB.BASEBOARD_FAB2(SCH_1):PAGE225
  C8T2    1      A CAP_A_0603V-47UF,4V,20%,X5R,60A   I198 @BASEBOARD_FAB2_LIB.BASEBOARD_FAB2(SCH_1):PAGE225
 C8U13    1      A CAP_A_0603V-47UF,4V,20%,X5R,60A   I199 @BASEBOARD_FAB2_LIB.BASEBOARD_FAB2(SCH_1):PAGE225
 C2G15    1      A CAP_A_0603V-47UF,4V,20%,X5R,60A   I200 @BASEBOARD_FAB2_LIB.BASEBOARD_FAB2(SCH_1):PAGE225
  C2F1    1      A CAP_A_0603V-47UF,4V,20%,X5R,60A   I201 @BASEBOARD_FAB2_LIB.BASEBOARD_FAB2(SCH_1):PAGE225
  C8T1    1      A CAP_A_0603V-47UF,4V,20%,X5R,60A   I202 @BASEBOARD_FAB2_LIB.BASEBOARD_FAB2(SCH_1):PAGE225
  C8U9    1      A CAP_A_0603V-47UF,4V,20%,X5R,60A   I203 @BASEBOARD_FAB2_LIB.BASEBOARD_FAB2(SCH_1):PAGE225
 C8T11    1      A CAP_A_0603V-47UF,4V,20%,X5R,60A   I204 @BASEBOARD_FAB2_LIB.BASEBOARD_FAB2(SCH_1):PAGE225
 SH7U1    2      B SHUNT_SH0201-EMPTY,N_A   I243 @BASEBOARD_FAB2_LIB.BASEBOARD_FAB2(SCH_1):PAGE225
 C5G79    1      A CAP_A_0603V-22.0UF,4V,20%,X6S,A    I53 @BASEBOARD_FAB2_LIB.BASEBOARD_FAB2(SCH_1):PAGE243
 C5G87    1      A CAP_A_0603V-22.0UF,4V,20%,X6S,A    I54 @BASEBOARD_FAB2_LIB.BASEBOARD_FAB2(SCH_1):PAGE243
 C5G86    1      A CAP_A_0603V-22.0UF,4V,20%,X6S,A    I55 @BASEBOARD_FAB2_LIB.BASEBOARD_FAB2(SCH_1):PAGE243
 C5G85    1      A CAP_A_0603V-22.0UF,4V,20%,X6S,A    I56 @BASEBOARD_FAB2_LIB.BASEBOARD_FAB2(SCH_1):PAGE243
 C5G84    1      A CAP_A_0603V-22.0UF,4V,20%,X6S,A    I57 @BASEBOARD_FAB2_LIB.BASEBOARD_FAB2(SCH_1):PAGE243
 C5G83    1      A CAP_A_0603V-22.0UF,4V,20%,X6S,A    I58 @BASEBOARD_FAB2_LIB.BASEBOARD_FAB2(SCH_1):PAGE243
 C5G82    1      A CAP_A_0603V-22.0UF,4V,20%,X6S,A    I59 @BASEBOARD_FAB2_LIB.BASEBOARD_FAB2(SCH_1):PAGE243
 C5G81    1      A CAP_A_0603V-22.0UF,4V,20%,X6S,A    I60 @BASEBOARD_FAB2_LIB.BASEBOARD_FAB2(SCH_1):PAGE243
 C5G80    1      A CAP_A_0603V-22.0UF,4V,20%,X6S,A    I61 @BASEBOARD_FAB2_LIB.BASEBOARD_FAB2(SCH_1):PAGE243
 C5G96    1      A CAP_A_0603V-22.0UF,4V,20%,X6S,A    I62 @BASEBOARD_FAB2_LIB.BASEBOARD_FAB2(SCH_1):PAGE243
 C5G95    1      A CAP_A_0603V-22.0UF,4V,20%,X6S,A    I63 @BASEBOARD_FAB2_LIB.BASEBOARD_FAB2(SCH_1):PAGE243
 C5G94    1      A CAP_A_0603V-22.0UF,4V,20%,X6S,A    I64 @BASEBOARD_FAB2_LIB.BASEBOARD_FAB2(SCH_1):PAGE243
 C5G93    1      A CAP_A_0603V-22.0UF,4V,20%,X6S,A    I65 @BASEBOARD_FAB2_LIB.BASEBOARD_FAB2(SCH_1):PAGE243
 C5G92    1      A CAP_A_0603V-22.0UF,4V,20%,X6S,A    I66 @BASEBOARD_FAB2_LIB.BASEBOARD_FAB2(SCH_1):PAGE243
 C5G91    1      A CAP_A_0603V-22.0UF,4V,20%,X6S,A    I67 @BASEBOARD_FAB2_LIB.BASEBOARD_FAB2(SCH_1):PAGE243
 C5G90    1      A CAP_A_0603V-22.0UF,4V,20%,X6S,A    I68 @BASEBOARD_FAB2_LIB.BASEBOARD_FAB2(SCH_1):PAGE243
 C5G89    1      A CAP_A_0603V-22.0UF,4V,20%,X6S,A    I69 @BASEBOARD_FAB2_LIB.BASEBOARD_FAB2(SCH_1):PAGE243
 C5G88    1      A CAP_A_0603V-22.0UF,4V,20%,X6S,A    I70 @BASEBOARD_FAB2_LIB.BASEBOARD_FAB2(SCH_1):PAGE243
C5G118    1      A CAP_0805-47UF,4V,20%,X6S,C9533A    I91 @BASEBOARD_FAB2_LIB.BASEBOARD_FAB2(SCH_1):PAGE243
C5G117    1      A CAP_0805-47UF,4V,20%,X6S,C9533A    I92 @BASEBOARD_FAB2_LIB.BASEBOARD_FAB2(SCH_1):PAGE243
  R6U6    1      A RES_0402-0.0,5%,1/16W,CHIP,G21A     I6 @BASEBOARD_FAB2_LIB.BASEBOARD_FAB2(SCH_1):PAGE229
 C6U13    1      A CAP_0603LF-10UF,4V,20%,X6S,E15A    I11 @BASEBOARD_FAB2_LIB.BASEBOARD_FAB2(SCH_1):PAGE229
 C6U14    1      A CAP_0603LF-10UF,4V,20%,X6S,E15A    I18 @BASEBOARD_FAB2_LIB.BASEBOARD_FAB2(SCH_1):PAGE229
 EU4G2   10    VIN MIC5166_DFN-IC,H55101-001    I37 @BASEBOARD_FAB2_LIB.BASEBOARD_FAB2(SCH_1):PAGE229
 C2D45    1      A CAP_A_0603V-22.0UF,4V,20%,X6S,A   I261 @BASEBOARD_FAB2_LIB.BASEBOARD_FAB2(SCH_1):PAGE225
 C3D25    1      A CAP_A_0603V-22.0UF,4V,20%,X6S,A   I262 @BASEBOARD_FAB2_LIB.BASEBOARD_FAB2(SCH_1):PAGE225
 C2D47    1      A CAP_A_0603V-22.0UF,4V,20%,X6S,A   I263 @BASEBOARD_FAB2_LIB.BASEBOARD_FAB2(SCH_1):PAGE225
 C2D46    1      A CAP_A_0603V-22.0UF,4V,20%,X6S,A   I264 @BASEBOARD_FAB2_LIB.BASEBOARD_FAB2(SCH_1):PAGE225
 C2D43    1      A CAP_A_0603V-22.0UF,4V,20%,X6S,A   I270 @BASEBOARD_FAB2_LIB.BASEBOARD_FAB2(SCH_1):PAGE225
 C2D41    1      A CAP_A_0603V-22.0UF,4V,20%,X6S,A   I271 @BASEBOARD_FAB2_LIB.BASEBOARD_FAB2(SCH_1):PAGE225
 C2D44    1      A CAP_A_0603V-22.0UF,4V,20%,X6S,A   I272 @BASEBOARD_FAB2_LIB.BASEBOARD_FAB2(SCH_1):PAGE225
 C2D42    1      A CAP_A_0603V-22.0UF,4V,20%,X6S,A   I273 @BASEBOARD_FAB2_LIB.BASEBOARD_FAB2(SCH_1):PAGE225
 C2G10    1      A CAP_A_0603V-47UF,4V,20%,X5R,60A   I274 @BASEBOARD_FAB2_LIB.BASEBOARD_FAB2(SCH_1):PAGE225
 C2G11    1      A CAP_A_0603V-47UF,4V,20%,X5R,60A   I275 @BASEBOARD_FAB2_LIB.BASEBOARD_FAB2(SCH_1):PAGE225
 C2G12    1      A CAP_A_0603V-47UF,4V,20%,X5R,60A   I276 @BASEBOARD_FAB2_LIB.BASEBOARD_FAB2(SCH_1):PAGE225
  C2G1    1      A CAP_A_0603V-47UF,4V,20%,X5R,60A   I277 @BASEBOARD_FAB2_LIB.BASEBOARD_FAB2(SCH_1):PAGE225
  C2G9    1      A CAP_A_0603V-47UF,4V,20%,X5R,60A   I278 @BASEBOARD_FAB2_LIB.BASEBOARD_FAB2(SCH_1):PAGE225
  C2G2    1      A CAP_A_0603V-47UF,4V,20%,X5R,60A   I279 @BASEBOARD_FAB2_LIB.BASEBOARD_FAB2(SCH_1):PAGE225
  C2G3    1      A CAP_A_0603V-47UF,4V,20%,X5R,60A   I280 @BASEBOARD_FAB2_LIB.BASEBOARD_FAB2(SCH_1):PAGE225
  C2G4    1      A CAP_A_0603V-47UF,4V,20%,X5R,60A   I281 @BASEBOARD_FAB2_LIB.BASEBOARD_FAB2(SCH_1):PAGE225
  C2G5    1      A CAP_A_0603V-47UF,4V,20%,X5R,60A   I282 @BASEBOARD_FAB2_LIB.BASEBOARD_FAB2(SCH_1):PAGE225
  C2G6    1      A CAP_A_0603V-47UF,4V,20%,X5R,60A   I283 @BASEBOARD_FAB2_LIB.BASEBOARD_FAB2(SCH_1):PAGE225
  C3G1    1      A CAP_A_0603V-47UF,4V,20%,X5R,60A   I284 @BASEBOARD_FAB2_LIB.BASEBOARD_FAB2(SCH_1):PAGE225
  C3G2    1      A CAP_A_0603V-47UF,4V,20%,X5R,60A   I285 @BASEBOARD_FAB2_LIB.BASEBOARD_FAB2(SCH_1):PAGE225
 C2G13    1      A CAP_A_0603V-47UF,4V,20%,X5R,60A   I286 @BASEBOARD_FAB2_LIB.BASEBOARD_FAB2(SCH_1):PAGE225
 C2G14    1      A CAP_A_0603V-47UF,4V,20%,X5R,60A   I287 @BASEBOARD_FAB2_LIB.BASEBOARD_FAB2(SCH_1):PAGE225
  C3G5    1      A CAP_A_0603V-47UF,4V,20%,X5R,60A   I288 @BASEBOARD_FAB2_LIB.BASEBOARD_FAB2(SCH_1):PAGE225
  C3G6    1      A CAP_A_0603V-47UF,4V,20%,X5R,60A   I289 @BASEBOARD_FAB2_LIB.BASEBOARD_FAB2(SCH_1):PAGE225
  C8U7    1      A CAP_A_0603V-47UF,4V,20%,X5R,60A   I290 @BASEBOARD_FAB2_LIB.BASEBOARD_FAB2(SCH_1):PAGE225
  C8U2    1      A CAP_A_0603V-47UF,4V,20%,X5R,60A   I291 @BASEBOARD_FAB2_LIB.BASEBOARD_FAB2(SCH_1):PAGE225
  C7U2    1      A CAP_A_0603V-47UF,4V,20%,X5R,60A   I292 @BASEBOARD_FAB2_LIB.BASEBOARD_FAB2(SCH_1):PAGE225
  C7U1    1      A CAP_A_0603V-47UF,4V,20%,X5R,60A   I293 @BASEBOARD_FAB2_LIB.BASEBOARD_FAB2(SCH_1):PAGE225
  C8U3    1      A CAP_A_0603V-47UF,4V,20%,X5R,60A   I294 @BASEBOARD_FAB2_LIB.BASEBOARD_FAB2(SCH_1):PAGE225
  C7T4    1      A CAP_A_0603V-47UF,4V,20%,X5R,60A   I295 @BASEBOARD_FAB2_LIB.BASEBOARD_FAB2(SCH_1):PAGE225
  C7T5    1      A CAP_A_0603V-47UF,4V,20%,X5R,60A   I296 @BASEBOARD_FAB2_LIB.BASEBOARD_FAB2(SCH_1):PAGE225
  C8T5    1      A CAP_A_0603V-47UF,4V,20%,X5R,60A   I297 @BASEBOARD_FAB2_LIB.BASEBOARD_FAB2(SCH_1):PAGE225
  C8U6    1      A CAP_A_0603V-47UF,4V,20%,X5R,60A   I298 @BASEBOARD_FAB2_LIB.BASEBOARD_FAB2(SCH_1):PAGE225
  C8T6    1      A CAP_A_0603V-47UF,4V,20%,X5R,60A   I299 @BASEBOARD_FAB2_LIB.BASEBOARD_FAB2(SCH_1):PAGE225
  C8T7    1      A CAP_A_0603V-47UF,4V,20%,X5R,60A   I300 @BASEBOARD_FAB2_LIB.BASEBOARD_FAB2(SCH_1):PAGE225
  C8T8    1      A CAP_A_0603V-47UF,4V,20%,X5R,60A   I301 @BASEBOARD_FAB2_LIB.BASEBOARD_FAB2(SCH_1):PAGE225
  C8U5    1      A CAP_A_0603V-47UF,4V,20%,X5R,60A   I302 @BASEBOARD_FAB2_LIB.BASEBOARD_FAB2(SCH_1):PAGE225
  C8T9    1      A CAP_A_0603V-47UF,4V,20%,X5R,60A   I303 @BASEBOARD_FAB2_LIB.BASEBOARD_FAB2(SCH_1):PAGE225
 C8T10    1      A CAP_A_0603V-47UF,4V,20%,X5R,60A   I304 @BASEBOARD_FAB2_LIB.BASEBOARD_FAB2(SCH_1):PAGE225
  C8U4    1      A CAP_A_0603V-47UF,4V,20%,X5R,60A   I305 @BASEBOARD_FAB2_LIB.BASEBOARD_FAB2(SCH_1):PAGE225
 C8U11    1      A CAP_0805-100UF,4V,20%,X5R,6024A   I307 @BASEBOARD_FAB2_LIB.BASEBOARD_FAB2(SCH_1):PAGE225
  C7U7    1      A CAP_0805-100UF,4V,20%,X5R,6024A   I308 @BASEBOARD_FAB2_LIB.BASEBOARD_FAB2(SCH_1):PAGE225
  C7T1    1      A CAP_0805-100UF,4V,20%,X5R,6024A   I309 @BASEBOARD_FAB2_LIB.BASEBOARD_FAB2(SCH_1):PAGE225
 C8U12    1      A CAP_0805-100UF,4V,20%,X5R,6024A   I310 @BASEBOARD_FAB2_LIB.BASEBOARD_FAB2(SCH_1):PAGE225
 C2G16    1      A CAP_0805-100UF,4V,20%,X5R,6024A   I311 @BASEBOARD_FAB2_LIB.BASEBOARD_FAB2(SCH_1):PAGE225
  C2G7    1      A CAP_0805-100UF,4V,20%,X5R,6024A   I312 @BASEBOARD_FAB2_LIB.BASEBOARD_FAB2(SCH_1):PAGE225
 C8P30    1      A CAP_0805-100UF,4V,20%,X5R,6024A   I313 @BASEBOARD_FAB2_LIB.BASEBOARD_FAB2(SCH_1):PAGE225
 C8P31    1      A CAP_0805-100UF,4V,20%,X5R,6024A   I314 @BASEBOARD_FAB2_LIB.BASEBOARD_FAB2(SCH_1):PAGE225
 C8P34    1      A CAP_0805-100UF,4V,20%,X5R,6024A   I315 @BASEBOARD_FAB2_LIB.BASEBOARD_FAB2(SCH_1):PAGE225
 C8P33    1      A CAP_0805-100UF,4V,20%,X5R,6024A   I316 @BASEBOARD_FAB2_LIB.BASEBOARD_FAB2(SCH_1):PAGE225
 C8P32    1      A CAP_0805-100UF,4V,20%,X5R,6024A   I317 @BASEBOARD_FAB2_LIB.BASEBOARD_FAB2(SCH_1):PAGE225
 C7P20    1      A CAP_0805-100UF,4V,20%,X5R,6024A   I318 @BASEBOARD_FAB2_LIB.BASEBOARD_FAB2(SCH_1):PAGE225
  C8U1    1      A CAP_0805-100UF,4V,20%,X5R,6024A   I319 @BASEBOARD_FAB2_LIB.BASEBOARD_FAB2(SCH_1):PAGE225
  C8U8    1      A CAP_0805-100UF,4V,20%,X5R,6024A   I320 @BASEBOARD_FAB2_LIB.BASEBOARD_FAB2(SCH_1):PAGE225
  L1G1    2      F IND-120NH-30-GP_DISCRET-GB2-INA   I160 @BASEBOARD_FAB2_LIB.BASEBOARD_FAB2(SCH_1):PAGE224
  L1F2    2      F IND-120NH-30-GP_DISCRET-GB2-INA   I161 @BASEBOARD_FAB2_LIB.BASEBOARD_FAB2(SCH_1):PAGE224

PVDDQ_KLM @BASEBOARD_FAB2_LIB.BASEBOARD_FAB2(SCH_1):PVDDQ_KLM
  U2D1 EF59 VCCD345<0> SKX_EXT_B_BGA1-IC,TBD    I32 @BASEBOARD_FAB2_LIB.BASEBOARD_FAB2(SCH_1):PAGE72
  U2D1 EF53 VCCD345<1> SKX_EXT_B_BGA1-IC,TBD    I32 @BASEBOARD_FAB2_LIB.BASEBOARD_FAB2(SCH_1):PAGE72
  U2D1 EF49 VCCD345<2> SKX_EXT_B_BGA1-IC,TBD    I32 @BASEBOARD_FAB2_LIB.BASEBOARD_FAB2(SCH_1):PAGE72
  U2D1 EC62 VCCD345<3> SKX_EXT_B_BGA1-IC,TBD    I32 @BASEBOARD_FAB2_LIB.BASEBOARD_FAB2(SCH_1):PAGE72
  U2D1 EC60 VCCD345<4> SKX_EXT_B_BGA1-IC,TBD    I32 @BASEBOARD_FAB2_LIB.BASEBOARD_FAB2(SCH_1):PAGE72
  U2D1 EC58 VCCD345<5> SKX_EXT_B_BGA1-IC,TBD    I32 @BASEBOARD_FAB2_LIB.BASEBOARD_FAB2(SCH_1):PAGE72
  U2D1 EC56 VCCD345<6> SKX_EXT_B_BGA1-IC,TBD    I32 @BASEBOARD_FAB2_LIB.BASEBOARD_FAB2(SCH_1):PAGE72
  U2D1 EC54 VCCD345<7> SKX_EXT_B_BGA1-IC,TBD    I32 @BASEBOARD_FAB2_LIB.BASEBOARD_FAB2(SCH_1):PAGE72
  U2D1 EC52 VCCD345<8> SKX_EXT_B_BGA1-IC,TBD    I32 @BASEBOARD_FAB2_LIB.BASEBOARD_FAB2(SCH_1):PAGE72
  U2D1 EC50 VCCD345<9> SKX_EXT_B_BGA1-IC,TBD    I32 @BASEBOARD_FAB2_LIB.BASEBOARD_FAB2(SCH_1):PAGE72
  U2D1 EC48 VCCD345<10> SKX_EXT_B_BGA1-IC,TBD    I32 @BASEBOARD_FAB2_LIB.BASEBOARD_FAB2(SCH_1):PAGE72
  U2D1 EC46 VCCD345<11> SKX_EXT_B_BGA1-IC,TBD    I32 @BASEBOARD_FAB2_LIB.BASEBOARD_FAB2(SCH_1):PAGE72
  U2D1 DU64 VCCD345<12> SKX_EXT_B_BGA1-IC,TBD    I32 @BASEBOARD_FAB2_LIB.BASEBOARD_FAB2(SCH_1):PAGE72
  U2D1 DU62 VCCD345<13> SKX_EXT_B_BGA1-IC,TBD    I32 @BASEBOARD_FAB2_LIB.BASEBOARD_FAB2(SCH_1):PAGE72
  U2D1 DU60 VCCD345<14> SKX_EXT_B_BGA1-IC,TBD    I32 @BASEBOARD_FAB2_LIB.BASEBOARD_FAB2(SCH_1):PAGE72
  U2D1 DU58 VCCD345<15> SKX_EXT_B_BGA1-IC,TBD    I32 @BASEBOARD_FAB2_LIB.BASEBOARD_FAB2(SCH_1):PAGE72
  U2D1 DU56 VCCD345<16> SKX_EXT_B_BGA1-IC,TBD    I32 @BASEBOARD_FAB2_LIB.BASEBOARD_FAB2(SCH_1):PAGE72
  U2D1 DU54 VCCD345<17> SKX_EXT_B_BGA1-IC,TBD    I32 @BASEBOARD_FAB2_LIB.BASEBOARD_FAB2(SCH_1):PAGE72
  U2D1 DU52 VCCD345<18> SKX_EXT_B_BGA1-IC,TBD    I32 @BASEBOARD_FAB2_LIB.BASEBOARD_FAB2(SCH_1):PAGE72
  U2D1 DU50 VCCD345<19> SKX_EXT_B_BGA1-IC,TBD    I32 @BASEBOARD_FAB2_LIB.BASEBOARD_FAB2(SCH_1):PAGE72
  U2D1 DU48 VCCD345<20> SKX_EXT_B_BGA1-IC,TBD    I32 @BASEBOARD_FAB2_LIB.BASEBOARD_FAB2(SCH_1):PAGE72
  U2D1 DU46 VCCD345<21> SKX_EXT_B_BGA1-IC,TBD    I32 @BASEBOARD_FAB2_LIB.BASEBOARD_FAB2(SCH_1):PAGE72
  U2D1 DL62 VCCD345<22> SKX_EXT_B_BGA1-IC,TBD    I32 @BASEBOARD_FAB2_LIB.BASEBOARD_FAB2(SCH_1):PAGE72
  U2D1 DL60 VCCD345<23> SKX_EXT_B_BGA1-IC,TBD    I32 @BASEBOARD_FAB2_LIB.BASEBOARD_FAB2(SCH_1):PAGE72
  U2D1 DL58 VCCD345<24> SKX_EXT_B_BGA1-IC,TBD    I32 @BASEBOARD_FAB2_LIB.BASEBOARD_FAB2(SCH_1):PAGE72
  U2D1 DL56 VCCD345<25> SKX_EXT_B_BGA1-IC,TBD    I32 @BASEBOARD_FAB2_LIB.BASEBOARD_FAB2(SCH_1):PAGE72
  U2D1 DL54 VCCD345<26> SKX_EXT_B_BGA1-IC,TBD    I32 @BASEBOARD_FAB2_LIB.BASEBOARD_FAB2(SCH_1):PAGE72
  U2D1 DL52 VCCD345<27> SKX_EXT_B_BGA1-IC,TBD    I32 @BASEBOARD_FAB2_LIB.BASEBOARD_FAB2(SCH_1):PAGE72
  U2D1 DL50 VCCD345<28> SKX_EXT_B_BGA1-IC,TBD    I32 @BASEBOARD_FAB2_LIB.BASEBOARD_FAB2(SCH_1):PAGE72
  U2D1 DL48 VCCD345<29> SKX_EXT_B_BGA1-IC,TBD    I32 @BASEBOARD_FAB2_LIB.BASEBOARD_FAB2(SCH_1):PAGE72
  U2D1 DL46 VCCD345<30> SKX_EXT_B_BGA1-IC,TBD    I32 @BASEBOARD_FAB2_LIB.BASEBOARD_FAB2(SCH_1):PAGE72
  U2D1 DJ64 VCCD345<31> SKX_EXT_B_BGA1-IC,TBD    I32 @BASEBOARD_FAB2_LIB.BASEBOARD_FAB2(SCH_1):PAGE72
  U2D1 DH63 VCCD345<32> SKX_EXT_B_BGA1-IC,TBD    I32 @BASEBOARD_FAB2_LIB.BASEBOARD_FAB2(SCH_1):PAGE72
  U2D1 DH61 VCCD345<33> SKX_EXT_B_BGA1-IC,TBD    I32 @BASEBOARD_FAB2_LIB.BASEBOARD_FAB2(SCH_1):PAGE72
  U2D1 DH59 VCCD345<34> SKX_EXT_B_BGA1-IC,TBD    I32 @BASEBOARD_FAB2_LIB.BASEBOARD_FAB2(SCH_1):PAGE72
  U2D1 DH57 VCCD345<35> SKX_EXT_B_BGA1-IC,TBD    I32 @BASEBOARD_FAB2_LIB.BASEBOARD_FAB2(SCH_1):PAGE72
  U2D1 DH55 VCCD345<36> SKX_EXT_B_BGA1-IC,TBD    I32 @BASEBOARD_FAB2_LIB.BASEBOARD_FAB2(SCH_1):PAGE72
  U2D1 DH53 VCCD345<37> SKX_EXT_B_BGA1-IC,TBD    I32 @BASEBOARD_FAB2_LIB.BASEBOARD_FAB2(SCH_1):PAGE72
  U2D1 DH51 VCCD345<38> SKX_EXT_B_BGA1-IC,TBD    I32 @BASEBOARD_FAB2_LIB.BASEBOARD_FAB2(SCH_1):PAGE72
  U2D1 DH49 VCCD345<39> SKX_EXT_B_BGA1-IC,TBD    I32 @BASEBOARD_FAB2_LIB.BASEBOARD_FAB2(SCH_1):PAGE72
  U2D1 DH47 VCCD345<40> SKX_EXT_B_BGA1-IC,TBD    I32 @BASEBOARD_FAB2_LIB.BASEBOARD_FAB2(SCH_1):PAGE72
  U2D1 DH45 VCCD345<41> SKX_EXT_B_BGA1-IC,TBD    I32 @BASEBOARD_FAB2_LIB.BASEBOARD_FAB2(SCH_1):PAGE72
  U2D1 DD45 VCCD345<42> SKX_EXT_B_BGA1-IC,TBD    I32 @BASEBOARD_FAB2_LIB.BASEBOARD_FAB2(SCH_1):PAGE72
  U2D1 DB63 VCCD345<43> SKX_EXT_B_BGA1-IC,TBD    I32 @BASEBOARD_FAB2_LIB.BASEBOARD_FAB2(SCH_1):PAGE72
  U2D1 DB61 VCCD345<44> SKX_EXT_B_BGA1-IC,TBD    I32 @BASEBOARD_FAB2_LIB.BASEBOARD_FAB2(SCH_1):PAGE72
  U2D1 DB59 VCCD345<45> SKX_EXT_B_BGA1-IC,TBD    I32 @BASEBOARD_FAB2_LIB.BASEBOARD_FAB2(SCH_1):PAGE72
  U2D1 DB57 VCCD345<46> SKX_EXT_B_BGA1-IC,TBD    I32 @BASEBOARD_FAB2_LIB.BASEBOARD_FAB2(SCH_1):PAGE72
  U2D1 DB55 VCCD345<47> SKX_EXT_B_BGA1-IC,TBD    I32 @BASEBOARD_FAB2_LIB.BASEBOARD_FAB2(SCH_1):PAGE72
  U2D1 DB53 VCCD345<48> SKX_EXT_B_BGA1-IC,TBD    I32 @BASEBOARD_FAB2_LIB.BASEBOARD_FAB2(SCH_1):PAGE72
  U2D1 EF45 VCCD345<49> SKX_EXT_B_BGA1-IC,TBD    I32 @BASEBOARD_FAB2_LIB.BASEBOARD_FAB2(SCH_1):PAGE72
  U2D1 EE44 VCCD345<50> SKX_EXT_B_BGA1-IC,TBD    I32 @BASEBOARD_FAB2_LIB.BASEBOARD_FAB2(SCH_1):PAGE72
  J1B1  236 VDD<0> SCONN288_H44441004_PIP-SCONN,HA   I167 @BASEBOARD_FAB2_LIB.BASEBOARD_FAB2(SCH_1):PAGE83
  J1B1  233 VDD<1> SCONN288_H44441004_PIP-SCONN,HA   I167 @BASEBOARD_FAB2_LIB.BASEBOARD_FAB2(SCH_1):PAGE83
  J1B1  231 VDD<2> SCONN288_H44441004_PIP-SCONN,HA   I167 @BASEBOARD_FAB2_LIB.BASEBOARD_FAB2(SCH_1):PAGE83
  J1B1  229 VDD<3> SCONN288_H44441004_PIP-SCONN,HA   I167 @BASEBOARD_FAB2_LIB.BASEBOARD_FAB2(SCH_1):PAGE83
  J1B1  226 VDD<4> SCONN288_H44441004_PIP-SCONN,HA   I167 @BASEBOARD_FAB2_LIB.BASEBOARD_FAB2(SCH_1):PAGE83
  J1B1  223 VDD<5> SCONN288_H44441004_PIP-SCONN,HA   I167 @BASEBOARD_FAB2_LIB.BASEBOARD_FAB2(SCH_1):PAGE83
  J1B1  220 VDD<6> SCONN288_H44441004_PIP-SCONN,HA   I167 @BASEBOARD_FAB2_LIB.BASEBOARD_FAB2(SCH_1):PAGE83
  J1B1  217 VDD<7> SCONN288_H44441004_PIP-SCONN,HA   I167 @BASEBOARD_FAB2_LIB.BASEBOARD_FAB2(SCH_1):PAGE83
  J1B1  215 VDD<8> SCONN288_H44441004_PIP-SCONN,HA   I167 @BASEBOARD_FAB2_LIB.BASEBOARD_FAB2(SCH_1):PAGE83
  J1B1  212 VDD<9> SCONN288_H44441004_PIP-SCONN,HA   I167 @BASEBOARD_FAB2_LIB.BASEBOARD_FAB2(SCH_1):PAGE83
  J1B1  209 VDD<10> SCONN288_H44441004_PIP-SCONN,HA   I167 @BASEBOARD_FAB2_LIB.BASEBOARD_FAB2(SCH_1):PAGE83
  J1B1  206 VDD<11> SCONN288_H44441004_PIP-SCONN,HA   I167 @BASEBOARD_FAB2_LIB.BASEBOARD_FAB2(SCH_1):PAGE83
  J1B1  204 VDD<12> SCONN288_H44441004_PIP-SCONN,HA   I167 @BASEBOARD_FAB2_LIB.BASEBOARD_FAB2(SCH_1):PAGE83
  J1B1   92 VDD<13> SCONN288_H44441004_PIP-SCONN,HA   I167 @BASEBOARD_FAB2_LIB.BASEBOARD_FAB2(SCH_1):PAGE83
  J1B1   90 VDD<14> SCONN288_H44441004_PIP-SCONN,HA   I167 @BASEBOARD_FAB2_LIB.BASEBOARD_FAB2(SCH_1):PAGE83
  J1B1   88 VDD<15> SCONN288_H44441004_PIP-SCONN,HA   I167 @BASEBOARD_FAB2_LIB.BASEBOARD_FAB2(SCH_1):PAGE83
  J1B1   85 VDD<16> SCONN288_H44441004_PIP-SCONN,HA   I167 @BASEBOARD_FAB2_LIB.BASEBOARD_FAB2(SCH_1):PAGE83
  J1B1   83 VDD<17> SCONN288_H44441004_PIP-SCONN,HA   I167 @BASEBOARD_FAB2_LIB.BASEBOARD_FAB2(SCH_1):PAGE83
  J1B1   80 VDD<18> SCONN288_H44441004_PIP-SCONN,HA   I167 @BASEBOARD_FAB2_LIB.BASEBOARD_FAB2(SCH_1):PAGE83
  J1B1   76 VDD<19> SCONN288_H44441004_PIP-SCONN,HA   I167 @BASEBOARD_FAB2_LIB.BASEBOARD_FAB2(SCH_1):PAGE83
  J1B1   73 VDD<20> SCONN288_H44441004_PIP-SCONN,HA   I167 @BASEBOARD_FAB2_LIB.BASEBOARD_FAB2(SCH_1):PAGE83
  J1B1   70 VDD<21> SCONN288_H44441004_PIP-SCONN,HA   I167 @BASEBOARD_FAB2_LIB.BASEBOARD_FAB2(SCH_1):PAGE83
  J1B1   67 VDD<22> SCONN288_H44441004_PIP-SCONN,HA   I167 @BASEBOARD_FAB2_LIB.BASEBOARD_FAB2(SCH_1):PAGE83
  J1B1   64 VDD<23> SCONN288_H44441004_PIP-SCONN,HA   I167 @BASEBOARD_FAB2_LIB.BASEBOARD_FAB2(SCH_1):PAGE83
  J1B1   61 VDD<24> SCONN288_H44441004_PIP-SCONN,HA   I167 @BASEBOARD_FAB2_LIB.BASEBOARD_FAB2(SCH_1):PAGE83
  J1B1   59 VDD<25> SCONN288_H44441004_PIP-SCONN,HA   I167 @BASEBOARD_FAB2_LIB.BASEBOARD_FAB2(SCH_1):PAGE83
  J9M1  236 VDD<0> SCONN288_H44441003_PIP-SCONN,HA    I57 @BASEBOARD_FAB2_LIB.BASEBOARD_FAB2(SCH_1):PAGE84
  J9M1  233 VDD<1> SCONN288_H44441003_PIP-SCONN,HA    I57 @BASEBOARD_FAB2_LIB.BASEBOARD_FAB2(SCH_1):PAGE84
  J9M1  231 VDD<2> SCONN288_H44441003_PIP-SCONN,HA    I57 @BASEBOARD_FAB2_LIB.BASEBOARD_FAB2(SCH_1):PAGE84
  J9M1  229 VDD<3> SCONN288_H44441003_PIP-SCONN,HA    I57 @BASEBOARD_FAB2_LIB.BASEBOARD_FAB2(SCH_1):PAGE84
  J9M1  226 VDD<4> SCONN288_H44441003_PIP-SCONN,HA    I57 @BASEBOARD_FAB2_LIB.BASEBOARD_FAB2(SCH_1):PAGE84
  J9M1  223 VDD<5> SCONN288_H44441003_PIP-SCONN,HA    I57 @BASEBOARD_FAB2_LIB.BASEBOARD_FAB2(SCH_1):PAGE84
  J9M1  220 VDD<6> SCONN288_H44441003_PIP-SCONN,HA    I57 @BASEBOARD_FAB2_LIB.BASEBOARD_FAB2(SCH_1):PAGE84
  J9M1  217 VDD<7> SCONN288_H44441003_PIP-SCONN,HA    I57 @BASEBOARD_FAB2_LIB.BASEBOARD_FAB2(SCH_1):PAGE84
  J9M1  215 VDD<8> SCONN288_H44441003_PIP-SCONN,HA    I57 @BASEBOARD_FAB2_LIB.BASEBOARD_FAB2(SCH_1):PAGE84
  J9M1  212 VDD<9> SCONN288_H44441003_PIP-SCONN,HA    I57 @BASEBOARD_FAB2_LIB.BASEBOARD_FAB2(SCH_1):PAGE84
  J9M1  209 VDD<10> SCONN288_H44441003_PIP-SCONN,HA    I57 @BASEBOARD_FAB2_LIB.BASEBOARD_FAB2(SCH_1):PAGE84
  J9M1  206 VDD<11> SCONN288_H44441003_PIP-SCONN,HA    I57 @BASEBOARD_FAB2_LIB.BASEBOARD_FAB2(SCH_1):PAGE84
  J9M1  204 VDD<12> SCONN288_H44441003_PIP-SCONN,HA    I57 @BASEBOARD_FAB2_LIB.BASEBOARD_FAB2(SCH_1):PAGE84
  J9M1   92 VDD<13> SCONN288_H44441003_PIP-SCONN,HA    I57 @BASEBOARD_FAB2_LIB.BASEBOARD_FAB2(SCH_1):PAGE84
  J9M1   90 VDD<14> SCONN288_H44441003_PIP-SCONN,HA    I57 @BASEBOARD_FAB2_LIB.BASEBOARD_FAB2(SCH_1):PAGE84
  J9M1   88 VDD<15> SCONN288_H44441003_PIP-SCONN,HA    I57 @BASEBOARD_FAB2_LIB.BASEBOARD_FAB2(SCH_1):PAGE84
  J9M1   85 VDD<16> SCONN288_H44441003_PIP-SCONN,HA    I57 @BASEBOARD_FAB2_LIB.BASEBOARD_FAB2(SCH_1):PAGE84
  J9M1   83 VDD<17> SCONN288_H44441003_PIP-SCONN,HA    I57 @BASEBOARD_FAB2_LIB.BASEBOARD_FAB2(SCH_1):PAGE84
  J9M1   80 VDD<18> SCONN288_H44441003_PIP-SCONN,HA    I57 @BASEBOARD_FAB2_LIB.BASEBOARD_FAB2(SCH_1):PAGE84
  J9M1   76 VDD<19> SCONN288_H44441003_PIP-SCONN,HA    I57 @BASEBOARD_FAB2_LIB.BASEBOARD_FAB2(SCH_1):PAGE84
  J9M1   73 VDD<20> SCONN288_H44441003_PIP-SCONN,HA    I57 @BASEBOARD_FAB2_LIB.BASEBOARD_FAB2(SCH_1):PAGE84
  J9M1   70 VDD<21> SCONN288_H44441003_PIP-SCONN,HA    I57 @BASEBOARD_FAB2_LIB.BASEBOARD_FAB2(SCH_1):PAGE84
  J9M1   67 VDD<22> SCONN288_H44441003_PIP-SCONN,HA    I57 @BASEBOARD_FAB2_LIB.BASEBOARD_FAB2(SCH_1):PAGE84
  J9M1   64 VDD<23> SCONN288_H44441003_PIP-SCONN,HA    I57 @BASEBOARD_FAB2_LIB.BASEBOARD_FAB2(SCH_1):PAGE84
  J9M1   61 VDD<24> SCONN288_H44441003_PIP-SCONN,HA    I57 @BASEBOARD_FAB2_LIB.BASEBOARD_FAB2(SCH_1):PAGE84
  J9M1   59 VDD<25> SCONN288_H44441003_PIP-SCONN,HA    I57 @BASEBOARD_FAB2_LIB.BASEBOARD_FAB2(SCH_1):PAGE84
  J1A2  236 VDD<0> SCONN288_H44441004_PIP-SCONN,HA   I172 @BASEBOARD_FAB2_LIB.BASEBOARD_FAB2(SCH_1):PAGE85
  J1A2  233 VDD<1> SCONN288_H44441004_PIP-SCONN,HA   I172 @BASEBOARD_FAB2_LIB.BASEBOARD_FAB2(SCH_1):PAGE85
  J1A2  231 VDD<2> SCONN288_H44441004_PIP-SCONN,HA   I172 @BASEBOARD_FAB2_LIB.BASEBOARD_FAB2(SCH_1):PAGE85
  J1A2  229 VDD<3> SCONN288_H44441004_PIP-SCONN,HA   I172 @BASEBOARD_FAB2_LIB.BASEBOARD_FAB2(SCH_1):PAGE85
  J1A2  226 VDD<4> SCONN288_H44441004_PIP-SCONN,HA   I172 @BASEBOARD_FAB2_LIB.BASEBOARD_FAB2(SCH_1):PAGE85
  J1A2  223 VDD<5> SCONN288_H44441004_PIP-SCONN,HA   I172 @BASEBOARD_FAB2_LIB.BASEBOARD_FAB2(SCH_1):PAGE85
  J1A2  220 VDD<6> SCONN288_H44441004_PIP-SCONN,HA   I172 @BASEBOARD_FAB2_LIB.BASEBOARD_FAB2(SCH_1):PAGE85
  J1A2  217 VDD<7> SCONN288_H44441004_PIP-SCONN,HA   I172 @BASEBOARD_FAB2_LIB.BASEBOARD_FAB2(SCH_1):PAGE85
  J1A2  215 VDD<8> SCONN288_H44441004_PIP-SCONN,HA   I172 @BASEBOARD_FAB2_LIB.BASEBOARD_FAB2(SCH_1):PAGE85
  J1A2  212 VDD<9> SCONN288_H44441004_PIP-SCONN,HA   I172 @BASEBOARD_FAB2_LIB.BASEBOARD_FAB2(SCH_1):PAGE85
  J1A2  209 VDD<10> SCONN288_H44441004_PIP-SCONN,HA   I172 @BASEBOARD_FAB2_LIB.BASEBOARD_FAB2(SCH_1):PAGE85
  J1A2  206 VDD<11> SCONN288_H44441004_PIP-SCONN,HA   I172 @BASEBOARD_FAB2_LIB.BASEBOARD_FAB2(SCH_1):PAGE85
  J1A2  204 VDD<12> SCONN288_H44441004_PIP-SCONN,HA   I172 @BASEBOARD_FAB2_LIB.BASEBOARD_FAB2(SCH_1):PAGE85
  J1A2   92 VDD<13> SCONN288_H44441004_PIP-SCONN,HA   I172 @BASEBOARD_FAB2_LIB.BASEBOARD_FAB2(SCH_1):PAGE85
  J1A2   90 VDD<14> SCONN288_H44441004_PIP-SCONN,HA   I172 @BASEBOARD_FAB2_LIB.BASEBOARD_FAB2(SCH_1):PAGE85
  J1A2   88 VDD<15> SCONN288_H44441004_PIP-SCONN,HA   I172 @BASEBOARD_FAB2_LIB.BASEBOARD_FAB2(SCH_1):PAGE85
  J1A2   85 VDD<16> SCONN288_H44441004_PIP-SCONN,HA   I172 @BASEBOARD_FAB2_LIB.BASEBOARD_FAB2(SCH_1):PAGE85
  J1A2   83 VDD<17> SCONN288_H44441004_PIP-SCONN,HA   I172 @BASEBOARD_FAB2_LIB.BASEBOARD_FAB2(SCH_1):PAGE85
  J1A2   80 VDD<18> SCONN288_H44441004_PIP-SCONN,HA   I172 @BASEBOARD_FAB2_LIB.BASEBOARD_FAB2(SCH_1):PAGE85
  J1A2   76 VDD<19> SCONN288_H44441004_PIP-SCONN,HA   I172 @BASEBOARD_FAB2_LIB.BASEBOARD_FAB2(SCH_1):PAGE85
  J1A2   73 VDD<20> SCONN288_H44441004_PIP-SCONN,HA   I172 @BASEBOARD_FAB2_LIB.BASEBOARD_FAB2(SCH_1):PAGE85
  J1A2   70 VDD<21> SCONN288_H44441004_PIP-SCONN,HA   I172 @BASEBOARD_FAB2_LIB.BASEBOARD_FAB2(SCH_1):PAGE85
  J1A2   67 VDD<22> SCONN288_H44441004_PIP-SCONN,HA   I172 @BASEBOARD_FAB2_LIB.BASEBOARD_FAB2(SCH_1):PAGE85
  J1A2   64 VDD<23> SCONN288_H44441004_PIP-SCONN,HA   I172 @BASEBOARD_FAB2_LIB.BASEBOARD_FAB2(SCH_1):PAGE85
  J1A2   61 VDD<24> SCONN288_H44441004_PIP-SCONN,HA   I172 @BASEBOARD_FAB2_LIB.BASEBOARD_FAB2(SCH_1):PAGE85
  J1A2   59 VDD<25> SCONN288_H44441004_PIP-SCONN,HA   I172 @BASEBOARD_FAB2_LIB.BASEBOARD_FAB2(SCH_1):PAGE85
  J9L2  236 VDD<0> SCONN288_H44441003_PIP-SCONN,HA    I55 @BASEBOARD_FAB2_LIB.BASEBOARD_FAB2(SCH_1):PAGE86
  J9L2  233 VDD<1> SCONN288_H44441003_PIP-SCONN,HA    I55 @BASEBOARD_FAB2_LIB.BASEBOARD_FAB2(SCH_1):PAGE86
  J9L2  231 VDD<2> SCONN288_H44441003_PIP-SCONN,HA    I55 @BASEBOARD_FAB2_LIB.BASEBOARD_FAB2(SCH_1):PAGE86
  J9L2  229 VDD<3> SCONN288_H44441003_PIP-SCONN,HA    I55 @BASEBOARD_FAB2_LIB.BASEBOARD_FAB2(SCH_1):PAGE86
  J9L2  226 VDD<4> SCONN288_H44441003_PIP-SCONN,HA    I55 @BASEBOARD_FAB2_LIB.BASEBOARD_FAB2(SCH_1):PAGE86
  J9L2  223 VDD<5> SCONN288_H44441003_PIP-SCONN,HA    I55 @BASEBOARD_FAB2_LIB.BASEBOARD_FAB2(SCH_1):PAGE86
  J9L2  220 VDD<6> SCONN288_H44441003_PIP-SCONN,HA    I55 @BASEBOARD_FAB2_LIB.BASEBOARD_FAB2(SCH_1):PAGE86
  J9L2  217 VDD<7> SCONN288_H44441003_PIP-SCONN,HA    I55 @BASEBOARD_FAB2_LIB.BASEBOARD_FAB2(SCH_1):PAGE86
  J9L2  215 VDD<8> SCONN288_H44441003_PIP-SCONN,HA    I55 @BASEBOARD_FAB2_LIB.BASEBOARD_FAB2(SCH_1):PAGE86
  J9L2  212 VDD<9> SCONN288_H44441003_PIP-SCONN,HA    I55 @BASEBOARD_FAB2_LIB.BASEBOARD_FAB2(SCH_1):PAGE86
  J9L2  209 VDD<10> SCONN288_H44441003_PIP-SCONN,HA    I55 @BASEBOARD_FAB2_LIB.BASEBOARD_FAB2(SCH_1):PAGE86
  J9L2  206 VDD<11> SCONN288_H44441003_PIP-SCONN,HA    I55 @BASEBOARD_FAB2_LIB.BASEBOARD_FAB2(SCH_1):PAGE86
  J9L2  204 VDD<12> SCONN288_H44441003_PIP-SCONN,HA    I55 @BASEBOARD_FAB2_LIB.BASEBOARD_FAB2(SCH_1):PAGE86
  J9L2   92 VDD<13> SCONN288_H44441003_PIP-SCONN,HA    I55 @BASEBOARD_FAB2_LIB.BASEBOARD_FAB2(SCH_1):PAGE86
  J9L2   90 VDD<14> SCONN288_H44441003_PIP-SCONN,HA    I55 @BASEBOARD_FAB2_LIB.BASEBOARD_FAB2(SCH_1):PAGE86
  J9L2   88 VDD<15> SCONN288_H44441003_PIP-SCONN,HA    I55 @BASEBOARD_FAB2_LIB.BASEBOARD_FAB2(SCH_1):PAGE86
  J9L2   85 VDD<16> SCONN288_H44441003_PIP-SCONN,HA    I55 @BASEBOARD_FAB2_LIB.BASEBOARD_FAB2(SCH_1):PAGE86
  J9L2   83 VDD<17> SCONN288_H44441003_PIP-SCONN,HA    I55 @BASEBOARD_FAB2_LIB.BASEBOARD_FAB2(SCH_1):PAGE86
  J9L2   80 VDD<18> SCONN288_H44441003_PIP-SCONN,HA    I55 @BASEBOARD_FAB2_LIB.BASEBOARD_FAB2(SCH_1):PAGE86
  J9L2   76 VDD<19> SCONN288_H44441003_PIP-SCONN,HA    I55 @BASEBOARD_FAB2_LIB.BASEBOARD_FAB2(SCH_1):PAGE86
  J9L2   73 VDD<20> SCONN288_H44441003_PIP-SCONN,HA    I55 @BASEBOARD_FAB2_LIB.BASEBOARD_FAB2(SCH_1):PAGE86
  J9L2   70 VDD<21> SCONN288_H44441003_PIP-SCONN,HA    I55 @BASEBOARD_FAB2_LIB.BASEBOARD_FAB2(SCH_1):PAGE86
  J9L2   67 VDD<22> SCONN288_H44441003_PIP-SCONN,HA    I55 @BASEBOARD_FAB2_LIB.BASEBOARD_FAB2(SCH_1):PAGE86
  J9L2   64 VDD<23> SCONN288_H44441003_PIP-SCONN,HA    I55 @BASEBOARD_FAB2_LIB.BASEBOARD_FAB2(SCH_1):PAGE86
  J9L2   61 VDD<24> SCONN288_H44441003_PIP-SCONN,HA    I55 @BASEBOARD_FAB2_LIB.BASEBOARD_FAB2(SCH_1):PAGE86
  J9L2   59 VDD<25> SCONN288_H44441003_PIP-SCONN,HA    I55 @BASEBOARD_FAB2_LIB.BASEBOARD_FAB2(SCH_1):PAGE86
  J1A1  236 VDD<0> SCONN288_H44441004_PIP-SCONN,HA   I169 @BASEBOARD_FAB2_LIB.BASEBOARD_FAB2(SCH_1):PAGE87
  J1A1  233 VDD<1> SCONN288_H44441004_PIP-SCONN,HA   I169 @BASEBOARD_FAB2_LIB.BASEBOARD_FAB2(SCH_1):PAGE87
  J1A1  231 VDD<2> SCONN288_H44441004_PIP-SCONN,HA   I169 @BASEBOARD_FAB2_LIB.BASEBOARD_FAB2(SCH_1):PAGE87
  J1A1  229 VDD<3> SCONN288_H44441004_PIP-SCONN,HA   I169 @BASEBOARD_FAB2_LIB.BASEBOARD_FAB2(SCH_1):PAGE87
  J1A1  226 VDD<4> SCONN288_H44441004_PIP-SCONN,HA   I169 @BASEBOARD_FAB2_LIB.BASEBOARD_FAB2(SCH_1):PAGE87
  J1A1  223 VDD<5> SCONN288_H44441004_PIP-SCONN,HA   I169 @BASEBOARD_FAB2_LIB.BASEBOARD_FAB2(SCH_1):PAGE87
  J1A1  220 VDD<6> SCONN288_H44441004_PIP-SCONN,HA   I169 @BASEBOARD_FAB2_LIB.BASEBOARD_FAB2(SCH_1):PAGE87
  J1A1  217 VDD<7> SCONN288_H44441004_PIP-SCONN,HA   I169 @BASEBOARD_FAB2_LIB.BASEBOARD_FAB2(SCH_1):PAGE87
  J1A1  215 VDD<8> SCONN288_H44441004_PIP-SCONN,HA   I169 @BASEBOARD_FAB2_LIB.BASEBOARD_FAB2(SCH_1):PAGE87
  J1A1  212 VDD<9> SCONN288_H44441004_PIP-SCONN,HA   I169 @BASEBOARD_FAB2_LIB.BASEBOARD_FAB2(SCH_1):PAGE87
  J1A1  209 VDD<10> SCONN288_H44441004_PIP-SCONN,HA   I169 @BASEBOARD_FAB2_LIB.BASEBOARD_FAB2(SCH_1):PAGE87
  J1A1  206 VDD<11> SCONN288_H44441004_PIP-SCONN,HA   I169 @BASEBOARD_FAB2_LIB.BASEBOARD_FAB2(SCH_1):PAGE87
  J1A1  204 VDD<12> SCONN288_H44441004_PIP-SCONN,HA   I169 @BASEBOARD_FAB2_LIB.BASEBOARD_FAB2(SCH_1):PAGE87
  J1A1   92 VDD<13> SCONN288_H44441004_PIP-SCONN,HA   I169 @BASEBOARD_FAB2_LIB.BASEBOARD_FAB2(SCH_1):PAGE87
  J1A1   90 VDD<14> SCONN288_H44441004_PIP-SCONN,HA   I169 @BASEBOARD_FAB2_LIB.BASEBOARD_FAB2(SCH_1):PAGE87
  J1A1   88 VDD<15> SCONN288_H44441004_PIP-SCONN,HA   I169 @BASEBOARD_FAB2_LIB.BASEBOARD_FAB2(SCH_1):PAGE87
  J1A1   85 VDD<16> SCONN288_H44441004_PIP-SCONN,HA   I169 @BASEBOARD_FAB2_LIB.BASEBOARD_FAB2(SCH_1):PAGE87
  J1A1   83 VDD<17> SCONN288_H44441004_PIP-SCONN,HA   I169 @BASEBOARD_FAB2_LIB.BASEBOARD_FAB2(SCH_1):PAGE87
  J1A1   80 VDD<18> SCONN288_H44441004_PIP-SCONN,HA   I169 @BASEBOARD_FAB2_LIB.BASEBOARD_FAB2(SCH_1):PAGE87
  J1A1   76 VDD<19> SCONN288_H44441004_PIP-SCONN,HA   I169 @BASEBOARD_FAB2_LIB.BASEBOARD_FAB2(SCH_1):PAGE87
  J1A1   73 VDD<20> SCONN288_H44441004_PIP-SCONN,HA   I169 @BASEBOARD_FAB2_LIB.BASEBOARD_FAB2(SCH_1):PAGE87
  J1A1   70 VDD<21> SCONN288_H44441004_PIP-SCONN,HA   I169 @BASEBOARD_FAB2_LIB.BASEBOARD_FAB2(SCH_1):PAGE87
  J1A1   67 VDD<22> SCONN288_H44441004_PIP-SCONN,HA   I169 @BASEBOARD_FAB2_LIB.BASEBOARD_FAB2(SCH_1):PAGE87
  J1A1   64 VDD<23> SCONN288_H44441004_PIP-SCONN,HA   I169 @BASEBOARD_FAB2_LIB.BASEBOARD_FAB2(SCH_1):PAGE87
  J1A1   61 VDD<24> SCONN288_H44441004_PIP-SCONN,HA   I169 @BASEBOARD_FAB2_LIB.BASEBOARD_FAB2(SCH_1):PAGE87
  J1A1   59 VDD<25> SCONN288_H44441004_PIP-SCONN,HA   I169 @BASEBOARD_FAB2_LIB.BASEBOARD_FAB2(SCH_1):PAGE87
  J9L1  236 VDD<0> SCONN288_H44441003_PIP-SCONN,HA   I168 @BASEBOARD_FAB2_LIB.BASEBOARD_FAB2(SCH_1):PAGE88
  J9L1  233 VDD<1> SCONN288_H44441003_PIP-SCONN,HA   I168 @BASEBOARD_FAB2_LIB.BASEBOARD_FAB2(SCH_1):PAGE88
  J9L1  231 VDD<2> SCONN288_H44441003_PIP-SCONN,HA   I168 @BASEBOARD_FAB2_LIB.BASEBOARD_FAB2(SCH_1):PAGE88
  J9L1  229 VDD<3> SCONN288_H44441003_PIP-SCONN,HA   I168 @BASEBOARD_FAB2_LIB.BASEBOARD_FAB2(SCH_1):PAGE88
  J9L1  226 VDD<4> SCONN288_H44441003_PIP-SCONN,HA   I168 @BASEBOARD_FAB2_LIB.BASEBOARD_FAB2(SCH_1):PAGE88
  J9L1  223 VDD<5> SCONN288_H44441003_PIP-SCONN,HA   I168 @BASEBOARD_FAB2_LIB.BASEBOARD_FAB2(SCH_1):PAGE88
  J9L1  220 VDD<6> SCONN288_H44441003_PIP-SCONN,HA   I168 @BASEBOARD_FAB2_LIB.BASEBOARD_FAB2(SCH_1):PAGE88
  J9L1  217 VDD<7> SCONN288_H44441003_PIP-SCONN,HA   I168 @BASEBOARD_FAB2_LIB.BASEBOARD_FAB2(SCH_1):PAGE88
  J9L1  215 VDD<8> SCONN288_H44441003_PIP-SCONN,HA   I168 @BASEBOARD_FAB2_LIB.BASEBOARD_FAB2(SCH_1):PAGE88
  J9L1  212 VDD<9> SCONN288_H44441003_PIP-SCONN,HA   I168 @BASEBOARD_FAB2_LIB.BASEBOARD_FAB2(SCH_1):PAGE88
  J9L1  209 VDD<10> SCONN288_H44441003_PIP-SCONN,HA   I168 @BASEBOARD_FAB2_LIB.BASEBOARD_FAB2(SCH_1):PAGE88
  J9L1  206 VDD<11> SCONN288_H44441003_PIP-SCONN,HA   I168 @BASEBOARD_FAB2_LIB.BASEBOARD_FAB2(SCH_1):PAGE88
  J9L1  204 VDD<12> SCONN288_H44441003_PIP-SCONN,HA   I168 @BASEBOARD_FAB2_LIB.BASEBOARD_FAB2(SCH_1):PAGE88
  J9L1   92 VDD<13> SCONN288_H44441003_PIP-SCONN,HA   I168 @BASEBOARD_FAB2_LIB.BASEBOARD_FAB2(SCH_1):PAGE88
  J9L1   90 VDD<14> SCONN288_H44441003_PIP-SCONN,HA   I168 @BASEBOARD_FAB2_LIB.BASEBOARD_FAB2(SCH_1):PAGE88
  J9L1   88 VDD<15> SCONN288_H44441003_PIP-SCONN,HA   I168 @BASEBOARD_FAB2_LIB.BASEBOARD_FAB2(SCH_1):PAGE88
  J9L1   85 VDD<16> SCONN288_H44441003_PIP-SCONN,HA   I168 @BASEBOARD_FAB2_LIB.BASEBOARD_FAB2(SCH_1):PAGE88
  J9L1   83 VDD<17> SCONN288_H44441003_PIP-SCONN,HA   I168 @BASEBOARD_FAB2_LIB.BASEBOARD_FAB2(SCH_1):PAGE88
  J9L1   80 VDD<18> SCONN288_H44441003_PIP-SCONN,HA   I168 @BASEBOARD_FAB2_LIB.BASEBOARD_FAB2(SCH_1):PAGE88
  J9L1   76 VDD<19> SCONN288_H44441003_PIP-SCONN,HA   I168 @BASEBOARD_FAB2_LIB.BASEBOARD_FAB2(SCH_1):PAGE88
  J9L1   73 VDD<20> SCONN288_H44441003_PIP-SCONN,HA   I168 @BASEBOARD_FAB2_LIB.BASEBOARD_FAB2(SCH_1):PAGE88
  J9L1   70 VDD<21> SCONN288_H44441003_PIP-SCONN,HA   I168 @BASEBOARD_FAB2_LIB.BASEBOARD_FAB2(SCH_1):PAGE88
  J9L1   67 VDD<22> SCONN288_H44441003_PIP-SCONN,HA   I168 @BASEBOARD_FAB2_LIB.BASEBOARD_FAB2(SCH_1):PAGE88
  J9L1   64 VDD<23> SCONN288_H44441003_PIP-SCONN,HA   I168 @BASEBOARD_FAB2_LIB.BASEBOARD_FAB2(SCH_1):PAGE88
  J9L1   61 VDD<24> SCONN288_H44441003_PIP-SCONN,HA   I168 @BASEBOARD_FAB2_LIB.BASEBOARD_FAB2(SCH_1):PAGE88
  J9L1   59 VDD<25> SCONN288_H44441003_PIP-SCONN,HA   I168 @BASEBOARD_FAB2_LIB.BASEBOARD_FAB2(SCH_1):PAGE88
  R7M9    1      A RES_0402-64.9,1.0%,1/16W,CHIP,A    I28 @BASEBOARD_FAB2_LIB.BASEBOARD_FAB2(SCH_1):PAGE96
  R9M1    1      A RES_0402-1.00K,1%,1/16W,CHIP,GA    I11 @BASEBOARD_FAB2_LIB.BASEBOARD_FAB2(SCH_1):PAGE100
  R9L7    1      A RES_0402-1.00K,1%,1/16W,CHIP,GA    I22 @BASEBOARD_FAB2_LIB.BASEBOARD_FAB2(SCH_1):PAGE100
  R9L2    1      A RES_0402-1.00K,1%,1/16W,CHIP,GA    I38 @BASEBOARD_FAB2_LIB.BASEBOARD_FAB2(SCH_1):PAGE100
 C1A12    1      A CAP_0805LF-22UF,4V,20%,X6S,C95A     I6 @BASEBOARD_FAB2_LIB.BASEBOARD_FAB2(SCH_1):PAGE227
  C1A1    1      A CAP_0805LF-22UF,4V,20%,X6S,C95A    I68 @BASEBOARD_FAB2_LIB.BASEBOARD_FAB2(SCH_1):PAGE227
 EU1A2    1    VOS IR354XX_SM-IR35411,IC,H73688-0A   I101 @BASEBOARD_FAB2_LIB.BASEBOARD_FAB2(SCH_1):PAGE227
 EU1A1    1    VOS IR354XX_SM-IR35411,IC,H73688-0A   I102 @BASEBOARD_FAB2_LIB.BASEBOARD_FAB2(SCH_1):PAGE227
  R1A1    1      A RES_0603-120.0,1%,1/10W,CHIP,GA    I58 @BASEBOARD_FAB2_LIB.BASEBOARD_FAB2(SCH_1):PAGE228
  C9L9    1      A CAPP_3018-470UF,2.5V,20%,ALUM,A    I75 @BASEBOARD_FAB2_LIB.BASEBOARD_FAB2(SCH_1):PAGE228
 C9L12    1      A CAPP_3018-470UF,2.5V,20%,ALUM,A    I76 @BASEBOARD_FAB2_LIB.BASEBOARD_FAB2(SCH_1):PAGE228
  C9L4    1      A CAPP_3018-470UF,2.5V,20%,ALUM,A    I77 @BASEBOARD_FAB2_LIB.BASEBOARD_FAB2(SCH_1):PAGE228
  C9L2    1      A CAPP_3018-470UF,2.5V,20%,ALUM,A    I78 @BASEBOARD_FAB2_LIB.BASEBOARD_FAB2(SCH_1):PAGE228
  C8M8    1      A CAP_A_0603V-47UF,4V,20%,X5R,60A   I198 @BASEBOARD_FAB2_LIB.BASEBOARD_FAB2(SCH_1):PAGE228
  C2A5    1      A CAP_A_0603V-47UF,4V,20%,X5R,60A   I199 @BASEBOARD_FAB2_LIB.BASEBOARD_FAB2(SCH_1):PAGE228
  C2B1    1      A CAP_A_0603V-47UF,4V,20%,X5R,60A   I200 @BASEBOARD_FAB2_LIB.BASEBOARD_FAB2(SCH_1):PAGE228
 C8L12    1      A CAP_A_0603V-47UF,4V,20%,X5R,60A   I201 @BASEBOARD_FAB2_LIB.BASEBOARD_FAB2(SCH_1):PAGE228
  C7M5    1      A CAP_A_0603V-47UF,4V,20%,X5R,60A   I202 @BASEBOARD_FAB2_LIB.BASEBOARD_FAB2(SCH_1):PAGE228
 C8M10    1      A CAP_A_0603V-47UF,4V,20%,X5R,60A   I203 @BASEBOARD_FAB2_LIB.BASEBOARD_FAB2(SCH_1):PAGE228
  C2B2    1      A CAP_A_0603V-47UF,4V,20%,X5R,60A   I204 @BASEBOARD_FAB2_LIB.BASEBOARD_FAB2(SCH_1):PAGE228
  C8M9    1      A CAP_A_0603V-47UF,4V,20%,X5R,60A   I205 @BASEBOARD_FAB2_LIB.BASEBOARD_FAB2(SCH_1):PAGE228
  C8M2    1      A CAP_A_0603V-47UF,4V,20%,X5R,60A   I206 @BASEBOARD_FAB2_LIB.BASEBOARD_FAB2(SCH_1):PAGE228
 SH7L2    2      B SHUNT_SH0201-EMPTY,N_A   I245 @BASEBOARD_FAB2_LIB.BASEBOARD_FAB2(SCH_1):PAGE228
C5G103    1      A CAP_A_0603V-22.0UF,4V,20%,X6S,A    I71 @BASEBOARD_FAB2_LIB.BASEBOARD_FAB2(SCH_1):PAGE243
C5G104    1      A CAP_A_0603V-22.0UF,4V,20%,X6S,A    I72 @BASEBOARD_FAB2_LIB.BASEBOARD_FAB2(SCH_1):PAGE243
C5G105    1      A CAP_A_0603V-22.0UF,4V,20%,X6S,A    I73 @BASEBOARD_FAB2_LIB.BASEBOARD_FAB2(SCH_1):PAGE243
C5G102    1      A CAP_A_0603V-22.0UF,4V,20%,X6S,A    I74 @BASEBOARD_FAB2_LIB.BASEBOARD_FAB2(SCH_1):PAGE243
C5G101    1      A CAP_A_0603V-22.0UF,4V,20%,X6S,A    I75 @BASEBOARD_FAB2_LIB.BASEBOARD_FAB2(SCH_1):PAGE243
C5G100    1      A CAP_A_0603V-22.0UF,4V,20%,X6S,A    I76 @BASEBOARD_FAB2_LIB.BASEBOARD_FAB2(SCH_1):PAGE243
 C5G99    1      A CAP_A_0603V-22.0UF,4V,20%,X6S,A    I77 @BASEBOARD_FAB2_LIB.BASEBOARD_FAB2(SCH_1):PAGE243
 C5G98    1      A CAP_A_0603V-22.0UF,4V,20%,X6S,A    I78 @BASEBOARD_FAB2_LIB.BASEBOARD_FAB2(SCH_1):PAGE243
 C5G97    1      A CAP_A_0603V-22.0UF,4V,20%,X6S,A    I79 @BASEBOARD_FAB2_LIB.BASEBOARD_FAB2(SCH_1):PAGE243
C5G114    1      A CAP_A_0603V-22.0UF,4V,20%,X6S,A    I80 @BASEBOARD_FAB2_LIB.BASEBOARD_FAB2(SCH_1):PAGE243
C5G113    1      A CAP_A_0603V-22.0UF,4V,20%,X6S,A    I81 @BASEBOARD_FAB2_LIB.BASEBOARD_FAB2(SCH_1):PAGE243
C5G112    1      A CAP_A_0603V-22.0UF,4V,20%,X6S,A    I82 @BASEBOARD_FAB2_LIB.BASEBOARD_FAB2(SCH_1):PAGE243
C5G111    1      A CAP_A_0603V-22.0UF,4V,20%,X6S,A    I83 @BASEBOARD_FAB2_LIB.BASEBOARD_FAB2(SCH_1):PAGE243
C5G110    1      A CAP_A_0603V-22.0UF,4V,20%,X6S,A    I84 @BASEBOARD_FAB2_LIB.BASEBOARD_FAB2(SCH_1):PAGE243
C5G109    1      A CAP_A_0603V-22.0UF,4V,20%,X6S,A    I85 @BASEBOARD_FAB2_LIB.BASEBOARD_FAB2(SCH_1):PAGE243
C5G108    1      A CAP_A_0603V-22.0UF,4V,20%,X6S,A    I86 @BASEBOARD_FAB2_LIB.BASEBOARD_FAB2(SCH_1):PAGE243
C5G107    1      A CAP_A_0603V-22.0UF,4V,20%,X6S,A    I87 @BASEBOARD_FAB2_LIB.BASEBOARD_FAB2(SCH_1):PAGE243
C5G106    1      A CAP_A_0603V-22.0UF,4V,20%,X6S,A    I88 @BASEBOARD_FAB2_LIB.BASEBOARD_FAB2(SCH_1):PAGE243
C5G115    1      A CAP_0805-47UF,4V,20%,X6S,C9533A    I89 @BASEBOARD_FAB2_LIB.BASEBOARD_FAB2(SCH_1):PAGE243
C5G116    1      A CAP_0805-47UF,4V,20%,X6S,C9533A    I90 @BASEBOARD_FAB2_LIB.BASEBOARD_FAB2(SCH_1):PAGE243
  R6L6    1      A RES_0402-0.0,5%,1/16W,CHIP,G21A     I6 @BASEBOARD_FAB2_LIB.BASEBOARD_FAB2(SCH_1):PAGE230
  C6L5    1      A CAP_0603LF-10UF,4V,20%,X6S,E15A    I35 @BASEBOARD_FAB2_LIB.BASEBOARD_FAB2(SCH_1):PAGE230
 C4A15    1      A CAP_0603LF-10UF,4V,20%,X6S,E15A    I17 @BASEBOARD_FAB2_LIB.BASEBOARD_FAB2(SCH_1):PAGE230
 EU4A2   10    VIN MIC5166_DFN-IC,H55101-001    I37 @BASEBOARD_FAB2_LIB.BASEBOARD_FAB2(SCH_1):PAGE230
  C3D1    1      A CAP_A_0603V-22.0UF,4V,20%,X6S,A   I255 @BASEBOARD_FAB2_LIB.BASEBOARD_FAB2(SCH_1):PAGE228
  C2D3    1      A CAP_A_0603V-22.0UF,4V,20%,X6S,A   I256 @BASEBOARD_FAB2_LIB.BASEBOARD_FAB2(SCH_1):PAGE228
  C2D2    1      A CAP_A_0603V-22.0UF,4V,20%,X6S,A   I257 @BASEBOARD_FAB2_LIB.BASEBOARD_FAB2(SCH_1):PAGE228
  C2D1    1      A CAP_A_0603V-22.0UF,4V,20%,X6S,A   I258 @BASEBOARD_FAB2_LIB.BASEBOARD_FAB2(SCH_1):PAGE228
  C2D7    1      A CAP_A_0603V-22.0UF,4V,20%,X6S,A   I264 @BASEBOARD_FAB2_LIB.BASEBOARD_FAB2(SCH_1):PAGE228
  C2D4    1      A CAP_A_0603V-22.0UF,4V,20%,X6S,A   I265 @BASEBOARD_FAB2_LIB.BASEBOARD_FAB2(SCH_1):PAGE228
  C2D5    1      A CAP_A_0603V-22.0UF,4V,20%,X6S,A   I266 @BASEBOARD_FAB2_LIB.BASEBOARD_FAB2(SCH_1):PAGE228
  C2D6    1      A CAP_A_0603V-22.0UF,4V,20%,X6S,A   I267 @BASEBOARD_FAB2_LIB.BASEBOARD_FAB2(SCH_1):PAGE228
  C7L5    1      A CAP_A_0603V-47UF,4V,20%,X5R,60A   I268 @BASEBOARD_FAB2_LIB.BASEBOARD_FAB2(SCH_1):PAGE228
  C3A6    1      A CAP_A_0603V-47UF,4V,20%,X5R,60A   I269 @BASEBOARD_FAB2_LIB.BASEBOARD_FAB2(SCH_1):PAGE228
  C3A5    1      A CAP_A_0603V-47UF,4V,20%,X5R,60A   I270 @BASEBOARD_FAB2_LIB.BASEBOARD_FAB2(SCH_1):PAGE228
 C2A15    1      A CAP_A_0603V-47UF,4V,20%,X5R,60A   I271 @BASEBOARD_FAB2_LIB.BASEBOARD_FAB2(SCH_1):PAGE228
 C2A14    1      A CAP_A_0603V-47UF,4V,20%,X5R,60A   I272 @BASEBOARD_FAB2_LIB.BASEBOARD_FAB2(SCH_1):PAGE228
  C2A6    1      A CAP_A_0603V-47UF,4V,20%,X5R,60A   I273 @BASEBOARD_FAB2_LIB.BASEBOARD_FAB2(SCH_1):PAGE228
  C2A7    1      A CAP_A_0603V-47UF,4V,20%,X5R,60A   I274 @BASEBOARD_FAB2_LIB.BASEBOARD_FAB2(SCH_1):PAGE228
  C3A1    1      A CAP_A_0603V-47UF,4V,20%,X5R,60A   I275 @BASEBOARD_FAB2_LIB.BASEBOARD_FAB2(SCH_1):PAGE228
  C3A2    1      A CAP_A_0603V-47UF,4V,20%,X5R,60A   I276 @BASEBOARD_FAB2_LIB.BASEBOARD_FAB2(SCH_1):PAGE228
  C2A9    1      A CAP_A_0603V-47UF,4V,20%,X5R,60A   I277 @BASEBOARD_FAB2_LIB.BASEBOARD_FAB2(SCH_1):PAGE228
 C2A10    1      A CAP_A_0603V-47UF,4V,20%,X5R,60A   I278 @BASEBOARD_FAB2_LIB.BASEBOARD_FAB2(SCH_1):PAGE228
 C2A11    1      A CAP_A_0603V-47UF,4V,20%,X5R,60A   I279 @BASEBOARD_FAB2_LIB.BASEBOARD_FAB2(SCH_1):PAGE228
 C2A13    1      A CAP_A_0603V-47UF,4V,20%,X5R,60A   I280 @BASEBOARD_FAB2_LIB.BASEBOARD_FAB2(SCH_1):PAGE228
 C2A12    1      A CAP_A_0603V-47UF,4V,20%,X5R,60A   I281 @BASEBOARD_FAB2_LIB.BASEBOARD_FAB2(SCH_1):PAGE228
  C2A1    1      A CAP_A_0603V-47UF,4V,20%,X5R,60A   I282 @BASEBOARD_FAB2_LIB.BASEBOARD_FAB2(SCH_1):PAGE228
  C2A2    1      A CAP_A_0603V-47UF,4V,20%,X5R,60A   I283 @BASEBOARD_FAB2_LIB.BASEBOARD_FAB2(SCH_1):PAGE228
  C8M1    1      A CAP_A_0603V-47UF,4V,20%,X5R,60A   I284 @BASEBOARD_FAB2_LIB.BASEBOARD_FAB2(SCH_1):PAGE228
  C8L5    1      A CAP_A_0603V-47UF,4V,20%,X5R,60A   I285 @BASEBOARD_FAB2_LIB.BASEBOARD_FAB2(SCH_1):PAGE228
  C8L6    1      A CAP_A_0603V-47UF,4V,20%,X5R,60A   I286 @BASEBOARD_FAB2_LIB.BASEBOARD_FAB2(SCH_1):PAGE228
  C8L7    1      A CAP_A_0603V-47UF,4V,20%,X5R,60A   I287 @BASEBOARD_FAB2_LIB.BASEBOARD_FAB2(SCH_1):PAGE228
  C7L4    1      A CAP_A_0603V-47UF,4V,20%,X5R,60A   I288 @BASEBOARD_FAB2_LIB.BASEBOARD_FAB2(SCH_1):PAGE228
  C8L8    1      A CAP_A_0603V-47UF,4V,20%,X5R,60A   I289 @BASEBOARD_FAB2_LIB.BASEBOARD_FAB2(SCH_1):PAGE228
  C8L9    1      A CAP_A_0603V-47UF,4V,20%,X5R,60A   I290 @BASEBOARD_FAB2_LIB.BASEBOARD_FAB2(SCH_1):PAGE228
  C8M6    1      A CAP_A_0603V-47UF,4V,20%,X5R,60A   I291 @BASEBOARD_FAB2_LIB.BASEBOARD_FAB2(SCH_1):PAGE228
  C2A4    1      A CAP_A_0603V-47UF,4V,20%,X5R,60A   I292 @BASEBOARD_FAB2_LIB.BASEBOARD_FAB2(SCH_1):PAGE228
  C8M4    1      A CAP_A_0603V-47UF,4V,20%,X5R,60A   I293 @BASEBOARD_FAB2_LIB.BASEBOARD_FAB2(SCH_1):PAGE228
  C7M2    1      A CAP_A_0603V-47UF,4V,20%,X5R,60A   I294 @BASEBOARD_FAB2_LIB.BASEBOARD_FAB2(SCH_1):PAGE228
  C7M1    1      A CAP_A_0603V-47UF,4V,20%,X5R,60A   I295 @BASEBOARD_FAB2_LIB.BASEBOARD_FAB2(SCH_1):PAGE228
  C2A3    1      A CAP_A_0603V-47UF,4V,20%,X5R,60A   I296 @BASEBOARD_FAB2_LIB.BASEBOARD_FAB2(SCH_1):PAGE228
 C8L10    1      A CAP_A_0603V-47UF,4V,20%,X5R,60A   I297 @BASEBOARD_FAB2_LIB.BASEBOARD_FAB2(SCH_1):PAGE228
  C8M5    1      A CAP_A_0603V-47UF,4V,20%,X5R,60A   I298 @BASEBOARD_FAB2_LIB.BASEBOARD_FAB2(SCH_1):PAGE228
  C8M3    1      A CAP_A_0603V-47UF,4V,20%,X5R,60A   I299 @BASEBOARD_FAB2_LIB.BASEBOARD_FAB2(SCH_1):PAGE228
  C8L1    1      A CAP_0805-100UF,4V,20%,X5R,6024A   I301 @BASEBOARD_FAB2_LIB.BASEBOARD_FAB2(SCH_1):PAGE228
 C8L11    1      A CAP_0805-100UF,4V,20%,X5R,6024A   I302 @BASEBOARD_FAB2_LIB.BASEBOARD_FAB2(SCH_1):PAGE228
  C8P2    1      A CAP_0805-100UF,4V,20%,X5R,6024A   I303 @BASEBOARD_FAB2_LIB.BASEBOARD_FAB2(SCH_1):PAGE228
  C8P1    1      A CAP_0805-100UF,4V,20%,X5R,6024A   I304 @BASEBOARD_FAB2_LIB.BASEBOARD_FAB2(SCH_1):PAGE228
  C7P2    1      A CAP_0805-100UF,4V,20%,X5R,6024A   I305 @BASEBOARD_FAB2_LIB.BASEBOARD_FAB2(SCH_1):PAGE228
  C8P3    1      A CAP_0805-100UF,4V,20%,X5R,6024A   I306 @BASEBOARD_FAB2_LIB.BASEBOARD_FAB2(SCH_1):PAGE228
  C8P4    1      A CAP_0805-100UF,4V,20%,X5R,6024A   I307 @BASEBOARD_FAB2_LIB.BASEBOARD_FAB2(SCH_1):PAGE228
  C7P1    1      A CAP_0805-100UF,4V,20%,X5R,6024A   I308 @BASEBOARD_FAB2_LIB.BASEBOARD_FAB2(SCH_1):PAGE228
  C2A8    1      A CAP_0805-100UF,4V,20%,X5R,6024A   I309 @BASEBOARD_FAB2_LIB.BASEBOARD_FAB2(SCH_1):PAGE228
  C8L2    1      A CAP_0805-100UF,4V,20%,X5R,6024A   I310 @BASEBOARD_FAB2_LIB.BASEBOARD_FAB2(SCH_1):PAGE228
 C8M11    1      A CAP_0805-100UF,4V,20%,X5R,6024A   I311 @BASEBOARD_FAB2_LIB.BASEBOARD_FAB2(SCH_1):PAGE228
  C8M7    1      A CAP_0805-100UF,4V,20%,X5R,6024A   I312 @BASEBOARD_FAB2_LIB.BASEBOARD_FAB2(SCH_1):PAGE228
 C2A16    1      A CAP_0805-100UF,4V,20%,X5R,6024A   I313 @BASEBOARD_FAB2_LIB.BASEBOARD_FAB2(SCH_1):PAGE228
  C7L1    1      A CAP_0805-100UF,4V,20%,X5R,6024A   I314 @BASEBOARD_FAB2_LIB.BASEBOARD_FAB2(SCH_1):PAGE228
  L1A2    2      F IND-120NH-30-GP_DISCRET-GB2-INA   I152 @BASEBOARD_FAB2_LIB.BASEBOARD_FAB2(SCH_1):PAGE227
  L1A1    2      F IND-120NH-30-GP_DISCRET-GB2-INA   I153 @BASEBOARD_FAB2_LIB.BASEBOARD_FAB2(SCH_1):PAGE227

PVNN_PCH_STBY @BASEBOARD_FAB2_LIB.BASEBOARD_FAB2(SCH_1):PVNN_PCH_STBY
  U7C1 AU36 VCCPRIM_AVID<0> LBG_CORE_QAT_EXT_D_BGA1-IC,H91A    I21 @BASEBOARD_FAB2_LIB.BASEBOARD_FAB2(SCH_1):PAGE123
  U7C1 AU34 VCCPRIM_AVID<1> LBG_CORE_QAT_EXT_D_BGA1-IC,H91A    I21 @BASEBOARD_FAB2_LIB.BASEBOARD_FAB2(SCH_1):PAGE123
  U7C1 AU32 VCCPRIM_AVID<2> LBG_CORE_QAT_EXT_D_BGA1-IC,H91A    I21 @BASEBOARD_FAB2_LIB.BASEBOARD_FAB2(SCH_1):PAGE123
  U7C1 AT36 VCCPRIM_AVID<3> LBG_CORE_QAT_EXT_D_BGA1-IC,H91A    I21 @BASEBOARD_FAB2_LIB.BASEBOARD_FAB2(SCH_1):PAGE123
  U7C1 AT34 VCCPRIM_AVID<4> LBG_CORE_QAT_EXT_D_BGA1-IC,H91A    I21 @BASEBOARD_FAB2_LIB.BASEBOARD_FAB2(SCH_1):PAGE123
  U7C1 AT32 VCCPRIM_AVID<5> LBG_CORE_QAT_EXT_D_BGA1-IC,H91A    I21 @BASEBOARD_FAB2_LIB.BASEBOARD_FAB2(SCH_1):PAGE123
  U7C1 AP39 VCCPRIM_AVID<6> LBG_CORE_QAT_EXT_D_BGA1-IC,H91A    I21 @BASEBOARD_FAB2_LIB.BASEBOARD_FAB2(SCH_1):PAGE123
  U7C1 AP37 VCCPRIM_AVID<7> LBG_CORE_QAT_EXT_D_BGA1-IC,H91A    I21 @BASEBOARD_FAB2_LIB.BASEBOARD_FAB2(SCH_1):PAGE123
  U7C1 AP36 VCCPRIM_AVID<8> LBG_CORE_QAT_EXT_D_BGA1-IC,H91A    I21 @BASEBOARD_FAB2_LIB.BASEBOARD_FAB2(SCH_1):PAGE123
  U7C1 AP34 VCCPRIM_AVID<9> LBG_CORE_QAT_EXT_D_BGA1-IC,H91A    I21 @BASEBOARD_FAB2_LIB.BASEBOARD_FAB2(SCH_1):PAGE123
  U7C1 AP32 VCCPRIM_AVID<10> LBG_CORE_QAT_EXT_D_BGA1-IC,H91A    I21 @BASEBOARD_FAB2_LIB.BASEBOARD_FAB2(SCH_1):PAGE123
  U7C1 AM39 VCCPRIM_AVID<11> LBG_CORE_QAT_EXT_D_BGA1-IC,H91A    I21 @BASEBOARD_FAB2_LIB.BASEBOARD_FAB2(SCH_1):PAGE123
  U7C1 AM37 VCCPRIM_AVID<12> LBG_CORE_QAT_EXT_D_BGA1-IC,H91A    I21 @BASEBOARD_FAB2_LIB.BASEBOARD_FAB2(SCH_1):PAGE123
  U7C1 AM36 VCCPRIM_AVID<13> LBG_CORE_QAT_EXT_D_BGA1-IC,H91A    I21 @BASEBOARD_FAB2_LIB.BASEBOARD_FAB2(SCH_1):PAGE123
  U7C1 AM34 VCCPRIM_AVID<14> LBG_CORE_QAT_EXT_D_BGA1-IC,H91A    I21 @BASEBOARD_FAB2_LIB.BASEBOARD_FAB2(SCH_1):PAGE123
  U7C1 AM32 VCCPRIM_AVID<15> LBG_CORE_QAT_EXT_D_BGA1-IC,H91A    I21 @BASEBOARD_FAB2_LIB.BASEBOARD_FAB2(SCH_1):PAGE123
  U7C1 AK39 VCCPRIM_AVID<16> LBG_CORE_QAT_EXT_D_BGA1-IC,H91A    I21 @BASEBOARD_FAB2_LIB.BASEBOARD_FAB2(SCH_1):PAGE123
  U7C1 AK37 VCCPRIM_AVID<17> LBG_CORE_QAT_EXT_D_BGA1-IC,H91A    I21 @BASEBOARD_FAB2_LIB.BASEBOARD_FAB2(SCH_1):PAGE123
  U7C1 AK34 VCCPRIM_AVID<18> LBG_CORE_QAT_EXT_D_BGA1-IC,H91A    I21 @BASEBOARD_FAB2_LIB.BASEBOARD_FAB2(SCH_1):PAGE123
  U7C1 AG39 VCCPRIM_AVID<19> LBG_CORE_QAT_EXT_D_BGA1-IC,H91A    I21 @BASEBOARD_FAB2_LIB.BASEBOARD_FAB2(SCH_1):PAGE123
  U7C1 AG37 VCCPRIM_AVID<20> LBG_CORE_QAT_EXT_D_BGA1-IC,H91A    I21 @BASEBOARD_FAB2_LIB.BASEBOARD_FAB2(SCH_1):PAGE123
  U7C1 AG36 VCCPRIM_AVID<21> LBG_CORE_QAT_EXT_D_BGA1-IC,H91A    I21 @BASEBOARD_FAB2_LIB.BASEBOARD_FAB2(SCH_1):PAGE123
  U7C1 AG34 VCCPRIM_AVID<22> LBG_CORE_QAT_EXT_D_BGA1-IC,H91A    I21 @BASEBOARD_FAB2_LIB.BASEBOARD_FAB2(SCH_1):PAGE123
  U7C1 AG32 VCCPRIM_AVID<23> LBG_CORE_QAT_EXT_D_BGA1-IC,H91A    I21 @BASEBOARD_FAB2_LIB.BASEBOARD_FAB2(SCH_1):PAGE123
  U7C1 AE41 VCCPRIM_AVID<24> LBG_CORE_QAT_EXT_D_BGA1-IC,H91A    I21 @BASEBOARD_FAB2_LIB.BASEBOARD_FAB2(SCH_1):PAGE123
  U7C1 AE39 VCCPRIM_AVID<25> LBG_CORE_QAT_EXT_D_BGA1-IC,H91A    I21 @BASEBOARD_FAB2_LIB.BASEBOARD_FAB2(SCH_1):PAGE123
  U7C1 AE37 VCCPRIM_AVID<26> LBG_CORE_QAT_EXT_D_BGA1-IC,H91A    I21 @BASEBOARD_FAB2_LIB.BASEBOARD_FAB2(SCH_1):PAGE123
  U7C1 AE36 VCCPRIM_AVID<27> LBG_CORE_QAT_EXT_D_BGA1-IC,H91A    I21 @BASEBOARD_FAB2_LIB.BASEBOARD_FAB2(SCH_1):PAGE123
  U7C1 AE34 VCCPRIM_AVID<28> LBG_CORE_QAT_EXT_D_BGA1-IC,H91A    I21 @BASEBOARD_FAB2_LIB.BASEBOARD_FAB2(SCH_1):PAGE123
  U7C1 AE32 VCCPRIM_AVID<29> LBG_CORE_QAT_EXT_D_BGA1-IC,H91A    I21 @BASEBOARD_FAB2_LIB.BASEBOARD_FAB2(SCH_1):PAGE123
  U7C1 AE30 VCCPRIM_AVID<30> LBG_CORE_QAT_EXT_D_BGA1-IC,H91A    I21 @BASEBOARD_FAB2_LIB.BASEBOARD_FAB2(SCH_1):PAGE123
  U7C1  U27 VCCPRIM_AVID<31> LBG_CORE_QAT_EXT_D_BGA1-IC,H91A    I21 @BASEBOARD_FAB2_LIB.BASEBOARD_FAB2(SCH_1):PAGE123
  U7C1 AC41 VCCPRIM_AVID<32> LBG_CORE_QAT_EXT_D_BGA1-IC,H91A    I21 @BASEBOARD_FAB2_LIB.BASEBOARD_FAB2(SCH_1):PAGE123
  U7C1 AC39 VCCPRIM_AVID<33> LBG_CORE_QAT_EXT_D_BGA1-IC,H91A    I21 @BASEBOARD_FAB2_LIB.BASEBOARD_FAB2(SCH_1):PAGE123
  U7C1 AC37 VCCPRIM_AVID<34> LBG_CORE_QAT_EXT_D_BGA1-IC,H91A    I21 @BASEBOARD_FAB2_LIB.BASEBOARD_FAB2(SCH_1):PAGE123
  U7C1 AC36 VCCPRIM_AVID<35> LBG_CORE_QAT_EXT_D_BGA1-IC,H91A    I21 @BASEBOARD_FAB2_LIB.BASEBOARD_FAB2(SCH_1):PAGE123
  U7C1 AC34 VCCPRIM_AVID<36> LBG_CORE_QAT_EXT_D_BGA1-IC,H91A    I21 @BASEBOARD_FAB2_LIB.BASEBOARD_FAB2(SCH_1):PAGE123
  U7C1 AC32 VCCPRIM_AVID<37> LBG_CORE_QAT_EXT_D_BGA1-IC,H91A    I21 @BASEBOARD_FAB2_LIB.BASEBOARD_FAB2(SCH_1):PAGE123
  U7C1 AC30 VCCPRIM_AVID<38> LBG_CORE_QAT_EXT_D_BGA1-IC,H91A    I21 @BASEBOARD_FAB2_LIB.BASEBOARD_FAB2(SCH_1):PAGE123
  U7C1 AC29 VCCPRIM_AVID<39> LBG_CORE_QAT_EXT_D_BGA1-IC,H91A    I21 @BASEBOARD_FAB2_LIB.BASEBOARD_FAB2(SCH_1):PAGE123
  U7C1 AA41 VCCPRIM_AVID<40> LBG_CORE_QAT_EXT_D_BGA1-IC,H91A    I21 @BASEBOARD_FAB2_LIB.BASEBOARD_FAB2(SCH_1):PAGE123
  U7C1 AA39 VCCPRIM_AVID<41> LBG_CORE_QAT_EXT_D_BGA1-IC,H91A    I21 @BASEBOARD_FAB2_LIB.BASEBOARD_FAB2(SCH_1):PAGE123
  U7C1 AA37 VCCPRIM_AVID<42> LBG_CORE_QAT_EXT_D_BGA1-IC,H91A    I21 @BASEBOARD_FAB2_LIB.BASEBOARD_FAB2(SCH_1):PAGE123
  U7C1 AA36 VCCPRIM_AVID<43> LBG_CORE_QAT_EXT_D_BGA1-IC,H91A    I21 @BASEBOARD_FAB2_LIB.BASEBOARD_FAB2(SCH_1):PAGE123
  U7C1 AA34 VCCPRIM_AVID<44> LBG_CORE_QAT_EXT_D_BGA1-IC,H91A    I21 @BASEBOARD_FAB2_LIB.BASEBOARD_FAB2(SCH_1):PAGE123
  U7C1 AA32 VCCPRIM_AVID<45> LBG_CORE_QAT_EXT_D_BGA1-IC,H91A    I21 @BASEBOARD_FAB2_LIB.BASEBOARD_FAB2(SCH_1):PAGE123
  U7C1 AA30 VCCPRIM_AVID<46> LBG_CORE_QAT_EXT_D_BGA1-IC,H91A    I21 @BASEBOARD_FAB2_LIB.BASEBOARD_FAB2(SCH_1):PAGE123
  U7C1 AA29 VCCPRIM_AVID<47> LBG_CORE_QAT_EXT_D_BGA1-IC,H91A    I21 @BASEBOARD_FAB2_LIB.BASEBOARD_FAB2(SCH_1):PAGE123
  U7C1  Y41 VCCPRIM_AVID<48> LBG_CORE_QAT_EXT_D_BGA1-IC,H91A    I21 @BASEBOARD_FAB2_LIB.BASEBOARD_FAB2(SCH_1):PAGE123
  U7C1  Y39 VCCPRIM_AVID<49> LBG_CORE_QAT_EXT_D_BGA1-IC,H91A    I21 @BASEBOARD_FAB2_LIB.BASEBOARD_FAB2(SCH_1):PAGE123
  U7C1  Y37 VCCPRIM_AVID<50> LBG_CORE_QAT_EXT_D_BGA1-IC,H91A    I21 @BASEBOARD_FAB2_LIB.BASEBOARD_FAB2(SCH_1):PAGE123
  U7C1  Y36 VCCPRIM_AVID<51> LBG_CORE_QAT_EXT_D_BGA1-IC,H91A    I21 @BASEBOARD_FAB2_LIB.BASEBOARD_FAB2(SCH_1):PAGE123
  U7C1  Y34 VCCPRIM_AVID<52> LBG_CORE_QAT_EXT_D_BGA1-IC,H91A    I21 @BASEBOARD_FAB2_LIB.BASEBOARD_FAB2(SCH_1):PAGE123
  U7C1  Y32 VCCPRIM_AVID<53> LBG_CORE_QAT_EXT_D_BGA1-IC,H91A    I21 @BASEBOARD_FAB2_LIB.BASEBOARD_FAB2(SCH_1):PAGE123
  U7C1  Y30 VCCPRIM_AVID<54> LBG_CORE_QAT_EXT_D_BGA1-IC,H91A    I21 @BASEBOARD_FAB2_LIB.BASEBOARD_FAB2(SCH_1):PAGE123
  U7C1  Y29 VCCPRIM_AVID<55> LBG_CORE_QAT_EXT_D_BGA1-IC,H91A    I21 @BASEBOARD_FAB2_LIB.BASEBOARD_FAB2(SCH_1):PAGE123
  U7C1  V40 VCCPRIM_AVID<56> LBG_CORE_QAT_EXT_D_BGA1-IC,H91A    I21 @BASEBOARD_FAB2_LIB.BASEBOARD_FAB2(SCH_1):PAGE123
  U7C1  V33 VCCPRIM_AVID<57> LBG_CORE_QAT_EXT_D_BGA1-IC,H91A    I21 @BASEBOARD_FAB2_LIB.BASEBOARD_FAB2(SCH_1):PAGE123
  U7C1  V29 VCCPRIM_AVID<58> LBG_CORE_QAT_EXT_D_BGA1-IC,H91A    I21 @BASEBOARD_FAB2_LIB.BASEBOARD_FAB2(SCH_1):PAGE123
  U7C1  U38 VCCPRIM_AVID<59> LBG_CORE_QAT_EXT_D_BGA1-IC,H91A    I21 @BASEBOARD_FAB2_LIB.BASEBOARD_FAB2(SCH_1):PAGE123
  U7C1  U35 VCCPRIM_AVID<60> LBG_CORE_QAT_EXT_D_BGA1-IC,H91A    I21 @BASEBOARD_FAB2_LIB.BASEBOARD_FAB2(SCH_1):PAGE123
  U7C1  U31 VCCPRIM_AVID<61> LBG_CORE_QAT_EXT_D_BGA1-IC,H91A    I21 @BASEBOARD_FAB2_LIB.BASEBOARD_FAB2(SCH_1):PAGE123
  U7C1 AK32 VCCPRIM_AVID<62> LBG_CORE_QAT_EXT_D_BGA1-IC,H91A    I21 @BASEBOARD_FAB2_LIB.BASEBOARD_FAB2(SCH_1):PAGE123
 C3L25    1      A CAP_A_0603V-22.0UF,4V,20%,X6S,A     I1 @BASEBOARD_FAB2_LIB.BASEBOARD_FAB2(SCH_1):PAGE132
  C3M7    1      A CAP_A_0603V-22.0UF,4V,20%,X6S,A     I2 @BASEBOARD_FAB2_LIB.BASEBOARD_FAB2(SCH_1):PAGE132
 C3L26    1      A CAP_A_0603V-22.0UF,4V,20%,X6S,A     I3 @BASEBOARD_FAB2_LIB.BASEBOARD_FAB2(SCH_1):PAGE132
 C3L27    1      A CAP_A_0603V-22.0UF,4V,20%,X6S,A     I4 @BASEBOARD_FAB2_LIB.BASEBOARD_FAB2(SCH_1):PAGE132
  C3M6    1      A CAP_A_0603V-22.0UF,4V,20%,X6S,A     I6 @BASEBOARD_FAB2_LIB.BASEBOARD_FAB2(SCH_1):PAGE132
  C7C9    1      A CAP_A_0603V-22.0UF,4V,20%,X6S,A     I7 @BASEBOARD_FAB2_LIB.BASEBOARD_FAB2(SCH_1):PAGE132
 C3N27    1      A CAP_A_0603V-22.0UF,4V,20%,X6S,A     I8 @BASEBOARD_FAB2_LIB.BASEBOARD_FAB2(SCH_1):PAGE132
 C3N30    1      A CAP_A_0603V-22.0UF,4V,20%,X6S,A     I9 @BASEBOARD_FAB2_LIB.BASEBOARD_FAB2(SCH_1):PAGE132
 C7A36    1      A CAP_A_0603V-22.0UF,4V,20%,X6S,A    I11 @BASEBOARD_FAB2_LIB.BASEBOARD_FAB2(SCH_1):PAGE132
 C3N12    1      A CAP_A_0603V-22.0UF,4V,20%,X6S,A    I12 @BASEBOARD_FAB2_LIB.BASEBOARD_FAB2(SCH_1):PAGE132
 C3N10    1      A CAP_A_0603V-22.0UF,4V,20%,X6S,A    I13 @BASEBOARD_FAB2_LIB.BASEBOARD_FAB2(SCH_1):PAGE132
 C3N24    1      A CAP_A_0603V-22.0UF,4V,20%,X6S,A    I16 @BASEBOARD_FAB2_LIB.BASEBOARD_FAB2(SCH_1):PAGE132
 C3N28    1      A CAP_A_0603V-22.0UF,4V,20%,X6S,A    I17 @BASEBOARD_FAB2_LIB.BASEBOARD_FAB2(SCH_1):PAGE132
 C3N11    1      A CAP_A_0603V-22.0UF,4V,20%,X6S,A    I19 @BASEBOARD_FAB2_LIB.BASEBOARD_FAB2(SCH_1):PAGE132
 C3N31    1      A CAP_A_0603V-22.0UF,4V,20%,X6S,A    I20 @BASEBOARD_FAB2_LIB.BASEBOARD_FAB2(SCH_1):PAGE132
 C7A33    1      A CAP_0805-47UF,4V,20%,X6S,C9533A    I23 @BASEBOARD_FAB2_LIB.BASEBOARD_FAB2(SCH_1):PAGE132
  C7B4    1      A CAP_0805-47UF,4V,20%,X6S,C9533A    I24 @BASEBOARD_FAB2_LIB.BASEBOARD_FAB2(SCH_1):PAGE132
  C2N9    1      A CAP_A_0402V-1.0UF,6.3V,10%,X6SA    I26 @BASEBOARD_FAB2_LIB.BASEBOARD_FAB2(SCH_1):PAGE132
  C2N3    1      A CAP_A_0402V-1.0UF,6.3V,10%,X6SA    I27 @BASEBOARD_FAB2_LIB.BASEBOARD_FAB2(SCH_1):PAGE132
  C2N4    1      A CAP_A_0402V-1.0UF,6.3V,10%,X6SA    I28 @BASEBOARD_FAB2_LIB.BASEBOARD_FAB2(SCH_1):PAGE132
 C2N12    1      A CAP_A_0402V-1.0UF,6.3V,10%,X6SA    I29 @BASEBOARD_FAB2_LIB.BASEBOARD_FAB2(SCH_1):PAGE132
 C2N11    1      A CAP_A_0402V-1.0UF,6.3V,10%,X6SA    I30 @BASEBOARD_FAB2_LIB.BASEBOARD_FAB2(SCH_1):PAGE132
 C3N19    1      A CAP_A_0402V-1.0UF,6.3V,10%,X6SA    I31 @BASEBOARD_FAB2_LIB.BASEBOARD_FAB2(SCH_1):PAGE132
  C3N3    1      A CAP_A_0402V-1.0UF,6.3V,10%,X6SA    I32 @BASEBOARD_FAB2_LIB.BASEBOARD_FAB2(SCH_1):PAGE132
  C3N1    1      A CAP_A_0402V-1.0UF,6.3V,10%,X6SA    I34 @BASEBOARD_FAB2_LIB.BASEBOARD_FAB2(SCH_1):PAGE132
  C3N7    1      A CAP_A_0402V-1.0UF,6.3V,10%,X6SA    I35 @BASEBOARD_FAB2_LIB.BASEBOARD_FAB2(SCH_1):PAGE132
 C3N16    1      A CAP_A_0402V-1.0UF,6.3V,10%,X6SA    I36 @BASEBOARD_FAB2_LIB.BASEBOARD_FAB2(SCH_1):PAGE132
 C7A32    1      A CAP_0805-47UF,4V,20%,X6S,C9533A    I38 @BASEBOARD_FAB2_LIB.BASEBOARD_FAB2(SCH_1):PAGE132
 C7A31    1      A CAP_0805-47UF,4V,20%,X6S,C9533A    I40 @BASEBOARD_FAB2_LIB.BASEBOARD_FAB2(SCH_1):PAGE132
 C3N18    1      A CAP_A_0402V-1.0UF,6.3V,10%,X6SA    I42 @BASEBOARD_FAB2_LIB.BASEBOARD_FAB2(SCH_1):PAGE132
  C3N2    1      A CAP_A_0402V-1.0UF,6.3V,10%,X6SA    I43 @BASEBOARD_FAB2_LIB.BASEBOARD_FAB2(SCH_1):PAGE132
  C3N6    1      A CAP_A_0402V-1.0UF,6.3V,10%,X6SA    I44 @BASEBOARD_FAB2_LIB.BASEBOARD_FAB2(SCH_1):PAGE132
 C3N17    1      A CAP_A_0402V-1.0UF,6.3V,10%,X6SA    I45 @BASEBOARD_FAB2_LIB.BASEBOARD_FAB2(SCH_1):PAGE132
  C3N4    1      A CAP_A_0402V-1.0UF,6.3V,10%,X6SA    I46 @BASEBOARD_FAB2_LIB.BASEBOARD_FAB2(SCH_1):PAGE132
  C3N5    1      A CAP_A_0402V-1.0UF,6.3V,10%,X6SA    I48 @BASEBOARD_FAB2_LIB.BASEBOARD_FAB2(SCH_1):PAGE132
 C3N15    1      A CAP_A_0402V-1.0UF,6.3V,10%,X6SA    I49 @BASEBOARD_FAB2_LIB.BASEBOARD_FAB2(SCH_1):PAGE132
 C3N20    1      A CAP_A_0402V-1.0UF,6.3V,10%,X6SA    I51 @BASEBOARD_FAB2_LIB.BASEBOARD_FAB2(SCH_1):PAGE132
 C3L23    1      A CAP_A_0603V-22.0UF,4V,20%,X6S,A    I52 @BASEBOARD_FAB2_LIB.BASEBOARD_FAB2(SCH_1):PAGE132
 C3L22    1      A CAP_A_0603V-22.0UF,4V,20%,X6S,A    I54 @BASEBOARD_FAB2_LIB.BASEBOARD_FAB2(SCH_1):PAGE132
 C3L24    1      A CAP_A_0603V-22.0UF,4V,20%,X6S,A    I56 @BASEBOARD_FAB2_LIB.BASEBOARD_FAB2(SCH_1):PAGE132
 FB1U4    2      B FERRITE_SMLF-30,FB,693286-021   I155 @BASEBOARD_FAB2_LIB.BASEBOARD_FAB2(SCH_1):PAGE169
 C7A30    1      A CAP_0805LF-22UF,4V,20%,X6S,C95A     I9 @BASEBOARD_FAB2_LIB.BASEBOARD_FAB2(SCH_1):PAGE236
 C3L18    1      A CAPP_SM-470UF,2V,20%,ALUM,6990A    I71 @BASEBOARD_FAB2_LIB.BASEBOARD_FAB2(SCH_1):PAGE236
 C3L20    1      A CAPP_SM-470UF,2V,20%,ALUM,6990A    I73 @BASEBOARD_FAB2_LIB.BASEBOARD_FAB2(SCH_1):PAGE236
 C3L21    1      A CAPP_SM-470UF,2V,20%,ALUM,6990A    I74 @BASEBOARD_FAB2_LIB.BASEBOARD_FAB2(SCH_1):PAGE236
 C7A27    1      A CAPP_SM-470UF,2V,20%,ALUM,6990A    I75 @BASEBOARD_FAB2_LIB.BASEBOARD_FAB2(SCH_1):PAGE236
 R7A13    2      B RES_0402-100.0,1%,1/16W,CHIP,GA    I90 @BASEBOARD_FAB2_LIB.BASEBOARD_FAB2(SCH_1):PAGE236
 EU7A3    1    VOS IR354XX_SM-IR35412,IC,H73684-0A   I116 @BASEBOARD_FAB2_LIB.BASEBOARD_FAB2(SCH_1):PAGE236
  L7A2    2      F IND-300NH-20-GP_DISCRET-GB1-INA   I178 @BASEBOARD_FAB2_LIB.BASEBOARD_FAB2(SCH_1):PAGE236

PVPP_ABC @BASEBOARD_FAB2_LIB.BASEBOARD_FAB2(SCH_1):PVPP_ABC
  U5D1  B11 CD_VPP<0> SKX_EXT_B_BGA1-IC,TBD    I34 @BASEBOARD_FAB2_LIB.BASEBOARD_FAB2(SCH_1):PAGE38
  U5D1  A12 CD_VPP<1> SKX_EXT_B_BGA1-IC,TBD    I34 @BASEBOARD_FAB2_LIB.BASEBOARD_FAB2(SCH_1):PAGE38
  U5D1  A10 CD_VPP<2> SKX_EXT_B_BGA1-IC,TBD    I34 @BASEBOARD_FAB2_LIB.BASEBOARD_FAB2(SCH_1):PAGE38
  U5D1   A8 CD_VPP<3> SKX_EXT_B_BGA1-IC,TBD    I34 @BASEBOARD_FAB2_LIB.BASEBOARD_FAB2(SCH_1):PAGE38
  J4G1  284 VDDSPD SCONN288_H44441004_PIP-SCONN,HA     I1 @BASEBOARD_FAB2_LIB.BASEBOARD_FAB2(SCH_1):PAGE43
  J4G1  287 VPP<0> SCONN288_H44441004_PIP-SCONN,HA   I260 @BASEBOARD_FAB2_LIB.BASEBOARD_FAB2(SCH_1):PAGE43
  J4G1  286 VPP<1> SCONN288_H44441004_PIP-SCONN,HA   I260 @BASEBOARD_FAB2_LIB.BASEBOARD_FAB2(SCH_1):PAGE43
  J4G1  288 VPP<2> SCONN288_H44441004_PIP-SCONN,HA   I260 @BASEBOARD_FAB2_LIB.BASEBOARD_FAB2(SCH_1):PAGE43
  J4G1  143 VPP<3> SCONN288_H44441004_PIP-SCONN,HA   I260 @BASEBOARD_FAB2_LIB.BASEBOARD_FAB2(SCH_1):PAGE43
  J4G1  142 VPP<4> SCONN288_H44441004_PIP-SCONN,HA   I260 @BASEBOARD_FAB2_LIB.BASEBOARD_FAB2(SCH_1):PAGE43
  J6T1  139  SA<0> SCONN288_H44441003_PIP-SCONN,HA    I13 @BASEBOARD_FAB2_LIB.BASEBOARD_FAB2(SCH_1):PAGE44
  J6T1  284 VDDSPD SCONN288_H44441003_PIP-SCONN,HA    I13 @BASEBOARD_FAB2_LIB.BASEBOARD_FAB2(SCH_1):PAGE44
  J6T1  287 VPP<0> SCONN288_H44441003_PIP-SCONN,HA    I75 @BASEBOARD_FAB2_LIB.BASEBOARD_FAB2(SCH_1):PAGE44
  J6T1  286 VPP<1> SCONN288_H44441003_PIP-SCONN,HA    I75 @BASEBOARD_FAB2_LIB.BASEBOARD_FAB2(SCH_1):PAGE44
  J6T1  288 VPP<2> SCONN288_H44441003_PIP-SCONN,HA    I75 @BASEBOARD_FAB2_LIB.BASEBOARD_FAB2(SCH_1):PAGE44
  J6T1  143 VPP<3> SCONN288_H44441003_PIP-SCONN,HA    I75 @BASEBOARD_FAB2_LIB.BASEBOARD_FAB2(SCH_1):PAGE44
  J6T1  142 VPP<4> SCONN288_H44441003_PIP-SCONN,HA    I75 @BASEBOARD_FAB2_LIB.BASEBOARD_FAB2(SCH_1):PAGE44
  J4G2  140  SA<1> SCONN288_H44441004_PIP-SCONN,HA   I111 @BASEBOARD_FAB2_LIB.BASEBOARD_FAB2(SCH_1):PAGE45
  J4G2  284 VDDSPD SCONN288_H44441004_PIP-SCONN,HA   I111 @BASEBOARD_FAB2_LIB.BASEBOARD_FAB2(SCH_1):PAGE45
  J4G2  287 VPP<0> SCONN288_H44441004_PIP-SCONN,HA   I169 @BASEBOARD_FAB2_LIB.BASEBOARD_FAB2(SCH_1):PAGE45
  J4G2  286 VPP<1> SCONN288_H44441004_PIP-SCONN,HA   I169 @BASEBOARD_FAB2_LIB.BASEBOARD_FAB2(SCH_1):PAGE45
  J4G2  288 VPP<2> SCONN288_H44441004_PIP-SCONN,HA   I169 @BASEBOARD_FAB2_LIB.BASEBOARD_FAB2(SCH_1):PAGE45
  J4G2  143 VPP<3> SCONN288_H44441004_PIP-SCONN,HA   I169 @BASEBOARD_FAB2_LIB.BASEBOARD_FAB2(SCH_1):PAGE45
  J4G2  142 VPP<4> SCONN288_H44441004_PIP-SCONN,HA   I169 @BASEBOARD_FAB2_LIB.BASEBOARD_FAB2(SCH_1):PAGE45
  J6U1  139  SA<0> SCONN288_H44441003_PIP-SCONN,HA    I14 @BASEBOARD_FAB2_LIB.BASEBOARD_FAB2(SCH_1):PAGE46
  J6U1  140  SA<1> SCONN288_H44441003_PIP-SCONN,HA    I14 @BASEBOARD_FAB2_LIB.BASEBOARD_FAB2(SCH_1):PAGE46
  J6U1  284 VDDSPD SCONN288_H44441003_PIP-SCONN,HA    I14 @BASEBOARD_FAB2_LIB.BASEBOARD_FAB2(SCH_1):PAGE46
  J6U1  287 VPP<0> SCONN288_H44441003_PIP-SCONN,HA    I67 @BASEBOARD_FAB2_LIB.BASEBOARD_FAB2(SCH_1):PAGE46
  J6U1  286 VPP<1> SCONN288_H44441003_PIP-SCONN,HA    I67 @BASEBOARD_FAB2_LIB.BASEBOARD_FAB2(SCH_1):PAGE46
  J6U1  288 VPP<2> SCONN288_H44441003_PIP-SCONN,HA    I67 @BASEBOARD_FAB2_LIB.BASEBOARD_FAB2(SCH_1):PAGE46
  J6U1  143 VPP<3> SCONN288_H44441003_PIP-SCONN,HA    I67 @BASEBOARD_FAB2_LIB.BASEBOARD_FAB2(SCH_1):PAGE46
  J6U1  142 VPP<4> SCONN288_H44441003_PIP-SCONN,HA    I67 @BASEBOARD_FAB2_LIB.BASEBOARD_FAB2(SCH_1):PAGE46
  J4G3  238  SA<2> SCONN288_H44441004_PIP-SCONN,HA   I111 @BASEBOARD_FAB2_LIB.BASEBOARD_FAB2(SCH_1):PAGE47
  J4G3  284 VDDSPD SCONN288_H44441004_PIP-SCONN,HA   I111 @BASEBOARD_FAB2_LIB.BASEBOARD_FAB2(SCH_1):PAGE47
  J4G3  287 VPP<0> SCONN288_H44441004_PIP-SCONN,HA   I179 @BASEBOARD_FAB2_LIB.BASEBOARD_FAB2(SCH_1):PAGE47
  J4G3  286 VPP<1> SCONN288_H44441004_PIP-SCONN,HA   I179 @BASEBOARD_FAB2_LIB.BASEBOARD_FAB2(SCH_1):PAGE47
  J4G3  288 VPP<2> SCONN288_H44441004_PIP-SCONN,HA   I179 @BASEBOARD_FAB2_LIB.BASEBOARD_FAB2(SCH_1):PAGE47
  J4G3  143 VPP<3> SCONN288_H44441004_PIP-SCONN,HA   I179 @BASEBOARD_FAB2_LIB.BASEBOARD_FAB2(SCH_1):PAGE47
  J4G3  142 VPP<4> SCONN288_H44441004_PIP-SCONN,HA   I179 @BASEBOARD_FAB2_LIB.BASEBOARD_FAB2(SCH_1):PAGE47
  J6U2  139  SA<0> SCONN288_H44441003_PIP-SCONN,HA   I111 @BASEBOARD_FAB2_LIB.BASEBOARD_FAB2(SCH_1):PAGE48
  J6U2  238  SA<2> SCONN288_H44441003_PIP-SCONN,HA   I111 @BASEBOARD_FAB2_LIB.BASEBOARD_FAB2(SCH_1):PAGE48
  J6U2  284 VDDSPD SCONN288_H44441003_PIP-SCONN,HA   I111 @BASEBOARD_FAB2_LIB.BASEBOARD_FAB2(SCH_1):PAGE48
  J6U2  287 VPP<0> SCONN288_H44441003_PIP-SCONN,HA   I171 @BASEBOARD_FAB2_LIB.BASEBOARD_FAB2(SCH_1):PAGE48
  J6U2  286 VPP<1> SCONN288_H44441003_PIP-SCONN,HA   I171 @BASEBOARD_FAB2_LIB.BASEBOARD_FAB2(SCH_1):PAGE48
  J6U2  288 VPP<2> SCONN288_H44441003_PIP-SCONN,HA   I171 @BASEBOARD_FAB2_LIB.BASEBOARD_FAB2(SCH_1):PAGE48
  J6U2  143 VPP<3> SCONN288_H44441003_PIP-SCONN,HA   I171 @BASEBOARD_FAB2_LIB.BASEBOARD_FAB2(SCH_1):PAGE48
  J6U2  142 VPP<4> SCONN288_H44441003_PIP-SCONN,HA   I171 @BASEBOARD_FAB2_LIB.BASEBOARD_FAB2(SCH_1):PAGE48
  R6F3    1      A RES_0402-10.0K,1%,1/16W,CHIP,GA     I7 @BASEBOARD_FAB2_LIB.BASEBOARD_FAB2(SCH_1):PAGE89
  J8B1   21   IO21 SCONN24_H46321001_SM-SCONN,H46A     I1 @BASEBOARD_FAB2_LIB.BASEBOARD_FAB2(SCH_1):PAGE91
  R8B8    1      A RES_0402-4.75K,1%,1/16W,CHIP,GA    I14 @BASEBOARD_FAB2_LIB.BASEBOARD_FAB2(SCH_1):PAGE91
 R8B10    1      A RES_0402-4.75K,1%,1/16W,CHIP,GA    I16 @BASEBOARD_FAB2_LIB.BASEBOARD_FAB2(SCH_1):PAGE91
 R8B16    1      A RES_0402-4.75K,1%,1/16W,CHIP,GA    I17 @BASEBOARD_FAB2_LIB.BASEBOARD_FAB2(SCH_1):PAGE91
 R8B17    1      A RES_0402-4.75K,1%,1/16W,CHIP,GA    I18 @BASEBOARD_FAB2_LIB.BASEBOARD_FAB2(SCH_1):PAGE91
 R8B18    1      A RES_0402-4.75K,1%,1/16W,CHIP,GA    I20 @BASEBOARD_FAB2_LIB.BASEBOARD_FAB2(SCH_1):PAGE91
 R8B19    1      A RES_0402-4.75K,1%,1/16W,CHIP,GA    I21 @BASEBOARD_FAB2_LIB.BASEBOARD_FAB2(SCH_1):PAGE91
  R8B5    1      A RES_0402-4.75K,1%,1/16W,CHIP,GA    I22 @BASEBOARD_FAB2_LIB.BASEBOARD_FAB2(SCH_1):PAGE91
  R8B3    1      A RES_0402-4.75K,1%,1/16W,CHIP,GA    I24 @BASEBOARD_FAB2_LIB.BASEBOARD_FAB2(SCH_1):PAGE91
 R8B13    1      A RES_0402-1.8K,1%,1/16W,CHIP,G2A    I34 @BASEBOARD_FAB2_LIB.BASEBOARD_FAB2(SCH_1):PAGE91
 R8B11    1      A RES_0402-1.8K,1%,1/16W,CHIP,G2A    I35 @BASEBOARD_FAB2_LIB.BASEBOARD_FAB2(SCH_1):PAGE91
  R8B7    1      A RES_0402-1.8K,1%,1/16W,CHIP,G2A    I36 @BASEBOARD_FAB2_LIB.BASEBOARD_FAB2(SCH_1):PAGE91
  R8B6    1      A RES_0402-1.8K,1%,1/16W,CHIP,G2A    I37 @BASEBOARD_FAB2_LIB.BASEBOARD_FAB2(SCH_1):PAGE91
  R4U3    1      A RES_0402-4.75K,1%,1/16W,CHIP,GA    I94 @BASEBOARD_FAB2_LIB.BASEBOARD_FAB2(SCH_1):PAGE94
  R4U2    1      A RES_0402-2.21K,1%,1/16W,CHIP,GA   I100 @BASEBOARD_FAB2_LIB.BASEBOARD_FAB2(SCH_1):PAGE94
  C6F3    1      A CAP_A_0402V-0.1UF,16V,10%,X7R,A     I7 @BASEBOARD_FAB2_LIB.BASEBOARD_FAB2(SCH_1):PAGE99
  R4T8    1      A RES_0402-665,1.0%,1/16W,CHIP,GA    I11 @BASEBOARD_FAB2_LIB.BASEBOARD_FAB2(SCH_1):PAGE99
  R4T7    1      A RES_0402-665,1.0%,1/16W,CHIP,GA    I13 @BASEBOARD_FAB2_LIB.BASEBOARD_FAB2(SCH_1):PAGE99
  U6F1    8   VCCB PCA9617_SSOP-IC,G81764-001-GNDA    I15 @BASEBOARD_FAB2_LIB.BASEBOARD_FAB2(SCH_1):PAGE99
 R3R16    1      A RES_0402-4.75K,1%,1/16W,CHIP,GA    I48 @BASEBOARD_FAB2_LIB.BASEBOARD_FAB2(SCH_1):PAGE192
  C6F6    1      A CAP_0603LF-10UF,4V,20%,X6S,E15A   I122 @BASEBOARD_FAB2_LIB.BASEBOARD_FAB2(SCH_1):PAGE231
  C4T6    1      A CAP_0603LF-10UF,4V,20%,X6S,E15A   I124 @BASEBOARD_FAB2_LIB.BASEBOARD_FAB2(SCH_1):PAGE231
  C4T5    1      A CAP_0603LF-10UF,4V,20%,X6S,E15A   I125 @BASEBOARD_FAB2_LIB.BASEBOARD_FAB2(SCH_1):PAGE231
  C6G1    1      A CAP_0603LF-10UF,4V,20%,X6S,E15A   I126 @BASEBOARD_FAB2_LIB.BASEBOARD_FAB2(SCH_1):PAGE231
  C6G2    1      A CAP_0603LF-10UF,4V,20%,X6S,E15A   I128 @BASEBOARD_FAB2_LIB.BASEBOARD_FAB2(SCH_1):PAGE231
  C4U2    1      A CAP_0603LF-10UF,4V,20%,X6S,E15A   I129 @BASEBOARD_FAB2_LIB.BASEBOARD_FAB2(SCH_1):PAGE231
  C4U1    1      A CAP_0603LF-10UF,4V,20%,X6S,E15A   I130 @BASEBOARD_FAB2_LIB.BASEBOARD_FAB2(SCH_1):PAGE231
  C6G4    1      A CAP_0603LF-10UF,4V,20%,X6S,E15A   I131 @BASEBOARD_FAB2_LIB.BASEBOARD_FAB2(SCH_1):PAGE231
  C6G5    1      A CAP_0603LF-10UF,4V,20%,X6S,E15A   I145 @BASEBOARD_FAB2_LIB.BASEBOARD_FAB2(SCH_1):PAGE231
  C4U4    1      A CAP_0603LF-10UF,4V,20%,X6S,E15A   I146 @BASEBOARD_FAB2_LIB.BASEBOARD_FAB2(SCH_1):PAGE231
  C4U3    1      A CAP_0603LF-10UF,4V,20%,X6S,E15A   I148 @BASEBOARD_FAB2_LIB.BASEBOARD_FAB2(SCH_1):PAGE231
  C6F5    1      A CAP_0603LF-10UF,4V,20%,X6S,E15A   I149 @BASEBOARD_FAB2_LIB.BASEBOARD_FAB2(SCH_1):PAGE231
 R7F12    1      A RES_0402-0.0,5%,1/16W,CHIP,G21A   I168 @BASEBOARD_FAB2_LIB.BASEBOARD_FAB2(SCH_1):PAGE231
 R7F10    1      A RES_0603-120.0,1%,1/10W,CHIP,GA   I177 @BASEBOARD_FAB2_LIB.BASEBOARD_FAB2(SCH_1):PAGE231
  L7F1    2    INB INDUCTOR_SM-0.47UH,IND,E13358-A   I178 @BASEBOARD_FAB2_LIB.BASEBOARD_FAB2(SCH_1):PAGE231
  C6F4    1      A CAPP_7343LF-330UF,6.3V,20%,POSA   I180 @BASEBOARD_FAB2_LIB.BASEBOARD_FAB2(SCH_1):PAGE231
  C3T7    1      A CAP_0805-47UF,4V,20%,X6S,C9533A   I184 @BASEBOARD_FAB2_LIB.BASEBOARD_FAB2(SCH_1):PAGE231
  C3T9    1      A CAP_0805-47UF,4V,20%,X6S,C9533A   I186 @BASEBOARD_FAB2_LIB.BASEBOARD_FAB2(SCH_1):PAGE231
  C4T3    1      A CAPP_7343-220UF,4V,20%,POSCAP,A   I217 @BASEBOARD_FAB2_LIB.BASEBOARD_FAB2(SCH_1):PAGE231
 R6W29    1      A RES_0402-10.0K,1%,1/16W,CHIP,GA    I40 @BASEBOARD_FAB2_LIB.BASEBOARD_FAB2(SCH_1):PAGE89

PVPP_DEF @BASEBOARD_FAB2_LIB.BASEBOARD_FAB2(SCH_1):PVPP_DEF
  J4B1  284 VDDSPD SCONN288_H44441004_PIP-SCONN,HA   I111 @BASEBOARD_FAB2_LIB.BASEBOARD_FAB2(SCH_1):PAGE49
  J4B1  287 VPP<0> SCONN288_H44441004_PIP-SCONN,HA   I169 @BASEBOARD_FAB2_LIB.BASEBOARD_FAB2(SCH_1):PAGE49
  J4B1  286 VPP<1> SCONN288_H44441004_PIP-SCONN,HA   I169 @BASEBOARD_FAB2_LIB.BASEBOARD_FAB2(SCH_1):PAGE49
  J4B1  288 VPP<2> SCONN288_H44441004_PIP-SCONN,HA   I169 @BASEBOARD_FAB2_LIB.BASEBOARD_FAB2(SCH_1):PAGE49
  J4B1  143 VPP<3> SCONN288_H44441004_PIP-SCONN,HA   I169 @BASEBOARD_FAB2_LIB.BASEBOARD_FAB2(SCH_1):PAGE49
  J4B1  142 VPP<4> SCONN288_H44441004_PIP-SCONN,HA   I169 @BASEBOARD_FAB2_LIB.BASEBOARD_FAB2(SCH_1):PAGE49
  J6M1  287 VPP<0> SCONN288_H44441003_PIP-SCONN,HA    I50 @BASEBOARD_FAB2_LIB.BASEBOARD_FAB2(SCH_1):PAGE50
  J6M1  286 VPP<1> SCONN288_H44441003_PIP-SCONN,HA    I50 @BASEBOARD_FAB2_LIB.BASEBOARD_FAB2(SCH_1):PAGE50
  J6M1  288 VPP<2> SCONN288_H44441003_PIP-SCONN,HA    I50 @BASEBOARD_FAB2_LIB.BASEBOARD_FAB2(SCH_1):PAGE50
  J6M1  143 VPP<3> SCONN288_H44441003_PIP-SCONN,HA    I50 @BASEBOARD_FAB2_LIB.BASEBOARD_FAB2(SCH_1):PAGE50
  J6M1  142 VPP<4> SCONN288_H44441003_PIP-SCONN,HA    I50 @BASEBOARD_FAB2_LIB.BASEBOARD_FAB2(SCH_1):PAGE50
  J6M1  139  SA<0> SCONN288_H44441003_PIP-SCONN,HA   I158 @BASEBOARD_FAB2_LIB.BASEBOARD_FAB2(SCH_1):PAGE50
  J6M1  284 VDDSPD SCONN288_H44441003_PIP-SCONN,HA   I158 @BASEBOARD_FAB2_LIB.BASEBOARD_FAB2(SCH_1):PAGE50
  J4A2  140  SA<1> SCONN288_H44441004_PIP-SCONN,HA   I111 @BASEBOARD_FAB2_LIB.BASEBOARD_FAB2(SCH_1):PAGE51
  J4A2  284 VDDSPD SCONN288_H44441004_PIP-SCONN,HA   I111 @BASEBOARD_FAB2_LIB.BASEBOARD_FAB2(SCH_1):PAGE51
  J4A2  287 VPP<0> SCONN288_H44441004_PIP-SCONN,HA   I167 @BASEBOARD_FAB2_LIB.BASEBOARD_FAB2(SCH_1):PAGE51
  J4A2  286 VPP<1> SCONN288_H44441004_PIP-SCONN,HA   I167 @BASEBOARD_FAB2_LIB.BASEBOARD_FAB2(SCH_1):PAGE51
  J4A2  288 VPP<2> SCONN288_H44441004_PIP-SCONN,HA   I167 @BASEBOARD_FAB2_LIB.BASEBOARD_FAB2(SCH_1):PAGE51
  J4A2  143 VPP<3> SCONN288_H44441004_PIP-SCONN,HA   I167 @BASEBOARD_FAB2_LIB.BASEBOARD_FAB2(SCH_1):PAGE51
  J4A2  142 VPP<4> SCONN288_H44441004_PIP-SCONN,HA   I167 @BASEBOARD_FAB2_LIB.BASEBOARD_FAB2(SCH_1):PAGE51
  J6L2  139  SA<0> SCONN288_H44441003_PIP-SCONN,HA    I12 @BASEBOARD_FAB2_LIB.BASEBOARD_FAB2(SCH_1):PAGE52
  J6L2  140  SA<1> SCONN288_H44441003_PIP-SCONN,HA    I12 @BASEBOARD_FAB2_LIB.BASEBOARD_FAB2(SCH_1):PAGE52
  J6L2  284 VDDSPD SCONN288_H44441003_PIP-SCONN,HA    I12 @BASEBOARD_FAB2_LIB.BASEBOARD_FAB2(SCH_1):PAGE52
  J6L2  287 VPP<0> SCONN288_H44441003_PIP-SCONN,HA    I55 @BASEBOARD_FAB2_LIB.BASEBOARD_FAB2(SCH_1):PAGE52
  J6L2  286 VPP<1> SCONN288_H44441003_PIP-SCONN,HA    I55 @BASEBOARD_FAB2_LIB.BASEBOARD_FAB2(SCH_1):PAGE52
  J6L2  288 VPP<2> SCONN288_H44441003_PIP-SCONN,HA    I55 @BASEBOARD_FAB2_LIB.BASEBOARD_FAB2(SCH_1):PAGE52
  J6L2  143 VPP<3> SCONN288_H44441003_PIP-SCONN,HA    I55 @BASEBOARD_FAB2_LIB.BASEBOARD_FAB2(SCH_1):PAGE52
  J6L2  142 VPP<4> SCONN288_H44441003_PIP-SCONN,HA    I55 @BASEBOARD_FAB2_LIB.BASEBOARD_FAB2(SCH_1):PAGE52
  J4A1  238  SA<2> SCONN288_H44441004_PIP-SCONN,HA   I111 @BASEBOARD_FAB2_LIB.BASEBOARD_FAB2(SCH_1):PAGE53
  J4A1  284 VDDSPD SCONN288_H44441004_PIP-SCONN,HA   I111 @BASEBOARD_FAB2_LIB.BASEBOARD_FAB2(SCH_1):PAGE53
  J4A1  287 VPP<0> SCONN288_H44441004_PIP-SCONN,HA   I171 @BASEBOARD_FAB2_LIB.BASEBOARD_FAB2(SCH_1):PAGE53
  J4A1  286 VPP<1> SCONN288_H44441004_PIP-SCONN,HA   I171 @BASEBOARD_FAB2_LIB.BASEBOARD_FAB2(SCH_1):PAGE53
  J4A1  288 VPP<2> SCONN288_H44441004_PIP-SCONN,HA   I171 @BASEBOARD_FAB2_LIB.BASEBOARD_FAB2(SCH_1):PAGE53
  J4A1  143 VPP<3> SCONN288_H44441004_PIP-SCONN,HA   I171 @BASEBOARD_FAB2_LIB.BASEBOARD_FAB2(SCH_1):PAGE53
  J4A1  142 VPP<4> SCONN288_H44441004_PIP-SCONN,HA   I171 @BASEBOARD_FAB2_LIB.BASEBOARD_FAB2(SCH_1):PAGE53
  J6L1  139  SA<0> SCONN288_H44441003_PIP-SCONN,HA   I111 @BASEBOARD_FAB2_LIB.BASEBOARD_FAB2(SCH_1):PAGE54
  J6L1  238  SA<2> SCONN288_H44441003_PIP-SCONN,HA   I111 @BASEBOARD_FAB2_LIB.BASEBOARD_FAB2(SCH_1):PAGE54
  J6L1  284 VDDSPD SCONN288_H44441003_PIP-SCONN,HA   I111 @BASEBOARD_FAB2_LIB.BASEBOARD_FAB2(SCH_1):PAGE54
  J6L1  287 VPP<0> SCONN288_H44441003_PIP-SCONN,HA   I170 @BASEBOARD_FAB2_LIB.BASEBOARD_FAB2(SCH_1):PAGE54
  J6L1  286 VPP<1> SCONN288_H44441003_PIP-SCONN,HA   I170 @BASEBOARD_FAB2_LIB.BASEBOARD_FAB2(SCH_1):PAGE54
  J6L1  288 VPP<2> SCONN288_H44441003_PIP-SCONN,HA   I170 @BASEBOARD_FAB2_LIB.BASEBOARD_FAB2(SCH_1):PAGE54
  J6L1  143 VPP<3> SCONN288_H44441003_PIP-SCONN,HA   I170 @BASEBOARD_FAB2_LIB.BASEBOARD_FAB2(SCH_1):PAGE54
  J6L1  142 VPP<4> SCONN288_H44441003_PIP-SCONN,HA   I170 @BASEBOARD_FAB2_LIB.BASEBOARD_FAB2(SCH_1):PAGE54
  C7E2    1      A CAP_A_0402V-0.1UF,16V,10%,X7R,A    I32 @BASEBOARD_FAB2_LIB.BASEBOARD_FAB2(SCH_1):PAGE99
  U7E1    8   VCCB PCA9617_SSOP-IC,G81764-001-GNDA    I61 @BASEBOARD_FAB2_LIB.BASEBOARD_FAB2(SCH_1):PAGE99
 R3R12    1      A RES_0402-665,1.0%,1/16W,CHIP,GA   I101 @BASEBOARD_FAB2_LIB.BASEBOARD_FAB2(SCH_1):PAGE99
  R3R5    1      A RES_0402-665,1.0%,1/16W,CHIP,GA   I103 @BASEBOARD_FAB2_LIB.BASEBOARD_FAB2(SCH_1):PAGE99
  C4L2    1      A CAP_0603LF-10UF,4V,20%,X6S,E15A   I102 @BASEBOARD_FAB2_LIB.BASEBOARD_FAB2(SCH_1):PAGE232
  C6A3    1      A CAP_0603LF-10UF,4V,20%,X6S,E15A   I104 @BASEBOARD_FAB2_LIB.BASEBOARD_FAB2(SCH_1):PAGE232
  C6A2    1      A CAP_0603LF-10UF,4V,20%,X6S,E15A   I105 @BASEBOARD_FAB2_LIB.BASEBOARD_FAB2(SCH_1):PAGE232
  C4L3    1      A CAP_0603LF-10UF,4V,20%,X6S,E15A   I106 @BASEBOARD_FAB2_LIB.BASEBOARD_FAB2(SCH_1):PAGE232
  C4L4    1      A CAP_0603LF-10UF,4V,20%,X6S,E15A   I108 @BASEBOARD_FAB2_LIB.BASEBOARD_FAB2(SCH_1):PAGE232
  C6A7    1      A CAP_0603LF-10UF,4V,20%,X6S,E15A   I109 @BASEBOARD_FAB2_LIB.BASEBOARD_FAB2(SCH_1):PAGE232
  C6A6    1      A CAP_0603LF-10UF,4V,20%,X6S,E15A   I110 @BASEBOARD_FAB2_LIB.BASEBOARD_FAB2(SCH_1):PAGE232
  C4M3    1      A CAP_0603LF-10UF,4V,20%,X6S,E15A   I111 @BASEBOARD_FAB2_LIB.BASEBOARD_FAB2(SCH_1):PAGE232
  C4M4    1      A CAP_0603LF-10UF,4V,20%,X6S,E15A   I125 @BASEBOARD_FAB2_LIB.BASEBOARD_FAB2(SCH_1):PAGE232
  C6B2    1      A CAP_0603LF-10UF,4V,20%,X6S,E15A   I126 @BASEBOARD_FAB2_LIB.BASEBOARD_FAB2(SCH_1):PAGE232
  C6B1    1      A CAP_0603LF-10UF,4V,20%,X6S,E15A   I128 @BASEBOARD_FAB2_LIB.BASEBOARD_FAB2(SCH_1):PAGE232
  C4L1    1      A CAP_0603LF-10UF,4V,20%,X6S,E15A   I129 @BASEBOARD_FAB2_LIB.BASEBOARD_FAB2(SCH_1):PAGE232
 R7B10    1      A RES_0603-120.0,1%,1/10W,CHIP,GA   I227 @BASEBOARD_FAB2_LIB.BASEBOARD_FAB2(SCH_1):PAGE232
  C6B7    1      A CAPP_7343LF-330UF,6.3V,20%,POSA   I229 @BASEBOARD_FAB2_LIB.BASEBOARD_FAB2(SCH_1):PAGE232
  C6B3    1      A CAP_0805-47UF,4V,20%,X6S,C9533A   I236 @BASEBOARD_FAB2_LIB.BASEBOARD_FAB2(SCH_1):PAGE232
  C7B7    1      A CAP_0805-47UF,4V,20%,X6S,C9533A   I238 @BASEBOARD_FAB2_LIB.BASEBOARD_FAB2(SCH_1):PAGE232
  L7B1    2    INB INDUCTOR_SM-0.47UH,IND,E13358-A   I239 @BASEBOARD_FAB2_LIB.BASEBOARD_FAB2(SCH_1):PAGE232
  C4M1    1      A CAPP_7343-220UF,4V,20%,POSCAP,A   I267 @BASEBOARD_FAB2_LIB.BASEBOARD_FAB2(SCH_1):PAGE232
 R7B11    1      A RES_0402-0.0,5%,1/16W,CHIP,G21A   I299 @BASEBOARD_FAB2_LIB.BASEBOARD_FAB2(SCH_1):PAGE232

PVPP_GHJ @BASEBOARD_FAB2_LIB.BASEBOARD_FAB2(SCH_1):PVPP_GHJ
  U2D1  B11 CD_VPP<0> SKX_EXT_B_BGA1-IC,TBD    I33 @BASEBOARD_FAB2_LIB.BASEBOARD_FAB2(SCH_1):PAGE72
  U2D1  A12 CD_VPP<1> SKX_EXT_B_BGA1-IC,TBD    I33 @BASEBOARD_FAB2_LIB.BASEBOARD_FAB2(SCH_1):PAGE72
  U2D1  A10 CD_VPP<2> SKX_EXT_B_BGA1-IC,TBD    I33 @BASEBOARD_FAB2_LIB.BASEBOARD_FAB2(SCH_1):PAGE72
  U2D1   A8 CD_VPP<3> SKX_EXT_B_BGA1-IC,TBD    I33 @BASEBOARD_FAB2_LIB.BASEBOARD_FAB2(SCH_1):PAGE72
  J1G1  284 VDDSPD SCONN288_H44441004_PIP-SCONN,HA   I111 @BASEBOARD_FAB2_LIB.BASEBOARD_FAB2(SCH_1):PAGE77
  J1G1  287 VPP<0> SCONN288_H44441004_PIP-SCONN,HA   I171 @BASEBOARD_FAB2_LIB.BASEBOARD_FAB2(SCH_1):PAGE77
  J1G1  286 VPP<1> SCONN288_H44441004_PIP-SCONN,HA   I171 @BASEBOARD_FAB2_LIB.BASEBOARD_FAB2(SCH_1):PAGE77
  J1G1  288 VPP<2> SCONN288_H44441004_PIP-SCONN,HA   I171 @BASEBOARD_FAB2_LIB.BASEBOARD_FAB2(SCH_1):PAGE77
  J1G1  143 VPP<3> SCONN288_H44441004_PIP-SCONN,HA   I171 @BASEBOARD_FAB2_LIB.BASEBOARD_FAB2(SCH_1):PAGE77
  J1G1  142 VPP<4> SCONN288_H44441004_PIP-SCONN,HA   I171 @BASEBOARD_FAB2_LIB.BASEBOARD_FAB2(SCH_1):PAGE77
  J9T1  139  SA<0> SCONN288_H44441003_PIP-SCONN,HA    I13 @BASEBOARD_FAB2_LIB.BASEBOARD_FAB2(SCH_1):PAGE78
  J9T1  284 VDDSPD SCONN288_H44441003_PIP-SCONN,HA    I13 @BASEBOARD_FAB2_LIB.BASEBOARD_FAB2(SCH_1):PAGE78
  J9T1  287 VPP<0> SCONN288_H44441003_PIP-SCONN,HA    I75 @BASEBOARD_FAB2_LIB.BASEBOARD_FAB2(SCH_1):PAGE78
  J9T1  286 VPP<1> SCONN288_H44441003_PIP-SCONN,HA    I75 @BASEBOARD_FAB2_LIB.BASEBOARD_FAB2(SCH_1):PAGE78
  J9T1  288 VPP<2> SCONN288_H44441003_PIP-SCONN,HA    I75 @BASEBOARD_FAB2_LIB.BASEBOARD_FAB2(SCH_1):PAGE78
  J9T1  143 VPP<3> SCONN288_H44441003_PIP-SCONN,HA    I75 @BASEBOARD_FAB2_LIB.BASEBOARD_FAB2(SCH_1):PAGE78
  J9T1  142 VPP<4> SCONN288_H44441003_PIP-SCONN,HA    I75 @BASEBOARD_FAB2_LIB.BASEBOARD_FAB2(SCH_1):PAGE78
  J1G2  140  SA<1> SCONN288_H44441004_PIP-SCONN,HA   I111 @BASEBOARD_FAB2_LIB.BASEBOARD_FAB2(SCH_1):PAGE79
  J1G2  284 VDDSPD SCONN288_H44441004_PIP-SCONN,HA   I111 @BASEBOARD_FAB2_LIB.BASEBOARD_FAB2(SCH_1):PAGE79
  J1G2  287 VPP<0> SCONN288_H44441004_PIP-SCONN,HA   I169 @BASEBOARD_FAB2_LIB.BASEBOARD_FAB2(SCH_1):PAGE79
  J1G2  286 VPP<1> SCONN288_H44441004_PIP-SCONN,HA   I169 @BASEBOARD_FAB2_LIB.BASEBOARD_FAB2(SCH_1):PAGE79
  J1G2  288 VPP<2> SCONN288_H44441004_PIP-SCONN,HA   I169 @BASEBOARD_FAB2_LIB.BASEBOARD_FAB2(SCH_1):PAGE79
  J1G2  143 VPP<3> SCONN288_H44441004_PIP-SCONN,HA   I169 @BASEBOARD_FAB2_LIB.BASEBOARD_FAB2(SCH_1):PAGE79
  J1G2  142 VPP<4> SCONN288_H44441004_PIP-SCONN,HA   I169 @BASEBOARD_FAB2_LIB.BASEBOARD_FAB2(SCH_1):PAGE79
  J9U1  139  SA<0> SCONN288_H44441003_PIP-SCONN,HA    I24 @BASEBOARD_FAB2_LIB.BASEBOARD_FAB2(SCH_1):PAGE80
  J9U1  140  SA<1> SCONN288_H44441003_PIP-SCONN,HA    I24 @BASEBOARD_FAB2_LIB.BASEBOARD_FAB2(SCH_1):PAGE80
  J9U1  284 VDDSPD SCONN288_H44441003_PIP-SCONN,HA    I24 @BASEBOARD_FAB2_LIB.BASEBOARD_FAB2(SCH_1):PAGE80
  J9U1  287 VPP<0> SCONN288_H44441003_PIP-SCONN,HA    I56 @BASEBOARD_FAB2_LIB.BASEBOARD_FAB2(SCH_1):PAGE80
  J9U1  286 VPP<1> SCONN288_H44441003_PIP-SCONN,HA    I56 @BASEBOARD_FAB2_LIB.BASEBOARD_FAB2(SCH_1):PAGE80
  J9U1  288 VPP<2> SCONN288_H44441003_PIP-SCONN,HA    I56 @BASEBOARD_FAB2_LIB.BASEBOARD_FAB2(SCH_1):PAGE80
  J9U1  143 VPP<3> SCONN288_H44441003_PIP-SCONN,HA    I56 @BASEBOARD_FAB2_LIB.BASEBOARD_FAB2(SCH_1):PAGE80
  J9U1  142 VPP<4> SCONN288_H44441003_PIP-SCONN,HA    I56 @BASEBOARD_FAB2_LIB.BASEBOARD_FAB2(SCH_1):PAGE80
  J1G3  287 VPP<0> SCONN288_H44441004_PIP-SCONN,HA   I169 @BASEBOARD_FAB2_LIB.BASEBOARD_FAB2(SCH_1):PAGE81
  J1G3  286 VPP<1> SCONN288_H44441004_PIP-SCONN,HA   I169 @BASEBOARD_FAB2_LIB.BASEBOARD_FAB2(SCH_1):PAGE81
  J1G3  288 VPP<2> SCONN288_H44441004_PIP-SCONN,HA   I169 @BASEBOARD_FAB2_LIB.BASEBOARD_FAB2(SCH_1):PAGE81
  J1G3  143 VPP<3> SCONN288_H44441004_PIP-SCONN,HA   I169 @BASEBOARD_FAB2_LIB.BASEBOARD_FAB2(SCH_1):PAGE81
  J1G3  142 VPP<4> SCONN288_H44441004_PIP-SCONN,HA   I169 @BASEBOARD_FAB2_LIB.BASEBOARD_FAB2(SCH_1):PAGE81
  J1G3  238  SA<2> SCONN288_H44441004_PIP-SCONN,HA   I186 @BASEBOARD_FAB2_LIB.BASEBOARD_FAB2(SCH_1):PAGE81
  J1G3  284 VDDSPD SCONN288_H44441004_PIP-SCONN,HA   I186 @BASEBOARD_FAB2_LIB.BASEBOARD_FAB2(SCH_1):PAGE81
  J9U2  287 VPP<0> SCONN288_H44441003_PIP-SCONN,HA   I171 @BASEBOARD_FAB2_LIB.BASEBOARD_FAB2(SCH_1):PAGE82
  J9U2  286 VPP<1> SCONN288_H44441003_PIP-SCONN,HA   I171 @BASEBOARD_FAB2_LIB.BASEBOARD_FAB2(SCH_1):PAGE82
  J9U2  288 VPP<2> SCONN288_H44441003_PIP-SCONN,HA   I171 @BASEBOARD_FAB2_LIB.BASEBOARD_FAB2(SCH_1):PAGE82
  J9U2  143 VPP<3> SCONN288_H44441003_PIP-SCONN,HA   I171 @BASEBOARD_FAB2_LIB.BASEBOARD_FAB2(SCH_1):PAGE82
  J9U2  142 VPP<4> SCONN288_H44441003_PIP-SCONN,HA   I171 @BASEBOARD_FAB2_LIB.BASEBOARD_FAB2(SCH_1):PAGE82
  J9U2  139  SA<0> SCONN288_H44441003_PIP-SCONN,HA   I187 @BASEBOARD_FAB2_LIB.BASEBOARD_FAB2(SCH_1):PAGE82
  J9U2  238  SA<2> SCONN288_H44441003_PIP-SCONN,HA   I187 @BASEBOARD_FAB2_LIB.BASEBOARD_FAB2(SCH_1):PAGE82
  J9U2  284 VDDSPD SCONN288_H44441003_PIP-SCONN,HA   I187 @BASEBOARD_FAB2_LIB.BASEBOARD_FAB2(SCH_1):PAGE82
 C4G25    1      A CAP_A_0402V-0.1UF,16V,10%,X7R,A    I41 @BASEBOARD_FAB2_LIB.BASEBOARD_FAB2(SCH_1):PAGE99
  U4G1    8   VCCB PCA9617_SSOP-IC,G81764-001-GNDA    I63 @BASEBOARD_FAB2_LIB.BASEBOARD_FAB2(SCH_1):PAGE99
 R6U18    1      A RES_0402-665,1.0%,1/16W,CHIP,GA   I104 @BASEBOARD_FAB2_LIB.BASEBOARD_FAB2(SCH_1):PAGE99
 R6U17    1      A RES_0402-665,1.0%,1/16W,CHIP,GA   I106 @BASEBOARD_FAB2_LIB.BASEBOARD_FAB2(SCH_1):PAGE99
  C7U4    1      A CAP_0603LF-10UF,4V,20%,X6S,E15A   I109 @BASEBOARD_FAB2_LIB.BASEBOARD_FAB2(SCH_1):PAGE233
  C7U5    1      A CAP_0603LF-10UF,4V,20%,X6S,E15A   I111 @BASEBOARD_FAB2_LIB.BASEBOARD_FAB2(SCH_1):PAGE233
  C7T2    1      A CAP_0603LF-10UF,4V,20%,X6S,E15A   I112 @BASEBOARD_FAB2_LIB.BASEBOARD_FAB2(SCH_1):PAGE233
  C7T3    1      A CAP_0603LF-10UF,4V,20%,X6S,E15A   I113 @BASEBOARD_FAB2_LIB.BASEBOARD_FAB2(SCH_1):PAGE233
  C7U6    1      A CAP_0603LF-10UF,4V,20%,X6S,E15A   I115 @BASEBOARD_FAB2_LIB.BASEBOARD_FAB2(SCH_1):PAGE233
  C3F3    1      A CAP_0603LF-10UF,4V,20%,X6S,E15A   I116 @BASEBOARD_FAB2_LIB.BASEBOARD_FAB2(SCH_1):PAGE233
  C3F4    1      A CAP_0603LF-10UF,4V,20%,X6S,E15A   I117 @BASEBOARD_FAB2_LIB.BASEBOARD_FAB2(SCH_1):PAGE233
  C3G3    1      A CAP_0603LF-10UF,4V,20%,X6S,E15A   I118 @BASEBOARD_FAB2_LIB.BASEBOARD_FAB2(SCH_1):PAGE233
  C3G7    1      A CAP_0603LF-10UF,4V,20%,X6S,E15A   I132 @BASEBOARD_FAB2_LIB.BASEBOARD_FAB2(SCH_1):PAGE233
  C3G4    1      A CAP_0603LF-10UF,4V,20%,X6S,E15A   I133 @BASEBOARD_FAB2_LIB.BASEBOARD_FAB2(SCH_1):PAGE233
  C3G8    1      A CAP_0603LF-10UF,4V,20%,X6S,E15A   I135 @BASEBOARD_FAB2_LIB.BASEBOARD_FAB2(SCH_1):PAGE233
  C7U3    1      A CAP_0603LF-10UF,4V,20%,X6S,E15A   I136 @BASEBOARD_FAB2_LIB.BASEBOARD_FAB2(SCH_1):PAGE233
  R4G6    1      A RES_0603-120.0,1%,1/10W,CHIP,GA   I211 @BASEBOARD_FAB2_LIB.BASEBOARD_FAB2(SCH_1):PAGE233
  C4F7    1      A CAPP_7343LF-330UF,6.3V,20%,POSA   I217 @BASEBOARD_FAB2_LIB.BASEBOARD_FAB2(SCH_1):PAGE233
  C6U3    1      A CAP_0805-47UF,4V,20%,X6S,C9533A   I221 @BASEBOARD_FAB2_LIB.BASEBOARD_FAB2(SCH_1):PAGE233
  C6U2    1      A CAP_0805-47UF,4V,20%,X6S,C9533A   I223 @BASEBOARD_FAB2_LIB.BASEBOARD_FAB2(SCH_1):PAGE233
 C4F11    1      A CAPP_7343-220UF,4V,20%,POSCAP,A   I256 @BASEBOARD_FAB2_LIB.BASEBOARD_FAB2(SCH_1):PAGE233
  R4G8    1      A RES_0402-0.0,5%,1/16W,CHIP,G21A   I271 @BASEBOARD_FAB2_LIB.BASEBOARD_FAB2(SCH_1):PAGE233
  L4G1    2    INB INDUCTOR_SM-0.47UH,IND,E13358-A   I277 @BASEBOARD_FAB2_LIB.BASEBOARD_FAB2(SCH_1):PAGE233

PVPP_KLM @BASEBOARD_FAB2_LIB.BASEBOARD_FAB2(SCH_1):PVPP_KLM
  J1B1  284 VDDSPD SCONN288_H44441004_PIP-SCONN,HA   I111 @BASEBOARD_FAB2_LIB.BASEBOARD_FAB2(SCH_1):PAGE83
  J1B1  287 VPP<0> SCONN288_H44441004_PIP-SCONN,HA   I167 @BASEBOARD_FAB2_LIB.BASEBOARD_FAB2(SCH_1):PAGE83
  J1B1  286 VPP<1> SCONN288_H44441004_PIP-SCONN,HA   I167 @BASEBOARD_FAB2_LIB.BASEBOARD_FAB2(SCH_1):PAGE83
  J1B1  288 VPP<2> SCONN288_H44441004_PIP-SCONN,HA   I167 @BASEBOARD_FAB2_LIB.BASEBOARD_FAB2(SCH_1):PAGE83
  J1B1  143 VPP<3> SCONN288_H44441004_PIP-SCONN,HA   I167 @BASEBOARD_FAB2_LIB.BASEBOARD_FAB2(SCH_1):PAGE83
  J1B1  142 VPP<4> SCONN288_H44441004_PIP-SCONN,HA   I167 @BASEBOARD_FAB2_LIB.BASEBOARD_FAB2(SCH_1):PAGE83
  J9M1  139  SA<0> SCONN288_H44441003_PIP-SCONN,HA    I14 @BASEBOARD_FAB2_LIB.BASEBOARD_FAB2(SCH_1):PAGE84
  J9M1  284 VDDSPD SCONN288_H44441003_PIP-SCONN,HA    I14 @BASEBOARD_FAB2_LIB.BASEBOARD_FAB2(SCH_1):PAGE84
  J9M1  287 VPP<0> SCONN288_H44441003_PIP-SCONN,HA    I57 @BASEBOARD_FAB2_LIB.BASEBOARD_FAB2(SCH_1):PAGE84
  J9M1  286 VPP<1> SCONN288_H44441003_PIP-SCONN,HA    I57 @BASEBOARD_FAB2_LIB.BASEBOARD_FAB2(SCH_1):PAGE84
  J9M1  288 VPP<2> SCONN288_H44441003_PIP-SCONN,HA    I57 @BASEBOARD_FAB2_LIB.BASEBOARD_FAB2(SCH_1):PAGE84
  J9M1  143 VPP<3> SCONN288_H44441003_PIP-SCONN,HA    I57 @BASEBOARD_FAB2_LIB.BASEBOARD_FAB2(SCH_1):PAGE84
  J9M1  142 VPP<4> SCONN288_H44441003_PIP-SCONN,HA    I57 @BASEBOARD_FAB2_LIB.BASEBOARD_FAB2(SCH_1):PAGE84
  J1A2  140  SA<1> SCONN288_H44441004_PIP-SCONN,HA   I111 @BASEBOARD_FAB2_LIB.BASEBOARD_FAB2(SCH_1):PAGE85
  J1A2  284 VDDSPD SCONN288_H44441004_PIP-SCONN,HA   I111 @BASEBOARD_FAB2_LIB.BASEBOARD_FAB2(SCH_1):PAGE85
  J1A2  287 VPP<0> SCONN288_H44441004_PIP-SCONN,HA   I172 @BASEBOARD_FAB2_LIB.BASEBOARD_FAB2(SCH_1):PAGE85
  J1A2  286 VPP<1> SCONN288_H44441004_PIP-SCONN,HA   I172 @BASEBOARD_FAB2_LIB.BASEBOARD_FAB2(SCH_1):PAGE85
  J1A2  288 VPP<2> SCONN288_H44441004_PIP-SCONN,HA   I172 @BASEBOARD_FAB2_LIB.BASEBOARD_FAB2(SCH_1):PAGE85
  J1A2  143 VPP<3> SCONN288_H44441004_PIP-SCONN,HA   I172 @BASEBOARD_FAB2_LIB.BASEBOARD_FAB2(SCH_1):PAGE85
  J1A2  142 VPP<4> SCONN288_H44441004_PIP-SCONN,HA   I172 @BASEBOARD_FAB2_LIB.BASEBOARD_FAB2(SCH_1):PAGE85
  J9L2  139  SA<0> SCONN288_H44441003_PIP-SCONN,HA    I12 @BASEBOARD_FAB2_LIB.BASEBOARD_FAB2(SCH_1):PAGE86
  J9L2  140  SA<1> SCONN288_H44441003_PIP-SCONN,HA    I12 @BASEBOARD_FAB2_LIB.BASEBOARD_FAB2(SCH_1):PAGE86
  J9L2  284 VDDSPD SCONN288_H44441003_PIP-SCONN,HA    I12 @BASEBOARD_FAB2_LIB.BASEBOARD_FAB2(SCH_1):PAGE86
  J9L2  287 VPP<0> SCONN288_H44441003_PIP-SCONN,HA    I55 @BASEBOARD_FAB2_LIB.BASEBOARD_FAB2(SCH_1):PAGE86
  J9L2  286 VPP<1> SCONN288_H44441003_PIP-SCONN,HA    I55 @BASEBOARD_FAB2_LIB.BASEBOARD_FAB2(SCH_1):PAGE86
  J9L2  288 VPP<2> SCONN288_H44441003_PIP-SCONN,HA    I55 @BASEBOARD_FAB2_LIB.BASEBOARD_FAB2(SCH_1):PAGE86
  J9L2  143 VPP<3> SCONN288_H44441003_PIP-SCONN,HA    I55 @BASEBOARD_FAB2_LIB.BASEBOARD_FAB2(SCH_1):PAGE86
  J9L2  142 VPP<4> SCONN288_H44441003_PIP-SCONN,HA    I55 @BASEBOARD_FAB2_LIB.BASEBOARD_FAB2(SCH_1):PAGE86
  J1A1  287 VPP<0> SCONN288_H44441004_PIP-SCONN,HA   I169 @BASEBOARD_FAB2_LIB.BASEBOARD_FAB2(SCH_1):PAGE87
  J1A1  286 VPP<1> SCONN288_H44441004_PIP-SCONN,HA   I169 @BASEBOARD_FAB2_LIB.BASEBOARD_FAB2(SCH_1):PAGE87
  J1A1  288 VPP<2> SCONN288_H44441004_PIP-SCONN,HA   I169 @BASEBOARD_FAB2_LIB.BASEBOARD_FAB2(SCH_1):PAGE87
  J1A1  143 VPP<3> SCONN288_H44441004_PIP-SCONN,HA   I169 @BASEBOARD_FAB2_LIB.BASEBOARD_FAB2(SCH_1):PAGE87
  J1A1  142 VPP<4> SCONN288_H44441004_PIP-SCONN,HA   I169 @BASEBOARD_FAB2_LIB.BASEBOARD_FAB2(SCH_1):PAGE87
  J1A1  238  SA<2> SCONN288_H44441004_PIP-SCONN,HA   I186 @BASEBOARD_FAB2_LIB.BASEBOARD_FAB2(SCH_1):PAGE87
  J1A1  284 VDDSPD SCONN288_H44441004_PIP-SCONN,HA   I186 @BASEBOARD_FAB2_LIB.BASEBOARD_FAB2(SCH_1):PAGE87
  J9L1  139  SA<0> SCONN288_H44441003_PIP-SCONN,HA   I111 @BASEBOARD_FAB2_LIB.BASEBOARD_FAB2(SCH_1):PAGE88
  J9L1  238  SA<2> SCONN288_H44441003_PIP-SCONN,HA   I111 @BASEBOARD_FAB2_LIB.BASEBOARD_FAB2(SCH_1):PAGE88
  J9L1  284 VDDSPD SCONN288_H44441003_PIP-SCONN,HA   I111 @BASEBOARD_FAB2_LIB.BASEBOARD_FAB2(SCH_1):PAGE88
  J9L1  287 VPP<0> SCONN288_H44441003_PIP-SCONN,HA   I168 @BASEBOARD_FAB2_LIB.BASEBOARD_FAB2(SCH_1):PAGE88
  J9L1  286 VPP<1> SCONN288_H44441003_PIP-SCONN,HA   I168 @BASEBOARD_FAB2_LIB.BASEBOARD_FAB2(SCH_1):PAGE88
  J9L1  288 VPP<2> SCONN288_H44441003_PIP-SCONN,HA   I168 @BASEBOARD_FAB2_LIB.BASEBOARD_FAB2(SCH_1):PAGE88
  J9L1  143 VPP<3> SCONN288_H44441003_PIP-SCONN,HA   I168 @BASEBOARD_FAB2_LIB.BASEBOARD_FAB2(SCH_1):PAGE88
  J9L1  142 VPP<4> SCONN288_H44441003_PIP-SCONN,HA   I168 @BASEBOARD_FAB2_LIB.BASEBOARD_FAB2(SCH_1):PAGE88
  C3B5    1      A CAP_A_0402V-0.1UF,16V,10%,X7R,A    I53 @BASEBOARD_FAB2_LIB.BASEBOARD_FAB2(SCH_1):PAGE99
  U3B1    8   VCCB PCA9617_SSOP-IC,G81764-001-GNDA    I75 @BASEBOARD_FAB2_LIB.BASEBOARD_FAB2(SCH_1):PAGE99
  R7M6    1      A RES_0402-665,1.0%,1/16W,CHIP,GA   I107 @BASEBOARD_FAB2_LIB.BASEBOARD_FAB2(SCH_1):PAGE99
  R7M1    1      A RES_0402-665,1.0%,1/16W,CHIP,GA   I109 @BASEBOARD_FAB2_LIB.BASEBOARD_FAB2(SCH_1):PAGE99
  R6M9    1      A RES_0402-4.75K,1%,1/16W,CHIP,GA    I49 @BASEBOARD_FAB2_LIB.BASEBOARD_FAB2(SCH_1):PAGE192
  C3B2    1      A CAP_0603LF-10UF,4V,20%,X6S,E15A    I84 @BASEBOARD_FAB2_LIB.BASEBOARD_FAB2(SCH_1):PAGE234
  C3A8    1      A CAP_0603LF-10UF,4V,20%,X6S,E15A    I86 @BASEBOARD_FAB2_LIB.BASEBOARD_FAB2(SCH_1):PAGE234
  C7L3    1      A CAP_0603LF-10UF,4V,20%,X6S,E15A    I87 @BASEBOARD_FAB2_LIB.BASEBOARD_FAB2(SCH_1):PAGE234
  C7L2    1      A CAP_0603LF-10UF,4V,20%,X6S,E15A    I88 @BASEBOARD_FAB2_LIB.BASEBOARD_FAB2(SCH_1):PAGE234
  C7L7    1      A CAP_0603LF-10UF,4V,20%,X6S,E15A    I89 @BASEBOARD_FAB2_LIB.BASEBOARD_FAB2(SCH_1):PAGE234
  C7L6    1      A CAP_0603LF-10UF,4V,20%,X6S,E15A    I90 @BASEBOARD_FAB2_LIB.BASEBOARD_FAB2(SCH_1):PAGE234
  C7M4    1      A CAP_0603LF-10UF,4V,20%,X6S,E15A    I91 @BASEBOARD_FAB2_LIB.BASEBOARD_FAB2(SCH_1):PAGE234
  C7M3    1      A CAP_0603LF-10UF,4V,20%,X6S,E15A    I92 @BASEBOARD_FAB2_LIB.BASEBOARD_FAB2(SCH_1):PAGE234
  C3A4    1      A CAP_0603LF-10UF,4V,20%,X6S,E15A    I93 @BASEBOARD_FAB2_LIB.BASEBOARD_FAB2(SCH_1):PAGE234
  C3B1    1      A CAP_0603LF-10UF,4V,20%,X6S,E15A    I94 @BASEBOARD_FAB2_LIB.BASEBOARD_FAB2(SCH_1):PAGE234
  C3A7    1      A CAP_0603LF-10UF,4V,20%,X6S,E15A    I95 @BASEBOARD_FAB2_LIB.BASEBOARD_FAB2(SCH_1):PAGE234
  C3A3    1      A CAP_0603LF-10UF,4V,20%,X6S,E15A    I97 @BASEBOARD_FAB2_LIB.BASEBOARD_FAB2(SCH_1):PAGE234
  L4A1    2    INB INDUCTOR_SM-0.47UH,IND,E13358-A   I164 @BASEBOARD_FAB2_LIB.BASEBOARD_FAB2(SCH_1):PAGE234
  C3B3    1      A CAPP_7343LF-330UF,6.3V,20%,POSA   I167 @BASEBOARD_FAB2_LIB.BASEBOARD_FAB2(SCH_1):PAGE234
  C4B3    1      A CAP_0805-47UF,4V,20%,X6S,C9533A   I177 @BASEBOARD_FAB2_LIB.BASEBOARD_FAB2(SCH_1):PAGE234
  C4B2    1      A CAP_0805-47UF,4V,20%,X6S,C9533A   I180 @BASEBOARD_FAB2_LIB.BASEBOARD_FAB2(SCH_1):PAGE234
  R4B2    1      A RES_0603-120.0,1%,1/10W,CHIP,GA   I183 @BASEBOARD_FAB2_LIB.BASEBOARD_FAB2(SCH_1):PAGE234
  C6L8    1      A CAPP_7343-220UF,4V,20%,POSCAP,A   I210 @BASEBOARD_FAB2_LIB.BASEBOARD_FAB2(SCH_1):PAGE234
  R4B3    1      A RES_0402-0.0,5%,1/16W,CHIP,G21A   I214 @BASEBOARD_FAB2_LIB.BASEBOARD_FAB2(SCH_1):PAGE234

PVSA_CPU0 @BASEBOARD_FAB2_LIB.BASEBOARD_FAB2(SCH_1):PVSA_CPU0
  U5D1 CJ66 VCCSA<0> SKX_EXT_B_BGA1-IC,TBD    I34 @BASEBOARD_FAB2_LIB.BASEBOARD_FAB2(SCH_1):PAGE38
  U5D1 CJ64 VCCSA<1> SKX_EXT_B_BGA1-IC,TBD    I34 @BASEBOARD_FAB2_LIB.BASEBOARD_FAB2(SCH_1):PAGE38
  U5D1 CH75 VCCSA<2> SKX_EXT_B_BGA1-IC,TBD    I34 @BASEBOARD_FAB2_LIB.BASEBOARD_FAB2(SCH_1):PAGE38
  U5D1 CH65 VCCSA<3> SKX_EXT_B_BGA1-IC,TBD    I34 @BASEBOARD_FAB2_LIB.BASEBOARD_FAB2(SCH_1):PAGE38
  U5D1 CG74 VCCSA<4> SKX_EXT_B_BGA1-IC,TBD    I34 @BASEBOARD_FAB2_LIB.BASEBOARD_FAB2(SCH_1):PAGE38
  U5D1 CG66 VCCSA<5> SKX_EXT_B_BGA1-IC,TBD    I34 @BASEBOARD_FAB2_LIB.BASEBOARD_FAB2(SCH_1):PAGE38
  U5D1 CG64 VCCSA<6> SKX_EXT_B_BGA1-IC,TBD    I34 @BASEBOARD_FAB2_LIB.BASEBOARD_FAB2(SCH_1):PAGE38
  U5D1 CF75 VCCSA<7> SKX_EXT_B_BGA1-IC,TBD    I34 @BASEBOARD_FAB2_LIB.BASEBOARD_FAB2(SCH_1):PAGE38
  U5D1 CF73 VCCSA<8> SKX_EXT_B_BGA1-IC,TBD    I34 @BASEBOARD_FAB2_LIB.BASEBOARD_FAB2(SCH_1):PAGE38
  U5D1 CF67 VCCSA<9> SKX_EXT_B_BGA1-IC,TBD    I34 @BASEBOARD_FAB2_LIB.BASEBOARD_FAB2(SCH_1):PAGE38
  U5D1 CF65 VCCSA<10> SKX_EXT_B_BGA1-IC,TBD    I34 @BASEBOARD_FAB2_LIB.BASEBOARD_FAB2(SCH_1):PAGE38
  U5D1 CE74 VCCSA<11> SKX_EXT_B_BGA1-IC,TBD    I34 @BASEBOARD_FAB2_LIB.BASEBOARD_FAB2(SCH_1):PAGE38
  U5D1 CE72 VCCSA<12> SKX_EXT_B_BGA1-IC,TBD    I34 @BASEBOARD_FAB2_LIB.BASEBOARD_FAB2(SCH_1):PAGE38
  U5D1 CE68 VCCSA<13> SKX_EXT_B_BGA1-IC,TBD    I34 @BASEBOARD_FAB2_LIB.BASEBOARD_FAB2(SCH_1):PAGE38
  U5D1 CE66 VCCSA<14> SKX_EXT_B_BGA1-IC,TBD    I34 @BASEBOARD_FAB2_LIB.BASEBOARD_FAB2(SCH_1):PAGE38
  U5D1 CE64 VCCSA<15> SKX_EXT_B_BGA1-IC,TBD    I34 @BASEBOARD_FAB2_LIB.BASEBOARD_FAB2(SCH_1):PAGE38
  U5D1 CD71 VCCSA<16> SKX_EXT_B_BGA1-IC,TBD    I34 @BASEBOARD_FAB2_LIB.BASEBOARD_FAB2(SCH_1):PAGE38
  U5D1 CD69 VCCSA<17> SKX_EXT_B_BGA1-IC,TBD    I34 @BASEBOARD_FAB2_LIB.BASEBOARD_FAB2(SCH_1):PAGE38
  U5D1 CD67 VCCSA<18> SKX_EXT_B_BGA1-IC,TBD    I34 @BASEBOARD_FAB2_LIB.BASEBOARD_FAB2(SCH_1):PAGE38
  U5D1 CD65 VCCSA<19> SKX_EXT_B_BGA1-IC,TBD    I34 @BASEBOARD_FAB2_LIB.BASEBOARD_FAB2(SCH_1):PAGE38
  U5D1 CC70 VCCSA<20> SKX_EXT_B_BGA1-IC,TBD    I34 @BASEBOARD_FAB2_LIB.BASEBOARD_FAB2(SCH_1):PAGE38
  U5D1 CC68 VCCSA<21> SKX_EXT_B_BGA1-IC,TBD    I34 @BASEBOARD_FAB2_LIB.BASEBOARD_FAB2(SCH_1):PAGE38
  U5D1 CC66 VCCSA<22> SKX_EXT_B_BGA1-IC,TBD    I34 @BASEBOARD_FAB2_LIB.BASEBOARD_FAB2(SCH_1):PAGE38
  U5D1 CB69 VCCSA<23> SKX_EXT_B_BGA1-IC,TBD    I34 @BASEBOARD_FAB2_LIB.BASEBOARD_FAB2(SCH_1):PAGE38
  U5D1 CB67 VCCSA<24> SKX_EXT_B_BGA1-IC,TBD    I34 @BASEBOARD_FAB2_LIB.BASEBOARD_FAB2(SCH_1):PAGE38
  U5D1 CB65 VCCSA<25> SKX_EXT_B_BGA1-IC,TBD    I34 @BASEBOARD_FAB2_LIB.BASEBOARD_FAB2(SCH_1):PAGE38
  C5P7    1      A CAP_0805LF-22UF,4V,20%,X6S,C95A    I25 @BASEBOARD_FAB2_LIB.BASEBOARD_FAB2(SCH_1):PAGE42
 C5D13    1      A CAP_0603LF-10UF,4V,20%,X6S,E15A    I91 @BASEBOARD_FAB2_LIB.BASEBOARD_FAB2(SCH_1):PAGE42
 C5D11    1      A CAP_0603LF-10UF,4V,20%,X6S,E15A    I93 @BASEBOARD_FAB2_LIB.BASEBOARD_FAB2(SCH_1):PAGE42
 C5D12    1      A CAP_0603LF-10UF,4V,20%,X6S,E15A    I94 @BASEBOARD_FAB2_LIB.BASEBOARD_FAB2(SCH_1):PAGE42
 C5D10    1      A CAP_0603LF-10UF,4V,20%,X6S,E15A   I108 @BASEBOARD_FAB2_LIB.BASEBOARD_FAB2(SCH_1):PAGE42
  C6N7    1      A CAP_A_0603V-22.0UF,4V,20%,X6S,A     I5 @BASEBOARD_FAB2_LIB.BASEBOARD_FAB2(SCH_1):PAGE205
  C6N1    1      A CAPP_3018-470UF,2.5V,20%,ALUM,A    I12 @BASEBOARD_FAB2_LIB.BASEBOARD_FAB2(SCH_1):PAGE205
  C6N4    1      A CAPP_3018-470UF,2.5V,20%,ALUM,A    I14 @BASEBOARD_FAB2_LIB.BASEBOARD_FAB2(SCH_1):PAGE205
  R4C5    2      B RES_0402-100.0,1%,1/16W,CHIP,GA    I24 @BASEBOARD_FAB2_LIB.BASEBOARD_FAB2(SCH_1):PAGE205
 C4C11    1      A CAP_A_0603V-22.0UF,4V,20%,X6S,A    I43 @BASEBOARD_FAB2_LIB.BASEBOARD_FAB2(SCH_1):PAGE205
  R6N4    1      A RES_0402-51.1,1.0%,1/16W,CHIP,A    I45 @BASEBOARD_FAB2_LIB.BASEBOARD_FAB2(SCH_1):PAGE205
 EU4C1    1    VOS IR354XX_SM-IR35412,IC,H73684-0A    I46 @BASEBOARD_FAB2_LIB.BASEBOARD_FAB2(SCH_1):PAGE205
  L4C2    2      F IND-300NH-20-GP_DISCRET-GB1-INA    I82 @BASEBOARD_FAB2_LIB.BASEBOARD_FAB2(SCH_1):PAGE205
  C5P8    1      A CAP_0805LF-22UF,4V,20%,X6S,C95A   I214 @BASEBOARD_FAB2_LIB.BASEBOARD_FAB2(SCH_1):PAGE42
  C5P9    1      A CAP_0805LF-22UF,4V,20%,X6S,C95A   I215 @BASEBOARD_FAB2_LIB.BASEBOARD_FAB2(SCH_1):PAGE42

PVSA_CPU1 @BASEBOARD_FAB2_LIB.BASEBOARD_FAB2(SCH_1):PVSA_CPU1
  U2D1 CJ66 VCCSA<0> SKX_EXT_B_BGA1-IC,TBD    I33 @BASEBOARD_FAB2_LIB.BASEBOARD_FAB2(SCH_1):PAGE72
  U2D1 CJ64 VCCSA<1> SKX_EXT_B_BGA1-IC,TBD    I33 @BASEBOARD_FAB2_LIB.BASEBOARD_FAB2(SCH_1):PAGE72
  U2D1 CH75 VCCSA<2> SKX_EXT_B_BGA1-IC,TBD    I33 @BASEBOARD_FAB2_LIB.BASEBOARD_FAB2(SCH_1):PAGE72
  U2D1 CH65 VCCSA<3> SKX_EXT_B_BGA1-IC,TBD    I33 @BASEBOARD_FAB2_LIB.BASEBOARD_FAB2(SCH_1):PAGE72
  U2D1 CG74 VCCSA<4> SKX_EXT_B_BGA1-IC,TBD    I33 @BASEBOARD_FAB2_LIB.BASEBOARD_FAB2(SCH_1):PAGE72
  U2D1 CG66 VCCSA<5> SKX_EXT_B_BGA1-IC,TBD    I33 @BASEBOARD_FAB2_LIB.BASEBOARD_FAB2(SCH_1):PAGE72
  U2D1 CG64 VCCSA<6> SKX_EXT_B_BGA1-IC,TBD    I33 @BASEBOARD_FAB2_LIB.BASEBOARD_FAB2(SCH_1):PAGE72
  U2D1 CF75 VCCSA<7> SKX_EXT_B_BGA1-IC,TBD    I33 @BASEBOARD_FAB2_LIB.BASEBOARD_FAB2(SCH_1):PAGE72
  U2D1 CF73 VCCSA<8> SKX_EXT_B_BGA1-IC,TBD    I33 @BASEBOARD_FAB2_LIB.BASEBOARD_FAB2(SCH_1):PAGE72
  U2D1 CF67 VCCSA<9> SKX_EXT_B_BGA1-IC,TBD    I33 @BASEBOARD_FAB2_LIB.BASEBOARD_FAB2(SCH_1):PAGE72
  U2D1 CF65 VCCSA<10> SKX_EXT_B_BGA1-IC,TBD    I33 @BASEBOARD_FAB2_LIB.BASEBOARD_FAB2(SCH_1):PAGE72
  U2D1 CE74 VCCSA<11> SKX_EXT_B_BGA1-IC,TBD    I33 @BASEBOARD_FAB2_LIB.BASEBOARD_FAB2(SCH_1):PAGE72
  U2D1 CE72 VCCSA<12> SKX_EXT_B_BGA1-IC,TBD    I33 @BASEBOARD_FAB2_LIB.BASEBOARD_FAB2(SCH_1):PAGE72
  U2D1 CE68 VCCSA<13> SKX_EXT_B_BGA1-IC,TBD    I33 @BASEBOARD_FAB2_LIB.BASEBOARD_FAB2(SCH_1):PAGE72
  U2D1 CE66 VCCSA<14> SKX_EXT_B_BGA1-IC,TBD    I33 @BASEBOARD_FAB2_LIB.BASEBOARD_FAB2(SCH_1):PAGE72
  U2D1 CE64 VCCSA<15> SKX_EXT_B_BGA1-IC,TBD    I33 @BASEBOARD_FAB2_LIB.BASEBOARD_FAB2(SCH_1):PAGE72
  U2D1 CD71 VCCSA<16> SKX_EXT_B_BGA1-IC,TBD    I33 @BASEBOARD_FAB2_LIB.BASEBOARD_FAB2(SCH_1):PAGE72
  U2D1 CD69 VCCSA<17> SKX_EXT_B_BGA1-IC,TBD    I33 @BASEBOARD_FAB2_LIB.BASEBOARD_FAB2(SCH_1):PAGE72
  U2D1 CD67 VCCSA<18> SKX_EXT_B_BGA1-IC,TBD    I33 @BASEBOARD_FAB2_LIB.BASEBOARD_FAB2(SCH_1):PAGE72
  U2D1 CD65 VCCSA<19> SKX_EXT_B_BGA1-IC,TBD    I33 @BASEBOARD_FAB2_LIB.BASEBOARD_FAB2(SCH_1):PAGE72
  U2D1 CC70 VCCSA<20> SKX_EXT_B_BGA1-IC,TBD    I33 @BASEBOARD_FAB2_LIB.BASEBOARD_FAB2(SCH_1):PAGE72
  U2D1 CC68 VCCSA<21> SKX_EXT_B_BGA1-IC,TBD    I33 @BASEBOARD_FAB2_LIB.BASEBOARD_FAB2(SCH_1):PAGE72
  U2D1 CC66 VCCSA<22> SKX_EXT_B_BGA1-IC,TBD    I33 @BASEBOARD_FAB2_LIB.BASEBOARD_FAB2(SCH_1):PAGE72
  U2D1 CB69 VCCSA<23> SKX_EXT_B_BGA1-IC,TBD    I33 @BASEBOARD_FAB2_LIB.BASEBOARD_FAB2(SCH_1):PAGE72
  U2D1 CB67 VCCSA<24> SKX_EXT_B_BGA1-IC,TBD    I33 @BASEBOARD_FAB2_LIB.BASEBOARD_FAB2(SCH_1):PAGE72
  U2D1 CB65 VCCSA<25> SKX_EXT_B_BGA1-IC,TBD    I33 @BASEBOARD_FAB2_LIB.BASEBOARD_FAB2(SCH_1):PAGE72
  C2D8    1      A CAP_0603LF-10UF,4V,20%,X6S,E15A    I33 @BASEBOARD_FAB2_LIB.BASEBOARD_FAB2(SCH_1):PAGE76
 C2D10    1      A CAP_0603LF-10UF,4V,20%,X6S,E15A    I37 @BASEBOARD_FAB2_LIB.BASEBOARD_FAB2(SCH_1):PAGE76
 C2D11    1      A CAP_0603LF-10UF,4V,20%,X6S,E15A    I42 @BASEBOARD_FAB2_LIB.BASEBOARD_FAB2(SCH_1):PAGE76
  C2D9    1      A CAP_0603LF-10UF,4V,20%,X6S,E15A    I43 @BASEBOARD_FAB2_LIB.BASEBOARD_FAB2(SCH_1):PAGE76
 C1C19    1      A CAP_A_0603V-22.0UF,4V,20%,X6S,A     I8 @BASEBOARD_FAB2_LIB.BASEBOARD_FAB2(SCH_1):PAGE210
 C9N11    1      A CAPP_3018-470UF,2.5V,20%,ALUM,A    I12 @BASEBOARD_FAB2_LIB.BASEBOARD_FAB2(SCH_1):PAGE210
 C9N20    1      A CAPP_3018-470UF,2.5V,20%,ALUM,A    I14 @BASEBOARD_FAB2_LIB.BASEBOARD_FAB2(SCH_1):PAGE210
 R1C12    2      B RES_0402-100.0,1%,1/16W,CHIP,GA    I29 @BASEBOARD_FAB2_LIB.BASEBOARD_FAB2(SCH_1):PAGE210
 C9N22    1      A CAP_A_0603V-22.0UF,4V,20%,X6S,A    I44 @BASEBOARD_FAB2_LIB.BASEBOARD_FAB2(SCH_1):PAGE210
  R9N4    1      A RES_0402-51.1,1.0%,1/16W,CHIP,A    I45 @BASEBOARD_FAB2_LIB.BASEBOARD_FAB2(SCH_1):PAGE210
 EU1C1    1    VOS IR354XX_SM-IR35412,IC,H73684-0A    I51 @BASEBOARD_FAB2_LIB.BASEBOARD_FAB2(SCH_1):PAGE210
  L1C1    2      F IND-300NH-20-GP_DISCRET-GB1-INA    I72 @BASEBOARD_FAB2_LIB.BASEBOARD_FAB2(SCH_1):PAGE210
  C8P5    1      A CAP_0805LF-22UF,4V,20%,X6S,C95A   I246 @BASEBOARD_FAB2_LIB.BASEBOARD_FAB2(SCH_1):PAGE76
  C8P6    1      A CAP_0805LF-22UF,4V,20%,X6S,C95A   I247 @BASEBOARD_FAB2_LIB.BASEBOARD_FAB2(SCH_1):PAGE76
  C8P7    1      A CAP_0805LF-22UF,4V,20%,X6S,C95A   I248 @BASEBOARD_FAB2_LIB.BASEBOARD_FAB2(SCH_1):PAGE76

PVTT_ABC @BASEBOARD_FAB2_LIB.BASEBOARD_FAB2(SCH_1):PVTT_ABC
  J4G1  221 VTT<0> SCONN288_H44441004_PIP-SCONN,HA   I260 @BASEBOARD_FAB2_LIB.BASEBOARD_FAB2(SCH_1):PAGE43
  J4G1   77 VTT<1> SCONN288_H44441004_PIP-SCONN,HA   I260 @BASEBOARD_FAB2_LIB.BASEBOARD_FAB2(SCH_1):PAGE43
  J6T1  221 VTT<0> SCONN288_H44441003_PIP-SCONN,HA    I75 @BASEBOARD_FAB2_LIB.BASEBOARD_FAB2(SCH_1):PAGE44
  J6T1   77 VTT<1> SCONN288_H44441003_PIP-SCONN,HA    I75 @BASEBOARD_FAB2_LIB.BASEBOARD_FAB2(SCH_1):PAGE44
  J4G2  221 VTT<0> SCONN288_H44441004_PIP-SCONN,HA   I169 @BASEBOARD_FAB2_LIB.BASEBOARD_FAB2(SCH_1):PAGE45
  J4G2   77 VTT<1> SCONN288_H44441004_PIP-SCONN,HA   I169 @BASEBOARD_FAB2_LIB.BASEBOARD_FAB2(SCH_1):PAGE45
  J6U1  221 VTT<0> SCONN288_H44441003_PIP-SCONN,HA    I67 @BASEBOARD_FAB2_LIB.BASEBOARD_FAB2(SCH_1):PAGE46
  J6U1   77 VTT<1> SCONN288_H44441003_PIP-SCONN,HA    I67 @BASEBOARD_FAB2_LIB.BASEBOARD_FAB2(SCH_1):PAGE46
  J4G3  221 VTT<0> SCONN288_H44441004_PIP-SCONN,HA   I179 @BASEBOARD_FAB2_LIB.BASEBOARD_FAB2(SCH_1):PAGE47
  J4G3   77 VTT<1> SCONN288_H44441004_PIP-SCONN,HA   I179 @BASEBOARD_FAB2_LIB.BASEBOARD_FAB2(SCH_1):PAGE47
  J6U2  221 VTT<0> SCONN288_H44441003_PIP-SCONN,HA   I171 @BASEBOARD_FAB2_LIB.BASEBOARD_FAB2(SCH_1):PAGE48
  J6U2   77 VTT<1> SCONN288_H44441003_PIP-SCONN,HA   I171 @BASEBOARD_FAB2_LIB.BASEBOARD_FAB2(SCH_1):PAGE48
 C4G24    1      A CAP_0805LF-22UF,4V,20%,X6S,C95A    I24 @BASEBOARD_FAB2_LIB.BASEBOARD_FAB2(SCH_1):PAGE221
 SH5U1    2      B SHUNT_SH0201-EMPTY,N_A     I9 @BASEBOARD_FAB2_LIB.BASEBOARD_FAB2(SCH_1):PAGE221
 EU4G3    9    VTT MIC5166_DFN-IC,H55101-001    I15 @BASEBOARD_FAB2_LIB.BASEBOARD_FAB2(SCH_1):PAGE221
  C5T3    1      A CAP_A_0603V-47UF,4V,20%,X5R,60A    I40 @BASEBOARD_FAB2_LIB.BASEBOARD_FAB2(SCH_1):PAGE221
 C6W11    1      A CAP_0805-100UF,4V,20%,X5R,6024A    I44 @BASEBOARD_FAB2_LIB.BASEBOARD_FAB2(SCH_1):PAGE221
 C5U12    1      A CAP_0805-100UF,4V,20%,X5R,6024A    I45 @BASEBOARD_FAB2_LIB.BASEBOARD_FAB2(SCH_1):PAGE221
 C5U16    1      A CAP_0805-100UF,4V,20%,X5R,6024A    I46 @BASEBOARD_FAB2_LIB.BASEBOARD_FAB2(SCH_1):PAGE221

PVTT_DEF @BASEBOARD_FAB2_LIB.BASEBOARD_FAB2(SCH_1):PVTT_DEF
  J4B1  221 VTT<0> SCONN288_H44441004_PIP-SCONN,HA   I169 @BASEBOARD_FAB2_LIB.BASEBOARD_FAB2(SCH_1):PAGE49
  J4B1   77 VTT<1> SCONN288_H44441004_PIP-SCONN,HA   I169 @BASEBOARD_FAB2_LIB.BASEBOARD_FAB2(SCH_1):PAGE49
  J6M1  221 VTT<0> SCONN288_H44441003_PIP-SCONN,HA    I50 @BASEBOARD_FAB2_LIB.BASEBOARD_FAB2(SCH_1):PAGE50
  J6M1   77 VTT<1> SCONN288_H44441003_PIP-SCONN,HA    I50 @BASEBOARD_FAB2_LIB.BASEBOARD_FAB2(SCH_1):PAGE50
  J4A2  221 VTT<0> SCONN288_H44441004_PIP-SCONN,HA   I167 @BASEBOARD_FAB2_LIB.BASEBOARD_FAB2(SCH_1):PAGE51
  J4A2   77 VTT<1> SCONN288_H44441004_PIP-SCONN,HA   I167 @BASEBOARD_FAB2_LIB.BASEBOARD_FAB2(SCH_1):PAGE51
  J6L2  221 VTT<0> SCONN288_H44441003_PIP-SCONN,HA    I55 @BASEBOARD_FAB2_LIB.BASEBOARD_FAB2(SCH_1):PAGE52
  J6L2   77 VTT<1> SCONN288_H44441003_PIP-SCONN,HA    I55 @BASEBOARD_FAB2_LIB.BASEBOARD_FAB2(SCH_1):PAGE52
  J4A1  221 VTT<0> SCONN288_H44441004_PIP-SCONN,HA   I171 @BASEBOARD_FAB2_LIB.BASEBOARD_FAB2(SCH_1):PAGE53
  J4A1   77 VTT<1> SCONN288_H44441004_PIP-SCONN,HA   I171 @BASEBOARD_FAB2_LIB.BASEBOARD_FAB2(SCH_1):PAGE53
  J6L1  221 VTT<0> SCONN288_H44441003_PIP-SCONN,HA   I170 @BASEBOARD_FAB2_LIB.BASEBOARD_FAB2(SCH_1):PAGE54
  J6L1   77 VTT<1> SCONN288_H44441003_PIP-SCONN,HA   I170 @BASEBOARD_FAB2_LIB.BASEBOARD_FAB2(SCH_1):PAGE54
  C4A1    1      A CAP_0805LF-22UF,4V,20%,X6S,C95A    I28 @BASEBOARD_FAB2_LIB.BASEBOARD_FAB2(SCH_1):PAGE222
 EU4A1    9    VTT MIC5166_DFN-IC,H55101-001    I13 @BASEBOARD_FAB2_LIB.BASEBOARD_FAB2(SCH_1):PAGE222
 SH5L1    2      B SHUNT_SH0201-EMPTY,N_A    I30 @BASEBOARD_FAB2_LIB.BASEBOARD_FAB2(SCH_1):PAGE222
 C5M13    1      A CAP_A_0603V-47UF,4V,20%,X5R,60A    I41 @BASEBOARD_FAB2_LIB.BASEBOARD_FAB2(SCH_1):PAGE222
  C5L5    1      A CAP_0805-100UF,4V,20%,X5R,6024A    I44 @BASEBOARD_FAB2_LIB.BASEBOARD_FAB2(SCH_1):PAGE222
  C5L4    1      A CAP_0805-100UF,4V,20%,X5R,6024A    I45 @BASEBOARD_FAB2_LIB.BASEBOARD_FAB2(SCH_1):PAGE222
  C4W5    1      A CAP_0805-100UF,4V,20%,X5R,6024A    I46 @BASEBOARD_FAB2_LIB.BASEBOARD_FAB2(SCH_1):PAGE222

PVTT_GHJ @BASEBOARD_FAB2_LIB.BASEBOARD_FAB2(SCH_1):PVTT_GHJ
  J1G1  221 VTT<0> SCONN288_H44441004_PIP-SCONN,HA   I171 @BASEBOARD_FAB2_LIB.BASEBOARD_FAB2(SCH_1):PAGE77
  J1G1   77 VTT<1> SCONN288_H44441004_PIP-SCONN,HA   I171 @BASEBOARD_FAB2_LIB.BASEBOARD_FAB2(SCH_1):PAGE77
  J9T1  221 VTT<0> SCONN288_H44441003_PIP-SCONN,HA    I75 @BASEBOARD_FAB2_LIB.BASEBOARD_FAB2(SCH_1):PAGE78
  J9T1   77 VTT<1> SCONN288_H44441003_PIP-SCONN,HA    I75 @BASEBOARD_FAB2_LIB.BASEBOARD_FAB2(SCH_1):PAGE78
  J1G2  221 VTT<0> SCONN288_H44441004_PIP-SCONN,HA   I169 @BASEBOARD_FAB2_LIB.BASEBOARD_FAB2(SCH_1):PAGE79
  J1G2   77 VTT<1> SCONN288_H44441004_PIP-SCONN,HA   I169 @BASEBOARD_FAB2_LIB.BASEBOARD_FAB2(SCH_1):PAGE79
  J9U1  221 VTT<0> SCONN288_H44441003_PIP-SCONN,HA    I56 @BASEBOARD_FAB2_LIB.BASEBOARD_FAB2(SCH_1):PAGE80
  J9U1   77 VTT<1> SCONN288_H44441003_PIP-SCONN,HA    I56 @BASEBOARD_FAB2_LIB.BASEBOARD_FAB2(SCH_1):PAGE80
  J1G3  221 VTT<0> SCONN288_H44441004_PIP-SCONN,HA   I169 @BASEBOARD_FAB2_LIB.BASEBOARD_FAB2(SCH_1):PAGE81
  J1G3   77 VTT<1> SCONN288_H44441004_PIP-SCONN,HA   I169 @BASEBOARD_FAB2_LIB.BASEBOARD_FAB2(SCH_1):PAGE81
  J9U2  221 VTT<0> SCONN288_H44441003_PIP-SCONN,HA   I171 @BASEBOARD_FAB2_LIB.BASEBOARD_FAB2(SCH_1):PAGE82
  J9U2   77 VTT<1> SCONN288_H44441003_PIP-SCONN,HA   I171 @BASEBOARD_FAB2_LIB.BASEBOARD_FAB2(SCH_1):PAGE82
 SH8U1    2      B SHUNT_SH0201-EMPTY,N_A    I12 @BASEBOARD_FAB2_LIB.BASEBOARD_FAB2(SCH_1):PAGE229
 C4G20    1      A CAP_0805LF-22UF,4V,20%,X6S,C95A    I23 @BASEBOARD_FAB2_LIB.BASEBOARD_FAB2(SCH_1):PAGE229
  C2F2    1      A CAP_A_0603V-47UF,4V,20%,X5R,60A    I28 @BASEBOARD_FAB2_LIB.BASEBOARD_FAB2(SCH_1):PAGE229
 EU4G2    9    VTT MIC5166_DFN-IC,H55101-001    I37 @BASEBOARD_FAB2_LIB.BASEBOARD_FAB2(SCH_1):PAGE229
  C8T3    1      A CAP_0805-100UF,4V,20%,X5R,6024A    I41 @BASEBOARD_FAB2_LIB.BASEBOARD_FAB2(SCH_1):PAGE229
 C8U10    1      A CAP_0805-100UF,4V,20%,X5R,6024A    I42 @BASEBOARD_FAB2_LIB.BASEBOARD_FAB2(SCH_1):PAGE229
 C6W12    1      A CAP_0805-100UF,4V,20%,X5R,6024A    I43 @BASEBOARD_FAB2_LIB.BASEBOARD_FAB2(SCH_1):PAGE229

PVTT_KLM @BASEBOARD_FAB2_LIB.BASEBOARD_FAB2(SCH_1):PVTT_KLM
  J1B1  221 VTT<0> SCONN288_H44441004_PIP-SCONN,HA   I167 @BASEBOARD_FAB2_LIB.BASEBOARD_FAB2(SCH_1):PAGE83
  J1B1   77 VTT<1> SCONN288_H44441004_PIP-SCONN,HA   I167 @BASEBOARD_FAB2_LIB.BASEBOARD_FAB2(SCH_1):PAGE83
  J9M1  221 VTT<0> SCONN288_H44441003_PIP-SCONN,HA    I57 @BASEBOARD_FAB2_LIB.BASEBOARD_FAB2(SCH_1):PAGE84
  J9M1   77 VTT<1> SCONN288_H44441003_PIP-SCONN,HA    I57 @BASEBOARD_FAB2_LIB.BASEBOARD_FAB2(SCH_1):PAGE84
  J1A2  221 VTT<0> SCONN288_H44441004_PIP-SCONN,HA   I172 @BASEBOARD_FAB2_LIB.BASEBOARD_FAB2(SCH_1):PAGE85
  J1A2   77 VTT<1> SCONN288_H44441004_PIP-SCONN,HA   I172 @BASEBOARD_FAB2_LIB.BASEBOARD_FAB2(SCH_1):PAGE85
  J9L2  221 VTT<0> SCONN288_H44441003_PIP-SCONN,HA    I55 @BASEBOARD_FAB2_LIB.BASEBOARD_FAB2(SCH_1):PAGE86
  J9L2   77 VTT<1> SCONN288_H44441003_PIP-SCONN,HA    I55 @BASEBOARD_FAB2_LIB.BASEBOARD_FAB2(SCH_1):PAGE86
  J1A1  221 VTT<0> SCONN288_H44441004_PIP-SCONN,HA   I169 @BASEBOARD_FAB2_LIB.BASEBOARD_FAB2(SCH_1):PAGE87
  J1A1   77 VTT<1> SCONN288_H44441004_PIP-SCONN,HA   I169 @BASEBOARD_FAB2_LIB.BASEBOARD_FAB2(SCH_1):PAGE87
  J9L1  221 VTT<0> SCONN288_H44441003_PIP-SCONN,HA   I168 @BASEBOARD_FAB2_LIB.BASEBOARD_FAB2(SCH_1):PAGE88
  J9L1   77 VTT<1> SCONN288_H44441003_PIP-SCONN,HA   I168 @BASEBOARD_FAB2_LIB.BASEBOARD_FAB2(SCH_1):PAGE88
 C4A13    1      A CAP_0805LF-22UF,4V,20%,X6S,C95A    I20 @BASEBOARD_FAB2_LIB.BASEBOARD_FAB2(SCH_1):PAGE230
 C8M12    1      A CAP_A_0603V-47UF,4V,20%,X5R,60A    I24 @BASEBOARD_FAB2_LIB.BASEBOARD_FAB2(SCH_1):PAGE230
 SH8L1    2      B SHUNT_SH0201-EMPTY,N_A    I30 @BASEBOARD_FAB2_LIB.BASEBOARD_FAB2(SCH_1):PAGE230
 EU4A2    9    VTT MIC5166_DFN-IC,H55101-001    I37 @BASEBOARD_FAB2_LIB.BASEBOARD_FAB2(SCH_1):PAGE230
  C8L3    1      A CAP_0805-100UF,4V,20%,X5R,6024A    I41 @BASEBOARD_FAB2_LIB.BASEBOARD_FAB2(SCH_1):PAGE230
  C8L4    1      A CAP_0805-100UF,4V,20%,X5R,6024A    I42 @BASEBOARD_FAB2_LIB.BASEBOARD_FAB2(SCH_1):PAGE230
 C6W13    1      A CAP_0805-100UF,4V,20%,X5R,6024A    I43 @BASEBOARD_FAB2_LIB.BASEBOARD_FAB2(SCH_1):PAGE230

PWRGD_CPU0_DRAMPWROK_ABC_G @BASEBOARD_FAB2_LIB.BASEBOARD_FAB2(SCH_1):PWRGD_CPU0_DRAMPWROK_ABC_G
  U5D1 AN30 DDR012_DRAM_PWR_OK SKX_EXT_B_BGA1-IC,TBD   I259 @BASEBOARD_FAB2_LIB.BASEBOARD_FAB2(SCH_1):PAGE21
 R3P38    2      B RES_0402-64.9,1.0%,1/16W,CHIP,A     I7 @BASEBOARD_FAB2_LIB.BASEBOARD_FAB2(SCH_1):PAGE96
  U3P1    3     B1 GTL2014_SM-IC,D66151-001    I42 @BASEBOARD_FAB2_LIB.BASEBOARD_FAB2(SCH_1):PAGE96

PWRGD_CPU0_DRAMPWROK_DEF_G @BASEBOARD_FAB2_LIB.BASEBOARD_FAB2(SCH_1):PWRGD_CPU0_DRAMPWROK_DEF_G
  U5D1 CR28 DDR345_DRAM_PWR_OK SKX_EXT_B_BGA1-IC,TBD   I259 @BASEBOARD_FAB2_LIB.BASEBOARD_FAB2(SCH_1):PAGE21
 R3P29    2      B RES_0402-64.9,1.0%,1/16W,CHIP,A     I5 @BASEBOARD_FAB2_LIB.BASEBOARD_FAB2(SCH_1):PAGE96
  U3P1    2     B0 GTL2014_SM-IC,D66151-001    I42 @BASEBOARD_FAB2_LIB.BASEBOARD_FAB2(SCH_1):PAGE96

PWRGD_CPU0_G @BASEBOARD_FAB2_LIB.BASEBOARD_FAB2(SCH_1):PWRGD_CPU0_G
  U5D1 BC24 PWRGOOD SKX_EXT_B_BGA1-IC,TBD   I259 @BASEBOARD_FAB2_LIB.BASEBOARD_FAB2(SCH_1):PAGE21
  R6D8    2      B RES_0402-49.9,1%,1/16W,CHIP,G2A     I3 @BASEBOARD_FAB2_LIB.BASEBOARD_FAB2(SCH_1):PAGE96
  U3P1    6     B3 GTL2014_SM-IC,D66151-001    I42 @BASEBOARD_FAB2_LIB.BASEBOARD_FAB2(SCH_1):PAGE96
 R9B14    1      A RES_0402-1.00K,1%,1/16W,CHIP,GA   I168 @BASEBOARD_FAB2_LIB.BASEBOARD_FAB2(SCH_1):PAGE113

PWRGD_CPU0_G_R @BASEBOARD_FAB2_LIB.BASEBOARD_FAB2(SCH_1):PWRGD_CPU0_G_R
 R9B14    2      B RES_0402-1.00K,1%,1/16W,CHIP,GA   I168 @BASEBOARD_FAB2_LIB.BASEBOARD_FAB2(SCH_1):PAGE113
  J9B4    7    IO7 SCONN10_C12536004_SMLF-CONN,C1A   I175 @BASEBOARD_FAB2_LIB.BASEBOARD_FAB2(SCH_1):PAGE113

PWRGD_CPU0_LVC3 @BASEBOARD_FAB2_LIB.BASEBOARD_FAB2(SCH_1):PWRGD_CPU0_LVC3
  U3P1    9     A3 GTL2014_SM-IC,D66151-001    I42 @BASEBOARD_FAB2_LIB.BASEBOARD_FAB2(SCH_1):PAGE96
  U8D7   L5  PL11D LCMXO2_A_256BGA-IC,H63395-001   I179 @BASEBOARD_FAB2_LIB.BASEBOARD_FAB2(SCH_1):PAGE190

PWRGD_CPU1_DRAMPWROK_GHJ_G @BASEBOARD_FAB2_LIB.BASEBOARD_FAB2(SCH_1):PWRGD_CPU1_DRAMPWROK_GHJ_G
  U2D1 AN30 DDR012_DRAM_PWR_OK SKX_EXT_B_BGA1-IC,TBD   I172 @BASEBOARD_FAB2_LIB.BASEBOARD_FAB2(SCH_1):PAGE55
 R3D21    2      B RES_0402-64.9,1.0%,1/16W,CHIP,A    I30 @BASEBOARD_FAB2_LIB.BASEBOARD_FAB2(SCH_1):PAGE96
  U4C2    3     B1 GTL2014_SM-IC,D66151-001    I46 @BASEBOARD_FAB2_LIB.BASEBOARD_FAB2(SCH_1):PAGE96

PWRGD_CPU1_DRAMPWROK_KLM_G @BASEBOARD_FAB2_LIB.BASEBOARD_FAB2(SCH_1):PWRGD_CPU1_DRAMPWROK_KLM_G
  U2D1 CR28 DDR345_DRAM_PWR_OK SKX_EXT_B_BGA1-IC,TBD   I172 @BASEBOARD_FAB2_LIB.BASEBOARD_FAB2(SCH_1):PAGE55
  R7M9    2      B RES_0402-64.9,1.0%,1/16W,CHIP,A    I28 @BASEBOARD_FAB2_LIB.BASEBOARD_FAB2(SCH_1):PAGE96
  U4C2    2     B0 GTL2014_SM-IC,D66151-001    I46 @BASEBOARD_FAB2_LIB.BASEBOARD_FAB2(SCH_1):PAGE96

PWRGD_CPU1_G @BASEBOARD_FAB2_LIB.BASEBOARD_FAB2(SCH_1):PWRGD_CPU1_G
  U2D1 BC24 PWRGOOD SKX_EXT_B_BGA1-IC,TBD   I172 @BASEBOARD_FAB2_LIB.BASEBOARD_FAB2(SCH_1):PAGE55
 R3D15    2      B RES_0402-49.9,1%,1/16W,CHIP,G2A    I26 @BASEBOARD_FAB2_LIB.BASEBOARD_FAB2(SCH_1):PAGE96
  U4C2    6     B3 GTL2014_SM-IC,D66151-001    I46 @BASEBOARD_FAB2_LIB.BASEBOARD_FAB2(SCH_1):PAGE96

PWRGD_CPU1_LVC3 @BASEBOARD_FAB2_LIB.BASEBOARD_FAB2(SCH_1):PWRGD_CPU1_LVC3
  U4C2    9     A3 GTL2014_SM-IC,D66151-001    I46 @BASEBOARD_FAB2_LIB.BASEBOARD_FAB2(SCH_1):PAGE96
  U8D7  M10  PB21C LCMXO2_A_256BGA-IC,H63395-001   I179 @BASEBOARD_FAB2_LIB.BASEBOARD_FAB2(SCH_1):PAGE190

PWRGD_CPUPWRGD @BASEBOARD_FAB2_LIB.BASEBOARD_FAB2(SCH_1):PWRGD_CPUPWRGD
  R3R3    2      B RES_0402-33.2,1%,1/16W,CHIP,G2A    I61 @BASEBOARD_FAB2_LIB.BASEBOARD_FAB2(SCH_1):PAGE92
  U8D7  F13   PR3C LCMXO2_A_256BGA-IC,H63395-001    I59 @BASEBOARD_FAB2_LIB.BASEBOARD_FAB2(SCH_1):PAGE191

PWRGD_CPUPWRGD_GTL @BASEBOARD_FAB2_LIB.BASEBOARD_FAB2(SCH_1):PWRGD_CPUPWRGD_GTL
  U3P2    2     B0 GTL2014_SM-IC,D66151-001     I1 @BASEBOARD_FAB2_LIB.BASEBOARD_FAB2(SCH_1):PAGE92
  U7C1   R9 PROC_PWRGD LBG_CORE_QAT_EXT_D_BGA1-IC,H91A    I73 @BASEBOARD_FAB2_LIB.BASEBOARD_FAB2(SCH_1):PAGE118

PWRGD_CPUPWRGD_R1 @BASEBOARD_FAB2_LIB.BASEBOARD_FAB2(SCH_1):PWRGD_CPUPWRGD_R1
  U3P2   13     A0 GTL2014_SM-IC,D66151-001     I1 @BASEBOARD_FAB2_LIB.BASEBOARD_FAB2(SCH_1):PAGE92
  R3R3    1      A RES_0402-33.2,1%,1/16W,CHIP,G2A    I61 @BASEBOARD_FAB2_LIB.BASEBOARD_FAB2(SCH_1):PAGE92

PWRGD_DRAMPWRGD @BASEBOARD_FAB2_LIB.BASEBOARD_FAB2(SCH_1):PWRGD_DRAMPWRGD
  U3P1   13     A0 GTL2014_SM-IC,D66151-001    I42 @BASEBOARD_FAB2_LIB.BASEBOARD_FAB2(SCH_1):PAGE96
  U3P1   12     A1 GTL2014_SM-IC,D66151-001    I42 @BASEBOARD_FAB2_LIB.BASEBOARD_FAB2(SCH_1):PAGE96
  U4C2   13     A0 GTL2014_SM-IC,D66151-001    I46 @BASEBOARD_FAB2_LIB.BASEBOARD_FAB2(SCH_1):PAGE96
  U4C2   12     A1 GTL2014_SM-IC,D66151-001    I46 @BASEBOARD_FAB2_LIB.BASEBOARD_FAB2(SCH_1):PAGE96
  U8D7  T15  PB25C LCMXO2_A_256BGA-IC,H63395-001   I179 @BASEBOARD_FAB2_LIB.BASEBOARD_FAB2(SCH_1):PAGE190

PWRGD_DSW_PWROK @BASEBOARD_FAB2_LIB.BASEBOARD_FAB2(SCH_1):PWRGD_DSW_PWROK
  U7C1  K13 DSW_PWROK LBG_CORE_QAT_EXT_D_BGA1-IC,H91A    I73 @BASEBOARD_FAB2_LIB.BASEBOARD_FAB2(SCH_1):PAGE118
  U8D2    2      A TTL1G07_A_SOP-74LVC1G07,IC,C88B   I374 @BASEBOARD_FAB2_LIB.BASEBOARD_FAB2(SCH_1):PAGE157
  U8D7  B11  PT22A LCMXO2_A_256BGA-IC,H63395-001    I59 @BASEBOARD_FAB2_LIB.BASEBOARD_FAB2(SCH_1):PAGE191
 R3P44    2      B RES_0402-4.75K,1%,1/16W,CHIP,GA    I59 @BASEBOARD_FAB2_LIB.BASEBOARD_FAB2(SCH_1):PAGE196
  U7D3    4  ENOUT ADM1085_SMT-IC,H46130-001    I70 @BASEBOARD_FAB2_LIB.BASEBOARD_FAB2(SCH_1):PAGE196
 CR7E1    2      A DIODE_SMLF-BAT54WS,IC,C73510-0A   I103 @BASEBOARD_FAB2_LIB.BASEBOARD_FAB2(SCH_1):PAGE196
  U9P2    6   OUTA TPS3700_SM-IC,H69492-001   I200 @BASEBOARD_FAB2_LIB.BASEBOARD_FAB2(SCH_1):PAGE200
  U6W1   17    P14 TCA9555PWR-GP_DISCRET-GC1-TCA9A   I120 @BASEBOARD_FAB2_LIB.BASEBOARD_FAB2(SCH_1):PAGE247
 U25W9    2      A TTL1G07_A_SOP-74LVC1G07,IC,C88B   I394 @BASEBOARD_FAB2_LIB.BASEBOARD_FAB2(SCH_1):PAGE157

PWRGD_P12V_HSC @BASEBOARD_FAB2_LIB.BASEBOARD_FAB2(SCH_1):PWRGD_P12V_HSC
  U8E2    3    VCC ADM809_SMLF-IC,D23047-001-GND=A    I89 @BASEBOARD_FAB2_LIB.BASEBOARD_FAB2(SCH_1):PAGE196
  C8E3    1      A CAP_A_0402V-0.1UF,16V,10%,X7R,A    I94 @BASEBOARD_FAB2_LIB.BASEBOARD_FAB2(SCH_1):PAGE196
 CR8E1    1      C DIODE_SMLF-BAT54WS,IC,C73510-0A   I128 @BASEBOARD_FAB2_LIB.BASEBOARD_FAB2(SCH_1):PAGE196
 R1D33    2      B RES_0402-33.2,1%,1/16W,CHIP,G2A   I108 @BASEBOARD_FAB2_LIB.BASEBOARD_FAB2(SCH_1):PAGE199

PWRGD_P12V_HSC_DLY @BASEBOARD_FAB2_LIB.BASEBOARD_FAB2(SCH_1):PWRGD_P12V_HSC_DLY
  R8E7    2      B RES_0402-22.1,1.0%,1/16W,CHIP,A    I90 @BASEBOARD_FAB2_LIB.BASEBOARD_FAB2(SCH_1):PAGE196
 CR8E1    2      A DIODE_SMLF-BAT54WS,IC,C73510-0A   I128 @BASEBOARD_FAB2_LIB.BASEBOARD_FAB2(SCH_1):PAGE196
 C8E13    1      A CAP_0402LF-1000PF,50V,10%,EMPTA    I41 @BASEBOARD_FAB2_LIB.BASEBOARD_FAB2(SCH_1):PAGE241
 R8E33    1      A RES_0402-0.0,5%,1/16W,CHIP,G21A    I91 @BASEBOARD_FAB2_LIB.BASEBOARD_FAB2(SCH_1):PAGE241
 U14E3    1   A<0> TTL1G08_SOTLF-NC7SZ08,IC,D1032C    I19 @BASEBOARD_FAB2_LIB.BASEBOARD_FAB2(SCH_1):PAGE248
  U8E1   10   B<0> TTL08_QFN15-74LVC08A,IC,D90404B    I60 @BASEBOARD_FAB2_LIB.BASEBOARD_FAB2(SCH_1):PAGE181

PWRGD_P12V_HSC_DLY_R @BASEBOARD_FAB2_LIB.BASEBOARD_FAB2(SCH_1):PWRGD_P12V_HSC_DLY_R
  U8E2    2 RESET_N ADM809_SMLF-IC,D23047-001-GND=A    I89 @BASEBOARD_FAB2_LIB.BASEBOARD_FAB2(SCH_1):PAGE196
  R8E7    1      A RES_0402-22.1,1.0%,1/16W,CHIP,A    I90 @BASEBOARD_FAB2_LIB.BASEBOARD_FAB2(SCH_1):PAGE196

PWRGD_P12V_MAIN @BASEBOARD_FAB2_LIB.BASEBOARD_FAB2(SCH_1):PWRGD_P12V_MAIN
  U8D7   B5   PT9B LCMXO2_A_256BGA-IC,H63395-001    I59 @BASEBOARD_FAB2_LIB.BASEBOARD_FAB2(SCH_1):PAGE191
 R8D42    2      B RES_0402-100.0,1%,1/16W,CHIP,GA   I106 @BASEBOARD_FAB2_LIB.BASEBOARD_FAB2(SCH_1):PAGE196

PWRGD_P12V_MAIN_R @BASEBOARD_FAB2_LIB.BASEBOARD_FAB2(SCH_1):PWRGD_P12V_MAIN_R
  U8D8    6   OUTA TPS3700_SM-IC,H69492-001   I104 @BASEBOARD_FAB2_LIB.BASEBOARD_FAB2(SCH_1):PAGE196
 R8D42    1      A RES_0402-100.0,1%,1/16W,CHIP,GA   I106 @BASEBOARD_FAB2_LIB.BASEBOARD_FAB2(SCH_1):PAGE196
 R8D41    2      B RES_0402-10.0K,1%,1/16W,CHIP,GA   I120 @BASEBOARD_FAB2_LIB.BASEBOARD_FAB2(SCH_1):PAGE196

PWRGD_P12V_R @BASEBOARD_FAB2_LIB.BASEBOARD_FAB2(SCH_1):PWRGD_P12V_R
 EU1D2   18  PWRGD ADM1278_SM-IC,G99251-001    I10 @BASEBOARD_FAB2_LIB.BASEBOARD_FAB2(SCH_1):PAGE199
 R9P18    2      B RES_0402-15.0K,1%,1/16W,CHIP,GA    I41 @BASEBOARD_FAB2_LIB.BASEBOARD_FAB2(SCH_1):PAGE199
 R1D31    1      A RES_0402-6.19K,1%,1/16W,CHIP,GA    I43 @BASEBOARD_FAB2_LIB.BASEBOARD_FAB2(SCH_1):PAGE199
 R1D33    1      A RES_0402-33.2,1%,1/16W,CHIP,G2A   I108 @BASEBOARD_FAB2_LIB.BASEBOARD_FAB2(SCH_1):PAGE199

PWRGD_P1V15_BMC_STBY @BASEBOARD_FAB2_LIB.BASEBOARD_FAB2(SCH_1):PWRGD_P1V15_BMC_STBY
  U8D7   E7  PT12B LCMXO2_A_256BGA-IC,H63395-001    I59 @BASEBOARD_FAB2_LIB.BASEBOARD_FAB2(SCH_1):PAGE191
 R9F11    2      B RES_0402-22.1,1.0%,1/16W,CHIP,A    I41 @BASEBOARD_FAB2_LIB.BASEBOARD_FAB2(SCH_1):PAGE238

PWRGD_P1V15_BMC_STBY_R @BASEBOARD_FAB2_LIB.BASEBOARD_FAB2(SCH_1):PWRGD_P1V15_BMC_STBY_R
  C9F8    1      A CAP_0402LF-1000PF,50V,10%,X7R,A    I19 @BASEBOARD_FAB2_LIB.BASEBOARD_FAB2(SCH_1):PAGE238
 R9F13    2      B RES_0402-10.0K,1%,1/16W,CHIP,GA    I21 @BASEBOARD_FAB2_LIB.BASEBOARD_FAB2(SCH_1):PAGE238
 EU9F1    5  PGOOD RT9059_DFN-IC,H65765-001    I40 @BASEBOARD_FAB2_LIB.BASEBOARD_FAB2(SCH_1):PAGE238
 R9F11    1      A RES_0402-22.1,1.0%,1/16W,CHIP,A    I41 @BASEBOARD_FAB2_LIB.BASEBOARD_FAB2(SCH_1):PAGE238

PWRGD_P1V2_BMC_STBY @BASEBOARD_FAB2_LIB.BASEBOARD_FAB2(SCH_1):PWRGD_P1V2_BMC_STBY
  C9F9    1      A CAP_0402LF-1000PF,50V,10%,EMPTA     I5 @BASEBOARD_FAB2_LIB.BASEBOARD_FAB2(SCH_1):PAGE238
 EU9F1    6     EN RT9059_DFN-IC,H65765-001    I40 @BASEBOARD_FAB2_LIB.BASEBOARD_FAB2(SCH_1):PAGE238
  R1T9    2      B RES_0402-22.1,1.0%,1/16W,CHIP,A    I72 @BASEBOARD_FAB2_LIB.BASEBOARD_FAB2(SCH_1):PAGE239

PWRGD_P1V2_BMC_STBY_R @BASEBOARD_FAB2_LIB.BASEBOARD_FAB2(SCH_1):PWRGD_P1V2_BMC_STBY_R
 C9F10    1      A CAP_0402LF-1000PF,50V,10%,X7R,A     I4 @BASEBOARD_FAB2_LIB.BASEBOARD_FAB2(SCH_1):PAGE239
 R9F12    2      B RES_0402-10.0K,1%,1/16W,CHIP,GA     I6 @BASEBOARD_FAB2_LIB.BASEBOARD_FAB2(SCH_1):PAGE239
 EU9F2    5  PGOOD RT9059_DFN-IC,H65765-001    I70 @BASEBOARD_FAB2_LIB.BASEBOARD_FAB2(SCH_1):PAGE239
  R1T9    1      A RES_0402-22.1,1.0%,1/16W,CHIP,A    I72 @BASEBOARD_FAB2_LIB.BASEBOARD_FAB2(SCH_1):PAGE239

PWRGD_P1V8MCP_CPU0 @BASEBOARD_FAB2_LIB.BASEBOARD_FAB2(SCH_1):PWRGD_P1V8MCP_CPU0
  U8D7  D15   PR2D LCMXO2_A_256BGA-IC,H63395-001    I59 @BASEBOARD_FAB2_LIB.BASEBOARD_FAB2(SCH_1):PAGE191
  J6B1  B15  IOB15 SCONN120_H61426002_SM-CONN,H61A    I56 @BASEBOARD_FAB2_LIB.BASEBOARD_FAB2(SCH_1):PAGE194

PWRGD_P1V8MCP_CPU1 @BASEBOARD_FAB2_LIB.BASEBOARD_FAB2(SCH_1):PWRGD_P1V8MCP_CPU1
  U8D7  D16   PR2A LCMXO2_A_256BGA-IC,H63395-001    I59 @BASEBOARD_FAB2_LIB.BASEBOARD_FAB2(SCH_1):PAGE191
  J4B2  B15  IOB15 SCONN120_H61426002_SM-CONN,H61A    I46 @BASEBOARD_FAB2_LIB.BASEBOARD_FAB2(SCH_1):PAGE193

PWRGD_P1V8_PCH_STBY @BASEBOARD_FAB2_LIB.BASEBOARD_FAB2(SCH_1):PWRGD_P1V8_PCH_STBY
 R2L17    1      A RES_0402-0.0,5%,1/16W,CHIP,G21A   I221 @BASEBOARD_FAB2_LIB.BASEBOARD_FAB2(SCH_1):PAGE235
 R8A11    2      B RES_0402-22.1,1.0%,1/16W,CHIP,A    I90 @BASEBOARD_FAB2_LIB.BASEBOARD_FAB2(SCH_1):PAGE237

PWRGD_P1V8_PCH_STBY_R @BASEBOARD_FAB2_LIB.BASEBOARD_FAB2(SCH_1):PWRGD_P1V8_PCH_STBY_R
 R8A10    2      B RES_0402-5.11K,1%,1/16W,CHIP,GA     I3 @BASEBOARD_FAB2_LIB.BASEBOARD_FAB2(SCH_1):PAGE237
 C8A11    1      A CAP_0402LF-1000PF,50V,10%,X7R,A     I5 @BASEBOARD_FAB2_LIB.BASEBOARD_FAB2(SCH_1):PAGE237
 EU8A2    5  PGOOD RT9059_DFN-IC,H65765-001    I86 @BASEBOARD_FAB2_LIB.BASEBOARD_FAB2(SCH_1):PAGE237
 R8A11    1      A RES_0402-22.1,1.0%,1/16W,CHIP,A    I90 @BASEBOARD_FAB2_LIB.BASEBOARD_FAB2(SCH_1):PAGE237

PWRGD_P2V5_BMC_STBY @BASEBOARD_FAB2_LIB.BASEBOARD_FAB2(SCH_1):PWRGD_P2V5_BMC_STBY
  C9F6    1      A CAP_0402LF-1000PF,50V,10%,EMPTA    I30 @BASEBOARD_FAB2_LIB.BASEBOARD_FAB2(SCH_1):PAGE239
 EU9F2    6     EN RT9059_DFN-IC,H65765-001    I70 @BASEBOARD_FAB2_LIB.BASEBOARD_FAB2(SCH_1):PAGE239
  R1W9    2      B RES_0402-22.1,1.0%,1/16W,CHIP,A    I77 @BASEBOARD_FAB2_LIB.BASEBOARD_FAB2(SCH_1):PAGE239

PWRGD_P2V5_BMC_STBY_R @BASEBOARD_FAB2_LIB.BASEBOARD_FAB2(SCH_1):PWRGD_P2V5_BMC_STBY_R
EU25F2    5  PGOOD RT9059_DFN-IC,H65765-001    I73 @BASEBOARD_FAB2_LIB.BASEBOARD_FAB2(SCH_1):PAGE239
  R1W9    1      A RES_0402-22.1,1.0%,1/16W,CHIP,A    I77 @BASEBOARD_FAB2_LIB.BASEBOARD_FAB2(SCH_1):PAGE239
 R9W12    2      B RES_0402-10.0K,1%,1/16W,CHIP,GA    I79 @BASEBOARD_FAB2_LIB.BASEBOARD_FAB2(SCH_1):PAGE239
 C9W10    1      A CAP_0402LF-1000PF,50V,10%,X7R,A    I84 @BASEBOARD_FAB2_LIB.BASEBOARD_FAB2(SCH_1):PAGE239

PWRGD_P3V3 @BASEBOARD_FAB2_LIB.BASEBOARD_FAB2(SCH_1):PWRGD_P3V3
 R1L12    1      A RES_0402-0.0,5%,1/16W,CHIP,G21A    I63 @BASEBOARD_FAB2_LIB.BASEBOARD_FAB2(SCH_1):PAGE175
  U8D7   H6   PL5D LCMXO2_A_256BGA-IC,H63395-001   I179 @BASEBOARD_FAB2_LIB.BASEBOARD_FAB2(SCH_1):PAGE190
 R1L16    2      B RES_0402-49.9,1%,1/16W,CHIP,G2A    I68 @BASEBOARD_FAB2_LIB.BASEBOARD_FAB2(SCH_1):PAGE196
 U14E3    2   B<0> TTL1G08_SOTLF-NC7SZ08,IC,D1032C    I19 @BASEBOARD_FAB2_LIB.BASEBOARD_FAB2(SCH_1):PAGE248

PWRGD_P3V3_R @BASEBOARD_FAB2_LIB.BASEBOARD_FAB2(SCH_1):PWRGD_P3V3_R
  U1L2    1      A TTL1G86_SOTLF-74AHCT1G86,IC,D3B    I57 @BASEBOARD_FAB2_LIB.BASEBOARD_FAB2(SCH_1):PAGE175
 R1L12    2      B RES_0402-0.0,5%,1/16W,CHIP,G21A    I63 @BASEBOARD_FAB2_LIB.BASEBOARD_FAB2(SCH_1):PAGE175

PWRGD_P3V3_R1 @BASEBOARD_FAB2_LIB.BASEBOARD_FAB2(SCH_1):PWRGD_P3V3_R1
 R1L16    1      A RES_0402-49.9,1%,1/16W,CHIP,G2A    I68 @BASEBOARD_FAB2_LIB.BASEBOARD_FAB2(SCH_1):PAGE196
  U1L3    2 RESET_N ADM809_SMLF-IC,D23047-001-GND=A    I80 @BASEBOARD_FAB2_LIB.BASEBOARD_FAB2(SCH_1):PAGE196

PWRGD_P3V3_STBY @BASEBOARD_FAB2_LIB.BASEBOARD_FAB2(SCH_1):PWRGD_P3V3_STBY
 EU8F2   40 VTTPWR_GD_PD_N ICS9FGP204_MLFP-IC,E95226-001    I34 @BASEBOARD_FAB2_LIB.BASEBOARD_FAB2(SCH_1):PAGE101
  J7G2    5    IO5 CONN8_C77962004_PIP-CONN,C7796A    I47 @BASEBOARD_FAB2_LIB.BASEBOARD_FAB2(SCH_1):PAGE189
  U8D7  L12  PR10D LCMXO2_A_256BGA-IC,H63395-001    I59 @BASEBOARD_FAB2_LIB.BASEBOARD_FAB2(SCH_1):PAGE191
  U7D3    1   ENIN ADM1085_SMT-IC,H46130-001    I70 @BASEBOARD_FAB2_LIB.BASEBOARD_FAB2(SCH_1):PAGE196
 R3P50    2      B RES_0402-10.0K,1%,1/16W,EMPTY,A    I71 @BASEBOARD_FAB2_LIB.BASEBOARD_FAB2(SCH_1):PAGE196
 CR7E1    1      C DIODE_SMLF-BAT54WS,IC,C73510-0A   I103 @BASEBOARD_FAB2_LIB.BASEBOARD_FAB2(SCH_1):PAGE196
 C8A10    1      A CAP_0402LF-1000PF,50V,10%,EMPTA    I55 @BASEBOARD_FAB2_LIB.BASEBOARD_FAB2(SCH_1):PAGE237
 EU8A2    6     EN RT9059_DFN-IC,H65765-001    I86 @BASEBOARD_FAB2_LIB.BASEBOARD_FAB2(SCH_1):PAGE237
 R8F10    2      B RES_0402-22.1,1.0%,1/16W,CHIP,A   I171 @BASEBOARD_FAB2_LIB.BASEBOARD_FAB2(SCH_1):PAGE240
EU25F2    6     EN RT9059_DFN-IC,H65765-001    I73 @BASEBOARD_FAB2_LIB.BASEBOARD_FAB2(SCH_1):PAGE239
  C9W6    1      A CAP_0402LF-1000PF,50V,10%,EMPTA    I91 @BASEBOARD_FAB2_LIB.BASEBOARD_FAB2(SCH_1):PAGE239

PWRGD_P3V3_STBY_R @BASEBOARD_FAB2_LIB.BASEBOARD_FAB2(SCH_1):PWRGD_P3V3_STBY_R
  C8F2    1      A CAP_0402LF-1000PF,50V,10%,X7R,A   I116 @BASEBOARD_FAB2_LIB.BASEBOARD_FAB2(SCH_1):PAGE240
  R8F5    2      B RES_0402-1.00K,1%,1/16W,CHIP,GA   I117 @BASEBOARD_FAB2_LIB.BASEBOARD_FAB2(SCH_1):PAGE240
 EU8F1    9  PGOOD RT8240_QFN-IC,H66262-001   I125 @BASEBOARD_FAB2_LIB.BASEBOARD_FAB2(SCH_1):PAGE240
 R8F10    1      A RES_0402-22.1,1.0%,1/16W,CHIP,A   I171 @BASEBOARD_FAB2_LIB.BASEBOARD_FAB2(SCH_1):PAGE240

PWRGD_P5V @BASEBOARD_FAB2_LIB.BASEBOARD_FAB2(SCH_1):PWRGD_P5V
  U8D7   J6   PL6D LCMXO2_A_256BGA-IC,H63395-001   I179 @BASEBOARD_FAB2_LIB.BASEBOARD_FAB2(SCH_1):PAGE190
 R2P20    2      B RES_0402-100.0,1%,1/16W,CHIP,GA    I65 @BASEBOARD_FAB2_LIB.BASEBOARD_FAB2(SCH_1):PAGE196

PWRGD_P5V_N @BASEBOARD_FAB2_LIB.BASEBOARD_FAB2(SCH_1):PWRGD_P5V_N
  U8D8    1   OUTB TPS3700_SM-IC,H69492-001   I104 @BASEBOARD_FAB2_LIB.BASEBOARD_FAB2(SCH_1):PAGE196
 R2P18    2      B RES_0402-10.0K,1%,1/16W,CHIP,GA   I121 @BASEBOARD_FAB2_LIB.BASEBOARD_FAB2(SCH_1):PAGE196
  Q1P2    1   GATE FET_N_SOT23LF-2N7002,FET,C7925A   I129 @BASEBOARD_FAB2_LIB.BASEBOARD_FAB2(SCH_1):PAGE196

PWRGD_P5V_R @BASEBOARD_FAB2_LIB.BASEBOARD_FAB2(SCH_1):PWRGD_P5V_R
 R2P20    1      A RES_0402-100.0,1%,1/16W,CHIP,GA    I65 @BASEBOARD_FAB2_LIB.BASEBOARD_FAB2(SCH_1):PAGE196
 R2P21    2      B RES_0402-10.0K,1%,1/16W,CHIP,GA   I122 @BASEBOARD_FAB2_LIB.BASEBOARD_FAB2(SCH_1):PAGE196
  Q1P2    3    DRN FET_N_SOT23LF-2N7002,FET,C7925A   I129 @BASEBOARD_FAB2_LIB.BASEBOARD_FAB2(SCH_1):PAGE196

PWRGD_P5V_STBY @BASEBOARD_FAB2_LIB.BASEBOARD_FAB2(SCH_1):PWRGD_P5V_STBY
  R8F1    1      A RES_0402-10.0K,1%,1/16W,EMPTY,A   I111 @BASEBOARD_FAB2_LIB.BASEBOARD_FAB2(SCH_1):PAGE240
 C8E17    1      A CAP_0402LF-1000PF,50V,10%,EMPTA   I113 @BASEBOARD_FAB2_LIB.BASEBOARD_FAB2(SCH_1):PAGE240
  R8F2    1      A RES_0402-0.0,5%,1/16W,CHIP,G21A   I176 @BASEBOARD_FAB2_LIB.BASEBOARD_FAB2(SCH_1):PAGE240
 R7E15    2      B RES_0402-22.1,1.0%,1/16W,CHIP,A    I89 @BASEBOARD_FAB2_LIB.BASEBOARD_FAB2(SCH_1):PAGE241

PWRGD_P5V_STBY_R @BASEBOARD_FAB2_LIB.BASEBOARD_FAB2(SCH_1):PWRGD_P5V_STBY_R
 R7E12    2      B RES_0402-1.00K,1%,1/16W,CHIP,GA    I11 @BASEBOARD_FAB2_LIB.BASEBOARD_FAB2(SCH_1):PAGE241
 C7E10    1      A CAP_0402LF-1000PF,50V,10%,X7R,A    I14 @BASEBOARD_FAB2_LIB.BASEBOARD_FAB2(SCH_1):PAGE241
 EU7E2   14  PWRGD TPS54821_LCC-IC,H63269-001    I83 @BASEBOARD_FAB2_LIB.BASEBOARD_FAB2(SCH_1):PAGE241
 R7E15    1      A RES_0402-22.1,1.0%,1/16W,CHIP,A    I89 @BASEBOARD_FAB2_LIB.BASEBOARD_FAB2(SCH_1):PAGE241

PWRGD_PCH_PWROK @BASEBOARD_FAB2_LIB.BASEBOARD_FAB2(SCH_1):PWRGD_PCH_PWROK
  U7C1  R17 PCH_PWROK LBG_CORE_QAT_EXT_D_BGA1-IC,H91A    I73 @BASEBOARD_FAB2_LIB.BASEBOARD_FAB2(SCH_1):PAGE118
  R3N3    2      B RES_0402-2.0K,1%,1/16W,CHIP,G2A   I120 @BASEBOARD_FAB2_LIB.BASEBOARD_FAB2(SCH_1):PAGE133
  U8D7  C16   PR2C LCMXO2_A_256BGA-IC,H63395-001    I59 @BASEBOARD_FAB2_LIB.BASEBOARD_FAB2(SCH_1):PAGE191
 U25W4  K19 GPIOB0 AST2520A1-GP-GP_ASIC2-GB1-AST2A    I95 @BASEBOARD_FAB2_LIB.BASEBOARD_FAB2(SCH_1):PAGE144

PWRGD_PVCCIN_CPU0 @BASEBOARD_FAB2_LIB.BASEBOARD_FAB2(SCH_1):PWRGD_PVCCIN_CPU0
  U1L1   13  OE<0> TTL3126_QFNLF-74CBTLV3126,IC,DB   I108 @BASEBOARD_FAB2_LIB.BASEBOARD_FAB2(SCH_1):PAGE112
  U1L1   10  OE<1> TTL3126_QFNLF-74CBTLV3126,IC,DB   I108 @BASEBOARD_FAB2_LIB.BASEBOARD_FAB2(SCH_1):PAGE112
  U1L1    4  OE<2> TTL3126_QFNLF-74CBTLV3126,IC,DB   I108 @BASEBOARD_FAB2_LIB.BASEBOARD_FAB2(SCH_1):PAGE112
  U1L1    1  OE<3> TTL3126_QFNLF-74CBTLV3126,IC,DB   I108 @BASEBOARD_FAB2_LIB.BASEBOARD_FAB2(SCH_1):PAGE112
  U1L5   13  OE<0> TTL3126_QFNLF-74CBTLV3126,IC,DB   I109 @BASEBOARD_FAB2_LIB.BASEBOARD_FAB2(SCH_1):PAGE112
  U1L5   10  OE<1> TTL3126_QFNLF-74CBTLV3126,IC,DB   I109 @BASEBOARD_FAB2_LIB.BASEBOARD_FAB2(SCH_1):PAGE112
  U1L5    4  OE<2> TTL3126_QFNLF-74CBTLV3126,IC,DB   I109 @BASEBOARD_FAB2_LIB.BASEBOARD_FAB2(SCH_1):PAGE112
  U1L5    1  OE<3> TTL3126_QFNLF-74CBTLV3126,IC,DB   I109 @BASEBOARD_FAB2_LIB.BASEBOARD_FAB2(SCH_1):PAGE112
  U8D7   K5  PL12C LCMXO2_A_256BGA-IC,H63395-001   I179 @BASEBOARD_FAB2_LIB.BASEBOARD_FAB2(SCH_1):PAGE190
 R4D63    2      B RES_0402-22.1,1.0%,1/16W,CHIP,A   I124 @BASEBOARD_FAB2_LIB.BASEBOARD_FAB2(SCH_1):PAGE201

PWRGD_PVCCIN_CPU1 @BASEBOARD_FAB2_LIB.BASEBOARD_FAB2(SCH_1):PWRGD_PVCCIN_CPU1
  U8D7   N1  PL13B LCMXO2_A_256BGA-IC,H63395-001   I179 @BASEBOARD_FAB2_LIB.BASEBOARD_FAB2(SCH_1):PAGE190
 R1C30    2      B RES_0402-22.1,1.0%,1/16W,CHIP,A   I113 @BASEBOARD_FAB2_LIB.BASEBOARD_FAB2(SCH_1):PAGE206

PWRGD_PVCCIOMCP_CPU0 @BASEBOARD_FAB2_LIB.BASEBOARD_FAB2(SCH_1):PWRGD_PVCCIOMCP_CPU0
  U8D7   N6   PB8C LCMXO2_A_256BGA-IC,H63395-001   I179 @BASEBOARD_FAB2_LIB.BASEBOARD_FAB2(SCH_1):PAGE190
  J6B1  B16  IOB16 SCONN120_H61426002_SM-CONN,H61A    I56 @BASEBOARD_FAB2_LIB.BASEBOARD_FAB2(SCH_1):PAGE194

PWRGD_PVCCIOMCP_CPU1 @BASEBOARD_FAB2_LIB.BASEBOARD_FAB2(SCH_1):PWRGD_PVCCIOMCP_CPU1
  U8D7   T5   PB6A LCMXO2_A_256BGA-IC,H63395-001   I179 @BASEBOARD_FAB2_LIB.BASEBOARD_FAB2(SCH_1):PAGE190
  J4B2  B16  IOB16 SCONN120_H61426002_SM-CONN,H61A    I46 @BASEBOARD_FAB2_LIB.BASEBOARD_FAB2(SCH_1):PAGE193

PWRGD_PVCCIO_CPU0 @BASEBOARD_FAB2_LIB.BASEBOARD_FAB2(SCH_1):PWRGD_PVCCIO_CPU0
  U7D1    1   OE_N 74CBTLV1G125_SMLF-IC,C88177-00A   I142 @BASEBOARD_FAB2_LIB.BASEBOARD_FAB2(SCH_1):PAGE118
  U8D7   L8  PB11D LCMXO2_A_256BGA-IC,H63395-001   I179 @BASEBOARD_FAB2_LIB.BASEBOARD_FAB2(SCH_1):PAGE190
 R3P20    2      B RES_0402-22.1,1.0%,1/16W,CHIP,A    I58 @BASEBOARD_FAB2_LIB.BASEBOARD_FAB2(SCH_1):PAGE211

PWRGD_PVCCIO_CPU0_R @BASEBOARD_FAB2_LIB.BASEBOARD_FAB2(SCH_1):PWRGD_PVCCIO_CPU0_R
 R3P25    2      B RES_0402-1.00K,1%,1/16W,CHIP,GA    I56 @BASEBOARD_FAB2_LIB.BASEBOARD_FAB2(SCH_1):PAGE211
 R3P20    1      A RES_0402-22.1,1.0%,1/16W,CHIP,A    I58 @BASEBOARD_FAB2_LIB.BASEBOARD_FAB2(SCH_1):PAGE211
  C3P6    1      A CAP_0402LF-1000PF,50V,10%,X7R,A    I71 @BASEBOARD_FAB2_LIB.BASEBOARD_FAB2(SCH_1):PAGE211
 EU3P1    9 AVRRDY PXE1110B_QFN-IC,H89187-001    I93 @BASEBOARD_FAB2_LIB.BASEBOARD_FAB2(SCH_1):PAGE211

PWRGD_PVCCIO_CPU1 @BASEBOARD_FAB2_LIB.BASEBOARD_FAB2(SCH_1):PWRGD_PVCCIO_CPU1
  U8D7  L16  PR11A LCMXO2_A_256BGA-IC,H63395-001    I59 @BASEBOARD_FAB2_LIB.BASEBOARD_FAB2(SCH_1):PAGE191
 R4D46    2      B RES_0402-22.1,1.0%,1/16W,CHIP,A    I13 @BASEBOARD_FAB2_LIB.BASEBOARD_FAB2(SCH_1):PAGE213

PWRGD_PVCCIO_CPU1_R @BASEBOARD_FAB2_LIB.BASEBOARD_FAB2(SCH_1):PWRGD_PVCCIO_CPU1_R
 R4D46    1      A RES_0402-22.1,1.0%,1/16W,CHIP,A    I13 @BASEBOARD_FAB2_LIB.BASEBOARD_FAB2(SCH_1):PAGE213
 R4D42    2      B RES_0402-1.00K,1%,1/16W,CHIP,GA    I15 @BASEBOARD_FAB2_LIB.BASEBOARD_FAB2(SCH_1):PAGE213
 C4D33    1      A CAP_0402LF-1000PF,50V,10%,X7R,A    I73 @BASEBOARD_FAB2_LIB.BASEBOARD_FAB2(SCH_1):PAGE213
 EU4D5    9 AVRRDY PXE1110B_QFN-IC,H89187-001    I96 @BASEBOARD_FAB2_LIB.BASEBOARD_FAB2(SCH_1):PAGE213

PWRGD_PVCCMCP_CPU0 @BASEBOARD_FAB2_LIB.BASEBOARD_FAB2(SCH_1):PWRGD_PVCCMCP_CPU0
  U8D7   P5   PB5B LCMXO2_A_256BGA-IC,H63395-001   I179 @BASEBOARD_FAB2_LIB.BASEBOARD_FAB2(SCH_1):PAGE190
  J6B1  D20  IOD20 SCONN120_H61426002_SM-CONN,H61A    I56 @BASEBOARD_FAB2_LIB.BASEBOARD_FAB2(SCH_1):PAGE194

PWRGD_PVCCMCP_CPU1 @BASEBOARD_FAB2_LIB.BASEBOARD_FAB2(SCH_1):PWRGD_PVCCMCP_CPU1
  U8D7   L4  PL12D LCMXO2_A_256BGA-IC,H63395-001   I179 @BASEBOARD_FAB2_LIB.BASEBOARD_FAB2(SCH_1):PAGE190
  J4B2  D20  IOD20 SCONN120_H61426002_SM-CONN,H61A    I46 @BASEBOARD_FAB2_LIB.BASEBOARD_FAB2(SCH_1):PAGE193

PWRGD_PVDDQ_ABC @BASEBOARD_FAB2_LIB.BASEBOARD_FAB2(SCH_1):PWRGD_PVDDQ_ABC
R12W26    2      B RES_0402-0.0,5%,1/16W,EMPTY,G2A    I45 @BASEBOARD_FAB2_LIB.BASEBOARD_FAB2(SCH_1):PAGE215
R12W27    2      B RES_0402-0.0,5%,1/16W,EMPTY,G2A    I54 @BASEBOARD_FAB2_LIB.BASEBOARD_FAB2(SCH_1):PAGE215
 R7F24    2      B RES_0402-22.1,1.0%,1/16W,CHIP,A    I56 @BASEBOARD_FAB2_LIB.BASEBOARD_FAB2(SCH_1):PAGE215
 Q12W1    1 GATE#1 BSL308C-H6327-GP_DISCRET-GB1-BA    I43 @BASEBOARD_FAB2_LIB.BASEBOARD_FAB2(SCH_1):PAGE197
R12W25    2      B RES_0402-0.0,5%,1/16W,CHIP,G21A    I74 @BASEBOARD_FAB2_LIB.BASEBOARD_FAB2(SCH_1):PAGE215
 R7F36    2      B RES_0402-2.26K,1.0%,1/16W,CHIPA    I75 @BASEBOARD_FAB2_LIB.BASEBOARD_FAB2(SCH_1):PAGE215

PWRGD_PVDDQ_ABC_N @BASEBOARD_FAB2_LIB.BASEBOARD_FAB2(SCH_1):PWRGD_PVDDQ_ABC_N
 Q12W1    6 DRAIN#6 BSL308C-H6327-GP_DISCRET-GB1-BA    I43 @BASEBOARD_FAB2_LIB.BASEBOARD_FAB2(SCH_1):PAGE197
 Q12W1    3 GATE#3 BSL308C-H6327-GP_DISCRET-GB1-BA    I43 @BASEBOARD_FAB2_LIB.BASEBOARD_FAB2(SCH_1):PAGE197
 R12W4    2      B RES_0603-100.0K,1%,1/10W,CHIP,A    I45 @BASEBOARD_FAB2_LIB.BASEBOARD_FAB2(SCH_1):PAGE197

PWRGD_PVDDQ_ABC_R @BASEBOARD_FAB2_LIB.BASEBOARD_FAB2(SCH_1):PWRGD_PVDDQ_ABC_R
 C7F14    1      A CAP_0402LF-1000PF,50V,10%,X7R,A    I44 @BASEBOARD_FAB2_LIB.BASEBOARD_FAB2(SCH_1):PAGE215
 R7F22    2      B RES_0402-1.00K,1%,1/16W,CHIP,GA    I51 @BASEBOARD_FAB2_LIB.BASEBOARD_FAB2(SCH_1):PAGE215
 R7F24    1      A RES_0402-22.1,1.0%,1/16W,CHIP,A    I56 @BASEBOARD_FAB2_LIB.BASEBOARD_FAB2(SCH_1):PAGE215
 EU7G1    9 AVRRDY PXM1310B_QFN-IC,H89186-001    I69 @BASEBOARD_FAB2_LIB.BASEBOARD_FAB2(SCH_1):PAGE215
 R4G23    1      A RES_0402-0.0,5%,1/16W,CHIP,G21A     I4 @BASEBOARD_FAB2_LIB.BASEBOARD_FAB2(SCH_1):PAGE221

PWRGD_PVDDQ_DEF @BASEBOARD_FAB2_LIB.BASEBOARD_FAB2(SCH_1):PWRGD_PVDDQ_DEF
  R3M3    2      B RES_0402-22.1,1.0%,1/16W,CHIP,A    I60 @BASEBOARD_FAB2_LIB.BASEBOARD_FAB2(SCH_1):PAGE218
R12W29    2      B RES_0402-0.0,5%,1/16W,EMPTY,G2A    I46 @BASEBOARD_FAB2_LIB.BASEBOARD_FAB2(SCH_1):PAGE218
R12W30    2      B RES_0402-0.0,5%,1/16W,EMPTY,G2A    I55 @BASEBOARD_FAB2_LIB.BASEBOARD_FAB2(SCH_1):PAGE218
 Q12W2    1 GATE#1 BSL308C-H6327-GP_DISCRET-GB1-BA    I19 @BASEBOARD_FAB2_LIB.BASEBOARD_FAB2(SCH_1):PAGE197
R12W28    2      B RES_0402-0.0,5%,1/16W,CHIP,G21A    I75 @BASEBOARD_FAB2_LIB.BASEBOARD_FAB2(SCH_1):PAGE218
  R7A9    2      B RES_0402-2.26K,1.0%,1/16W,CHIPA    I76 @BASEBOARD_FAB2_LIB.BASEBOARD_FAB2(SCH_1):PAGE218

PWRGD_PVDDQ_DEF_N @BASEBOARD_FAB2_LIB.BASEBOARD_FAB2(SCH_1):PWRGD_PVDDQ_DEF_N
 Q12W2    6 DRAIN#6 BSL308C-H6327-GP_DISCRET-GB1-BA    I19 @BASEBOARD_FAB2_LIB.BASEBOARD_FAB2(SCH_1):PAGE197
 Q12W2    3 GATE#3 BSL308C-H6327-GP_DISCRET-GB1-BA    I19 @BASEBOARD_FAB2_LIB.BASEBOARD_FAB2(SCH_1):PAGE197
 R12W9    2      B RES_0603-100.0K,1%,1/10W,CHIP,A    I21 @BASEBOARD_FAB2_LIB.BASEBOARD_FAB2(SCH_1):PAGE197

PWRGD_PVDDQ_DEF_R @BASEBOARD_FAB2_LIB.BASEBOARD_FAB2(SCH_1):PWRGD_PVDDQ_DEF_R
  R3M3    1      A RES_0402-22.1,1.0%,1/16W,CHIP,A    I60 @BASEBOARD_FAB2_LIB.BASEBOARD_FAB2(SCH_1):PAGE218
  C7B3    1      A CAP_0402LF-1000PF,50V,10%,X7R,A    I41 @BASEBOARD_FAB2_LIB.BASEBOARD_FAB2(SCH_1):PAGE218
  R7B5    2      B RES_0402-1.00K,1%,1/16W,CHIP,GA    I58 @BASEBOARD_FAB2_LIB.BASEBOARD_FAB2(SCH_1):PAGE218
 EU7A5    9 AVRRDY PXM1310B_QFN-IC,H89186-001    I69 @BASEBOARD_FAB2_LIB.BASEBOARD_FAB2(SCH_1):PAGE218
  R4A2    1      A RES_0402-0.0,5%,1/16W,CHIP,G21A     I4 @BASEBOARD_FAB2_LIB.BASEBOARD_FAB2(SCH_1):PAGE222

PWRGD_PVDDQ_GHJ @BASEBOARD_FAB2_LIB.BASEBOARD_FAB2(SCH_1):PWRGD_PVDDQ_GHJ
R12W33    2      B RES_0402-0.0,5%,1/16W,EMPTY,G2A    I53 @BASEBOARD_FAB2_LIB.BASEBOARD_FAB2(SCH_1):PAGE223
R12W32    2      B RES_0402-0.0,5%,1/16W,EMPTY,G2A    I45 @BASEBOARD_FAB2_LIB.BASEBOARD_FAB2(SCH_1):PAGE223
 R1G12    2      B RES_0402-22.1,1.0%,1/16W,CHIP,A    I54 @BASEBOARD_FAB2_LIB.BASEBOARD_FAB2(SCH_1):PAGE223
 Q12W3    1 GATE#1 BSL308C-H6327-GP_DISCRET-GB1-BA    I91 @BASEBOARD_FAB2_LIB.BASEBOARD_FAB2(SCH_1):PAGE197
R12W31    2      B RES_0402-0.0,5%,1/16W,CHIP,G21A    I75 @BASEBOARD_FAB2_LIB.BASEBOARD_FAB2(SCH_1):PAGE223
  R1G6    2      B RES_0402-2.26K,1.0%,1/16W,CHIPA    I76 @BASEBOARD_FAB2_LIB.BASEBOARD_FAB2(SCH_1):PAGE223

PWRGD_PVDDQ_GHJ_N @BASEBOARD_FAB2_LIB.BASEBOARD_FAB2(SCH_1):PWRGD_PVDDQ_GHJ_N
R12W14    2      B RES_0603-100.0K,1%,1/10W,CHIP,A    I53 @BASEBOARD_FAB2_LIB.BASEBOARD_FAB2(SCH_1):PAGE197
 Q12W3    6 DRAIN#6 BSL308C-H6327-GP_DISCRET-GB1-BA    I91 @BASEBOARD_FAB2_LIB.BASEBOARD_FAB2(SCH_1):PAGE197
 Q12W3    3 GATE#3 BSL308C-H6327-GP_DISCRET-GB1-BA    I91 @BASEBOARD_FAB2_LIB.BASEBOARD_FAB2(SCH_1):PAGE197

PWRGD_PVDDQ_GHJ_R @BASEBOARD_FAB2_LIB.BASEBOARD_FAB2(SCH_1):PWRGD_PVDDQ_GHJ_R
 C1G21    1      A CAP_0402LF-1000PF,50V,10%,X7R,A    I40 @BASEBOARD_FAB2_LIB.BASEBOARD_FAB2(SCH_1):PAGE223
 R1G16    2      B RES_0402-1.00K,1%,1/16W,CHIP,GA    I48 @BASEBOARD_FAB2_LIB.BASEBOARD_FAB2(SCH_1):PAGE223
 R1G12    1      A RES_0402-22.1,1.0%,1/16W,CHIP,A    I54 @BASEBOARD_FAB2_LIB.BASEBOARD_FAB2(SCH_1):PAGE223
 EU1G2    9 AVRRDY PXM1310B_QFN-IC,H89186-001    I69 @BASEBOARD_FAB2_LIB.BASEBOARD_FAB2(SCH_1):PAGE223
 R4G16    1      A RES_0402-0.0,5%,1/16W,CHIP,G21A     I4 @BASEBOARD_FAB2_LIB.BASEBOARD_FAB2(SCH_1):PAGE229

PWRGD_PVDDQ_KLM @BASEBOARD_FAB2_LIB.BASEBOARD_FAB2(SCH_1):PWRGD_PVDDQ_KLM
R12W36    2      B RES_0402-0.0,5%,1/16W,EMPTY,G2A    I53 @BASEBOARD_FAB2_LIB.BASEBOARD_FAB2(SCH_1):PAGE226
R12W35    2      B RES_0402-0.0,5%,1/16W,EMPTY,G2A    I46 @BASEBOARD_FAB2_LIB.BASEBOARD_FAB2(SCH_1):PAGE226
  R1B5    2      B RES_0402-22.1,1.0%,1/16W,CHIP,A    I55 @BASEBOARD_FAB2_LIB.BASEBOARD_FAB2(SCH_1):PAGE226
 Q12W4    1 GATE#1 BSL308C-H6327-GP_DISCRET-GB1-BA    I35 @BASEBOARD_FAB2_LIB.BASEBOARD_FAB2(SCH_1):PAGE197
R12W34    2      B RES_0402-0.0,5%,1/16W,CHIP,G21A    I74 @BASEBOARD_FAB2_LIB.BASEBOARD_FAB2(SCH_1):PAGE226
 R1B13    2      B RES_0402-2.26K,1.0%,1/16W,CHIPA    I75 @BASEBOARD_FAB2_LIB.BASEBOARD_FAB2(SCH_1):PAGE226

PWRGD_PVDDQ_KLM_N @BASEBOARD_FAB2_LIB.BASEBOARD_FAB2(SCH_1):PWRGD_PVDDQ_KLM_N
 Q12W4    6 DRAIN#6 BSL308C-H6327-GP_DISCRET-GB1-BA    I35 @BASEBOARD_FAB2_LIB.BASEBOARD_FAB2(SCH_1):PAGE197
 Q12W4    3 GATE#3 BSL308C-H6327-GP_DISCRET-GB1-BA    I35 @BASEBOARD_FAB2_LIB.BASEBOARD_FAB2(SCH_1):PAGE197
R12W19    2      B RES_0603-100.0K,1%,1/10W,CHIP,A    I37 @BASEBOARD_FAB2_LIB.BASEBOARD_FAB2(SCH_1):PAGE197

PWRGD_PVDDQ_KLM_R @BASEBOARD_FAB2_LIB.BASEBOARD_FAB2(SCH_1):PWRGD_PVDDQ_KLM_R
  R1B2    2      B RES_0402-1.00K,1%,1/16W,CHIP,GA    I50 @BASEBOARD_FAB2_LIB.BASEBOARD_FAB2(SCH_1):PAGE226
  C1B4    1      A CAP_0402LF-1000PF,50V,10%,X7R,A    I40 @BASEBOARD_FAB2_LIB.BASEBOARD_FAB2(SCH_1):PAGE226
  R1B5    1      A RES_0402-22.1,1.0%,1/16W,CHIP,A    I55 @BASEBOARD_FAB2_LIB.BASEBOARD_FAB2(SCH_1):PAGE226
 EU1B1    9 AVRRDY PXM1310B_QFN-IC,H89186-001    I69 @BASEBOARD_FAB2_LIB.BASEBOARD_FAB2(SCH_1):PAGE226
  R4A3    1      A RES_0402-0.0,5%,1/16W,CHIP,G21A     I4 @BASEBOARD_FAB2_LIB.BASEBOARD_FAB2(SCH_1):PAGE230

PWRGD_PVNN_P1V05_PCH @BASEBOARD_FAB2_LIB.BASEBOARD_FAB2(SCH_1):PWRGD_PVNN_P1V05_PCH
  U8D7   P8  PB12A LCMXO2_A_256BGA-IC,H63395-001   I179 @BASEBOARD_FAB2_LIB.BASEBOARD_FAB2(SCH_1):PAGE190
 R2L16    2      B RES_0402-22.1,1.0%,1/16W,CHIP,A   I147 @BASEBOARD_FAB2_LIB.BASEBOARD_FAB2(SCH_1):PAGE235

PWRGD_PVNN_PCH_R @BASEBOARD_FAB2_LIB.BASEBOARD_FAB2(SCH_1):PWRGD_PVNN_PCH_R
 R2L16    1      A RES_0402-22.1,1.0%,1/16W,CHIP,A   I147 @BASEBOARD_FAB2_LIB.BASEBOARD_FAB2(SCH_1):PAGE235
  R8A6    2      B RES_0402-1.00K,1%,1/16W,CHIP,GA   I149 @BASEBOARD_FAB2_LIB.BASEBOARD_FAB2(SCH_1):PAGE235
  C8A9    1      A CAP_0402LF-1000PF,50V,10%,X7R,A   I218 @BASEBOARD_FAB2_LIB.BASEBOARD_FAB2(SCH_1):PAGE235
 EU8A1    9 AVRRDY PXE1110B_QFN-IC,H89187-001   I229 @BASEBOARD_FAB2_LIB.BASEBOARD_FAB2(SCH_1):PAGE235

PWRGD_PVPP_ABC @BASEBOARD_FAB2_LIB.BASEBOARD_FAB2(SCH_1):PWRGD_PVPP_ABC
  J8B1   19   IO19 SCONN24_H46321001_SM-SCONN,H46A     I1 @BASEBOARD_FAB2_LIB.BASEBOARD_FAB2(SCH_1):PAGE91
  U8D7   N7   PB9D LCMXO2_A_256BGA-IC,H63395-001   I179 @BASEBOARD_FAB2_LIB.BASEBOARD_FAB2(SCH_1):PAGE190
 R7F16    2      B RES_0402-22.1,1.0%,1/16W,CHIP,A   I208 @BASEBOARD_FAB2_LIB.BASEBOARD_FAB2(SCH_1):PAGE231

PWRGD_PVPP_ABC_R @BASEBOARD_FAB2_LIB.BASEBOARD_FAB2(SCH_1):PWRGD_PVPP_ABC_R
 C7F11    1      A CAP_0402LF-1000PF,50V,10%,X7R,A   I142 @BASEBOARD_FAB2_LIB.BASEBOARD_FAB2(SCH_1):PAGE231
 R7F19    2      B RES_0402-1.00K,1%,1/16W,CHIP,GA   I143 @BASEBOARD_FAB2_LIB.BASEBOARD_FAB2(SCH_1):PAGE231
 EU7F1    7     PG NCP3232L_SM-IC,H86355-001   I193 @BASEBOARD_FAB2_LIB.BASEBOARD_FAB2(SCH_1):PAGE231
 R7F16    1      A RES_0402-22.1,1.0%,1/16W,CHIP,A   I208 @BASEBOARD_FAB2_LIB.BASEBOARD_FAB2(SCH_1):PAGE231

PWRGD_PVPP_DEF @BASEBOARD_FAB2_LIB.BASEBOARD_FAB2(SCH_1):PWRGD_PVPP_DEF
  U8D7   M6  PB11C LCMXO2_A_256BGA-IC,H63395-001   I179 @BASEBOARD_FAB2_LIB.BASEBOARD_FAB2(SCH_1):PAGE190
 R7B12    2      B RES_0402-22.1,1.0%,1/16W,CHIP,A   I257 @BASEBOARD_FAB2_LIB.BASEBOARD_FAB2(SCH_1):PAGE232

PWRGD_PVPP_DEF_R @BASEBOARD_FAB2_LIB.BASEBOARD_FAB2(SCH_1):PWRGD_PVPP_DEF_R
 C7B12    1      A CAP_0402LF-1000PF,50V,10%,X7R,A   I209 @BASEBOARD_FAB2_LIB.BASEBOARD_FAB2(SCH_1):PAGE232
 R7B17    2      B RES_0402-1.00K,1%,1/16W,CHIP,GA   I210 @BASEBOARD_FAB2_LIB.BASEBOARD_FAB2(SCH_1):PAGE232
 EU7B1    7     PG NCP3232L_SM-IC,H86355-001   I214 @BASEBOARD_FAB2_LIB.BASEBOARD_FAB2(SCH_1):PAGE232
 R7B12    1      A RES_0402-22.1,1.0%,1/16W,CHIP,A   I257 @BASEBOARD_FAB2_LIB.BASEBOARD_FAB2(SCH_1):PAGE232

PWRGD_PVPP_GHJ @BASEBOARD_FAB2_LIB.BASEBOARD_FAB2(SCH_1):PWRGD_PVPP_GHJ
  U8D7   M2  PL14A LCMXO2_A_256BGA-IC,H63395-001   I179 @BASEBOARD_FAB2_LIB.BASEBOARD_FAB2(SCH_1):PAGE190
 R4G12    2      B RES_0402-22.1,1.0%,1/16W,CHIP,A   I247 @BASEBOARD_FAB2_LIB.BASEBOARD_FAB2(SCH_1):PAGE233

PWRGD_PVPP_GHJ_R @BASEBOARD_FAB2_LIB.BASEBOARD_FAB2(SCH_1):PWRGD_PVPP_GHJ_R
 R4G14    2      B RES_0402-1.00K,1%,1/16W,CHIP,GA   I185 @BASEBOARD_FAB2_LIB.BASEBOARD_FAB2(SCH_1):PAGE233
  C4G9    1      A CAP_0402LF-1000PF,50V,10%,X7R,A   I201 @BASEBOARD_FAB2_LIB.BASEBOARD_FAB2(SCH_1):PAGE233
 EU4G1    7     PG NCP3232L_SM-IC,H86355-001   I225 @BASEBOARD_FAB2_LIB.BASEBOARD_FAB2(SCH_1):PAGE233
 R4G12    1      A RES_0402-22.1,1.0%,1/16W,CHIP,A   I247 @BASEBOARD_FAB2_LIB.BASEBOARD_FAB2(SCH_1):PAGE233

PWRGD_PVPP_KLM @BASEBOARD_FAB2_LIB.BASEBOARD_FAB2(SCH_1):PWRGD_PVPP_KLM
  U8D7   N2  PL13C LCMXO2_A_256BGA-IC,H63395-001   I179 @BASEBOARD_FAB2_LIB.BASEBOARD_FAB2(SCH_1):PAGE190
  R4B7    2      B RES_0402-22.1,1.0%,1/16W,CHIP,A   I201 @BASEBOARD_FAB2_LIB.BASEBOARD_FAB2(SCH_1):PAGE234

PWRGD_PVPP_KLM_R @BASEBOARD_FAB2_LIB.BASEBOARD_FAB2(SCH_1):PWRGD_PVPP_KLM_R
  C4B8    1      A CAP_0402LF-1000PF,50V,10%,X7R,A   I139 @BASEBOARD_FAB2_LIB.BASEBOARD_FAB2(SCH_1):PAGE234
 R4B10    2      B RES_0402-1.00K,1%,1/16W,CHIP,GA   I143 @BASEBOARD_FAB2_LIB.BASEBOARD_FAB2(SCH_1):PAGE234
 EU4A3    7     PG NCP3232L_SM-IC,H86355-001   I184 @BASEBOARD_FAB2_LIB.BASEBOARD_FAB2(SCH_1):PAGE234
  R4B7    1      A RES_0402-22.1,1.0%,1/16W,CHIP,A   I201 @BASEBOARD_FAB2_LIB.BASEBOARD_FAB2(SCH_1):PAGE234

PWRGD_PVSA_CPU0 @BASEBOARD_FAB2_LIB.BASEBOARD_FAB2(SCH_1):PWRGD_PVSA_CPU0
  U8D7   L1  PL11A LCMXO2_A_256BGA-IC,H63395-001   I179 @BASEBOARD_FAB2_LIB.BASEBOARD_FAB2(SCH_1):PAGE190
 R4D65    2      B RES_0402-33.2,1%,1/16W,CHIP,G2A   I127 @BASEBOARD_FAB2_LIB.BASEBOARD_FAB2(SCH_1):PAGE201

PWRGD_PVSA_CPU0_R @BASEBOARD_FAB2_LIB.BASEBOARD_FAB2(SCH_1):PWRGD_PVSA_CPU0_R
  R4E5    2      B RES_0402-1.00K,1%,1/16W,CHIP,GA    I27 @BASEBOARD_FAB2_LIB.BASEBOARD_FAB2(SCH_1):PAGE201
 R4D65    1      A RES_0402-33.2,1%,1/16W,CHIP,G2A   I127 @BASEBOARD_FAB2_LIB.BASEBOARD_FAB2(SCH_1):PAGE201
 EU4D4   15    MP0 PXE1610B_QFN-IC,H79206-001   I155 @BASEBOARD_FAB2_LIB.BASEBOARD_FAB2(SCH_1):PAGE201

PWRGD_PVSA_CPU1 @BASEBOARD_FAB2_LIB.BASEBOARD_FAB2(SCH_1):PWRGD_PVSA_CPU1
  U8D7   T4   PB3B LCMXO2_A_256BGA-IC,H63395-001   I179 @BASEBOARD_FAB2_LIB.BASEBOARD_FAB2(SCH_1):PAGE190
  R1D1    2      B RES_0402-33.2,1%,1/16W,CHIP,G2A   I116 @BASEBOARD_FAB2_LIB.BASEBOARD_FAB2(SCH_1):PAGE206

PWRGD_PVSA_CPU1_R @BASEBOARD_FAB2_LIB.BASEBOARD_FAB2(SCH_1):PWRGD_PVSA_CPU1_R
  R1D8    2      B RES_0402-1.00K,1%,1/16W,CHIP,GA    I36 @BASEBOARD_FAB2_LIB.BASEBOARD_FAB2(SCH_1):PAGE206
  R1D1    1      A RES_0402-33.2,1%,1/16W,CHIP,G2A   I116 @BASEBOARD_FAB2_LIB.BASEBOARD_FAB2(SCH_1):PAGE206
 EU1C2   15    MP0 PXE1610B_QFN-IC,H79206-001   I130 @BASEBOARD_FAB2_LIB.BASEBOARD_FAB2(SCH_1):PAGE206

PWRGD_PVTT_ABC_CPU0_R @BASEBOARD_FAB2_LIB.BASEBOARD_FAB2(SCH_1):PWRGD_PVTT_ABC_CPU0_R
 R4G18    2      B RES_0402-10.0K,1%,1/16W,CHIP,GA    I25 @BASEBOARD_FAB2_LIB.BASEBOARD_FAB2(SCH_1):PAGE221
 C4G14    1      A CAP_0402LF-1000PF,50V,10%,X7R,A    I30 @BASEBOARD_FAB2_LIB.BASEBOARD_FAB2(SCH_1):PAGE221
 R4G19    1      A RES_0402-33.2,1%,1/16W,CHIP,G2A    I33 @BASEBOARD_FAB2_LIB.BASEBOARD_FAB2(SCH_1):PAGE221
 EU4G3    5     PG MIC5166_DFN-IC,H55101-001    I15 @BASEBOARD_FAB2_LIB.BASEBOARD_FAB2(SCH_1):PAGE221

PWRGD_PVTT_CPU0 @BASEBOARD_FAB2_LIB.BASEBOARD_FAB2(SCH_1):PWRGD_PVTT_CPU0
  U8D7   B4  PT11D LCMXO2_A_256BGA-IC,H63395-001    I59 @BASEBOARD_FAB2_LIB.BASEBOARD_FAB2(SCH_1):PAGE191
 R4G19    2      B RES_0402-33.2,1%,1/16W,CHIP,G2A    I33 @BASEBOARD_FAB2_LIB.BASEBOARD_FAB2(SCH_1):PAGE221
  R4A6    2      B RES_0402-33.2,1%,1/16W,CHIP,G2A    I31 @BASEBOARD_FAB2_LIB.BASEBOARD_FAB2(SCH_1):PAGE222

PWRGD_PVTT_CPU1 @BASEBOARD_FAB2_LIB.BASEBOARD_FAB2(SCH_1):PWRGD_PVTT_CPU1
  U8D7   R7   PB9A LCMXO2_A_256BGA-IC,H63395-001   I179 @BASEBOARD_FAB2_LIB.BASEBOARD_FAB2(SCH_1):PAGE190
 R4G15    2      B RES_0402-33.2,1%,1/16W,CHIP,G2A    I32 @BASEBOARD_FAB2_LIB.BASEBOARD_FAB2(SCH_1):PAGE229
  R4A4    2      B RES_0402-33.2,1%,1/16W,CHIP,G2A    I32 @BASEBOARD_FAB2_LIB.BASEBOARD_FAB2(SCH_1):PAGE230

PWRGD_PVTT_DEF_CPU0_R @BASEBOARD_FAB2_LIB.BASEBOARD_FAB2(SCH_1):PWRGD_PVTT_DEF_CPU0_R
 EU4A1    5     PG MIC5166_DFN-IC,H55101-001    I13 @BASEBOARD_FAB2_LIB.BASEBOARD_FAB2(SCH_1):PAGE222
 C4A12    1      A CAP_0402LF-1000PF,50V,10%,X7R,A    I22 @BASEBOARD_FAB2_LIB.BASEBOARD_FAB2(SCH_1):PAGE222
  R6L9    2      B RES_0402-10.0K,1%,1/16W,CHIP,GA    I23 @BASEBOARD_FAB2_LIB.BASEBOARD_FAB2(SCH_1):PAGE222
  R4A6    1      A RES_0402-33.2,1%,1/16W,CHIP,G2A    I31 @BASEBOARD_FAB2_LIB.BASEBOARD_FAB2(SCH_1):PAGE222

PWRGD_PVTT_GHJ_CPU1_R @BASEBOARD_FAB2_LIB.BASEBOARD_FAB2(SCH_1):PWRGD_PVTT_GHJ_CPU1_R
 R4G15    1      A RES_0402-33.2,1%,1/16W,CHIP,G2A    I32 @BASEBOARD_FAB2_LIB.BASEBOARD_FAB2(SCH_1):PAGE229
 C4G13    1      A CAP_0402LF-1000PF,50V,10%,X7R,A    I26 @BASEBOARD_FAB2_LIB.BASEBOARD_FAB2(SCH_1):PAGE229
 EU4G2    5     PG MIC5166_DFN-IC,H55101-001    I37 @BASEBOARD_FAB2_LIB.BASEBOARD_FAB2(SCH_1):PAGE229
 R4G17    2      B RES_0402-10.0K,1%,1/16W,CHIP,GA    I24 @BASEBOARD_FAB2_LIB.BASEBOARD_FAB2(SCH_1):PAGE229

PWRGD_PVTT_KLM_CPU1_R @BASEBOARD_FAB2_LIB.BASEBOARD_FAB2(SCH_1):PWRGD_PVTT_KLM_CPU1_R
  C4A3    1      A CAP_0402LF-1000PF,50V,10%,X7R,A    I23 @BASEBOARD_FAB2_LIB.BASEBOARD_FAB2(SCH_1):PAGE230
  R4A4    1      A RES_0402-33.2,1%,1/16W,CHIP,G2A    I32 @BASEBOARD_FAB2_LIB.BASEBOARD_FAB2(SCH_1):PAGE230
  R4A5    2      B RES_0402-10.0K,1%,1/16W,CHIP,GA    I21 @BASEBOARD_FAB2_LIB.BASEBOARD_FAB2(SCH_1):PAGE230
 EU4A2    5     PG MIC5166_DFN-IC,H55101-001    I37 @BASEBOARD_FAB2_LIB.BASEBOARD_FAB2(SCH_1):PAGE230

PWRGD_SYS_PWROK @BASEBOARD_FAB2_LIB.BASEBOARD_FAB2(SCH_1):PWRGD_SYS_PWROK
  U7C1 BY19 SYS_PWROK LBG_CORE_QAT_EXT_D_BGA1-IC,H91A    I73 @BASEBOARD_FAB2_LIB.BASEBOARD_FAB2(SCH_1):PAGE118
 R2N12    2      B RES_0402-10.0K,1%,1/16W,EMPTY,A   I122 @BASEBOARD_FAB2_LIB.BASEBOARD_FAB2(SCH_1):PAGE133
  U8D7  D14   PR1A LCMXO2_A_256BGA-IC,H63395-001    I59 @BASEBOARD_FAB2_LIB.BASEBOARD_FAB2(SCH_1):PAGE191
 U25W4  H22 GPIOB6_LPCPME# AST2520A1-GP-GP_ASIC2-GB1-AST2A    I95 @BASEBOARD_FAB2_LIB.BASEBOARD_FAB2(SCH_1):PAGE144
  U6W1   15    P12 TCA9555PWR-GP_DISCRET-GC1-TCA9A   I120 @BASEBOARD_FAB2_LIB.BASEBOARD_FAB2(SCH_1):PAGE247
R25W182    2      B RES_0402-0.0,5%,1/16W,CHIP,G21A   I151 @BASEBOARD_FAB2_LIB.BASEBOARD_FAB2(SCH_1):PAGE144

Q25W1_GATE @BASEBOARD_FAB2_LIB.BASEBOARD_FAB2(SCH_1):Q25W1_GATE
R25W131    2      B RES_0402-4.75K,1%,1/16W,CHIP,GA    I30 @BASEBOARD_FAB2_LIB.BASEBOARD_FAB2(SCH_1):PAGE255
 Q25W4    2 GATE<0> FET_N_DUAL_SMLF-2N7002DW,FET,DA    I95 @BASEBOARD_FAB2_LIB.BASEBOARD_FAB2(SCH_1):PAGE255

Q25W2_GATE @BASEBOARD_FAB2_LIB.BASEBOARD_FAB2(SCH_1):Q25W2_GATE
R25W134    2      B RES_0402-4.75K,1%,1/16W,CHIP,GA    I43 @BASEBOARD_FAB2_LIB.BASEBOARD_FAB2(SCH_1):PAGE255
 Q25W4    5 GATE<0> FET_N_DUAL_SMLF-2N7002DW,FET,DA    I96 @BASEBOARD_FAB2_LIB.BASEBOARD_FAB2(SCH_1):PAGE255

RMII_BMC_OCP_CRSDV @BASEBOARD_FAB2_LIB.BASEBOARD_FAB2(SCH_1):RMII_BMC_OCP_CRSDV
 R1M15    1      A RES_0402-0.0,5%,1/16W,CHIP,G21A   I339 @BASEBOARD_FAB2_LIB.BASEBOARD_FAB2(SCH_1):PAGE186
 U25W4   C5 RGMII1RXD2_RMII1CRSDV_GPIOV0 AST2520A1-GP-GP_ASIC2-GB1-AST2A   I106 @BASEBOARD_FAB2_LIB.BASEBOARD_FAB2(SCH_1):PAGE147

RMII_BMC_OCP_CRSDV_R @BASEBOARD_FAB2_LIB.BASEBOARD_FAB2(SCH_1):RMII_BMC_OCP_CRSDV_R
  J9B3   27   IO27 SCONN120_A28699018_SM-SCONN,A2A   I336 @BASEBOARD_FAB2_LIB.BASEBOARD_FAB2(SCH_1):PAGE186
 R1M15    2      B RES_0402-0.0,5%,1/16W,CHIP,G21A   I339 @BASEBOARD_FAB2_LIB.BASEBOARD_FAB2(SCH_1):PAGE186

RMII_BMC_OCP_RXD0 @BASEBOARD_FAB2_LIB.BASEBOARD_FAB2(SCH_1):RMII_BMC_OCP_RXD0
 R1M17    1      A RES_0402-0.0,5%,1/16W,CHIP,G21A   I338 @BASEBOARD_FAB2_LIB.BASEBOARD_FAB2(SCH_1):PAGE186
 U25W4   A3 RGMII1RXD0_RMII1RXD0_GPIOU6 AST2520A1-GP-GP_ASIC2-GB1-AST2A   I106 @BASEBOARD_FAB2_LIB.BASEBOARD_FAB2(SCH_1):PAGE147

RMII_BMC_OCP_RXD0_R @BASEBOARD_FAB2_LIB.BASEBOARD_FAB2(SCH_1):RMII_BMC_OCP_RXD0_R
  J9B3   43   IO43 SCONN120_A28699018_SM-SCONN,A2A   I336 @BASEBOARD_FAB2_LIB.BASEBOARD_FAB2(SCH_1):PAGE186
 R1M17    2      B RES_0402-0.0,5%,1/16W,CHIP,G21A   I338 @BASEBOARD_FAB2_LIB.BASEBOARD_FAB2(SCH_1):PAGE186

RMII_BMC_OCP_RXD1 @BASEBOARD_FAB2_LIB.BASEBOARD_FAB2(SCH_1):RMII_BMC_OCP_RXD1
 R1M16    1      A RES_0402-0.0,5%,1/16W,CHIP,G21A   I337 @BASEBOARD_FAB2_LIB.BASEBOARD_FAB2(SCH_1):PAGE186
 U25W4   D6 RGMII1RXD1_RMII1RXD1_GPIOU7 AST2520A1-GP-GP_ASIC2-GB1-AST2A   I106 @BASEBOARD_FAB2_LIB.BASEBOARD_FAB2(SCH_1):PAGE147

RMII_BMC_OCP_RXD1_R @BASEBOARD_FAB2_LIB.BASEBOARD_FAB2(SCH_1):RMII_BMC_OCP_RXD1_R
  J9B3   45   IO45 SCONN120_A28699018_SM-SCONN,A2A   I336 @BASEBOARD_FAB2_LIB.BASEBOARD_FAB2(SCH_1):PAGE186
 R1M16    2      B RES_0402-0.0,5%,1/16W,CHIP,G21A   I337 @BASEBOARD_FAB2_LIB.BASEBOARD_FAB2(SCH_1):PAGE186

RMII_BMC_OCP_RXER @BASEBOARD_FAB2_LIB.BASEBOARD_FAB2(SCH_1):RMII_BMC_OCP_RXER
 R1M18    2      B RES_0402-0.0,5%,1/16W,CHIP,G21A   I340 @BASEBOARD_FAB2_LIB.BASEBOARD_FAB2(SCH_1):PAGE186
 U25W4   C4 RGMII1RXD3_RMII1RXER_GPIOV1 AST2520A1-GP-GP_ASIC2-GB1-AST2A   I106 @BASEBOARD_FAB2_LIB.BASEBOARD_FAB2(SCH_1):PAGE147

RMII_BMC_OCP_RXER_R @BASEBOARD_FAB2_LIB.BASEBOARD_FAB2(SCH_1):RMII_BMC_OCP_RXER_R
  J9B3   36   IO36 SCONN120_A28699018_SM-SCONN,A2A   I336 @BASEBOARD_FAB2_LIB.BASEBOARD_FAB2(SCH_1):PAGE186
 R1M18    1      A RES_0402-0.0,5%,1/16W,CHIP,G21A   I340 @BASEBOARD_FAB2_LIB.BASEBOARD_FAB2(SCH_1):PAGE186

RMII_BMC_OCP_TXD0 @BASEBOARD_FAB2_LIB.BASEBOARD_FAB2(SCH_1):RMII_BMC_OCP_TXD0
  J9B3   40   IO40 SCONN120_A28699018_SM-SCONN,A2A   I336 @BASEBOARD_FAB2_LIB.BASEBOARD_FAB2(SCH_1):PAGE186
R25W86    2      B RES_0402-22.1,1.0%,1/16W,CHIP,A    I24 @BASEBOARD_FAB2_LIB.BASEBOARD_FAB2(SCH_1):PAGE147

RMII_BMC_OCP_TXD0_R @BASEBOARD_FAB2_LIB.BASEBOARD_FAB2(SCH_1):RMII_BMC_OCP_TXD0_R
R25W86    1      A RES_0402-22.1,1.0%,1/16W,CHIP,A    I24 @BASEBOARD_FAB2_LIB.BASEBOARD_FAB2(SCH_1):PAGE147
 U25W4   F9 RGMII1TXD0_RMII1TXD0_GPIOT2 AST2520A1-GP-GP_ASIC2-GB1-AST2A   I106 @BASEBOARD_FAB2_LIB.BASEBOARD_FAB2(SCH_1):PAGE147
R25W107    2      B RES_0402-4.75K,1%,1/16W,CHIP,GA   I190 @BASEBOARD_FAB2_LIB.BASEBOARD_FAB2(SCH_1):PAGE150

RMII_BMC_OCP_TXD1 @BASEBOARD_FAB2_LIB.BASEBOARD_FAB2(SCH_1):RMII_BMC_OCP_TXD1
  J9B3   42   IO42 SCONN120_A28699018_SM-SCONN,A2A   I336 @BASEBOARD_FAB2_LIB.BASEBOARD_FAB2(SCH_1):PAGE186
R25W87    2      B RES_0402-22.1,1.0%,1/16W,CHIP,A    I25 @BASEBOARD_FAB2_LIB.BASEBOARD_FAB2(SCH_1):PAGE147

RMII_BMC_OCP_TXD1_R @BASEBOARD_FAB2_LIB.BASEBOARD_FAB2(SCH_1):RMII_BMC_OCP_TXD1_R
R25W87    1      A RES_0402-22.1,1.0%,1/16W,CHIP,A    I25 @BASEBOARD_FAB2_LIB.BASEBOARD_FAB2(SCH_1):PAGE147
 U25W4   A5 RGMII1TXD1_RMII1TXD1_GPIOT3 AST2520A1-GP-GP_ASIC2-GB1-AST2A   I106 @BASEBOARD_FAB2_LIB.BASEBOARD_FAB2(SCH_1):PAGE147
R25W108    2      B RES_0402-4.75K,1%,1/16W,EMPTY,A   I191 @BASEBOARD_FAB2_LIB.BASEBOARD_FAB2(SCH_1):PAGE150
R25W148    2      B RES_0402-4.75K,1%,1/16W,CHIP,GA   I216 @BASEBOARD_FAB2_LIB.BASEBOARD_FAB2(SCH_1):PAGE150

RMII_BMC_OCP_TXEN @BASEBOARD_FAB2_LIB.BASEBOARD_FAB2(SCH_1):RMII_BMC_OCP_TXEN
  J9B3   31   IO31 SCONN120_A28699018_SM-SCONN,A2A   I336 @BASEBOARD_FAB2_LIB.BASEBOARD_FAB2(SCH_1):PAGE186
R25W85    2      B RES_0402-22.1,1.0%,1/16W,CHIP,A    I23 @BASEBOARD_FAB2_LIB.BASEBOARD_FAB2(SCH_1):PAGE147
R25W106    2      B RES_0402-4.75K,1%,1/16W,EMPTY,A   I175 @BASEBOARD_FAB2_LIB.BASEBOARD_FAB2(SCH_1):PAGE150
R25W146    2      B RES_0402-4.75K,1%,1/16W,CHIP,GA   I199 @BASEBOARD_FAB2_LIB.BASEBOARD_FAB2(SCH_1):PAGE150

RMII_BMC_OCP_TXEN_R @BASEBOARD_FAB2_LIB.BASEBOARD_FAB2(SCH_1):RMII_BMC_OCP_TXEN_R
R25W85    1      A RES_0402-22.1,1.0%,1/16W,CHIP,A    I23 @BASEBOARD_FAB2_LIB.BASEBOARD_FAB2(SCH_1):PAGE147
 U25W4   E9 RGMII1TXCTL_RMII1TXEN_GPIOT1 AST2520A1-GP-GP_ASIC2-GB1-AST2A   I106 @BASEBOARD_FAB2_LIB.BASEBOARD_FAB2(SCH_1):PAGE147

RMII_BMC_PCH_SPRNGVLLE_CRSDV @BASEBOARD_FAB2_LIB.BASEBOARD_FAB2(SCH_1):RMII_BMC_PCH_SPRNGVLLE_CRSDV
  R3P2    1      A RES_0402-0.0,5%,1/16W,CHIP,G21A    I90 @BASEBOARD_FAB2_LIB.BASEBOARD_FAB2(SCH_1):PAGE121
  R1T1    1      A RES_0402-10.0K,1%,1/16W,CHIP,GA   I214 @BASEBOARD_FAB2_LIB.BASEBOARD_FAB2(SCH_1):PAGE139
  R9F1    2      B RES_0402-22.1,1.0%,1/16W,CHIP,A   I225 @BASEBOARD_FAB2_LIB.BASEBOARD_FAB2(SCH_1):PAGE139
 U25W4   D2 RGMII2RXD2_RMII2CRSDV_GPIOV6 AST2520A1-GP-GP_ASIC2-GB1-AST2A   I106 @BASEBOARD_FAB2_LIB.BASEBOARD_FAB2(SCH_1):PAGE147

RMII_BMC_PCH_SPRNGVLLE_CRSDV_R @BASEBOARD_FAB2_LIB.BASEBOARD_FAB2(SCH_1):RMII_BMC_PCH_SPRNGVLLE_CRSDV_R
 EU9E1    3 NC_SI_CRS_DV SPRINGVILLE_SM1-IC,G47144-004    I72 @BASEBOARD_FAB2_LIB.BASEBOARD_FAB2(SCH_1):PAGE139
  R9F1    1      A RES_0402-22.1,1.0%,1/16W,CHIP,A   I225 @BASEBOARD_FAB2_LIB.BASEBOARD_FAB2(SCH_1):PAGE139

RMII_BMC_PCH_SPRNGVLLE_CRSDV_R1 @BASEBOARD_FAB2_LIB.BASEBOARD_FAB2(SCH_1):RMII_BMC_PCH_SPRNGVLLE_CRSDV_R1
  U7C1  AN3 GPP_K4_LAN_NCSI_CRS_DV LBG_CORE_QAT_EXT_D_BGA1-IC,H91A    I34 @BASEBOARD_FAB2_LIB.BASEBOARD_FAB2(SCH_1):PAGE121
  R3P2    2      B RES_0402-0.0,5%,1/16W,CHIP,G21A    I90 @BASEBOARD_FAB2_LIB.BASEBOARD_FAB2(SCH_1):PAGE121

RMII_BMC_PCH_SPRNGVLLE_RXER @BASEBOARD_FAB2_LIB.BASEBOARD_FAB2(SCH_1):RMII_BMC_PCH_SPRNGVLLE_RXER
 R7C14    1      A RES_0402-33.2,1%,1/16W,CHIP,G2A    I98 @BASEBOARD_FAB2_LIB.BASEBOARD_FAB2(SCH_1):PAGE121
 R7D13    2      B RES_0402-8.2K,1%,1/16W,EMPTY,GA    I60 @BASEBOARD_FAB2_LIB.BASEBOARD_FAB2(SCH_1):PAGE125
 U25W4   E6 RGMII2RXD3_RMII2RXER_GPIOV7 AST2520A1-GP-GP_ASIC2-GB1-AST2A   I106 @BASEBOARD_FAB2_LIB.BASEBOARD_FAB2(SCH_1):PAGE147

RMII_BMC_PCH_SPRNGVLLE_RXER_R @BASEBOARD_FAB2_LIB.BASEBOARD_FAB2(SCH_1):RMII_BMC_PCH_SPRNGVLLE_RXER_R
  U7C1  AH2 GPP_K7 LBG_CORE_QAT_EXT_D_BGA1-IC,H91A    I34 @BASEBOARD_FAB2_LIB.BASEBOARD_FAB2(SCH_1):PAGE121
 R7C14    2      B RES_0402-33.2,1%,1/16W,CHIP,G2A    I98 @BASEBOARD_FAB2_LIB.BASEBOARD_FAB2(SCH_1):PAGE121

RMII_BMC_PCH_SPRNGVLLE_TXD0 @BASEBOARD_FAB2_LIB.BASEBOARD_FAB2(SCH_1):RMII_BMC_PCH_SPRNGVLLE_TXD0
  U7C1  AM2 GPP_K1_LAN_NCSI_TXD0 LBG_CORE_QAT_EXT_D_BGA1-IC,H91A    I34 @BASEBOARD_FAB2_LIB.BASEBOARD_FAB2(SCH_1):PAGE121
 EU9E1    9 NC_SI_TXD0 SPRINGVILLE_SM1-IC,G47144-004    I72 @BASEBOARD_FAB2_LIB.BASEBOARD_FAB2(SCH_1):PAGE139
R25W89    2      B RES_0402-22.1,1.0%,1/16W,CHIP,A    I22 @BASEBOARD_FAB2_LIB.BASEBOARD_FAB2(SCH_1):PAGE147

RMII_BMC_PCH_SPRNGVLLE_TXD0_R @BASEBOARD_FAB2_LIB.BASEBOARD_FAB2(SCH_1):RMII_BMC_PCH_SPRNGVLLE_TXD0_R
R25W89    1      A RES_0402-22.1,1.0%,1/16W,CHIP,A    I22 @BASEBOARD_FAB2_LIB.BASEBOARD_FAB2(SCH_1):PAGE147
 U25W4   A2 RGMII2TXD0_RMII2TXD0_GPIOU0 AST2520A1-GP-GP_ASIC2-GB1-AST2A   I106 @BASEBOARD_FAB2_LIB.BASEBOARD_FAB2(SCH_1):PAGE147
R25W112    2      B RES_0402-4.75K,1%,1/16W,EMPTY,A   I228 @BASEBOARD_FAB2_LIB.BASEBOARD_FAB2(SCH_1):PAGE150
R25W150    2      B RES_0402-4.75K,1%,1/16W,CHIP,GA   I229 @BASEBOARD_FAB2_LIB.BASEBOARD_FAB2(SCH_1):PAGE150

RMII_BMC_PCH_SPRNGVLLE_TXD1 @BASEBOARD_FAB2_LIB.BASEBOARD_FAB2(SCH_1):RMII_BMC_PCH_SPRNGVLLE_TXD1
  U7C1  AK2 GPP_K2_LAN_NCSI_TXD1 LBG_CORE_QAT_EXT_D_BGA1-IC,H91A    I34 @BASEBOARD_FAB2_LIB.BASEBOARD_FAB2(SCH_1):PAGE121
 EU9E1    8 NC_SI_TXD1 SPRINGVILLE_SM1-IC,G47144-004    I72 @BASEBOARD_FAB2_LIB.BASEBOARD_FAB2(SCH_1):PAGE139
R25W90    2      B RES_0402-22.1,1.0%,1/16W,CHIP,A    I21 @BASEBOARD_FAB2_LIB.BASEBOARD_FAB2(SCH_1):PAGE147

RMII_BMC_PCH_SPRNGVLLE_TXD1_R @BASEBOARD_FAB2_LIB.BASEBOARD_FAB2(SCH_1):RMII_BMC_PCH_SPRNGVLLE_TXD1_R
R25W90    1      A RES_0402-22.1,1.0%,1/16W,CHIP,A    I21 @BASEBOARD_FAB2_LIB.BASEBOARD_FAB2(SCH_1):PAGE147
 U25W4   B3 RGMII2TXD1_RMII2TXD1_GPIOU1 AST2520A1-GP-GP_ASIC2-GB1-AST2A   I106 @BASEBOARD_FAB2_LIB.BASEBOARD_FAB2(SCH_1):PAGE147
R25W113    2      B RES_0402-4.75K,1%,1/16W,EMPTY,A   I230 @BASEBOARD_FAB2_LIB.BASEBOARD_FAB2(SCH_1):PAGE150
R25W151    2      B RES_0402-4.75K,1%,1/16W,CHIP,GA   I232 @BASEBOARD_FAB2_LIB.BASEBOARD_FAB2(SCH_1):PAGE150

RMII_BMC_PCH_SPRNGVLLE_TXEN @BASEBOARD_FAB2_LIB.BASEBOARD_FAB2(SCH_1):RMII_BMC_PCH_SPRNGVLLE_TXEN
  U7C1  AL3 GPP_K3_LAN_NCSI_TX_EN LBG_CORE_QAT_EXT_D_BGA1-IC,H91A    I34 @BASEBOARD_FAB2_LIB.BASEBOARD_FAB2(SCH_1):PAGE121
 EU9E1    7 NC_SI_TX_EN SPRINGVILLE_SM1-IC,G47144-004    I72 @BASEBOARD_FAB2_LIB.BASEBOARD_FAB2(SCH_1):PAGE139
 R9E13    1      A RES_0402-10.0K,1%,1/16W,CHIP,GA   I212 @BASEBOARD_FAB2_LIB.BASEBOARD_FAB2(SCH_1):PAGE139
R25W88    2      B RES_0402-22.1,1.0%,1/16W,CHIP,A     I8 @BASEBOARD_FAB2_LIB.BASEBOARD_FAB2(SCH_1):PAGE147
R25W111    2      B RES_0402-4.75K,1%,1/16W,EMPTY,A   I180 @BASEBOARD_FAB2_LIB.BASEBOARD_FAB2(SCH_1):PAGE150

RMII_BMC_SPRNGVLLE_TXEN_R @BASEBOARD_FAB2_LIB.BASEBOARD_FAB2(SCH_1):RMII_BMC_SPRNGVLLE_TXEN_R
R25W88    1      A RES_0402-22.1,1.0%,1/16W,CHIP,A     I8 @BASEBOARD_FAB2_LIB.BASEBOARD_FAB2(SCH_1):PAGE147
 U25W4   B1 RGMII2TXCTL_RMII2TXEN_GPIOT7 AST2520A1-GP-GP_ASIC2-GB1-AST2A   I106 @BASEBOARD_FAB2_LIB.BASEBOARD_FAB2(SCH_1):PAGE147

RMII_PCH_SPRNGVLLE_ARB_IN @BASEBOARD_FAB2_LIB.BASEBOARD_FAB2(SCH_1):RMII_PCH_SPRNGVLLE_ARB_IN
  U7C1  AJ3 GPP_K8_LAN_NCSI_ARB_IN LBG_CORE_QAT_EXT_D_BGA1-IC,H91A    I34 @BASEBOARD_FAB2_LIB.BASEBOARD_FAB2(SCH_1):PAGE121
 R9E16    2      B RES_0402-33.2,1%,1/16W,CHIP,G2A   I235 @BASEBOARD_FAB2_LIB.BASEBOARD_FAB2(SCH_1):PAGE139

RMII_PCH_SPRNGVLLE_ARB_IN_R @BASEBOARD_FAB2_LIB.BASEBOARD_FAB2(SCH_1):RMII_PCH_SPRNGVLLE_ARB_IN_R
 EU9E1   44 NC_SI_ARB_OUT SPRINGVILLE_SM1-IC,G47144-004    I72 @BASEBOARD_FAB2_LIB.BASEBOARD_FAB2(SCH_1):PAGE139
 R9E16    1      A RES_0402-33.2,1%,1/16W,CHIP,G2A   I235 @BASEBOARD_FAB2_LIB.BASEBOARD_FAB2(SCH_1):PAGE139

RMII_PCH_SPRNGVLLE_ARB_OUT @BASEBOARD_FAB2_LIB.BASEBOARD_FAB2(SCH_1):RMII_PCH_SPRNGVLLE_ARB_OUT
 R8D11    1      A RES_0402-33.2,1%,1/16W,CHIP,G2A   I101 @BASEBOARD_FAB2_LIB.BASEBOARD_FAB2(SCH_1):PAGE121
 EU9E1   43 NC_SI_ARB_IN SPRINGVILLE_SM1-IC,G47144-004    I72 @BASEBOARD_FAB2_LIB.BASEBOARD_FAB2(SCH_1):PAGE139
 R8D16    2      B RES_0402-10.0K,1%,1/16W,CHIP,GA    I85 @BASEBOARD_FAB2_LIB.BASEBOARD_FAB2(SCH_1):PAGE125
  R7D1    1      A RES_0402-1.00K,1%,1/16W,EMPTY,A    I86 @BASEBOARD_FAB2_LIB.BASEBOARD_FAB2(SCH_1):PAGE125

RMII_PCH_SPRNGVLLE_ARB_OUT_R @BASEBOARD_FAB2_LIB.BASEBOARD_FAB2(SCH_1):RMII_PCH_SPRNGVLLE_ARB_OUT_R
  U7C1  AK4 GPP_K9_LAN_NCSI_ARB_OUT LBG_CORE_QAT_EXT_D_BGA1-IC,H91A    I34 @BASEBOARD_FAB2_LIB.BASEBOARD_FAB2(SCH_1):PAGE121
 R8D11    2      B RES_0402-33.2,1%,1/16W,CHIP,G2A   I101 @BASEBOARD_FAB2_LIB.BASEBOARD_FAB2(SCH_1):PAGE121

RMII_SPRNGVLLE_BMC_PCH_RXD0 @BASEBOARD_FAB2_LIB.BASEBOARD_FAB2(SCH_1):RMII_SPRNGVLLE_BMC_PCH_RXD0
  R3P3    1      A RES_0402-0.0,5%,1/16W,CHIP,G21A    I89 @BASEBOARD_FAB2_LIB.BASEBOARD_FAB2(SCH_1):PAGE121
 R9E17    2      B RES_0402-22.1,1.0%,1/16W,CHIP,A   I229 @BASEBOARD_FAB2_LIB.BASEBOARD_FAB2(SCH_1):PAGE139
R25W79    2      B RES_0402-10.0K,1%,1/16W,CHIP,GA    I42 @BASEBOARD_FAB2_LIB.BASEBOARD_FAB2(SCH_1):PAGE147
 U25W4   C3 RGMII2RXD0_RMII2RXD0_GPIOV4 AST2520A1-GP-GP_ASIC2-GB1-AST2A   I106 @BASEBOARD_FAB2_LIB.BASEBOARD_FAB2(SCH_1):PAGE147

RMII_SPRNGVLLE_BMC_PCH_RXD0_R @BASEBOARD_FAB2_LIB.BASEBOARD_FAB2(SCH_1):RMII_SPRNGVLLE_BMC_PCH_RXD0_R
 EU9E1    6 NC_SI_RXD0 SPRINGVILLE_SM1-IC,G47144-004    I72 @BASEBOARD_FAB2_LIB.BASEBOARD_FAB2(SCH_1):PAGE139
 R9E17    1      A RES_0402-22.1,1.0%,1/16W,CHIP,A   I229 @BASEBOARD_FAB2_LIB.BASEBOARD_FAB2(SCH_1):PAGE139

RMII_SPRNGVLLE_BMC_PCH_RXD0_R1 @BASEBOARD_FAB2_LIB.BASEBOARD_FAB2(SCH_1):RMII_SPRNGVLLE_BMC_PCH_RXD0_R1
  U7C1  AL1 GPP_K5_LAN_NCSI_RXD0 LBG_CORE_QAT_EXT_D_BGA1-IC,H91A    I34 @BASEBOARD_FAB2_LIB.BASEBOARD_FAB2(SCH_1):PAGE121
  R3P3    2      B RES_0402-0.0,5%,1/16W,CHIP,G21A    I89 @BASEBOARD_FAB2_LIB.BASEBOARD_FAB2(SCH_1):PAGE121

RMII_SPRNGVLLE_BMC_PCH_RXD1 @BASEBOARD_FAB2_LIB.BASEBOARD_FAB2(SCH_1):RMII_SPRNGVLLE_BMC_PCH_RXD1
  R2P1    1      A RES_0402-0.0,5%,1/16W,CHIP,G21A    I91 @BASEBOARD_FAB2_LIB.BASEBOARD_FAB2(SCH_1):PAGE121
 R9E19    2      B RES_0402-22.1,1.0%,1/16W,CHIP,A   I228 @BASEBOARD_FAB2_LIB.BASEBOARD_FAB2(SCH_1):PAGE139
R25W80    2      B RES_0402-10.0K,1%,1/16W,CHIP,GA    I43 @BASEBOARD_FAB2_LIB.BASEBOARD_FAB2(SCH_1):PAGE147
 U25W4   D1 RGMII2RXD1_RMII2RXD1_GPIOV5 AST2520A1-GP-GP_ASIC2-GB1-AST2A   I106 @BASEBOARD_FAB2_LIB.BASEBOARD_FAB2(SCH_1):PAGE147

RMII_SPRNGVLLE_BMC_PCH_RXD1_R @BASEBOARD_FAB2_LIB.BASEBOARD_FAB2(SCH_1):RMII_SPRNGVLLE_BMC_PCH_RXD1_R
 EU9E1    5 NC_SI_RXD1 SPRINGVILLE_SM1-IC,G47144-004    I72 @BASEBOARD_FAB2_LIB.BASEBOARD_FAB2(SCH_1):PAGE139
 R9E19    1      A RES_0402-22.1,1.0%,1/16W,CHIP,A   I228 @BASEBOARD_FAB2_LIB.BASEBOARD_FAB2(SCH_1):PAGE139

RMII_SPRNGVLLE_BMC_PCH_RXD1_R1 @BASEBOARD_FAB2_LIB.BASEBOARD_FAB2(SCH_1):RMII_SPRNGVLLE_BMC_PCH_RXD1_R1
  U7C1  AN1 GPP_K6_LAN_NCSI_RXD1 LBG_CORE_QAT_EXT_D_BGA1-IC,H91A    I34 @BASEBOARD_FAB2_LIB.BASEBOARD_FAB2(SCH_1):PAGE121
  R2P1    2      B RES_0402-0.0,5%,1/16W,CHIP,G21A    I91 @BASEBOARD_FAB2_LIB.BASEBOARD_FAB2(SCH_1):PAGE121

RST_BMC_DDR3_BUF_IN_N @BASEBOARD_FAB2_LIB.BASEBOARD_FAB2(SCH_1):RST_BMC_DDR3_BUF_IN_N
 R8D36    2      B RES_0402-33.2,1%,1/16W,CHIP,G2A   I388 @BASEBOARD_FAB2_LIB.BASEBOARD_FAB2(SCH_1):PAGE157
  U9F3    2      A TTL1G07_A_SOP-74LVC1G07,IC,C88B    I56 @BASEBOARD_FAB2_LIB.BASEBOARD_FAB2(SCH_1):PAGE151

RST_BMC_DDR3_R_N @BASEBOARD_FAB2_LIB.BASEBOARD_FAB2(SCH_1):RST_BMC_DDR3_R_N
 R9F29    2      B RES_0402-4.75K,1%,1/16W,CHIP,GA    I55 @BASEBOARD_FAB2_LIB.BASEBOARD_FAB2(SCH_1):PAGE151
  U9F3    4      Y TTL1G07_A_SOP-74LVC1G07,IC,C88B    I56 @BASEBOARD_FAB2_LIB.BASEBOARD_FAB2(SCH_1):PAGE151
 R9F34    1      A RES_0402-33.2,1%,1/16W,EMPTY,GA   I209 @BASEBOARD_FAB2_LIB.BASEBOARD_FAB2(SCH_1):PAGE151

RST_BMC_EXTRST_N @BASEBOARD_FAB2_LIB.BASEBOARD_FAB2(SCH_1):RST_BMC_EXTRST_N
 U25W4  V18 EXTRST# AST2520A1-GP-GP_ASIC2-GB1-AST2A   I105 @BASEBOARD_FAB2_LIB.BASEBOARD_FAB2(SCH_1):PAGE146
  R3W6    2      B RES_0402-4.75K,1%,1/16W,CHIP,GA    I48 @BASEBOARD_FAB2_LIB.BASEBOARD_FAB2(SCH_1):PAGE249
  Q9W3    3      C NPN_SM-MMBT3904,IC,C52245-001    I49 @BASEBOARD_FAB2_LIB.BASEBOARD_FAB2(SCH_1):PAGE249

RST_BMC_LVC3_N @BASEBOARD_FAB2_LIB.BASEBOARD_FAB2(SCH_1):RST_BMC_LVC3_N
R25W74    2      B RES_0402-0.0,5%,1/16W,CHIP,G21A    I70 @BASEBOARD_FAB2_LIB.BASEBOARD_FAB2(SCH_1):PAGE146
 U25W4  G22 GPIOAC7_ESPIRST#_LPCRST# AST2520A1-GP-GP_ASIC2-GB1-AST2A   I105 @BASEBOARD_FAB2_LIB.BASEBOARD_FAB2(SCH_1):PAGE146

RST_BMC_PLTRST_BUF_N @BASEBOARD_FAB2_LIB.BASEBOARD_FAB2(SCH_1):RST_BMC_PLTRST_BUF_N
 U25W4  V19 GPIOR5_SPI2MISO AST2520A1-GP-GP_ASIC2-GB1-AST2A   I105 @BASEBOARD_FAB2_LIB.BASEBOARD_FAB2(SCH_1):PAGE146
R25W184    1      A RES_0402-0.0,5%,1/16W,CHIP,G21A   I166 @BASEBOARD_FAB2_LIB.BASEBOARD_FAB2(SCH_1):PAGE146

RST_BMC_SRST_N @BASEBOARD_FAB2_LIB.BASEBOARD_FAB2(SCH_1):RST_BMC_SRST_N
 R7D23    1      A RES_0402-0.0,5%,1/16W,CHIP,G21A   I131 @BASEBOARD_FAB2_LIB.BASEBOARD_FAB2(SCH_1):PAGE118
  J8G2    3    IO3 CONN12_C73564003_PIP-CONN,C735A   I124 @BASEBOARD_FAB2_LIB.BASEBOARD_FAB2(SCH_1):PAGE135
 U25W4  U18  SRST# AST2520A1-GP-GP_ASIC2-GB1-AST2A   I117 @BASEBOARD_FAB2_LIB.BASEBOARD_FAB2(SCH_1):PAGE145
 U25W9    4      Y TTL1G07_A_SOP-74LVC1G07,IC,C88B   I394 @BASEBOARD_FAB2_LIB.BASEBOARD_FAB2(SCH_1):PAGE157
R25W153    2      B RES_0402-4.75K,1%,1/16W,CHIP,GA   I396 @BASEBOARD_FAB2_LIB.BASEBOARD_FAB2(SCH_1):PAGE157

RST_BMC_SRST_R2_N @BASEBOARD_FAB2_LIB.BASEBOARD_FAB2(SCH_1):RST_BMC_SRST_R2_N
 R8D25    2      B RES_0402-4.75K,1%,1/16W,CHIP,GA   I335 @BASEBOARD_FAB2_LIB.BASEBOARD_FAB2(SCH_1):PAGE157
  U8D2    4      Y TTL1G07_A_SOP-74LVC1G07,IC,C88B   I374 @BASEBOARD_FAB2_LIB.BASEBOARD_FAB2(SCH_1):PAGE157
 R8D22    1      A RES_0402-33.2,1%,1/16W,CHIP,G2A   I386 @BASEBOARD_FAB2_LIB.BASEBOARD_FAB2(SCH_1):PAGE157
 R8D36    1      A RES_0402-33.2,1%,1/16W,CHIP,G2A   I388 @BASEBOARD_FAB2_LIB.BASEBOARD_FAB2(SCH_1):PAGE157

RST_BMC_SRST_R_N @BASEBOARD_FAB2_LIB.BASEBOARD_FAB2(SCH_1):RST_BMC_SRST_R_N
  U7C1  M11 GPD2_GBE_WAKE_N LBG_CORE_QAT_EXT_D_BGA1-IC,H91A    I73 @BASEBOARD_FAB2_LIB.BASEBOARD_FAB2(SCH_1):PAGE118
 R7D23    2      B RES_0402-0.0,5%,1/16W,CHIP,G21A   I131 @BASEBOARD_FAB2_LIB.BASEBOARD_FAB2(SCH_1):PAGE118
 R7W21    2      B RES_0402-4.75K,1%,1/16W,CHIP,GA   I183 @BASEBOARD_FAB2_LIB.BASEBOARD_FAB2(SCH_1):PAGE118

RST_BMC_SYSRST_BTN_OUT_B_N @BASEBOARD_FAB2_LIB.BASEBOARD_FAB2(SCH_1):RST_BMC_SYSRST_BTN_OUT_B_N
  U7C1 BV19 SYS_RESET_N LBG_CORE_QAT_EXT_D_BGA1-IC,H91A    I73 @BASEBOARD_FAB2_LIB.BASEBOARD_FAB2(SCH_1):PAGE118
 R2T18    2      B RES_0402-49.9,1%,1/16W,CHIP,G2A   I288 @BASEBOARD_FAB2_LIB.BASEBOARD_FAB2(SCH_1):PAGE156
 R1W29    1      A RES_0402-0.0,5%,1/16W,CHIP,G21A   I198 @BASEBOARD_FAB2_LIB.BASEBOARD_FAB2(SCH_1):PAGE191
 R1W30    1      A RES_0402-0.0,5%,1/16W,EMPTY,G2A   I168 @BASEBOARD_FAB2_LIB.BASEBOARD_FAB2(SCH_1):PAGE118

RST_BMC_SYSRST_BTN_OUT_B_R1_N @BASEBOARD_FAB2_LIB.BASEBOARD_FAB2(SCH_1):RST_BMC_SYSRST_BTN_OUT_B_R1_N
  U8D7  F14   PR4A LCMXO2_A_256BGA-IC,H63395-001    I59 @BASEBOARD_FAB2_LIB.BASEBOARD_FAB2(SCH_1):PAGE191
 R1W29    2      B RES_0402-0.0,5%,1/16W,CHIP,G21A   I198 @BASEBOARD_FAB2_LIB.BASEBOARD_FAB2(SCH_1):PAGE191

RST_BMC_SYSRST_BTN_OUT_B_R_N @BASEBOARD_FAB2_LIB.BASEBOARD_FAB2(SCH_1):RST_BMC_SYSRST_BTN_OUT_B_R_N
 R2T22    2      B RES_0402-10.0K,1%,1/16W,CHIP,GA   I210 @BASEBOARD_FAB2_LIB.BASEBOARD_FAB2(SCH_1):PAGE156
 R2T18    1      A RES_0402-49.9,1%,1/16W,CHIP,G2A   I288 @BASEBOARD_FAB2_LIB.BASEBOARD_FAB2(SCH_1):PAGE156
  U8F3    6     1Y SN74LVC2G07DCKR-GP_DISCRET-G4-A   I340 @BASEBOARD_FAB2_LIB.BASEBOARD_FAB2(SCH_1):PAGE156
  U8G1    6     1Y SN74LVC2G07DCKR-GP_DISCRET-G4-A   I342 @BASEBOARD_FAB2_LIB.BASEBOARD_FAB2(SCH_1):PAGE156

RST_BMC_SYSRST_BTN_OUT_N @BASEBOARD_FAB2_LIB.BASEBOARD_FAB2(SCH_1):RST_BMC_SYSRST_BTN_OUT_N
 R2T35    2      B RES_0402-4.75K,1%,1/16W,CHIP,GA   I207 @BASEBOARD_FAB2_LIB.BASEBOARD_FAB2(SCH_1):PAGE156
 U25W4  C20 GPIOE1_NDCD3 AST2520A1-GP-GP_ASIC2-GB1-AST2A   I117 @BASEBOARD_FAB2_LIB.BASEBOARD_FAB2(SCH_1):PAGE145
  U8F3    1     1A SN74LVC2G07DCKR-GP_DISCRET-G4-A   I340 @BASEBOARD_FAB2_LIB.BASEBOARD_FAB2(SCH_1):PAGE156

RST_CD_CPU0_POR_N @BASEBOARD_FAB2_LIB.BASEBOARD_FAB2(SCH_1):RST_CD_CPU0_POR_N
  U5D1 CF25 CD_POR_N SKX_EXT_B_BGA1-IC,TBD    I61 @BASEBOARD_FAB2_LIB.BASEBOARD_FAB2(SCH_1):PAGE29
  U8D7   N3  PL14B LCMXO2_A_256BGA-IC,H63395-001   I179 @BASEBOARD_FAB2_LIB.BASEBOARD_FAB2(SCH_1):PAGE190
 R3R16    2      B RES_0402-4.75K,1%,1/16W,CHIP,GA    I48 @BASEBOARD_FAB2_LIB.BASEBOARD_FAB2(SCH_1):PAGE192

RST_CD_CPU1_POR_N @BASEBOARD_FAB2_LIB.BASEBOARD_FAB2(SCH_1):RST_CD_CPU1_POR_N
  U2D1 CF25 CD_POR_N SKX_EXT_B_BGA1-IC,TBD    I23 @BASEBOARD_FAB2_LIB.BASEBOARD_FAB2(SCH_1):PAGE63
  U8D7  P10  PB19A LCMXO2_A_256BGA-IC,H63395-001   I179 @BASEBOARD_FAB2_LIB.BASEBOARD_FAB2(SCH_1):PAGE190
  R6M9    2      B RES_0402-4.75K,1%,1/16W,CHIP,GA    I49 @BASEBOARD_FAB2_LIB.BASEBOARD_FAB2(SCH_1):PAGE192

RST_CPU0_G_N @BASEBOARD_FAB2_LIB.BASEBOARD_FAB2(SCH_1):RST_CPU0_G_N
  U5D1 AP21 RESET_N SKX_EXT_B_BGA1-IC,TBD   I259 @BASEBOARD_FAB2_LIB.BASEBOARD_FAB2(SCH_1):PAGE21
 R6D12    2      B RES_0402-49.9,1%,1/16W,CHIP,G2A     I2 @BASEBOARD_FAB2_LIB.BASEBOARD_FAB2(SCH_1):PAGE96
  U3P1    5     B2 GTL2014_SM-IC,D66151-001    I42 @BASEBOARD_FAB2_LIB.BASEBOARD_FAB2(SCH_1):PAGE96

RST_CPU0_LVC3_N @BASEBOARD_FAB2_LIB.BASEBOARD_FAB2(SCH_1):RST_CPU0_LVC3_N
  U3P1   10     A2 GTL2014_SM-IC,D66151-001    I42 @BASEBOARD_FAB2_LIB.BASEBOARD_FAB2(SCH_1):PAGE96
 R3P34    2      B RES_0402-0.0,5%,1/16W,CHIP,G21A   I116 @BASEBOARD_FAB2_LIB.BASEBOARD_FAB2(SCH_1):PAGE190

RST_CPU0_LVC3_R1_N @BASEBOARD_FAB2_LIB.BASEBOARD_FAB2(SCH_1):RST_CPU0_LVC3_R1_N
 R3P34    1      A RES_0402-0.0,5%,1/16W,CHIP,G21A   I116 @BASEBOARD_FAB2_LIB.BASEBOARD_FAB2(SCH_1):PAGE190
  U8D7  R10  PB19B LCMXO2_A_256BGA-IC,H63395-001   I179 @BASEBOARD_FAB2_LIB.BASEBOARD_FAB2(SCH_1):PAGE190

RST_CPU1_G_N @BASEBOARD_FAB2_LIB.BASEBOARD_FAB2(SCH_1):RST_CPU1_G_N
  U2D1 AP21 RESET_N SKX_EXT_B_BGA1-IC,TBD   I172 @BASEBOARD_FAB2_LIB.BASEBOARD_FAB2(SCH_1):PAGE55
 R3D20    2      B RES_0402-49.9,1%,1/16W,CHIP,G2A    I25 @BASEBOARD_FAB2_LIB.BASEBOARD_FAB2(SCH_1):PAGE96
  U4C2    5     B2 GTL2014_SM-IC,D66151-001    I46 @BASEBOARD_FAB2_LIB.BASEBOARD_FAB2(SCH_1):PAGE96

RST_CPU1_LVC3_N @BASEBOARD_FAB2_LIB.BASEBOARD_FAB2(SCH_1):RST_CPU1_LVC3_N
  U4C2   10     A2 GTL2014_SM-IC,D66151-001    I46 @BASEBOARD_FAB2_LIB.BASEBOARD_FAB2(SCH_1):PAGE96
 R3P35    2      B RES_0402-0.0,5%,1/16W,CHIP,G21A   I117 @BASEBOARD_FAB2_LIB.BASEBOARD_FAB2(SCH_1):PAGE190

RST_CPU1_LVC3_R1_N @BASEBOARD_FAB2_LIB.BASEBOARD_FAB2(SCH_1):RST_CPU1_LVC3_R1_N
 R3P35    1      A RES_0402-0.0,5%,1/16W,CHIP,G21A   I117 @BASEBOARD_FAB2_LIB.BASEBOARD_FAB2(SCH_1):PAGE190
  U8D7  N10  PB19C LCMXO2_A_256BGA-IC,H63395-001   I179 @BASEBOARD_FAB2_LIB.BASEBOARD_FAB2(SCH_1):PAGE190

RST_HFI0_CPU0_LVT2_N @BASEBOARD_FAB2_LIB.BASEBOARD_FAB2(SCH_1):RST_HFI0_CPU0_LVT2_N
  U5D1 BN24 CD_HFI0_RESET_N SKX_EXT_B_BGA1-IC,TBD    I61 @BASEBOARD_FAB2_LIB.BASEBOARD_FAB2(SCH_1):PAGE29
  J8B1    6    IO6 SCONN24_H46321001_SM-SCONN,H46A     I1 @BASEBOARD_FAB2_LIB.BASEBOARD_FAB2(SCH_1):PAGE91
  R8B8    2      B RES_0402-4.75K,1%,1/16W,CHIP,GA    I14 @BASEBOARD_FAB2_LIB.BASEBOARD_FAB2(SCH_1):PAGE91

RST_HFI1_CPU0_LVT2_N @BASEBOARD_FAB2_LIB.BASEBOARD_FAB2(SCH_1):RST_HFI1_CPU0_LVT2_N
  U5D1 BK23 CD_HFI1_RESET_N SKX_EXT_B_BGA1-IC,TBD    I61 @BASEBOARD_FAB2_LIB.BASEBOARD_FAB2(SCH_1):PAGE29
  J8B1   14   IO14 SCONN24_H46321001_SM-SCONN,H46A     I1 @BASEBOARD_FAB2_LIB.BASEBOARD_FAB2(SCH_1):PAGE91
 R8B16    2      B RES_0402-4.75K,1%,1/16W,CHIP,GA    I17 @BASEBOARD_FAB2_LIB.BASEBOARD_FAB2(SCH_1):PAGE91

RST_PCH_SYSRST_BTN_OUT_N @BASEBOARD_FAB2_LIB.BASEBOARD_FAB2(SCH_1):RST_PCH_SYSRST_BTN_OUT_N
  U7C1  AD3 GPP_A18 LBG_CORE_QAT_EXT_D_BGA1-IC,H91A   I115 @BASEBOARD_FAB2_LIB.BASEBOARD_FAB2(SCH_1):PAGE119
  R2U2    2      B RES_0402-4.75K,1%,1/16W,CHIP,GA   I265 @BASEBOARD_FAB2_LIB.BASEBOARD_FAB2(SCH_1):PAGE156
  U8G1    1     1A SN74LVC2G07DCKR-GP_DISCRET-G4-A   I342 @BASEBOARD_FAB2_LIB.BASEBOARD_FAB2(SCH_1):PAGE156

RST_PCIE_CPU_DEV0_N @BASEBOARD_FAB2_LIB.BASEBOARD_FAB2(SCH_1):RST_PCIE_CPU_DEV0_N
 R1M14    1      A RES_0402-200.0,1%,1/16W,CHIP,GA   I220 @BASEBOARD_FAB2_LIB.BASEBOARD_FAB2(SCH_1):PAGE186
  U8D7   D6  PT12A LCMXO2_A_256BGA-IC,H63395-001    I59 @BASEBOARD_FAB2_LIB.BASEBOARD_FAB2(SCH_1):PAGE191

RST_PCIE_CPU_DEV0_R_N @BASEBOARD_FAB2_LIB.BASEBOARD_FAB2(SCH_1):RST_PCIE_CPU_DEV0_R_N
 R1M14    2      B RES_0402-200.0,1%,1/16W,CHIP,GA   I220 @BASEBOARD_FAB2_LIB.BASEBOARD_FAB2(SCH_1):PAGE186
  J9B3   33   IO33 SCONN120_A28699018_SM-SCONN,A2A   I336 @BASEBOARD_FAB2_LIB.BASEBOARD_FAB2(SCH_1):PAGE186

RST_PCIE_CPU_DEV1_N @BASEBOARD_FAB2_LIB.BASEBOARD_FAB2(SCH_1):RST_PCIE_CPU_DEV1_N
 R9E10    2      B RES_0402-200.0,1%,1/16W,CHIP,GA   I145 @BASEBOARD_FAB2_LIB.BASEBOARD_FAB2(SCH_1):PAGE187
  U8D7   C1   PL2C LCMXO2_A_256BGA-IC,H63395-001   I179 @BASEBOARD_FAB2_LIB.BASEBOARD_FAB2(SCH_1):PAGE190

RST_PCIE_CPU_DEV1_R_N @BASEBOARD_FAB2_LIB.BASEBOARD_FAB2(SCH_1):RST_PCIE_CPU_DEV1_R_N
  J8E3   75   IO75 SCONN80_E67482007_SM-CONN,E674A   I119 @BASEBOARD_FAB2_LIB.BASEBOARD_FAB2(SCH_1):PAGE187
 R9E10    1      A RES_0402-200.0,1%,1/16W,CHIP,GA   I145 @BASEBOARD_FAB2_LIB.BASEBOARD_FAB2(SCH_1):PAGE187

RST_PCIE_CPU_DEV2_N @BASEBOARD_FAB2_LIB.BASEBOARD_FAB2(SCH_1):RST_PCIE_CPU_DEV2_N
 R9E11    2      B RES_0402-200.0,1%,1/16W,CHIP,GA   I150 @BASEBOARD_FAB2_LIB.BASEBOARD_FAB2(SCH_1):PAGE187
  U8D7   H3   PL7A LCMXO2_A_256BGA-IC,H63395-001   I179 @BASEBOARD_FAB2_LIB.BASEBOARD_FAB2(SCH_1):PAGE190

RST_PCIE_CPU_DEV2_R_N @BASEBOARD_FAB2_LIB.BASEBOARD_FAB2(SCH_1):RST_PCIE_CPU_DEV2_R_N
  J8E3   77   IO77 SCONN80_E67482007_SM-CONN,E674A   I119 @BASEBOARD_FAB2_LIB.BASEBOARD_FAB2(SCH_1):PAGE187
 R9E11    1      A RES_0402-200.0,1%,1/16W,CHIP,GA   I150 @BASEBOARD_FAB2_LIB.BASEBOARD_FAB2(SCH_1):PAGE187

RST_PCIE_CPU_DEV3_N @BASEBOARD_FAB2_LIB.BASEBOARD_FAB2(SCH_1):RST_PCIE_CPU_DEV3_N
 R9E12    2      B RES_0402-200.0,1%,1/16W,CHIP,GA   I153 @BASEBOARD_FAB2_LIB.BASEBOARD_FAB2(SCH_1):PAGE187
  U8D7   H1   PL7B LCMXO2_A_256BGA-IC,H63395-001   I179 @BASEBOARD_FAB2_LIB.BASEBOARD_FAB2(SCH_1):PAGE190

RST_PCIE_CPU_DEV3_R_N @BASEBOARD_FAB2_LIB.BASEBOARD_FAB2(SCH_1):RST_PCIE_CPU_DEV3_R_N
  J8E3   79   IO79 SCONN80_E67482007_SM-CONN,E674A   I119 @BASEBOARD_FAB2_LIB.BASEBOARD_FAB2(SCH_1):PAGE187
 R9E12    1      A RES_0402-200.0,1%,1/16W,CHIP,GA   I153 @BASEBOARD_FAB2_LIB.BASEBOARD_FAB2(SCH_1):PAGE187

RST_PCIE_M2_DEV_AND @BASEBOARD_FAB2_LIB.BASEBOARD_FAB2(SCH_1):RST_PCIE_M2_DEV_AND
 U14E2    2   B<0> TTL1G08_SOTLF-NC7SZ08,IC,D1032C    I11 @BASEBOARD_FAB2_LIB.BASEBOARD_FAB2(SCH_1):PAGE248
 U14E3    4   Y<0> TTL1G08_SOTLF-NC7SZ08,IC,D1032C    I19 @BASEBOARD_FAB2_LIB.BASEBOARD_FAB2(SCH_1):PAGE248

RST_PCIE_M2_DEV_IC_N @BASEBOARD_FAB2_LIB.BASEBOARD_FAB2(SCH_1):RST_PCIE_M2_DEV_IC_N
 U14E2    4   Y<0> TTL1G08_SOTLF-NC7SZ08,IC,D1032C    I11 @BASEBOARD_FAB2_LIB.BASEBOARD_FAB2(SCH_1):PAGE248
  J8F1   50     50 SKT-MINI67P-41-GP_SOCKET-G4-SKA   I143 @BASEBOARD_FAB2_LIB.BASEBOARD_FAB2(SCH_1):PAGE185

RST_PCIE_M2_DEV_N @BASEBOARD_FAB2_LIB.BASEBOARD_FAB2(SCH_1):RST_PCIE_M2_DEV_N
  U8D7   R6   PB6B LCMXO2_A_256BGA-IC,H63395-001   I179 @BASEBOARD_FAB2_LIB.BASEBOARD_FAB2(SCH_1):PAGE190
 U14E2    1   A<0> TTL1G08_SOTLF-NC7SZ08,IC,D1032C    I11 @BASEBOARD_FAB2_LIB.BASEBOARD_FAB2(SCH_1):PAGE248

RST_PCIE_MIDPLANE_N @BASEBOARD_FAB2_LIB.BASEBOARD_FAB2(SCH_1):RST_PCIE_MIDPLANE_N
  U8D7   D9  PT18B LCMXO2_A_256BGA-IC,H63395-001    I59 @BASEBOARD_FAB2_LIB.BASEBOARD_FAB2(SCH_1):PAGE191
  J1F1   I5 PCIE_PERST# DM-FCI-CONN76-8R-GP-U-01_CONN-A   I134 @BASEBOARD_FAB2_LIB.BASEBOARD_FAB2(SCH_1):PAGE181

RST_PCIE_PCH_PERST_N @BASEBOARD_FAB2_LIB.BASEBOARD_FAB2(SCH_1):RST_PCIE_PCH_PERST_N
  U7C1  AH4 GPP_K10_PE_RST_N LBG_CORE_QAT_EXT_D_BGA1-IC,H91A    I34 @BASEBOARD_FAB2_LIB.BASEBOARD_FAB2(SCH_1):PAGE121
  U8D7   B1   PL1C LCMXO2_A_256BGA-IC,H63395-001   I179 @BASEBOARD_FAB2_LIB.BASEBOARD_FAB2(SCH_1):PAGE190

RST_PCIE_RISER1_PERST_N @BASEBOARD_FAB2_LIB.BASEBOARD_FAB2(SCH_1):RST_PCIE_RISER1_PERST_N
 R2U37    1      A RES_0402-0.0,5%,1/16W,CHIP,G21A   I173 @BASEBOARD_FAB2_LIB.BASEBOARD_FAB2(SCH_1):PAGE108
  U8D7   M3  PL13A LCMXO2_A_256BGA-IC,H63395-001   I179 @BASEBOARD_FAB2_LIB.BASEBOARD_FAB2(SCH_1):PAGE190

RST_PCIE_RISER1_PERST_R_N @BASEBOARD_FAB2_LIB.BASEBOARD_FAB2(SCH_1):RST_PCIE_RISER1_PERST_R_N
 R2U37    2      B RES_0402-0.0,5%,1/16W,CHIP,G21A   I173 @BASEBOARD_FAB2_LIB.BASEBOARD_FAB2(SCH_1):PAGE108
  J8G1   29   IO29 SCONN200_H68296001_SM-CONN,H68A   I258 @BASEBOARD_FAB2_LIB.BASEBOARD_FAB2(SCH_1):PAGE108

RST_PLTRST_BUF_N @BASEBOARD_FAB2_LIB.BASEBOARD_FAB2(SCH_1):RST_PLTRST_BUF_N
  J8E1    2    IO2 SCONN11_H67026001_SM-CONN,H670A    I87 @BASEBOARD_FAB2_LIB.BASEBOARD_FAB2(SCH_1):PAGE184
  U8D7  K11  PR12C LCMXO2_A_256BGA-IC,H63395-001    I59 @BASEBOARD_FAB2_LIB.BASEBOARD_FAB2(SCH_1):PAGE191
R25W74    1      A RES_0402-0.0,5%,1/16W,CHIP,G21A    I70 @BASEBOARD_FAB2_LIB.BASEBOARD_FAB2(SCH_1):PAGE146
  Q8D2    1   GATE FET_N_SOT23LF-2N7002,FET,C7925A    I15 @BASEBOARD_FAB2_LIB.BASEBOARD_FAB2(SCH_1):PAGE134
R25W141    1      A RES_0402-0.0,5%,1/16W,CHIP,G21A   I160 @BASEBOARD_FAB2_LIB.BASEBOARD_FAB2(SCH_1):PAGE145
R25W184    2      B RES_0402-0.0,5%,1/16W,CHIP,G21A   I166 @BASEBOARD_FAB2_LIB.BASEBOARD_FAB2(SCH_1):PAGE146

RST_PLTRST_BUF_N_R @BASEBOARD_FAB2_LIB.BASEBOARD_FAB2(SCH_1):RST_PLTRST_BUF_N_R
R25W62    1      A RES_0402-100.0K,1%,1/16W,CHIP,A    I31 @BASEBOARD_FAB2_LIB.BASEBOARD_FAB2(SCH_1):PAGE145
 U25W4  L20 PERST# AST2520A1-GP-GP_ASIC2-GB1-AST2A   I117 @BASEBOARD_FAB2_LIB.BASEBOARD_FAB2(SCH_1):PAGE145
R25W141    2      B RES_0402-0.0,5%,1/16W,CHIP,G21A   I160 @BASEBOARD_FAB2_LIB.BASEBOARD_FAB2(SCH_1):PAGE145

RST_PLTRST_N @BASEBOARD_FAB2_LIB.BASEBOARD_FAB2(SCH_1):RST_PLTRST_N
  U7C1 BN18 GPP_B13_PLTRST_N LBG_CORE_QAT_EXT_D_BGA1-IC,H91A   I115 @BASEBOARD_FAB2_LIB.BASEBOARD_FAB2(SCH_1):PAGE119
  Q8E1    1   GATE FET_N_SOT23LF-2N7002,FET,C7925A   I134 @BASEBOARD_FAB2_LIB.BASEBOARD_FAB2(SCH_1):PAGE136
  R1R1    1      A RES_0402-0.0,5%,1/16W,CHIP,G21A   I195 @BASEBOARD_FAB2_LIB.BASEBOARD_FAB2(SCH_1):PAGE139
  U8D7  E15   PR1B LCMXO2_A_256BGA-IC,H63395-001    I59 @BASEBOARD_FAB2_LIB.BASEBOARD_FAB2(SCH_1):PAGE191
  U6W1   16    P13 TCA9555PWR-GP_DISCRET-GC1-TCA9A   I120 @BASEBOARD_FAB2_LIB.BASEBOARD_FAB2(SCH_1):PAGE247

RST_PLTRST_SPRV_R_N @BASEBOARD_FAB2_LIB.BASEBOARD_FAB2(SCH_1):RST_PLTRST_SPRV_R_N
 EU9E1   17 PE_RST_N SPRINGVILLE_SM1-IC,G47144-004    I72 @BASEBOARD_FAB2_LIB.BASEBOARD_FAB2(SCH_1):PAGE139
  R1R1    2      B RES_0402-0.0,5%,1/16W,CHIP,G21A   I195 @BASEBOARD_FAB2_LIB.BASEBOARD_FAB2(SCH_1):PAGE139
  R9E4    2      B RES_0402-10.0K,1%,1/16W,CHIP,GA   I200 @BASEBOARD_FAB2_LIB.BASEBOARD_FAB2(SCH_1):PAGE139

RST_PLTRST_TOP_SWAP @BASEBOARD_FAB2_LIB.BASEBOARD_FAB2(SCH_1):RST_PLTRST_TOP_SWAP
  U8E3    1     OE TTL1G126_A_SOT-74HC1G126,IC,A7B   I130 @BASEBOARD_FAB2_LIB.BASEBOARD_FAB2(SCH_1):PAGE136
 R8E14    2      B RES_0402-4.75K,1%,1/16W,CHIP,GA   I133 @BASEBOARD_FAB2_LIB.BASEBOARD_FAB2(SCH_1):PAGE136
  Q8E1    3    DRN FET_N_SOT23LF-2N7002,FET,C7925A   I134 @BASEBOARD_FAB2_LIB.BASEBOARD_FAB2(SCH_1):PAGE136

RST_RSMRST_DLY @BASEBOARD_FAB2_LIB.BASEBOARD_FAB2(SCH_1):RST_RSMRST_DLY
  Q8E2    1   GATE FET_N_SOT23LF-2N7002,FET,C7925A    I13 @BASEBOARD_FAB2_LIB.BASEBOARD_FAB2(SCH_1):PAGE126
  U8D7   M1 PL12B_PCLKC3_0 LCMXO2_A_256BGA-IC,H63395-001   I179 @BASEBOARD_FAB2_LIB.BASEBOARD_FAB2(SCH_1):PAGE190

RST_RSMRST_N @BASEBOARD_FAB2_LIB.BASEBOARD_FAB2(SCH_1):RST_RSMRST_N
 R9A15    1      A RES_0402-1.00K,1%,1/16W,CHIP,GA    I60 @BASEBOARD_FAB2_LIB.BASEBOARD_FAB2(SCH_1):PAGE111
  U7C1  P15 RSMRST_N LBG_CORE_QAT_EXT_D_BGA1-IC,H91A    I73 @BASEBOARD_FAB2_LIB.BASEBOARD_FAB2(SCH_1):PAGE118
  R2R2    2      B RES_0402-33.2,1%,1/16W,CHIP,G2A   I338 @BASEBOARD_FAB2_LIB.BASEBOARD_FAB2(SCH_1):PAGE190
 R7E18    2      B RES_0402-4.75K,1%,1/16W,CHIP,GA    I55 @BASEBOARD_FAB2_LIB.BASEBOARD_FAB2(SCH_1):PAGE192
R25W181    1      A RES_0402-0.0,5%,1/16W,CHIP,G21A   I173 @BASEBOARD_FAB2_LIB.BASEBOARD_FAB2(SCH_1):PAGE147

RST_RSMRST_R_N @BASEBOARD_FAB2_LIB.BASEBOARD_FAB2(SCH_1):RST_RSMRST_R_N
  U8D7   G4   PL4D LCMXO2_A_256BGA-IC,H63395-001   I179 @BASEBOARD_FAB2_LIB.BASEBOARD_FAB2(SCH_1):PAGE190
  R2R2    1      A RES_0402-33.2,1%,1/16W,CHIP,G2A   I338 @BASEBOARD_FAB2_LIB.BASEBOARD_FAB2(SCH_1):PAGE190
 R1W26    1      A RES_0402-10.0K,1%,1/16W,EMPTY,A   I349 @BASEBOARD_FAB2_LIB.BASEBOARD_FAB2(SCH_1):PAGE190

RST_RTCRST_N @BASEBOARD_FAB2_LIB.BASEBOARD_FAB2(SCH_1):RST_RTCRST_N
  U7C1  P11 RTCRST_N LBG_CORE_QAT_EXT_D_BGA1-IC,H91A    I34 @BASEBOARD_FAB2_LIB.BASEBOARD_FAB2(SCH_1):PAGE121
 R7C11    2      B RES_0402-1.0M,1%,1/16W,EMPTY,GA    I11 @BASEBOARD_FAB2_LIB.BASEBOARD_FAB2(SCH_1):PAGE137
 R7C10    2      B RES_0402-20.0K,1%,1/16W,CHIP,GA    I13 @BASEBOARD_FAB2_LIB.BASEBOARD_FAB2(SCH_1):PAGE137
 C7C19    1      A CAP_A_0402V-1.0UF,6.3V,10%,X6SA    I14 @BASEBOARD_FAB2_LIB.BASEBOARD_FAB2(SCH_1):PAGE137
  J9G1    4    IO4 CONN12_C73564003_PIP-CONN,C735A   I128 @BASEBOARD_FAB2_LIB.BASEBOARD_FAB2(SCH_1):PAGE137

RST_SRTCRST_N @BASEBOARD_FAB2_LIB.BASEBOARD_FAB2(SCH_1):RST_SRTCRST_N
  U7C1  G18 SRTCRST_N LBG_CORE_QAT_EXT_D_BGA1-IC,H91A    I34 @BASEBOARD_FAB2_LIB.BASEBOARD_FAB2(SCH_1):PAGE121
  R3N4    2      B RES_0402-20.0K,1%,1/16W,CHIP,GA    I19 @BASEBOARD_FAB2_LIB.BASEBOARD_FAB2(SCH_1):PAGE137
 C3N32    1      A CAP_A_0402V-1.0UF,6.3V,10%,X6SA    I20 @BASEBOARD_FAB2_LIB.BASEBOARD_FAB2(SCH_1):PAGE137

RST_SYSTEM_BTN_BUF_N @BASEBOARD_FAB2_LIB.BASEBOARD_FAB2(SCH_1):RST_SYSTEM_BTN_BUF_N
  U9A3    4     2Y TC7PZ14FU-GP_DISCRET-GA1-TC7PZA    I93 @BASEBOARD_FAB2_LIB.BASEBOARD_FAB2(SCH_1):PAGE175
  R9A9    1      A RES_0402-100.0,1%,1/16W,CHIP,GA    I95 @BASEBOARD_FAB2_LIB.BASEBOARD_FAB2(SCH_1):PAGE175
 R1W30    2      B RES_0402-0.0,5%,1/16W,EMPTY,G2A   I168 @BASEBOARD_FAB2_LIB.BASEBOARD_FAB2(SCH_1):PAGE118

RST_SYSTEM_BTN_N @BASEBOARD_FAB2_LIB.BASEBOARD_FAB2(SCH_1):RST_SYSTEM_BTN_N
  U7C1 BL11 GPP_B10_SRCCLKREQ5_N LBG_CORE_QAT_EXT_D_BGA1-IC,H91A   I115 @BASEBOARD_FAB2_LIB.BASEBOARD_FAB2(SCH_1):PAGE119
  R9A9    2      B RES_0402-100.0,1%,1/16W,CHIP,GA    I95 @BASEBOARD_FAB2_LIB.BASEBOARD_FAB2(SCH_1):PAGE175
R25W145    2      B RES_0402-0.0,5%,1/16W,CHIP,G21A   I175 @BASEBOARD_FAB2_LIB.BASEBOARD_FAB2(SCH_1):PAGE145

RST_SYSTEM_BTN_R_N @BASEBOARD_FAB2_LIB.BASEBOARD_FAB2(SCH_1):RST_SYSTEM_BTN_R_N
 U25W4  B20 GPIOE0_NCTS3 AST2520A1-GP-GP_ASIC2-GB1-AST2A   I117 @BASEBOARD_FAB2_LIB.BASEBOARD_FAB2(SCH_1):PAGE145
R25W145    1      A RES_0402-0.0,5%,1/16W,CHIP,G21A   I175 @BASEBOARD_FAB2_LIB.BASEBOARD_FAB2(SCH_1):PAGE145

SATA6G_P0_RX_C_DN @BASEBOARD_FAB2_LIB.BASEBOARD_FAB2(SCH_1):SATA6G_P0_RX_C_DN
  J8A1  1B5 RXA0_DN CONN72_G97614002_A_CP-CONN,G97A   I163 @BASEBOARD_FAB2_LIB.BASEBOARD_FAB2(SCH_1):PAGE173
 C2L17    2      B CAP_A_0402V-0.01UF,25V,10%,X7RA   I174 @BASEBOARD_FAB2_LIB.BASEBOARD_FAB2(SCH_1):PAGE173

SATA6G_P0_RX_C_DP @BASEBOARD_FAB2_LIB.BASEBOARD_FAB2(SCH_1):SATA6G_P0_RX_C_DP
  J8A1  1B4 RXA0_DP CONN72_G97614002_A_CP-CONN,G97A   I163 @BASEBOARD_FAB2_LIB.BASEBOARD_FAB2(SCH_1):PAGE173
 C2L19    2      B CAP_A_0402V-0.01UF,25V,10%,X7RA   I172 @BASEBOARD_FAB2_LIB.BASEBOARD_FAB2(SCH_1):PAGE173

SATA6G_P0_TX_C_DN @BASEBOARD_FAB2_LIB.BASEBOARD_FAB2(SCH_1):SATA6G_P0_TX_C_DN
  J8A1  1D5 TXA0_DN CONN72_G97614002_A_CP-CONN,G97A   I163 @BASEBOARD_FAB2_LIB.BASEBOARD_FAB2(SCH_1):PAGE173
 C2L40    1      A CAP_A_0402V-0.01UF,25V,10%,X7RA   I220 @BASEBOARD_FAB2_LIB.BASEBOARD_FAB2(SCH_1):PAGE173

SATA6G_P0_TX_C_DP @BASEBOARD_FAB2_LIB.BASEBOARD_FAB2(SCH_1):SATA6G_P0_TX_C_DP
  J8A1  1D4 TXA0_DP CONN72_G97614002_A_CP-CONN,G97A   I163 @BASEBOARD_FAB2_LIB.BASEBOARD_FAB2(SCH_1):PAGE173
 C2L39    1      A CAP_A_0402V-0.01UF,25V,10%,X7RA   I221 @BASEBOARD_FAB2_LIB.BASEBOARD_FAB2(SCH_1):PAGE173

SATA6G_P1_RX_C_DN @BASEBOARD_FAB2_LIB.BASEBOARD_FAB2(SCH_1):SATA6G_P1_RX_C_DN
  J8A1  1A5 RXA1_DN CONN72_G97614002_A_CP-CONN,G97A   I163 @BASEBOARD_FAB2_LIB.BASEBOARD_FAB2(SCH_1):PAGE173
  C2L6    2      B CAP_A_0402V-0.01UF,25V,10%,X7RA   I166 @BASEBOARD_FAB2_LIB.BASEBOARD_FAB2(SCH_1):PAGE173

SATA6G_P1_RX_C_DP @BASEBOARD_FAB2_LIB.BASEBOARD_FAB2(SCH_1):SATA6G_P1_RX_C_DP
  J8A1  1A4 RXA1_DP CONN72_G97614002_A_CP-CONN,G97A   I163 @BASEBOARD_FAB2_LIB.BASEBOARD_FAB2(SCH_1):PAGE173
 C2L10    2      B CAP_A_0402V-0.01UF,25V,10%,X7RA   I173 @BASEBOARD_FAB2_LIB.BASEBOARD_FAB2(SCH_1):PAGE173

SATA6G_P1_TX_C_DN @BASEBOARD_FAB2_LIB.BASEBOARD_FAB2(SCH_1):SATA6G_P1_TX_C_DN
  J8A1  1C5 TXA1_DN CONN72_G97614002_A_CP-CONN,G97A   I163 @BASEBOARD_FAB2_LIB.BASEBOARD_FAB2(SCH_1):PAGE173
 C2L44    1      A CAP_A_0402V-0.01UF,25V,10%,X7RA   I228 @BASEBOARD_FAB2_LIB.BASEBOARD_FAB2(SCH_1):PAGE173

SATA6G_P1_TX_C_DP @BASEBOARD_FAB2_LIB.BASEBOARD_FAB2(SCH_1):SATA6G_P1_TX_C_DP
  J8A1  1C4 TXA1_DP CONN72_G97614002_A_CP-CONN,G97A   I163 @BASEBOARD_FAB2_LIB.BASEBOARD_FAB2(SCH_1):PAGE173
 C2L43    1      A CAP_A_0402V-0.01UF,25V,10%,X7RA   I222 @BASEBOARD_FAB2_LIB.BASEBOARD_FAB2(SCH_1):PAGE173

SATA6G_P2_RX_C_DN @BASEBOARD_FAB2_LIB.BASEBOARD_FAB2(SCH_1):SATA6G_P2_RX_C_DN
  J8A1  1B8 RXA2_DN CONN72_G97614002_A_CP-CONN,G97A   I163 @BASEBOARD_FAB2_LIB.BASEBOARD_FAB2(SCH_1):PAGE173
 C2L13    2      B CAP_A_0402V-0.01UF,25V,10%,X7RA   I165 @BASEBOARD_FAB2_LIB.BASEBOARD_FAB2(SCH_1):PAGE173

SATA6G_P2_RX_C_DP @BASEBOARD_FAB2_LIB.BASEBOARD_FAB2(SCH_1):SATA6G_P2_RX_C_DP
  J8A1  1B7 RXA2_DP CONN72_G97614002_A_CP-CONN,G97A   I163 @BASEBOARD_FAB2_LIB.BASEBOARD_FAB2(SCH_1):PAGE173
 C2L15    2      B CAP_A_0402V-0.01UF,25V,10%,X7RA   I191 @BASEBOARD_FAB2_LIB.BASEBOARD_FAB2(SCH_1):PAGE173

SATA6G_P2_TX_C_DN @BASEBOARD_FAB2_LIB.BASEBOARD_FAB2(SCH_1):SATA6G_P2_TX_C_DN
  J8A1  1D8 TXA2_DN CONN72_G97614002_A_CP-CONN,G97A   I163 @BASEBOARD_FAB2_LIB.BASEBOARD_FAB2(SCH_1):PAGE173
 C2L42    1      A CAP_A_0402V-0.01UF,25V,10%,X7RA   I233 @BASEBOARD_FAB2_LIB.BASEBOARD_FAB2(SCH_1):PAGE173

SATA6G_P2_TX_C_DP @BASEBOARD_FAB2_LIB.BASEBOARD_FAB2(SCH_1):SATA6G_P2_TX_C_DP
  J8A1  1D7 TXA2_DP CONN72_G97614002_A_CP-CONN,G97A   I163 @BASEBOARD_FAB2_LIB.BASEBOARD_FAB2(SCH_1):PAGE173
 C2L41    1      A CAP_A_0402V-0.01UF,25V,10%,X7RA   I242 @BASEBOARD_FAB2_LIB.BASEBOARD_FAB2(SCH_1):PAGE173

SATA6G_P3_RX_C_DN @BASEBOARD_FAB2_LIB.BASEBOARD_FAB2(SCH_1):SATA6G_P3_RX_C_DN
  J8A1  1A8 RXA3_DN CONN72_G97614002_A_CP-CONN,G97A   I163 @BASEBOARD_FAB2_LIB.BASEBOARD_FAB2(SCH_1):PAGE173
  C2L3    2      B CAP_A_0402V-0.01UF,25V,10%,X7RA   I194 @BASEBOARD_FAB2_LIB.BASEBOARD_FAB2(SCH_1):PAGE173

SATA6G_P3_RX_C_DP @BASEBOARD_FAB2_LIB.BASEBOARD_FAB2(SCH_1):SATA6G_P3_RX_C_DP
  J8A1  1A7 RXA3_DP CONN72_G97614002_A_CP-CONN,G97A   I163 @BASEBOARD_FAB2_LIB.BASEBOARD_FAB2(SCH_1):PAGE173
  C2L4    2      B CAP_A_0402V-0.01UF,25V,10%,X7RA   I192 @BASEBOARD_FAB2_LIB.BASEBOARD_FAB2(SCH_1):PAGE173

SATA6G_P3_TX_C_DN @BASEBOARD_FAB2_LIB.BASEBOARD_FAB2(SCH_1):SATA6G_P3_TX_C_DN
  J8A1  1C8 TXA3_DN CONN72_G97614002_A_CP-CONN,G97A   I163 @BASEBOARD_FAB2_LIB.BASEBOARD_FAB2(SCH_1):PAGE173
 C2L22    1      A CAP_A_0402V-0.01UF,25V,10%,X7RA   I234 @BASEBOARD_FAB2_LIB.BASEBOARD_FAB2(SCH_1):PAGE173

SATA6G_P3_TX_C_DP @BASEBOARD_FAB2_LIB.BASEBOARD_FAB2(SCH_1):SATA6G_P3_TX_C_DP
  J8A1  1C7 TXA3_DP CONN72_G97614002_A_CP-CONN,G97A   I163 @BASEBOARD_FAB2_LIB.BASEBOARD_FAB2(SCH_1):PAGE173
 C2L23    1      A CAP_A_0402V-0.01UF,25V,10%,X7RA   I241 @BASEBOARD_FAB2_LIB.BASEBOARD_FAB2(SCH_1):PAGE173

SATA6G_P4_RX_C_DN @BASEBOARD_FAB2_LIB.BASEBOARD_FAB2(SCH_1):SATA6G_P4_RX_C_DN
  J8A1  2B5 RXB0_DN CONN72_G97614002_A_CP-CONN,G97A   I163 @BASEBOARD_FAB2_LIB.BASEBOARD_FAB2(SCH_1):PAGE173
 C2L18    2      B CAP_A_0402V-0.01UF,25V,10%,X7RA   I197 @BASEBOARD_FAB2_LIB.BASEBOARD_FAB2(SCH_1):PAGE173

SATA6G_P4_RX_C_DP @BASEBOARD_FAB2_LIB.BASEBOARD_FAB2(SCH_1):SATA6G_P4_RX_C_DP
  J8A1  2B4 RXB0_DP CONN72_G97614002_A_CP-CONN,G97A   I163 @BASEBOARD_FAB2_LIB.BASEBOARD_FAB2(SCH_1):PAGE173
 C2L20    2      B CAP_A_0402V-0.01UF,25V,10%,X7RA   I195 @BASEBOARD_FAB2_LIB.BASEBOARD_FAB2(SCH_1):PAGE173

SATA6G_P4_TX_C_DN @BASEBOARD_FAB2_LIB.BASEBOARD_FAB2(SCH_1):SATA6G_P4_TX_C_DN
  J8A1  2D5 TXB0_DN CONN72_G97614002_A_CP-CONN,G97A   I163 @BASEBOARD_FAB2_LIB.BASEBOARD_FAB2(SCH_1):PAGE173
 C2L37    1      A CAP_A_0402V-0.01UF,25V,10%,X7RA   I238 @BASEBOARD_FAB2_LIB.BASEBOARD_FAB2(SCH_1):PAGE173

SATA6G_P4_TX_C_DP @BASEBOARD_FAB2_LIB.BASEBOARD_FAB2(SCH_1):SATA6G_P4_TX_C_DP
  J8A1  2D4 TXB0_DP CONN72_G97614002_A_CP-CONN,G97A   I163 @BASEBOARD_FAB2_LIB.BASEBOARD_FAB2(SCH_1):PAGE173
 C2L47    1      A CAP_A_0402V-0.01UF,25V,10%,X7RA   I239 @BASEBOARD_FAB2_LIB.BASEBOARD_FAB2(SCH_1):PAGE173

SATA6G_P5_RX_C_DN @BASEBOARD_FAB2_LIB.BASEBOARD_FAB2(SCH_1):SATA6G_P5_RX_C_DN
  J8A1  2A5 RXB1_DN CONN72_G97614002_A_CP-CONN,G97A   I163 @BASEBOARD_FAB2_LIB.BASEBOARD_FAB2(SCH_1):PAGE173
  C2L9    2      B CAP_A_0402V-0.01UF,25V,10%,X7RA   I207 @BASEBOARD_FAB2_LIB.BASEBOARD_FAB2(SCH_1):PAGE173

SATA6G_P5_RX_C_DP @BASEBOARD_FAB2_LIB.BASEBOARD_FAB2(SCH_1):SATA6G_P5_RX_C_DP
  J8A1  2A4 RXB1_DP CONN72_G97614002_A_CP-CONN,G97A   I163 @BASEBOARD_FAB2_LIB.BASEBOARD_FAB2(SCH_1):PAGE173
 C2L12    2      B CAP_A_0402V-0.01UF,25V,10%,X7RA   I196 @BASEBOARD_FAB2_LIB.BASEBOARD_FAB2(SCH_1):PAGE173

SATA6G_P5_TX_C_DN @BASEBOARD_FAB2_LIB.BASEBOARD_FAB2(SCH_1):SATA6G_P5_TX_C_DN
  J8A1  2C5 TXB1_DN CONN72_G97614002_A_CP-CONN,G97A   I163 @BASEBOARD_FAB2_LIB.BASEBOARD_FAB2(SCH_1):PAGE173
 C2L26    1      A CAP_A_0402V-0.01UF,25V,10%,X7RA   I255 @BASEBOARD_FAB2_LIB.BASEBOARD_FAB2(SCH_1):PAGE173

SATA6G_P5_TX_C_DP @BASEBOARD_FAB2_LIB.BASEBOARD_FAB2(SCH_1):SATA6G_P5_TX_C_DP
  J8A1  2C4 TXB1_DP CONN72_G97614002_A_CP-CONN,G97A   I163 @BASEBOARD_FAB2_LIB.BASEBOARD_FAB2(SCH_1):PAGE173
 C2L27    1      A CAP_A_0402V-0.01UF,25V,10%,X7RA   I240 @BASEBOARD_FAB2_LIB.BASEBOARD_FAB2(SCH_1):PAGE173

SATA6G_P6_RX_C_DN @BASEBOARD_FAB2_LIB.BASEBOARD_FAB2(SCH_1):SATA6G_P6_RX_C_DN
  J8A1  2B8 RXB2_DN CONN72_G97614002_A_CP-CONN,G97A   I163 @BASEBOARD_FAB2_LIB.BASEBOARD_FAB2(SCH_1):PAGE173
 C2L14    2      B CAP_A_0402V-0.01UF,25V,10%,X7RA   I208 @BASEBOARD_FAB2_LIB.BASEBOARD_FAB2(SCH_1):PAGE173

SATA6G_P6_RX_C_DP @BASEBOARD_FAB2_LIB.BASEBOARD_FAB2(SCH_1):SATA6G_P6_RX_C_DP
  J8A1  2B7 RXB2_DP CONN72_G97614002_A_CP-CONN,G97A   I163 @BASEBOARD_FAB2_LIB.BASEBOARD_FAB2(SCH_1):PAGE173
 C2L16    2      B CAP_A_0402V-0.01UF,25V,10%,X7RA   I205 @BASEBOARD_FAB2_LIB.BASEBOARD_FAB2(SCH_1):PAGE173

SATA6G_P6_TX_C_DN @BASEBOARD_FAB2_LIB.BASEBOARD_FAB2(SCH_1):SATA6G_P6_TX_C_DN
  J8A1  2D8 TXB2_DN CONN72_G97614002_A_CP-CONN,G97A   I163 @BASEBOARD_FAB2_LIB.BASEBOARD_FAB2(SCH_1):PAGE173
 C2L38    1      A CAP_A_0402V-0.01UF,25V,10%,X7RA   I256 @BASEBOARD_FAB2_LIB.BASEBOARD_FAB2(SCH_1):PAGE173

SATA6G_P6_TX_C_DP @BASEBOARD_FAB2_LIB.BASEBOARD_FAB2(SCH_1):SATA6G_P6_TX_C_DP
  J8A1  2D7 TXB2_DP CONN72_G97614002_A_CP-CONN,G97A   I163 @BASEBOARD_FAB2_LIB.BASEBOARD_FAB2(SCH_1):PAGE173
 C2L48    1      A CAP_A_0402V-0.01UF,25V,10%,X7RA   I257 @BASEBOARD_FAB2_LIB.BASEBOARD_FAB2(SCH_1):PAGE173

SATA6G_P7_RX_C_DN @BASEBOARD_FAB2_LIB.BASEBOARD_FAB2(SCH_1):SATA6G_P7_RX_C_DN
  J8A1  2A8 RXB3_DN CONN72_G97614002_A_CP-CONN,G97A   I163 @BASEBOARD_FAB2_LIB.BASEBOARD_FAB2(SCH_1):PAGE173
  C2L5    2      B CAP_A_0402V-0.01UF,25V,10%,X7RA   I209 @BASEBOARD_FAB2_LIB.BASEBOARD_FAB2(SCH_1):PAGE173

SATA6G_P7_RX_C_DP @BASEBOARD_FAB2_LIB.BASEBOARD_FAB2(SCH_1):SATA6G_P7_RX_C_DP
  J8A1  2A7 RXB3_DP CONN72_G97614002_A_CP-CONN,G97A   I163 @BASEBOARD_FAB2_LIB.BASEBOARD_FAB2(SCH_1):PAGE173
  C2L7    2      B CAP_A_0402V-0.01UF,25V,10%,X7RA   I206 @BASEBOARD_FAB2_LIB.BASEBOARD_FAB2(SCH_1):PAGE173

SATA6G_P7_TX_C_DN @BASEBOARD_FAB2_LIB.BASEBOARD_FAB2(SCH_1):SATA6G_P7_TX_C_DN
  J8A1  2C8 TXB3_DN CONN72_G97614002_A_CP-CONN,G97A   I163 @BASEBOARD_FAB2_LIB.BASEBOARD_FAB2(SCH_1):PAGE173
 C2L21    1      A CAP_A_0402V-0.01UF,25V,10%,X7RA   I259 @BASEBOARD_FAB2_LIB.BASEBOARD_FAB2(SCH_1):PAGE173

SATA6G_P7_TX_C_DP @BASEBOARD_FAB2_LIB.BASEBOARD_FAB2(SCH_1):SATA6G_P7_TX_C_DP
  J8A1  2C7 TXB3_DP CONN72_G97614002_A_CP-CONN,G97A   I163 @BASEBOARD_FAB2_LIB.BASEBOARD_FAB2(SCH_1):PAGE173
 C2L24    1      A CAP_A_0402V-0.01UF,25V,10%,X7RA   I258 @BASEBOARD_FAB2_LIB.BASEBOARD_FAB2(SCH_1):PAGE173

SATA6G_PCH_PCIE_UP_SATA_RXN<0> @BASEBOARD_FAB2_LIB.BASEBOARD_FAB2(SCH_1):SATA6G_PCH_PCIE_UP_SATA_RXN(0)
  U7C1 AR61 PCIE12_UP0_SATA0_RXN LBG_CORE_QAT_EXT_D_BGA1-IC,H91A   I220 @BASEBOARD_FAB2_LIB.BASEBOARD_FAB2(SCH_1):PAGE116
 C2L17    1      A CAP_A_0402V-0.01UF,25V,10%,X7RA   I174 @BASEBOARD_FAB2_LIB.BASEBOARD_FAB2(SCH_1):PAGE173

SATA6G_PCH_PCIE_UP_SATA_RXN<1> @BASEBOARD_FAB2_LIB.BASEBOARD_FAB2(SCH_1):SATA6G_PCH_PCIE_UP_SATA_RXN(1)
  U7C1 AL66 PCIE13_UP1_SATA1_RXN LBG_CORE_QAT_EXT_D_BGA1-IC,H91A   I220 @BASEBOARD_FAB2_LIB.BASEBOARD_FAB2(SCH_1):PAGE116
  C2L6    1      A CAP_A_0402V-0.01UF,25V,10%,X7RA   I166 @BASEBOARD_FAB2_LIB.BASEBOARD_FAB2(SCH_1):PAGE173

SATA6G_PCH_PCIE_UP_SATA_RXN<2> @BASEBOARD_FAB2_LIB.BASEBOARD_FAB2(SCH_1):SATA6G_PCH_PCIE_UP_SATA_RXN(2)
  U7C1 AK65 PCIE14_UP2_SATA2_RXN LBG_CORE_QAT_EXT_D_BGA1-IC,H91A   I220 @BASEBOARD_FAB2_LIB.BASEBOARD_FAB2(SCH_1):PAGE116
 C2L13    1      A CAP_A_0402V-0.01UF,25V,10%,X7RA   I165 @BASEBOARD_FAB2_LIB.BASEBOARD_FAB2(SCH_1):PAGE173

SATA6G_PCH_PCIE_UP_SATA_RXN<3> @BASEBOARD_FAB2_LIB.BASEBOARD_FAB2(SCH_1):SATA6G_PCH_PCIE_UP_SATA_RXN(3)
  U7C1 AP63 PCIE15_UP3_SATA3_RXN LBG_CORE_QAT_EXT_D_BGA1-IC,H91A   I220 @BASEBOARD_FAB2_LIB.BASEBOARD_FAB2(SCH_1):PAGE116
  C2L3    1      A CAP_A_0402V-0.01UF,25V,10%,X7RA   I194 @BASEBOARD_FAB2_LIB.BASEBOARD_FAB2(SCH_1):PAGE173

SATA6G_PCH_PCIE_UP_SATA_RXN<4> @BASEBOARD_FAB2_LIB.BASEBOARD_FAB2(SCH_1):SATA6G_PCH_PCIE_UP_SATA_RXN(4)
  U7C1 AF65 PCIE16_UP4_SATA4_RXN LBG_CORE_QAT_EXT_D_BGA1-IC,H91A   I220 @BASEBOARD_FAB2_LIB.BASEBOARD_FAB2(SCH_1):PAGE116
 C2L18    1      A CAP_A_0402V-0.01UF,25V,10%,X7RA   I197 @BASEBOARD_FAB2_LIB.BASEBOARD_FAB2(SCH_1):PAGE173

SATA6G_PCH_PCIE_UP_SATA_RXN<5> @BASEBOARD_FAB2_LIB.BASEBOARD_FAB2(SCH_1):SATA6G_PCH_PCIE_UP_SATA_RXN(5)
  U7C1 AH61 PCIE17_UP5_SATA5_RXN LBG_CORE_QAT_EXT_D_BGA1-IC,H91A   I220 @BASEBOARD_FAB2_LIB.BASEBOARD_FAB2(SCH_1):PAGE116
  C2L9    1      A CAP_A_0402V-0.01UF,25V,10%,X7RA   I207 @BASEBOARD_FAB2_LIB.BASEBOARD_FAB2(SCH_1):PAGE173

SATA6G_PCH_PCIE_UP_SATA_RXN<6> @BASEBOARD_FAB2_LIB.BASEBOARD_FAB2(SCH_1):SATA6G_PCH_PCIE_UP_SATA_RXN(6)
  U7C1 AP59 PCIE18_UP6_SATA6_RXN LBG_CORE_QAT_EXT_D_BGA1-IC,H91A   I220 @BASEBOARD_FAB2_LIB.BASEBOARD_FAB2(SCH_1):PAGE116
 C2L14    1      A CAP_A_0402V-0.01UF,25V,10%,X7RA   I208 @BASEBOARD_FAB2_LIB.BASEBOARD_FAB2(SCH_1):PAGE173

SATA6G_PCH_PCIE_UP_SATA_RXN<7> @BASEBOARD_FAB2_LIB.BASEBOARD_FAB2(SCH_1):SATA6G_PCH_PCIE_UP_SATA_RXN(7)
  U7C1 AA61 PCIE19_UP7_SATA7_RXN LBG_CORE_QAT_EXT_D_BGA1-IC,H91A   I220 @BASEBOARD_FAB2_LIB.BASEBOARD_FAB2(SCH_1):PAGE116
  C2L5    1      A CAP_A_0402V-0.01UF,25V,10%,X7RA   I209 @BASEBOARD_FAB2_LIB.BASEBOARD_FAB2(SCH_1):PAGE173

SATA6G_PCH_PCIE_UP_SATA_RXP<0> @BASEBOARD_FAB2_LIB.BASEBOARD_FAB2(SCH_1):SATA6G_PCH_PCIE_UP_SATA_RXP(0)
  U7C1 AT63 PCIE12_UP0_SATA0_RXP LBG_CORE_QAT_EXT_D_BGA1-IC,H91A   I220 @BASEBOARD_FAB2_LIB.BASEBOARD_FAB2(SCH_1):PAGE116
 C2L19    1      A CAP_A_0402V-0.01UF,25V,10%,X7RA   I172 @BASEBOARD_FAB2_LIB.BASEBOARD_FAB2(SCH_1):PAGE173

SATA6G_PCH_PCIE_UP_SATA_RXP<1> @BASEBOARD_FAB2_LIB.BASEBOARD_FAB2(SCH_1):SATA6G_PCH_PCIE_UP_SATA_RXP(1)
  U7C1 AN65 PCIE13_UP1_SATA1_RXP LBG_CORE_QAT_EXT_D_BGA1-IC,H91A   I220 @BASEBOARD_FAB2_LIB.BASEBOARD_FAB2(SCH_1):PAGE116
 C2L10    1      A CAP_A_0402V-0.01UF,25V,10%,X7RA   I173 @BASEBOARD_FAB2_LIB.BASEBOARD_FAB2(SCH_1):PAGE173

SATA6G_PCH_PCIE_UP_SATA_RXP<2> @BASEBOARD_FAB2_LIB.BASEBOARD_FAB2(SCH_1):SATA6G_PCH_PCIE_UP_SATA_RXP(2)
  U7C1 AJ63 PCIE14_UP2_SATA2_RXP LBG_CORE_QAT_EXT_D_BGA1-IC,H91A   I220 @BASEBOARD_FAB2_LIB.BASEBOARD_FAB2(SCH_1):PAGE116
 C2L15    1      A CAP_A_0402V-0.01UF,25V,10%,X7RA   I191 @BASEBOARD_FAB2_LIB.BASEBOARD_FAB2(SCH_1):PAGE173

SATA6G_PCH_PCIE_UP_SATA_RXP<3> @BASEBOARD_FAB2_LIB.BASEBOARD_FAB2(SCH_1):SATA6G_PCH_PCIE_UP_SATA_RXP(3)
  U7C1 AL63 PCIE15_UP3_SATA3_RXP LBG_CORE_QAT_EXT_D_BGA1-IC,H91A   I220 @BASEBOARD_FAB2_LIB.BASEBOARD_FAB2(SCH_1):PAGE116
  C2L4    1      A CAP_A_0402V-0.01UF,25V,10%,X7RA   I192 @BASEBOARD_FAB2_LIB.BASEBOARD_FAB2(SCH_1):PAGE173

SATA6G_PCH_PCIE_UP_SATA_RXP<4> @BASEBOARD_FAB2_LIB.BASEBOARD_FAB2(SCH_1):SATA6G_PCH_PCIE_UP_SATA_RXP(4)
  U7C1 AH65 PCIE16_UP4_SATA4_RXP LBG_CORE_QAT_EXT_D_BGA1-IC,H91A   I220 @BASEBOARD_FAB2_LIB.BASEBOARD_FAB2(SCH_1):PAGE116
 C2L20    1      A CAP_A_0402V-0.01UF,25V,10%,X7RA   I195 @BASEBOARD_FAB2_LIB.BASEBOARD_FAB2(SCH_1):PAGE173

SATA6G_PCH_PCIE_UP_SATA_RXP<5> @BASEBOARD_FAB2_LIB.BASEBOARD_FAB2(SCH_1):SATA6G_PCH_PCIE_UP_SATA_RXP(5)
  U7C1 AG63 PCIE17_UP5_SATA5_RXP LBG_CORE_QAT_EXT_D_BGA1-IC,H91A   I220 @BASEBOARD_FAB2_LIB.BASEBOARD_FAB2(SCH_1):PAGE116
 C2L12    1      A CAP_A_0402V-0.01UF,25V,10%,X7RA   I196 @BASEBOARD_FAB2_LIB.BASEBOARD_FAB2(SCH_1):PAGE173

SATA6G_PCH_PCIE_UP_SATA_RXP<6> @BASEBOARD_FAB2_LIB.BASEBOARD_FAB2(SCH_1):SATA6G_PCH_PCIE_UP_SATA_RXP(6)
  U7C1 AN61 PCIE18_UP6_SATA6_RXP LBG_CORE_QAT_EXT_D_BGA1-IC,H91A   I220 @BASEBOARD_FAB2_LIB.BASEBOARD_FAB2(SCH_1):PAGE116
 C2L16    1      A CAP_A_0402V-0.01UF,25V,10%,X7RA   I205 @BASEBOARD_FAB2_LIB.BASEBOARD_FAB2(SCH_1):PAGE173

SATA6G_PCH_PCIE_UP_SATA_RXP<7> @BASEBOARD_FAB2_LIB.BASEBOARD_FAB2(SCH_1):SATA6G_PCH_PCIE_UP_SATA_RXP(7)
  U7C1 AD61 PCIE19_UP7_SATA7_RXP LBG_CORE_QAT_EXT_D_BGA1-IC,H91A   I220 @BASEBOARD_FAB2_LIB.BASEBOARD_FAB2(SCH_1):PAGE116
  C2L7    1      A CAP_A_0402V-0.01UF,25V,10%,X7RA   I206 @BASEBOARD_FAB2_LIB.BASEBOARD_FAB2(SCH_1):PAGE173

SATA6G_PCH_PCIE_UP_SATA_TXN<0> @BASEBOARD_FAB2_LIB.BASEBOARD_FAB2(SCH_1):SATA6G_PCH_PCIE_UP_SATA_TXN(0)
  U7C1  W69 PCIE12_UP0_SATA0_TXN LBG_CORE_QAT_EXT_D_BGA1-IC,H91A   I220 @BASEBOARD_FAB2_LIB.BASEBOARD_FAB2(SCH_1):PAGE116
 C2L40    2      B CAP_A_0402V-0.01UF,25V,10%,X7RA   I220 @BASEBOARD_FAB2_LIB.BASEBOARD_FAB2(SCH_1):PAGE173

SATA6G_PCH_PCIE_UP_SATA_TXN<1> @BASEBOARD_FAB2_LIB.BASEBOARD_FAB2(SCH_1):SATA6G_PCH_PCIE_UP_SATA_TXN(1)
  U7C1  V70 PCIE13_UP1_SATA1_TXN LBG_CORE_QAT_EXT_D_BGA1-IC,H91A   I220 @BASEBOARD_FAB2_LIB.BASEBOARD_FAB2(SCH_1):PAGE116
 C2L44    2      B CAP_A_0402V-0.01UF,25V,10%,X7RA   I228 @BASEBOARD_FAB2_LIB.BASEBOARD_FAB2(SCH_1):PAGE173

SATA6G_PCH_PCIE_UP_SATA_TXN<2> @BASEBOARD_FAB2_LIB.BASEBOARD_FAB2(SCH_1):SATA6G_PCH_PCIE_UP_SATA_TXN(2)
  U7C1  T69 PCIE14_UP2_SATA2_TXN LBG_CORE_QAT_EXT_D_BGA1-IC,H91A   I220 @BASEBOARD_FAB2_LIB.BASEBOARD_FAB2(SCH_1):PAGE116
 C2L42    2      B CAP_A_0402V-0.01UF,25V,10%,X7RA   I233 @BASEBOARD_FAB2_LIB.BASEBOARD_FAB2(SCH_1):PAGE173

SATA6G_PCH_PCIE_UP_SATA_TXN<3> @BASEBOARD_FAB2_LIB.BASEBOARD_FAB2(SCH_1):SATA6G_PCH_PCIE_UP_SATA_TXN(3)
  U7C1  R70 PCIE15_UP3_SATA3_TXN LBG_CORE_QAT_EXT_D_BGA1-IC,H91A   I220 @BASEBOARD_FAB2_LIB.BASEBOARD_FAB2(SCH_1):PAGE116
 C2L22    2      B CAP_A_0402V-0.01UF,25V,10%,X7RA   I234 @BASEBOARD_FAB2_LIB.BASEBOARD_FAB2(SCH_1):PAGE173

SATA6G_PCH_PCIE_UP_SATA_TXN<4> @BASEBOARD_FAB2_LIB.BASEBOARD_FAB2(SCH_1):SATA6G_PCH_PCIE_UP_SATA_TXN(4)
  U7C1  P69 PCIE16_UP4_SATA4_TXN LBG_CORE_QAT_EXT_D_BGA1-IC,H91A   I220 @BASEBOARD_FAB2_LIB.BASEBOARD_FAB2(SCH_1):PAGE116
 C2L37    2      B CAP_A_0402V-0.01UF,25V,10%,X7RA   I238 @BASEBOARD_FAB2_LIB.BASEBOARD_FAB2(SCH_1):PAGE173

SATA6G_PCH_PCIE_UP_SATA_TXN<5> @BASEBOARD_FAB2_LIB.BASEBOARD_FAB2(SCH_1):SATA6G_PCH_PCIE_UP_SATA_TXN(5)
  U7C1  N70 PCIE17_UP5_SATA5_TXN LBG_CORE_QAT_EXT_D_BGA1-IC,H91A   I220 @BASEBOARD_FAB2_LIB.BASEBOARD_FAB2(SCH_1):PAGE116
 C2L26    2      B CAP_A_0402V-0.01UF,25V,10%,X7RA   I255 @BASEBOARD_FAB2_LIB.BASEBOARD_FAB2(SCH_1):PAGE173

SATA6G_PCH_PCIE_UP_SATA_TXN<6> @BASEBOARD_FAB2_LIB.BASEBOARD_FAB2(SCH_1):SATA6G_PCH_PCIE_UP_SATA_TXN(6)
  U7C1  M69 PCIE18_UP6_SATA6_TXN LBG_CORE_QAT_EXT_D_BGA1-IC,H91A   I220 @BASEBOARD_FAB2_LIB.BASEBOARD_FAB2(SCH_1):PAGE116
 C2L38    2      B CAP_A_0402V-0.01UF,25V,10%,X7RA   I256 @BASEBOARD_FAB2_LIB.BASEBOARD_FAB2(SCH_1):PAGE173

SATA6G_PCH_PCIE_UP_SATA_TXN<7> @BASEBOARD_FAB2_LIB.BASEBOARD_FAB2(SCH_1):SATA6G_PCH_PCIE_UP_SATA_TXN(7)
  U7C1  L70 PCIE19_UP7_SATA7_TXN LBG_CORE_QAT_EXT_D_BGA1-IC,H91A   I220 @BASEBOARD_FAB2_LIB.BASEBOARD_FAB2(SCH_1):PAGE116
 C2L21    2      B CAP_A_0402V-0.01UF,25V,10%,X7RA   I259 @BASEBOARD_FAB2_LIB.BASEBOARD_FAB2(SCH_1):PAGE173

SATA6G_PCH_PCIE_UP_SATA_TXP<0> @BASEBOARD_FAB2_LIB.BASEBOARD_FAB2(SCH_1):SATA6G_PCH_PCIE_UP_SATA_TXP(0)
  U7C1  W71 PCIE12_UP0_SATA0_TXP LBG_CORE_QAT_EXT_D_BGA1-IC,H91A   I220 @BASEBOARD_FAB2_LIB.BASEBOARD_FAB2(SCH_1):PAGE116
 C2L39    2      B CAP_A_0402V-0.01UF,25V,10%,X7RA   I221 @BASEBOARD_FAB2_LIB.BASEBOARD_FAB2(SCH_1):PAGE173

SATA6G_PCH_PCIE_UP_SATA_TXP<1> @BASEBOARD_FAB2_LIB.BASEBOARD_FAB2(SCH_1):SATA6G_PCH_PCIE_UP_SATA_TXP(1)
  U7C1  V72 PCIE13_UP1_SATA1_TXP LBG_CORE_QAT_EXT_D_BGA1-IC,H91A   I220 @BASEBOARD_FAB2_LIB.BASEBOARD_FAB2(SCH_1):PAGE116
 C2L43    2      B CAP_A_0402V-0.01UF,25V,10%,X7RA   I222 @BASEBOARD_FAB2_LIB.BASEBOARD_FAB2(SCH_1):PAGE173

SATA6G_PCH_PCIE_UP_SATA_TXP<2> @BASEBOARD_FAB2_LIB.BASEBOARD_FAB2(SCH_1):SATA6G_PCH_PCIE_UP_SATA_TXP(2)
  U7C1  T71 PCIE14_UP2_SATA2_TXP LBG_CORE_QAT_EXT_D_BGA1-IC,H91A   I220 @BASEBOARD_FAB2_LIB.BASEBOARD_FAB2(SCH_1):PAGE116
 C2L41    2      B CAP_A_0402V-0.01UF,25V,10%,X7RA   I242 @BASEBOARD_FAB2_LIB.BASEBOARD_FAB2(SCH_1):PAGE173

SATA6G_PCH_PCIE_UP_SATA_TXP<3> @BASEBOARD_FAB2_LIB.BASEBOARD_FAB2(SCH_1):SATA6G_PCH_PCIE_UP_SATA_TXP(3)
  U7C1  R72 PCIE15_UP3_SATA3_TXP LBG_CORE_QAT_EXT_D_BGA1-IC,H91A   I220 @BASEBOARD_FAB2_LIB.BASEBOARD_FAB2(SCH_1):PAGE116
 C2L23    2      B CAP_A_0402V-0.01UF,25V,10%,X7RA   I241 @BASEBOARD_FAB2_LIB.BASEBOARD_FAB2(SCH_1):PAGE173

SATA6G_PCH_PCIE_UP_SATA_TXP<4> @BASEBOARD_FAB2_LIB.BASEBOARD_FAB2(SCH_1):SATA6G_PCH_PCIE_UP_SATA_TXP(4)
  U7C1  P71 PCIE16_UP4_SATA4_TXP LBG_CORE_QAT_EXT_D_BGA1-IC,H91A   I220 @BASEBOARD_FAB2_LIB.BASEBOARD_FAB2(SCH_1):PAGE116
 C2L47    2      B CAP_A_0402V-0.01UF,25V,10%,X7RA   I239 @BASEBOARD_FAB2_LIB.BASEBOARD_FAB2(SCH_1):PAGE173

SATA6G_PCH_PCIE_UP_SATA_TXP<5> @BASEBOARD_FAB2_LIB.BASEBOARD_FAB2(SCH_1):SATA6G_PCH_PCIE_UP_SATA_TXP(5)
  U7C1  N72 PCIE17_UP5_SATA5_TXP LBG_CORE_QAT_EXT_D_BGA1-IC,H91A   I220 @BASEBOARD_FAB2_LIB.BASEBOARD_FAB2(SCH_1):PAGE116
 C2L27    2      B CAP_A_0402V-0.01UF,25V,10%,X7RA   I240 @BASEBOARD_FAB2_LIB.BASEBOARD_FAB2(SCH_1):PAGE173

SATA6G_PCH_PCIE_UP_SATA_TXP<6> @BASEBOARD_FAB2_LIB.BASEBOARD_FAB2(SCH_1):SATA6G_PCH_PCIE_UP_SATA_TXP(6)
  U7C1  M71 PCIE18_UP6_SATA6_TXP LBG_CORE_QAT_EXT_D_BGA1-IC,H91A   I220 @BASEBOARD_FAB2_LIB.BASEBOARD_FAB2(SCH_1):PAGE116
 C2L48    2      B CAP_A_0402V-0.01UF,25V,10%,X7RA   I257 @BASEBOARD_FAB2_LIB.BASEBOARD_FAB2(SCH_1):PAGE173

SATA6G_PCH_PCIE_UP_SATA_TXP<7> @BASEBOARD_FAB2_LIB.BASEBOARD_FAB2(SCH_1):SATA6G_PCH_PCIE_UP_SATA_TXP(7)
  U7C1  L72 PCIE19_UP7_SATA7_TXP LBG_CORE_QAT_EXT_D_BGA1-IC,H91A   I220 @BASEBOARD_FAB2_LIB.BASEBOARD_FAB2(SCH_1):PAGE116
 C2L24    2      B CAP_A_0402V-0.01UF,25V,10%,X7RA   I258 @BASEBOARD_FAB2_LIB.BASEBOARD_FAB2(SCH_1):PAGE173

SATA6G_S0_RX_DN @BASEBOARD_FAB2_LIB.BASEBOARD_FAB2(SCH_1):SATA6G_S0_RX_DN
  U7C1 BB63 PCIE6_SSATA0_RXN LBG_CORE_QAT_EXT_D_BGA1-IC,H91A   I220 @BASEBOARD_FAB2_LIB.BASEBOARD_FAB2(SCH_1):PAGE116
 C8F15    1      A CAP_A_0402V-0.01UF,25V,10%,X7RA   I142 @BASEBOARD_FAB2_LIB.BASEBOARD_FAB2(SCH_1):PAGE185

SATA6G_S0_RX_DP @BASEBOARD_FAB2_LIB.BASEBOARD_FAB2(SCH_1):SATA6G_S0_RX_DP
  U7C1 BD61 PCIE6_SSATA0_RXP LBG_CORE_QAT_EXT_D_BGA1-IC,H91A   I220 @BASEBOARD_FAB2_LIB.BASEBOARD_FAB2(SCH_1):PAGE116
 C8F13    1      A CAP_A_0402V-0.01UF,25V,10%,X7RA   I141 @BASEBOARD_FAB2_LIB.BASEBOARD_FAB2(SCH_1):PAGE185

SATA6G_S0_TX_DN @BASEBOARD_FAB2_LIB.BASEBOARD_FAB2(SCH_1):SATA6G_S0_TX_DN
  U7C1 AJ70 PCIE6_SSATA0_TXN LBG_CORE_QAT_EXT_D_BGA1-IC,H91A   I220 @BASEBOARD_FAB2_LIB.BASEBOARD_FAB2(SCH_1):PAGE116
 C8F11    1      A CAP_A_0402V-0.01UF,25V,10%,X7RA   I139 @BASEBOARD_FAB2_LIB.BASEBOARD_FAB2(SCH_1):PAGE185

SATA6G_S0_TX_DP @BASEBOARD_FAB2_LIB.BASEBOARD_FAB2(SCH_1):SATA6G_S0_TX_DP
  U7C1 AJ72 PCIE6_SSATA0_TXP LBG_CORE_QAT_EXT_D_BGA1-IC,H91A   I220 @BASEBOARD_FAB2_LIB.BASEBOARD_FAB2(SCH_1):PAGE116
  C8F6    1      A CAP_A_0402V-0.01UF,25V,10%,X7RA   I138 @BASEBOARD_FAB2_LIB.BASEBOARD_FAB2(SCH_1):PAGE185

SATA6G_S1_RX_C_DN @BASEBOARD_FAB2_LIB.BASEBOARD_FAB2(SCH_1):SATA6G_S1_RX_C_DN
 C2L50    1      A CAP_A_0402V-0.01UF,25V,10%,X7RA     I7 @BASEBOARD_FAB2_LIB.BASEBOARD_FAB2(SCH_1):PAGE172
  J2W1   S5     S5 SKT-SATA7P-6P-165-GP-U1_SOCKETA    I67 @BASEBOARD_FAB2_LIB.BASEBOARD_FAB2(SCH_1):PAGE172
  J2W2   S5     S5 SKT-SATA7P-6P-165-GP-U1_SOCKETA    I68 @BASEBOARD_FAB2_LIB.BASEBOARD_FAB2(SCH_1):PAGE172

SATA6G_S1_RX_C_DP @BASEBOARD_FAB2_LIB.BASEBOARD_FAB2(SCH_1):SATA6G_S1_RX_C_DP
 C2L49    1      A CAP_A_0402V-0.01UF,25V,10%,X7RA     I5 @BASEBOARD_FAB2_LIB.BASEBOARD_FAB2(SCH_1):PAGE172
  J2W1   S6     S6 SKT-SATA7P-6P-165-GP-U1_SOCKETA    I67 @BASEBOARD_FAB2_LIB.BASEBOARD_FAB2(SCH_1):PAGE172
  J2W2   S6     S6 SKT-SATA7P-6P-165-GP-U1_SOCKETA    I68 @BASEBOARD_FAB2_LIB.BASEBOARD_FAB2(SCH_1):PAGE172

SATA6G_S1_RX_DN @BASEBOARD_FAB2_LIB.BASEBOARD_FAB2(SCH_1):SATA6G_S1_RX_DN
  U7C1 AY59 PCIE7_SSATA1_RXN LBG_CORE_QAT_EXT_D_BGA1-IC,H91A   I220 @BASEBOARD_FAB2_LIB.BASEBOARD_FAB2(SCH_1):PAGE116
 C2L50    2      B CAP_A_0402V-0.01UF,25V,10%,X7RA     I7 @BASEBOARD_FAB2_LIB.BASEBOARD_FAB2(SCH_1):PAGE172

SATA6G_S1_RX_DP @BASEBOARD_FAB2_LIB.BASEBOARD_FAB2(SCH_1):SATA6G_S1_RX_DP
  U7C1 BA61 PCIE7_SSATA1_RXP LBG_CORE_QAT_EXT_D_BGA1-IC,H91A   I220 @BASEBOARD_FAB2_LIB.BASEBOARD_FAB2(SCH_1):PAGE116
 C2L49    2      B CAP_A_0402V-0.01UF,25V,10%,X7RA     I5 @BASEBOARD_FAB2_LIB.BASEBOARD_FAB2(SCH_1):PAGE172

SATA6G_S1_TX_C_DN @BASEBOARD_FAB2_LIB.BASEBOARD_FAB2(SCH_1):SATA6G_S1_TX_C_DN
 C2L51    1      A CAP_A_0402V-0.01UF,25V,10%,X7RA     I8 @BASEBOARD_FAB2_LIB.BASEBOARD_FAB2(SCH_1):PAGE172
  J2W1   S3     S3 SKT-SATA7P-6P-165-GP-U1_SOCKETA    I67 @BASEBOARD_FAB2_LIB.BASEBOARD_FAB2(SCH_1):PAGE172
  J2W2   S3     S3 SKT-SATA7P-6P-165-GP-U1_SOCKETA    I68 @BASEBOARD_FAB2_LIB.BASEBOARD_FAB2(SCH_1):PAGE172

SATA6G_S1_TX_C_DP @BASEBOARD_FAB2_LIB.BASEBOARD_FAB2(SCH_1):SATA6G_S1_TX_C_DP
 C2L52    1      A CAP_A_0402V-0.01UF,25V,10%,X7RA     I6 @BASEBOARD_FAB2_LIB.BASEBOARD_FAB2(SCH_1):PAGE172
  J2W1   S2     S2 SKT-SATA7P-6P-165-GP-U1_SOCKETA    I67 @BASEBOARD_FAB2_LIB.BASEBOARD_FAB2(SCH_1):PAGE172
  J2W2   S2     S2 SKT-SATA7P-6P-165-GP-U1_SOCKETA    I68 @BASEBOARD_FAB2_LIB.BASEBOARD_FAB2(SCH_1):PAGE172

SATA6G_S1_TX_DN @BASEBOARD_FAB2_LIB.BASEBOARD_FAB2(SCH_1):SATA6G_S1_TX_DN
  U7C1 AH69 PCIE7_SSATA1_TXN LBG_CORE_QAT_EXT_D_BGA1-IC,H91A   I220 @BASEBOARD_FAB2_LIB.BASEBOARD_FAB2(SCH_1):PAGE116
 C2L51    2      B CAP_A_0402V-0.01UF,25V,10%,X7RA     I8 @BASEBOARD_FAB2_LIB.BASEBOARD_FAB2(SCH_1):PAGE172

SATA6G_S1_TX_DP @BASEBOARD_FAB2_LIB.BASEBOARD_FAB2(SCH_1):SATA6G_S1_TX_DP
  U7C1 AH71 PCIE7_SSATA1_TXP LBG_CORE_QAT_EXT_D_BGA1-IC,H91A   I220 @BASEBOARD_FAB2_LIB.BASEBOARD_FAB2(SCH_1):PAGE116
 C2L52    2      B CAP_A_0402V-0.01UF,25V,10%,X7RA     I6 @BASEBOARD_FAB2_LIB.BASEBOARD_FAB2(SCH_1):PAGE172

SGPIO_BMC_CLK @BASEBOARD_FAB2_LIB.BASEBOARD_FAB2(SCH_1):SGPIO_BMC_CLK
  U8D7   J1 PL7C_PCLKT4_0 LCMXO2_A_256BGA-IC,H63395-001   I179 @BASEBOARD_FAB2_LIB.BASEBOARD_FAB2(SCH_1):PAGE190
 R1U14    2      B RES_0402-51,5.0%,1/16W,CHIP,G2A    I57 @BASEBOARD_FAB2_LIB.BASEBOARD_FAB2(SCH_1):PAGE144

SGPIO_BMC_CLK_R @BASEBOARD_FAB2_LIB.BASEBOARD_FAB2(SCH_1):SGPIO_BMC_CLK_R
 R1U14    1      A RES_0402-51,5.0%,1/16W,CHIP,G2A    I57 @BASEBOARD_FAB2_LIB.BASEBOARD_FAB2(SCH_1):PAGE144
 U25W4   R2 GPIOJ0_SGPMCK AST2520A1-GP-GP_ASIC2-GB1-AST2A    I95 @BASEBOARD_FAB2_LIB.BASEBOARD_FAB2(SCH_1):PAGE144

SGPIO_BMC_DIN @BASEBOARD_FAB2_LIB.BASEBOARD_FAB2(SCH_1):SGPIO_BMC_DIN
  R2R6    2      B RES_0402-51,5.0%,1/16W,CHIP,G2A   I166 @BASEBOARD_FAB2_LIB.BASEBOARD_FAB2(SCH_1):PAGE191
 U25W4   N4 GPIOJ3_SGPMI AST2520A1-GP-GP_ASIC2-GB1-AST2A    I95 @BASEBOARD_FAB2_LIB.BASEBOARD_FAB2(SCH_1):PAGE144

SGPIO_BMC_DIN_R @BASEBOARD_FAB2_LIB.BASEBOARD_FAB2(SCH_1):SGPIO_BMC_DIN_R
  U8D7   F8  PT18A LCMXO2_A_256BGA-IC,H63395-001    I59 @BASEBOARD_FAB2_LIB.BASEBOARD_FAB2(SCH_1):PAGE191
  R2R6    1      A RES_0402-51,5.0%,1/16W,CHIP,G2A   I166 @BASEBOARD_FAB2_LIB.BASEBOARD_FAB2(SCH_1):PAGE191

SGPIO_BMC_DOUT @BASEBOARD_FAB2_LIB.BASEBOARD_FAB2(SCH_1):SGPIO_BMC_DOUT
  U8D7   J2   PL9A LCMXO2_A_256BGA-IC,H63395-001   I179 @BASEBOARD_FAB2_LIB.BASEBOARD_FAB2(SCH_1):PAGE190
 R1U13    2      B RES_0402-51,5.0%,1/16W,CHIP,G2A    I58 @BASEBOARD_FAB2_LIB.BASEBOARD_FAB2(SCH_1):PAGE144

SGPIO_BMC_DOUT_R @BASEBOARD_FAB2_LIB.BASEBOARD_FAB2(SCH_1):SGPIO_BMC_DOUT_R
 R1U13    1      A RES_0402-51,5.0%,1/16W,CHIP,G2A    I58 @BASEBOARD_FAB2_LIB.BASEBOARD_FAB2(SCH_1):PAGE144
 U25W4   N3 GPIOJ2_SGPMO AST2520A1-GP-GP_ASIC2-GB1-AST2A    I95 @BASEBOARD_FAB2_LIB.BASEBOARD_FAB2(SCH_1):PAGE144

SGPIO_BMC_LD_N @BASEBOARD_FAB2_LIB.BASEBOARD_FAB2(SCH_1):SGPIO_BMC_LD_N
  U8D7   K4  PL11C LCMXO2_A_256BGA-IC,H63395-001   I179 @BASEBOARD_FAB2_LIB.BASEBOARD_FAB2(SCH_1):PAGE190
 R1U12    2      B RES_0402-51,5.0%,1/16W,CHIP,G2A    I59 @BASEBOARD_FAB2_LIB.BASEBOARD_FAB2(SCH_1):PAGE144

SGPIO_BMC_LD_R_N @BASEBOARD_FAB2_LIB.BASEBOARD_FAB2(SCH_1):SGPIO_BMC_LD_R_N
 R1U12    1      A RES_0402-51,5.0%,1/16W,CHIP,G2A    I59 @BASEBOARD_FAB2_LIB.BASEBOARD_FAB2(SCH_1):PAGE144
 U25W4   L2 GPIOJ1_SGPMLD AST2520A1-GP-GP_ASIC2-GB1-AST2A    I95 @BASEBOARD_FAB2_LIB.BASEBOARD_FAB2(SCH_1):PAGE144

SGPIO_PCH_SATA_CLOCK @BASEBOARD_FAB2_LIB.BASEBOARD_FAB2(SCH_1):SGPIO_PCH_SATA_CLOCK
  U7C1  AL7 GPP_F10_SATA_SCLOCK LBG_CORE_QAT_EXT_D_BGA1-IC,H91A   I147 @BASEBOARD_FAB2_LIB.BASEBOARD_FAB2(SCH_1):PAGE120
 R2N31    1      A RES_0402-49.9,1%,1/16W,CHIP,G2A    I11 @BASEBOARD_FAB2_LIB.BASEBOARD_FAB2(SCH_1):PAGE178

SGPIO_PCH_SATA_CLOCK_R @BASEBOARD_FAB2_LIB.BASEBOARD_FAB2(SCH_1):SGPIO_PCH_SATA_CLOCK_R
  J8A1  1A2 SIDEBANDA_0 CONN72_G97614002_A_CP-CONN,G97A   I163 @BASEBOARD_FAB2_LIB.BASEBOARD_FAB2(SCH_1):PAGE173
 R2N31    2      B RES_0402-49.9,1%,1/16W,CHIP,G2A    I11 @BASEBOARD_FAB2_LIB.BASEBOARD_FAB2(SCH_1):PAGE178
 R2L11    2      B RES_0402-2.0K,1%,1/16W,CHIP,G2A    I13 @BASEBOARD_FAB2_LIB.BASEBOARD_FAB2(SCH_1):PAGE178

SGPIO_PCH_SATA_DOUT0 @BASEBOARD_FAB2_LIB.BASEBOARD_FAB2(SCH_1):SGPIO_PCH_SATA_DOUT0
  U7C1 AP11 GPP_F13_SATA_SDATAOUT0 LBG_CORE_QAT_EXT_D_BGA1-IC,H91A   I147 @BASEBOARD_FAB2_LIB.BASEBOARD_FAB2(SCH_1):PAGE120
 R8D19    1      A RES_0402-49.9,1%,1/16W,CHIP,G2A     I8 @BASEBOARD_FAB2_LIB.BASEBOARD_FAB2(SCH_1):PAGE178

SGPIO_PCH_SATA_DOUT0_R @BASEBOARD_FAB2_LIB.BASEBOARD_FAB2(SCH_1):SGPIO_PCH_SATA_DOUT0_R
  J8A1  1C1 SIDEBANDA_4 CONN72_G97614002_A_CP-CONN,G97A   I163 @BASEBOARD_FAB2_LIB.BASEBOARD_FAB2(SCH_1):PAGE173
 R8D19    2      B RES_0402-49.9,1%,1/16W,CHIP,G2A     I8 @BASEBOARD_FAB2_LIB.BASEBOARD_FAB2(SCH_1):PAGE178
 R2L15    2      B RES_0402-2.0K,1%,1/16W,CHIP,G2A    I12 @BASEBOARD_FAB2_LIB.BASEBOARD_FAB2(SCH_1):PAGE178

SGPIO_PCH_SATA_LOAD @BASEBOARD_FAB2_LIB.BASEBOARD_FAB2(SCH_1):SGPIO_PCH_SATA_LOAD
  U7C1  AR9 GPP_F11_SATA_SLOAD LBG_CORE_QAT_EXT_D_BGA1-IC,H91A   I147 @BASEBOARD_FAB2_LIB.BASEBOARD_FAB2(SCH_1):PAGE120
 R8D20    1      A RES_0402-49.9,1%,1/16W,CHIP,G2A     I1 @BASEBOARD_FAB2_LIB.BASEBOARD_FAB2(SCH_1):PAGE178

SGPIO_PCH_SATA_LOAD_R @BASEBOARD_FAB2_LIB.BASEBOARD_FAB2(SCH_1):SGPIO_PCH_SATA_LOAD_R
  J8A1  1B2 SIDEBANDA_1 CONN72_G97614002_A_CP-CONN,G97A   I163 @BASEBOARD_FAB2_LIB.BASEBOARD_FAB2(SCH_1):PAGE173
 R8D20    2      B RES_0402-49.9,1%,1/16W,CHIP,G2A     I1 @BASEBOARD_FAB2_LIB.BASEBOARD_FAB2(SCH_1):PAGE178
 R2L12    2      B RES_0402-2.0K,1%,1/16W,CHIP,G2A     I2 @BASEBOARD_FAB2_LIB.BASEBOARD_FAB2(SCH_1):PAGE178

SGPIO_PCH_SSATA_CLOCK @BASEBOARD_FAB2_LIB.BASEBOARD_FAB2(SCH_1):SGPIO_PCH_SSATA_CLOCK
  U7C1 AP18 GPP_F22_SSATA_SCLOCK LBG_CORE_QAT_EXT_D_BGA1-IC,H91A   I147 @BASEBOARD_FAB2_LIB.BASEBOARD_FAB2(SCH_1):PAGE120
 R2N22    1      A RES_0402-49.9,1%,1/16W,CHIP,G2A    I23 @BASEBOARD_FAB2_LIB.BASEBOARD_FAB2(SCH_1):PAGE178

SGPIO_PCH_SSATA_CLOCK_R @BASEBOARD_FAB2_LIB.BASEBOARD_FAB2(SCH_1):SGPIO_PCH_SSATA_CLOCK_R
  R2L6    2      B RES_0402-2.0K,1%,1/16W,CHIP,G2A    I17 @BASEBOARD_FAB2_LIB.BASEBOARD_FAB2(SCH_1):PAGE178
 R2N22    2      B RES_0402-49.9,1%,1/16W,CHIP,G2A    I23 @BASEBOARD_FAB2_LIB.BASEBOARD_FAB2(SCH_1):PAGE178

SGPIO_PCH_SSATA_DOUT0 @BASEBOARD_FAB2_LIB.BASEBOARD_FAB2(SCH_1):SGPIO_PCH_SSATA_DOUT0
  U7C1 BW43 GPP_D15_SSATA_SDATAOUT0 LBG_CORE_QAT_EXT_D_BGA1-IC,H91A   I115 @BASEBOARD_FAB2_LIB.BASEBOARD_FAB2(SCH_1):PAGE119
 R8B29    1      A RES_0402-49.9,1%,1/16W,CHIP,G2A    I21 @BASEBOARD_FAB2_LIB.BASEBOARD_FAB2(SCH_1):PAGE178

SGPIO_PCH_SSATA_DOUT0_R @BASEBOARD_FAB2_LIB.BASEBOARD_FAB2(SCH_1):SGPIO_PCH_SSATA_DOUT0_R
  R2L4    2      B RES_0402-2.0K,1%,1/16W,CHIP,G2A    I18 @BASEBOARD_FAB2_LIB.BASEBOARD_FAB2(SCH_1):PAGE178
 R8B29    2      B RES_0402-49.9,1%,1/16W,CHIP,G2A    I21 @BASEBOARD_FAB2_LIB.BASEBOARD_FAB2(SCH_1):PAGE178

SGPIO_PCH_SSATA_LOAD @BASEBOARD_FAB2_LIB.BASEBOARD_FAB2(SCH_1):SGPIO_PCH_SSATA_LOAD
  U7C1 AU17 GPP_F23_SSATA_SLOAD LBG_CORE_QAT_EXT_D_BGA1-IC,H91A   I147 @BASEBOARD_FAB2_LIB.BASEBOARD_FAB2(SCH_1):PAGE120
 R2N19    1      A RES_0402-49.9,1%,1/16W,CHIP,G2A    I22 @BASEBOARD_FAB2_LIB.BASEBOARD_FAB2(SCH_1):PAGE178

SGPIO_PCH_SSATA_LOAD_R @BASEBOARD_FAB2_LIB.BASEBOARD_FAB2(SCH_1):SGPIO_PCH_SSATA_LOAD_R
  R2L5    2      B RES_0402-2.0K,1%,1/16W,CHIP,G2A    I20 @BASEBOARD_FAB2_LIB.BASEBOARD_FAB2(SCH_1):PAGE178
 R2N19    2      B RES_0402-49.9,1%,1/16W,CHIP,G2A    I22 @BASEBOARD_FAB2_LIB.BASEBOARD_FAB2(SCH_1):PAGE178

SMB_3V3SB_HSC_SCL_R @BASEBOARD_FAB2_LIB.BASEBOARD_FAB2(SCH_1):SMB_3V3SB_HSC_SCL_R
 EU1D2   16    SCL ADM1278_SM-IC,G99251-001    I10 @BASEBOARD_FAB2_LIB.BASEBOARD_FAB2(SCH_1):PAGE199
 R1D24    2      B RES_0402-0.0,5%,1/16W,CHIP,G21A    I27 @BASEBOARD_FAB2_LIB.BASEBOARD_FAB2(SCH_1):PAGE199

SMB_3V3SB_HSC_SDA_R @BASEBOARD_FAB2_LIB.BASEBOARD_FAB2(SCH_1):SMB_3V3SB_HSC_SDA_R
 EU1D2   15    SDA ADM1278_SM-IC,G99251-001    I10 @BASEBOARD_FAB2_LIB.BASEBOARD_FAB2(SCH_1):PAGE199
 R1D25    2      B RES_0402-0.0,5%,1/16W,CHIP,G21A    I28 @BASEBOARD_FAB2_LIB.BASEBOARD_FAB2(SCH_1):PAGE199

SMB_BMC_PMBUS_STBY_LVC3_SCL @BASEBOARD_FAB2_LIB.BASEBOARD_FAB2(SCH_1):SMB_BMC_PMBUS_STBY_LVC3_SCL
 R2T54    2      B RES_0402-665,1.0%,1/16W,CHIP,GA    I84 @BASEBOARD_FAB2_LIB.BASEBOARD_FAB2(SCH_1):PAGE138
  R2U1    2      B RES_0402-20.0,1%,1/16W,CHIP,G2A   I218 @BASEBOARD_FAB2_LIB.BASEBOARD_FAB2(SCH_1):PAGE159
 R1D24    1      A RES_0402-0.0,5%,1/16W,CHIP,G21A    I27 @BASEBOARD_FAB2_LIB.BASEBOARD_FAB2(SCH_1):PAGE199
  U6W2    7   SCLB TCA9517DGKR-GP_DISCRET-G8-TCA9A   I118 @BASEBOARD_FAB2_LIB.BASEBOARD_FAB2(SCH_1):PAGE247
  J1F3    7    IO7 CONN8_H62179001_PIP-CONN,H6217A   I106 @BASEBOARD_FAB2_LIB.BASEBOARD_FAB2(SCH_1):PAGE181
  J1F1   C6 PMBUS_CLK DM-FCI-CONN76-8R-GP-U-01_CONN-A   I134 @BASEBOARD_FAB2_LIB.BASEBOARD_FAB2(SCH_1):PAGE181

SMB_BMC_PMBUS_STBY_LVC3_SCL_R @BASEBOARD_FAB2_LIB.BASEBOARD_FAB2(SCH_1):SMB_BMC_PMBUS_STBY_LVC3_SCL_R
  R2U1    1      A RES_0402-20.0,1%,1/16W,CHIP,G2A   I218 @BASEBOARD_FAB2_LIB.BASEBOARD_FAB2(SCH_1):PAGE159
 U25W4   P2 GPIOK6_SCL8 AST2520A1-GP-GP_ASIC2-GB1-AST2A    I95 @BASEBOARD_FAB2_LIB.BASEBOARD_FAB2(SCH_1):PAGE144

SMB_BMC_PMBUS_STBY_LVC3_SDA @BASEBOARD_FAB2_LIB.BASEBOARD_FAB2(SCH_1):SMB_BMC_PMBUS_STBY_LVC3_SDA
 R2T53    2      B RES_0402-665,1.0%,1/16W,CHIP,GA    I83 @BASEBOARD_FAB2_LIB.BASEBOARD_FAB2(SCH_1):PAGE138
 R2T49    2      B RES_0402-20.0,1%,1/16W,CHIP,G2A   I219 @BASEBOARD_FAB2_LIB.BASEBOARD_FAB2(SCH_1):PAGE159
 R1D25    1      A RES_0402-0.0,5%,1/16W,CHIP,G21A    I28 @BASEBOARD_FAB2_LIB.BASEBOARD_FAB2(SCH_1):PAGE199
  U6W2    6   SDAB TCA9517DGKR-GP_DISCRET-G8-TCA9A   I118 @BASEBOARD_FAB2_LIB.BASEBOARD_FAB2(SCH_1):PAGE247
  J1F3    6    IO6 CONN8_H62179001_PIP-CONN,H6217A   I106 @BASEBOARD_FAB2_LIB.BASEBOARD_FAB2(SCH_1):PAGE181
  J1F1   B6 PMBUS_DATA DM-FCI-CONN76-8R-GP-U-01_CONN-A   I134 @BASEBOARD_FAB2_LIB.BASEBOARD_FAB2(SCH_1):PAGE181

SMB_BMC_PMBUS_STBY_LVC3_SDA_R @BASEBOARD_FAB2_LIB.BASEBOARD_FAB2(SCH_1):SMB_BMC_PMBUS_STBY_LVC3_SDA_R
 R2T49    1      A RES_0402-20.0,1%,1/16W,CHIP,G2A   I219 @BASEBOARD_FAB2_LIB.BASEBOARD_FAB2(SCH_1):PAGE159
 U25W4   R1 GPIOK7_SDA8 AST2520A1-GP-GP_ASIC2-GB1-AST2A    I95 @BASEBOARD_FAB2_LIB.BASEBOARD_FAB2(SCH_1):PAGE144

SMB_CPU0_PE_HP_GTL_R_SCL @BASEBOARD_FAB2_LIB.BASEBOARD_FAB2(SCH_1):SMB_CPU0_PE_HP_GTL_R_SCL
 R6W26    2      B RES_0402-10.0,1%,1/16W,CHIP,G2A    I24 @BASEBOARD_FAB2_LIB.BASEBOARD_FAB2(SCH_1):PAGE248
 R9W19    2      B RES_0402-240,1.0%,1/16W,CHIP,GA    I26 @BASEBOARD_FAB2_LIB.BASEBOARD_FAB2(SCH_1):PAGE248
  U1W2    2   SCLA TCA9517DGKR-GP_DISCRET-G8-TCA9A    I49 @BASEBOARD_FAB2_LIB.BASEBOARD_FAB2(SCH_1):PAGE248

SMB_CPU0_PE_HP_GTL_R_SDA @BASEBOARD_FAB2_LIB.BASEBOARD_FAB2(SCH_1):SMB_CPU0_PE_HP_GTL_R_SDA
 R6W27    2      B RES_0402-10.0,1%,1/16W,CHIP,G2A    I25 @BASEBOARD_FAB2_LIB.BASEBOARD_FAB2(SCH_1):PAGE248
 R9W18    2      B RES_0402-240,1.0%,1/16W,CHIP,GA    I27 @BASEBOARD_FAB2_LIB.BASEBOARD_FAB2(SCH_1):PAGE248
  U1W2    3   SDAA TCA9517DGKR-GP_DISCRET-G8-TCA9A    I49 @BASEBOARD_FAB2_LIB.BASEBOARD_FAB2(SCH_1):PAGE248

SMB_CPU0_PE_HP_GTL_SCL @BASEBOARD_FAB2_LIB.BASEBOARD_FAB2(SCH_1):SMB_CPU0_PE_HP_GTL_SCL
  U5D1 AM19 PE_HP_SCL SKX_EXT_B_BGA1-IC,TBD   I259 @BASEBOARD_FAB2_LIB.BASEBOARD_FAB2(SCH_1):PAGE21
 R6W26    1      A RES_0402-10.0,1%,1/16W,CHIP,G2A    I24 @BASEBOARD_FAB2_LIB.BASEBOARD_FAB2(SCH_1):PAGE248

SMB_CPU0_PE_HP_GTL_SDA @BASEBOARD_FAB2_LIB.BASEBOARD_FAB2(SCH_1):SMB_CPU0_PE_HP_GTL_SDA
  U5D1 AL18 PE_HP_SDA SKX_EXT_B_BGA1-IC,TBD   I259 @BASEBOARD_FAB2_LIB.BASEBOARD_FAB2(SCH_1):PAGE21
 R6W27    1      A RES_0402-10.0,1%,1/16W,CHIP,G2A    I25 @BASEBOARD_FAB2_LIB.BASEBOARD_FAB2(SCH_1):PAGE248

SMB_CPU1_PE_HP_GTL_R_SCL @BASEBOARD_FAB2_LIB.BASEBOARD_FAB2(SCH_1):SMB_CPU1_PE_HP_GTL_R_SCL
  R6N8    2      B RES_0402-10.0,1%,1/16W,CHIP,G2A     I2 @BASEBOARD_FAB2_LIB.BASEBOARD_FAB2(SCH_1):PAGE163
 R9M19    2      B RES_0402-240,1.0%,1/16W,CHIP,GA     I7 @BASEBOARD_FAB2_LIB.BASEBOARD_FAB2(SCH_1):PAGE163
  U1B2    2   SCLA TCA9517DGKR-GP_DISCRET-G8-TCA9A    I28 @BASEBOARD_FAB2_LIB.BASEBOARD_FAB2(SCH_1):PAGE163

SMB_CPU1_PE_HP_GTL_R_SDA @BASEBOARD_FAB2_LIB.BASEBOARD_FAB2(SCH_1):SMB_CPU1_PE_HP_GTL_R_SDA
  R6N9    2      B RES_0402-10.0,1%,1/16W,CHIP,G2A     I3 @BASEBOARD_FAB2_LIB.BASEBOARD_FAB2(SCH_1):PAGE163
 R9M18    2      B RES_0402-240,1.0%,1/16W,CHIP,GA     I6 @BASEBOARD_FAB2_LIB.BASEBOARD_FAB2(SCH_1):PAGE163
  U1B2    3   SDAA TCA9517DGKR-GP_DISCRET-G8-TCA9A    I28 @BASEBOARD_FAB2_LIB.BASEBOARD_FAB2(SCH_1):PAGE163

SMB_CPU1_PE_HP_GTL_SCL @BASEBOARD_FAB2_LIB.BASEBOARD_FAB2(SCH_1):SMB_CPU1_PE_HP_GTL_SCL
  U2D1 AM19 PE_HP_SCL SKX_EXT_B_BGA1-IC,TBD   I172 @BASEBOARD_FAB2_LIB.BASEBOARD_FAB2(SCH_1):PAGE55
  R6N8    1      A RES_0402-10.0,1%,1/16W,CHIP,G2A     I2 @BASEBOARD_FAB2_LIB.BASEBOARD_FAB2(SCH_1):PAGE163

SMB_CPU1_PE_HP_GTL_SDA @BASEBOARD_FAB2_LIB.BASEBOARD_FAB2(SCH_1):SMB_CPU1_PE_HP_GTL_SDA
  U2D1 AL18 PE_HP_SDA SKX_EXT_B_BGA1-IC,TBD   I172 @BASEBOARD_FAB2_LIB.BASEBOARD_FAB2(SCH_1):PAGE55
  R6N9    1      A RES_0402-10.0,1%,1/16W,CHIP,G2A     I3 @BASEBOARD_FAB2_LIB.BASEBOARD_FAB2(SCH_1):PAGE163

SMB_DDR_ABC_SCL_G @BASEBOARD_FAB2_LIB.BASEBOARD_FAB2(SCH_1):SMB_DDR_ABC_SCL_G
  U6F1    2   SCLA PCA9617_SSOP-IC,G81764-001-GNDA    I15 @BASEBOARD_FAB2_LIB.BASEBOARD_FAB2(SCH_1):PAGE99
  R4T5    2      B RES_0402-240,1.0%,1/16W,CHIP,GA    I19 @BASEBOARD_FAB2_LIB.BASEBOARD_FAB2(SCH_1):PAGE99
  R4T3    2      B RES_0402-10.0,1%,1/16W,CHIP,G2A    I83 @BASEBOARD_FAB2_LIB.BASEBOARD_FAB2(SCH_1):PAGE99

SMB_DDR_ABC_SCL_G_R @BASEBOARD_FAB2_LIB.BASEBOARD_FAB2(SCH_1):SMB_DDR_ABC_SCL_G_R
  U5D1 AJ18 DDR012_SPDSCL SKX_EXT_B_BGA1-IC,TBD   I259 @BASEBOARD_FAB2_LIB.BASEBOARD_FAB2(SCH_1):PAGE21
  R4T3    1      A RES_0402-10.0,1%,1/16W,CHIP,G2A    I83 @BASEBOARD_FAB2_LIB.BASEBOARD_FAB2(SCH_1):PAGE99

SMB_DDR_ABC_SDA_G @BASEBOARD_FAB2_LIB.BASEBOARD_FAB2(SCH_1):SMB_DDR_ABC_SDA_G
  U6F1    3   SDAA PCA9617_SSOP-IC,G81764-001-GNDA    I15 @BASEBOARD_FAB2_LIB.BASEBOARD_FAB2(SCH_1):PAGE99
  R4T6    2      B RES_0402-240,1.0%,1/16W,CHIP,GA    I17 @BASEBOARD_FAB2_LIB.BASEBOARD_FAB2(SCH_1):PAGE99
  R4T4    2      B RES_0402-10.0,1%,1/16W,CHIP,G2A    I20 @BASEBOARD_FAB2_LIB.BASEBOARD_FAB2(SCH_1):PAGE99

SMB_DDR_ABC_SDA_G_R @BASEBOARD_FAB2_LIB.BASEBOARD_FAB2(SCH_1):SMB_DDR_ABC_SDA_G_R
  U5D1 AF17 DDR012_SPDSDA SKX_EXT_B_BGA1-IC,TBD   I259 @BASEBOARD_FAB2_LIB.BASEBOARD_FAB2(SCH_1):PAGE21
  R4T4    1      A RES_0402-10.0,1%,1/16W,CHIP,G2A    I20 @BASEBOARD_FAB2_LIB.BASEBOARD_FAB2(SCH_1):PAGE99

SMB_DDR_ABC_VPP_SCL @BASEBOARD_FAB2_LIB.BASEBOARD_FAB2(SCH_1):SMB_DDR_ABC_VPP_SCL
  J4G1  141    SCL SCONN288_H44441004_PIP-SCONN,HA     I1 @BASEBOARD_FAB2_LIB.BASEBOARD_FAB2(SCH_1):PAGE43
  J6T1  141    SCL SCONN288_H44441003_PIP-SCONN,HA    I13 @BASEBOARD_FAB2_LIB.BASEBOARD_FAB2(SCH_1):PAGE44
  J4G2  141    SCL SCONN288_H44441004_PIP-SCONN,HA   I111 @BASEBOARD_FAB2_LIB.BASEBOARD_FAB2(SCH_1):PAGE45
  J6U1  141    SCL SCONN288_H44441003_PIP-SCONN,HA    I14 @BASEBOARD_FAB2_LIB.BASEBOARD_FAB2(SCH_1):PAGE46
  J4G3  141    SCL SCONN288_H44441004_PIP-SCONN,HA   I111 @BASEBOARD_FAB2_LIB.BASEBOARD_FAB2(SCH_1):PAGE47
  J6U2  141    SCL SCONN288_H44441003_PIP-SCONN,HA   I111 @BASEBOARD_FAB2_LIB.BASEBOARD_FAB2(SCH_1):PAGE48
  R4T9    2      B RES_0402-20.0,1%,1/16W,CHIP,G2A     I9 @BASEBOARD_FAB2_LIB.BASEBOARD_FAB2(SCH_1):PAGE99

SMB_DDR_ABC_VPP_SCL_R @BASEBOARD_FAB2_LIB.BASEBOARD_FAB2(SCH_1):SMB_DDR_ABC_VPP_SCL_R
  R4T9    1      A RES_0402-20.0,1%,1/16W,CHIP,G2A     I9 @BASEBOARD_FAB2_LIB.BASEBOARD_FAB2(SCH_1):PAGE99
  R4T7    2      B RES_0402-665,1.0%,1/16W,CHIP,GA    I13 @BASEBOARD_FAB2_LIB.BASEBOARD_FAB2(SCH_1):PAGE99
  U6F1    7   SCLB PCA9617_SSOP-IC,G81764-001-GNDA    I15 @BASEBOARD_FAB2_LIB.BASEBOARD_FAB2(SCH_1):PAGE99

SMB_DDR_ABC_VPP_SDA @BASEBOARD_FAB2_LIB.BASEBOARD_FAB2(SCH_1):SMB_DDR_ABC_VPP_SDA
  J4G1  285    SDA SCONN288_H44441004_PIP-SCONN,HA     I1 @BASEBOARD_FAB2_LIB.BASEBOARD_FAB2(SCH_1):PAGE43
  J6T1  285    SDA SCONN288_H44441003_PIP-SCONN,HA    I13 @BASEBOARD_FAB2_LIB.BASEBOARD_FAB2(SCH_1):PAGE44
  J4G2  285    SDA SCONN288_H44441004_PIP-SCONN,HA   I111 @BASEBOARD_FAB2_LIB.BASEBOARD_FAB2(SCH_1):PAGE45
  J6U1  285    SDA SCONN288_H44441003_PIP-SCONN,HA    I14 @BASEBOARD_FAB2_LIB.BASEBOARD_FAB2(SCH_1):PAGE46
  J4G3  285    SDA SCONN288_H44441004_PIP-SCONN,HA   I111 @BASEBOARD_FAB2_LIB.BASEBOARD_FAB2(SCH_1):PAGE47
  J6U2  285    SDA SCONN288_H44441003_PIP-SCONN,HA   I111 @BASEBOARD_FAB2_LIB.BASEBOARD_FAB2(SCH_1):PAGE48
 R4T10    2      B RES_0402-20.0,1%,1/16W,CHIP,G2A    I10 @BASEBOARD_FAB2_LIB.BASEBOARD_FAB2(SCH_1):PAGE99

SMB_DDR_ABC_VPP_SDA_R @BASEBOARD_FAB2_LIB.BASEBOARD_FAB2(SCH_1):SMB_DDR_ABC_VPP_SDA_R
 R4T10    1      A RES_0402-20.0,1%,1/16W,CHIP,G2A    I10 @BASEBOARD_FAB2_LIB.BASEBOARD_FAB2(SCH_1):PAGE99
  R4T8    2      B RES_0402-665,1.0%,1/16W,CHIP,GA    I11 @BASEBOARD_FAB2_LIB.BASEBOARD_FAB2(SCH_1):PAGE99
  U6F1    6   SDAB PCA9617_SSOP-IC,G81764-001-GNDA    I15 @BASEBOARD_FAB2_LIB.BASEBOARD_FAB2(SCH_1):PAGE99

SMB_DDR_DEF_SCL_G @BASEBOARD_FAB2_LIB.BASEBOARD_FAB2(SCH_1):SMB_DDR_DEF_SCL_G
  U7E1    2   SCLA PCA9617_SSOP-IC,G81764-001-GNDA    I61 @BASEBOARD_FAB2_LIB.BASEBOARD_FAB2(SCH_1):PAGE99
 R3P60    2      B RES_0402-240,1.0%,1/16W,CHIP,GA    I67 @BASEBOARD_FAB2_LIB.BASEBOARD_FAB2(SCH_1):PAGE99
  R3R7    2      B RES_0402-10.0,1%,1/16W,CHIP,G2A    I88 @BASEBOARD_FAB2_LIB.BASEBOARD_FAB2(SCH_1):PAGE99

SMB_DDR_DEF_SCL_G_R @BASEBOARD_FAB2_LIB.BASEBOARD_FAB2(SCH_1):SMB_DDR_DEF_SCL_G_R
  U5D1 AE18 DDR345_SPDSCL SKX_EXT_B_BGA1-IC,TBD   I259 @BASEBOARD_FAB2_LIB.BASEBOARD_FAB2(SCH_1):PAGE21
  R3R7    1      A RES_0402-10.0,1%,1/16W,CHIP,G2A    I88 @BASEBOARD_FAB2_LIB.BASEBOARD_FAB2(SCH_1):PAGE99

SMB_DDR_DEF_SDA_G @BASEBOARD_FAB2_LIB.BASEBOARD_FAB2(SCH_1):SMB_DDR_DEF_SDA_G
  U7E1    3   SDAA PCA9617_SSOP-IC,G81764-001-GNDA    I61 @BASEBOARD_FAB2_LIB.BASEBOARD_FAB2(SCH_1):PAGE99
 R3R13    2      B RES_0402-240,1.0%,1/16W,CHIP,GA    I65 @BASEBOARD_FAB2_LIB.BASEBOARD_FAB2(SCH_1):PAGE99
 R3R14    2      B RES_0402-10.0,1%,1/16W,CHIP,G2A   I110 @BASEBOARD_FAB2_LIB.BASEBOARD_FAB2(SCH_1):PAGE99

SMB_DDR_DEF_SDA_G_R @BASEBOARD_FAB2_LIB.BASEBOARD_FAB2(SCH_1):SMB_DDR_DEF_SDA_G_R
  U5D1 AD17 DDR345_SPDSDA SKX_EXT_B_BGA1-IC,TBD   I259 @BASEBOARD_FAB2_LIB.BASEBOARD_FAB2(SCH_1):PAGE21
 R3R14    1      A RES_0402-10.0,1%,1/16W,CHIP,G2A   I110 @BASEBOARD_FAB2_LIB.BASEBOARD_FAB2(SCH_1):PAGE99

SMB_DDR_DEF_VPP_SCL @BASEBOARD_FAB2_LIB.BASEBOARD_FAB2(SCH_1):SMB_DDR_DEF_VPP_SCL
  J4B1  141    SCL SCONN288_H44441004_PIP-SCONN,HA   I111 @BASEBOARD_FAB2_LIB.BASEBOARD_FAB2(SCH_1):PAGE49
  J6M1  141    SCL SCONN288_H44441003_PIP-SCONN,HA   I158 @BASEBOARD_FAB2_LIB.BASEBOARD_FAB2(SCH_1):PAGE50
  J4A2  141    SCL SCONN288_H44441004_PIP-SCONN,HA   I111 @BASEBOARD_FAB2_LIB.BASEBOARD_FAB2(SCH_1):PAGE51
  J6L2  141    SCL SCONN288_H44441003_PIP-SCONN,HA    I12 @BASEBOARD_FAB2_LIB.BASEBOARD_FAB2(SCH_1):PAGE52
  J4A1  141    SCL SCONN288_H44441004_PIP-SCONN,HA   I111 @BASEBOARD_FAB2_LIB.BASEBOARD_FAB2(SCH_1):PAGE53
  J6L1  141    SCL SCONN288_H44441003_PIP-SCONN,HA   I111 @BASEBOARD_FAB2_LIB.BASEBOARD_FAB2(SCH_1):PAGE54
  R3R8    2      B RES_0402-20.0,1%,1/16W,CHIP,G2A    I35 @BASEBOARD_FAB2_LIB.BASEBOARD_FAB2(SCH_1):PAGE99

SMB_DDR_DEF_VPP_SCL_R @BASEBOARD_FAB2_LIB.BASEBOARD_FAB2(SCH_1):SMB_DDR_DEF_VPP_SCL_R
  R3R8    1      A RES_0402-20.0,1%,1/16W,CHIP,G2A    I35 @BASEBOARD_FAB2_LIB.BASEBOARD_FAB2(SCH_1):PAGE99
  U7E1    7   SCLB PCA9617_SSOP-IC,G81764-001-GNDA    I61 @BASEBOARD_FAB2_LIB.BASEBOARD_FAB2(SCH_1):PAGE99
  R3R5    2      B RES_0402-665,1.0%,1/16W,CHIP,GA   I103 @BASEBOARD_FAB2_LIB.BASEBOARD_FAB2(SCH_1):PAGE99

SMB_DDR_DEF_VPP_SDA @BASEBOARD_FAB2_LIB.BASEBOARD_FAB2(SCH_1):SMB_DDR_DEF_VPP_SDA
  J4B1  285    SDA SCONN288_H44441004_PIP-SCONN,HA   I111 @BASEBOARD_FAB2_LIB.BASEBOARD_FAB2(SCH_1):PAGE49
  J6M1  285    SDA SCONN288_H44441003_PIP-SCONN,HA   I158 @BASEBOARD_FAB2_LIB.BASEBOARD_FAB2(SCH_1):PAGE50
  J4A2  285    SDA SCONN288_H44441004_PIP-SCONN,HA   I111 @BASEBOARD_FAB2_LIB.BASEBOARD_FAB2(SCH_1):PAGE51
  J6L2  285    SDA SCONN288_H44441003_PIP-SCONN,HA    I12 @BASEBOARD_FAB2_LIB.BASEBOARD_FAB2(SCH_1):PAGE52
  J4A1  285    SDA SCONN288_H44441004_PIP-SCONN,HA   I111 @BASEBOARD_FAB2_LIB.BASEBOARD_FAB2(SCH_1):PAGE53
  J6L1  285    SDA SCONN288_H44441003_PIP-SCONN,HA   I111 @BASEBOARD_FAB2_LIB.BASEBOARD_FAB2(SCH_1):PAGE54
  R3R9    2      B RES_0402-20.0,1%,1/16W,CHIP,G2A    I34 @BASEBOARD_FAB2_LIB.BASEBOARD_FAB2(SCH_1):PAGE99

SMB_DDR_DEF_VPP_SDA_R @BASEBOARD_FAB2_LIB.BASEBOARD_FAB2(SCH_1):SMB_DDR_DEF_VPP_SDA_R
  R3R9    1      A RES_0402-20.0,1%,1/16W,CHIP,G2A    I34 @BASEBOARD_FAB2_LIB.BASEBOARD_FAB2(SCH_1):PAGE99
  U7E1    6   SDAB PCA9617_SSOP-IC,G81764-001-GNDA    I61 @BASEBOARD_FAB2_LIB.BASEBOARD_FAB2(SCH_1):PAGE99
 R3R12    2      B RES_0402-665,1.0%,1/16W,CHIP,GA   I101 @BASEBOARD_FAB2_LIB.BASEBOARD_FAB2(SCH_1):PAGE99

SMB_DDR_GHJ_SCL_G @BASEBOARD_FAB2_LIB.BASEBOARD_FAB2(SCH_1):SMB_DDR_GHJ_SCL_G
  U4G1    2   SCLA PCA9617_SSOP-IC,G81764-001-GNDA    I63 @BASEBOARD_FAB2_LIB.BASEBOARD_FAB2(SCH_1):PAGE99
  R6T2    2      B RES_0402-240,1.0%,1/16W,CHIP,GA    I72 @BASEBOARD_FAB2_LIB.BASEBOARD_FAB2(SCH_1):PAGE99
  R6T3    2      B RES_0402-10.0,1%,1/16W,CHIP,G2A    I92 @BASEBOARD_FAB2_LIB.BASEBOARD_FAB2(SCH_1):PAGE99

SMB_DDR_GHJ_SCL_G_R @BASEBOARD_FAB2_LIB.BASEBOARD_FAB2(SCH_1):SMB_DDR_GHJ_SCL_G_R
  U2D1 AJ18 DDR012_SPDSCL SKX_EXT_B_BGA1-IC,TBD   I172 @BASEBOARD_FAB2_LIB.BASEBOARD_FAB2(SCH_1):PAGE55
  R6T3    1      A RES_0402-10.0,1%,1/16W,CHIP,G2A    I92 @BASEBOARD_FAB2_LIB.BASEBOARD_FAB2(SCH_1):PAGE99

SMB_DDR_GHJ_SDA_G @BASEBOARD_FAB2_LIB.BASEBOARD_FAB2(SCH_1):SMB_DDR_GHJ_SDA_G
  U4G1    3   SDAA PCA9617_SSOP-IC,G81764-001-GNDA    I63 @BASEBOARD_FAB2_LIB.BASEBOARD_FAB2(SCH_1):PAGE99
  R6T1    2      B RES_0402-240,1.0%,1/16W,CHIP,GA    I70 @BASEBOARD_FAB2_LIB.BASEBOARD_FAB2(SCH_1):PAGE99
  R6T4    2      B RES_0402-10.0,1%,1/16W,CHIP,G2A   I111 @BASEBOARD_FAB2_LIB.BASEBOARD_FAB2(SCH_1):PAGE99

SMB_DDR_GHJ_SDA_G_R @BASEBOARD_FAB2_LIB.BASEBOARD_FAB2(SCH_1):SMB_DDR_GHJ_SDA_G_R
  U2D1 AF17 DDR012_SPDSDA SKX_EXT_B_BGA1-IC,TBD   I172 @BASEBOARD_FAB2_LIB.BASEBOARD_FAB2(SCH_1):PAGE55
  R6T4    1      A RES_0402-10.0,1%,1/16W,CHIP,G2A   I111 @BASEBOARD_FAB2_LIB.BASEBOARD_FAB2(SCH_1):PAGE99

SMB_DDR_GHJ_VPP_SCL @BASEBOARD_FAB2_LIB.BASEBOARD_FAB2(SCH_1):SMB_DDR_GHJ_VPP_SCL
  J1G1  141    SCL SCONN288_H44441004_PIP-SCONN,HA   I111 @BASEBOARD_FAB2_LIB.BASEBOARD_FAB2(SCH_1):PAGE77
  J9T1  141    SCL SCONN288_H44441003_PIP-SCONN,HA    I13 @BASEBOARD_FAB2_LIB.BASEBOARD_FAB2(SCH_1):PAGE78
  J1G2  141    SCL SCONN288_H44441004_PIP-SCONN,HA   I111 @BASEBOARD_FAB2_LIB.BASEBOARD_FAB2(SCH_1):PAGE79
  J9U1  141    SCL SCONN288_H44441003_PIP-SCONN,HA    I24 @BASEBOARD_FAB2_LIB.BASEBOARD_FAB2(SCH_1):PAGE80
  J1G3  141    SCL SCONN288_H44441004_PIP-SCONN,HA   I186 @BASEBOARD_FAB2_LIB.BASEBOARD_FAB2(SCH_1):PAGE81
  J9U2  141    SCL SCONN288_H44441003_PIP-SCONN,HA   I187 @BASEBOARD_FAB2_LIB.BASEBOARD_FAB2(SCH_1):PAGE82
 R6U13    2      B RES_0402-20.0,1%,1/16W,CHIP,G2A    I42 @BASEBOARD_FAB2_LIB.BASEBOARD_FAB2(SCH_1):PAGE99

SMB_DDR_GHJ_VPP_SCL_R @BASEBOARD_FAB2_LIB.BASEBOARD_FAB2(SCH_1):SMB_DDR_GHJ_VPP_SCL_R
 R6U13    1      A RES_0402-20.0,1%,1/16W,CHIP,G2A    I42 @BASEBOARD_FAB2_LIB.BASEBOARD_FAB2(SCH_1):PAGE99
  U4G1    7   SCLB PCA9617_SSOP-IC,G81764-001-GNDA    I63 @BASEBOARD_FAB2_LIB.BASEBOARD_FAB2(SCH_1):PAGE99
 R6U17    2      B RES_0402-665,1.0%,1/16W,CHIP,GA   I106 @BASEBOARD_FAB2_LIB.BASEBOARD_FAB2(SCH_1):PAGE99

SMB_DDR_GHJ_VPP_SDA @BASEBOARD_FAB2_LIB.BASEBOARD_FAB2(SCH_1):SMB_DDR_GHJ_VPP_SDA
  J1G1  285    SDA SCONN288_H44441004_PIP-SCONN,HA   I111 @BASEBOARD_FAB2_LIB.BASEBOARD_FAB2(SCH_1):PAGE77
  J9T1  285    SDA SCONN288_H44441003_PIP-SCONN,HA    I13 @BASEBOARD_FAB2_LIB.BASEBOARD_FAB2(SCH_1):PAGE78
  J1G2  285    SDA SCONN288_H44441004_PIP-SCONN,HA   I111 @BASEBOARD_FAB2_LIB.BASEBOARD_FAB2(SCH_1):PAGE79
  J9U1  285    SDA SCONN288_H44441003_PIP-SCONN,HA    I24 @BASEBOARD_FAB2_LIB.BASEBOARD_FAB2(SCH_1):PAGE80
  J1G3  285    SDA SCONN288_H44441004_PIP-SCONN,HA   I186 @BASEBOARD_FAB2_LIB.BASEBOARD_FAB2(SCH_1):PAGE81
  J9U2  285    SDA SCONN288_H44441003_PIP-SCONN,HA   I187 @BASEBOARD_FAB2_LIB.BASEBOARD_FAB2(SCH_1):PAGE82
 R6U14    2      B RES_0402-20.0,1%,1/16W,CHIP,G2A   I115 @BASEBOARD_FAB2_LIB.BASEBOARD_FAB2(SCH_1):PAGE99

SMB_DDR_GHJ_VPP_SDA_R @BASEBOARD_FAB2_LIB.BASEBOARD_FAB2(SCH_1):SMB_DDR_GHJ_VPP_SDA_R
  U4G1    6   SDAB PCA9617_SSOP-IC,G81764-001-GNDA    I63 @BASEBOARD_FAB2_LIB.BASEBOARD_FAB2(SCH_1):PAGE99
 R6U18    2      B RES_0402-665,1.0%,1/16W,CHIP,GA   I104 @BASEBOARD_FAB2_LIB.BASEBOARD_FAB2(SCH_1):PAGE99
 R6U14    1      A RES_0402-20.0,1%,1/16W,CHIP,G2A   I115 @BASEBOARD_FAB2_LIB.BASEBOARD_FAB2(SCH_1):PAGE99

SMB_DDR_KLM_SCL_G @BASEBOARD_FAB2_LIB.BASEBOARD_FAB2(SCH_1):SMB_DDR_KLM_SCL_G
  U3B1    2   SCLA PCA9617_SSOP-IC,G81764-001-GNDA    I75 @BASEBOARD_FAB2_LIB.BASEBOARD_FAB2(SCH_1):PAGE99
  R7M2    2      B RES_0402-240,1.0%,1/16W,CHIP,GA    I79 @BASEBOARD_FAB2_LIB.BASEBOARD_FAB2(SCH_1):PAGE99
  R7M3    2      B RES_0402-10.0,1%,1/16W,CHIP,G2A    I98 @BASEBOARD_FAB2_LIB.BASEBOARD_FAB2(SCH_1):PAGE99

SMB_DDR_KLM_SCL_G_R @BASEBOARD_FAB2_LIB.BASEBOARD_FAB2(SCH_1):SMB_DDR_KLM_SCL_G_R
  U2D1 AE18 DDR345_SPDSCL SKX_EXT_B_BGA1-IC,TBD   I172 @BASEBOARD_FAB2_LIB.BASEBOARD_FAB2(SCH_1):PAGE55
  R7M3    1      A RES_0402-10.0,1%,1/16W,CHIP,G2A    I98 @BASEBOARD_FAB2_LIB.BASEBOARD_FAB2(SCH_1):PAGE99

SMB_DDR_KLM_SDA_G @BASEBOARD_FAB2_LIB.BASEBOARD_FAB2(SCH_1):SMB_DDR_KLM_SDA_G
  U3B1    3   SDAA PCA9617_SSOP-IC,G81764-001-GNDA    I75 @BASEBOARD_FAB2_LIB.BASEBOARD_FAB2(SCH_1):PAGE99
  R7M7    2      B RES_0402-240,1.0%,1/16W,CHIP,GA    I77 @BASEBOARD_FAB2_LIB.BASEBOARD_FAB2(SCH_1):PAGE99
  R7M8    2      B RES_0402-10.0,1%,1/16W,CHIP,G2A   I112 @BASEBOARD_FAB2_LIB.BASEBOARD_FAB2(SCH_1):PAGE99

SMB_DDR_KLM_SDA_G_R @BASEBOARD_FAB2_LIB.BASEBOARD_FAB2(SCH_1):SMB_DDR_KLM_SDA_G_R
  U2D1 AD17 DDR345_SPDSDA SKX_EXT_B_BGA1-IC,TBD   I172 @BASEBOARD_FAB2_LIB.BASEBOARD_FAB2(SCH_1):PAGE55
  R7M8    1      A RES_0402-10.0,1%,1/16W,CHIP,G2A   I112 @BASEBOARD_FAB2_LIB.BASEBOARD_FAB2(SCH_1):PAGE99

SMB_DDR_KLM_VPP_SCL @BASEBOARD_FAB2_LIB.BASEBOARD_FAB2(SCH_1):SMB_DDR_KLM_VPP_SCL
  J1B1  141    SCL SCONN288_H44441004_PIP-SCONN,HA   I111 @BASEBOARD_FAB2_LIB.BASEBOARD_FAB2(SCH_1):PAGE83
  J9M1  141    SCL SCONN288_H44441003_PIP-SCONN,HA    I14 @BASEBOARD_FAB2_LIB.BASEBOARD_FAB2(SCH_1):PAGE84
  J1A2  141    SCL SCONN288_H44441004_PIP-SCONN,HA   I111 @BASEBOARD_FAB2_LIB.BASEBOARD_FAB2(SCH_1):PAGE85
  J9L2  141    SCL SCONN288_H44441003_PIP-SCONN,HA    I12 @BASEBOARD_FAB2_LIB.BASEBOARD_FAB2(SCH_1):PAGE86
  J1A1  141    SCL SCONN288_H44441004_PIP-SCONN,HA   I186 @BASEBOARD_FAB2_LIB.BASEBOARD_FAB2(SCH_1):PAGE87
  J9L1  141    SCL SCONN288_H44441003_PIP-SCONN,HA   I111 @BASEBOARD_FAB2_LIB.BASEBOARD_FAB2(SCH_1):PAGE88
  R7M4    2      B RES_0402-20.0,1%,1/16W,CHIP,G2A    I56 @BASEBOARD_FAB2_LIB.BASEBOARD_FAB2(SCH_1):PAGE99

SMB_DDR_KLM_VPP_SCL_R @BASEBOARD_FAB2_LIB.BASEBOARD_FAB2(SCH_1):SMB_DDR_KLM_VPP_SCL_R
  R7M4    1      A RES_0402-20.0,1%,1/16W,CHIP,G2A    I56 @BASEBOARD_FAB2_LIB.BASEBOARD_FAB2(SCH_1):PAGE99
  U3B1    7   SCLB PCA9617_SSOP-IC,G81764-001-GNDA    I75 @BASEBOARD_FAB2_LIB.BASEBOARD_FAB2(SCH_1):PAGE99
  R7M1    2      B RES_0402-665,1.0%,1/16W,CHIP,GA   I109 @BASEBOARD_FAB2_LIB.BASEBOARD_FAB2(SCH_1):PAGE99

SMB_DDR_KLM_VPP_SDA @BASEBOARD_FAB2_LIB.BASEBOARD_FAB2(SCH_1):SMB_DDR_KLM_VPP_SDA
  J1B1  285    SDA SCONN288_H44441004_PIP-SCONN,HA   I111 @BASEBOARD_FAB2_LIB.BASEBOARD_FAB2(SCH_1):PAGE83
  J9M1  285    SDA SCONN288_H44441003_PIP-SCONN,HA    I14 @BASEBOARD_FAB2_LIB.BASEBOARD_FAB2(SCH_1):PAGE84
  J1A2  285    SDA SCONN288_H44441004_PIP-SCONN,HA   I111 @BASEBOARD_FAB2_LIB.BASEBOARD_FAB2(SCH_1):PAGE85
  J9L2  285    SDA SCONN288_H44441003_PIP-SCONN,HA    I12 @BASEBOARD_FAB2_LIB.BASEBOARD_FAB2(SCH_1):PAGE86
  J1A1  285    SDA SCONN288_H44441004_PIP-SCONN,HA   I186 @BASEBOARD_FAB2_LIB.BASEBOARD_FAB2(SCH_1):PAGE87
  J9L1  285    SDA SCONN288_H44441003_PIP-SCONN,HA   I111 @BASEBOARD_FAB2_LIB.BASEBOARD_FAB2(SCH_1):PAGE88
  R7M5    2      B RES_0402-20.0,1%,1/16W,CHIP,G2A    I55 @BASEBOARD_FAB2_LIB.BASEBOARD_FAB2(SCH_1):PAGE99

SMB_DDR_KLM_VPP_SDA_R @BASEBOARD_FAB2_LIB.BASEBOARD_FAB2(SCH_1):SMB_DDR_KLM_VPP_SDA_R
  R7M5    1      A RES_0402-20.0,1%,1/16W,CHIP,G2A    I55 @BASEBOARD_FAB2_LIB.BASEBOARD_FAB2(SCH_1):PAGE99
  U3B1    6   SDAB PCA9617_SSOP-IC,G81764-001-GNDA    I75 @BASEBOARD_FAB2_LIB.BASEBOARD_FAB2(SCH_1):PAGE99
  R7M6    2      B RES_0402-665,1.0%,1/16W,CHIP,GA   I107 @BASEBOARD_FAB2_LIB.BASEBOARD_FAB2(SCH_1):PAGE99

SMB_DEBUG_STBY_LVC3_SCL @BASEBOARD_FAB2_LIB.BASEBOARD_FAB2(SCH_1):SMB_DEBUG_STBY_LVC3_SCL
 R6W17    1      A RES_0402-0.0,5%,1/16W,CHIP,G21A   I120 @BASEBOARD_FAB2_LIB.BASEBOARD_FAB2(SCH_1):PAGE145
 R6W11    1      A RES_0402-4.75K,1%,1/16W,CHIP,GA    I98 @BASEBOARD_FAB2_LIB.BASEBOARD_FAB2(SCH_1):PAGE247
  U6W1   22    SCL TCA9555PWR-GP_DISCRET-GC1-TCA9A   I120 @BASEBOARD_FAB2_LIB.BASEBOARD_FAB2(SCH_1):PAGE247
 R1W33    2      B RES_0402-0.0,5%,1/16W,CHIP,G21A   I142 @BASEBOARD_FAB2_LIB.BASEBOARD_FAB2(SCH_1):PAGE176

SMB_DEBUG_STBY_LVC3_SCL_CONN @BASEBOARD_FAB2_LIB.BASEBOARD_FAB2(SCH_1):SMB_DEBUG_STBY_LVC3_SCL_CONN
  J9B1    5 STDA_SSRXN CONN9_H51826001_PIP2-CONN,H518A    I69 @BASEBOARD_FAB2_LIB.BASEBOARD_FAB2(SCH_1):PAGE176
  U1W3    2   SCLA PCA9617_SSOP-IC,G81764-001-GNDA   I162 @BASEBOARD_FAB2_LIB.BASEBOARD_FAB2(SCH_1):PAGE176
 R1W36    2      B RES_0402-4.75K,1%,1/16W,CHIP,GA   I172 @BASEBOARD_FAB2_LIB.BASEBOARD_FAB2(SCH_1):PAGE176
 R1W38    1      A RES_0402-0.0,5%,1/16W,CHIP,G21A   I176 @BASEBOARD_FAB2_LIB.BASEBOARD_FAB2(SCH_1):PAGE176

SMB_DEBUG_STBY_LVC3_SCL_R @BASEBOARD_FAB2_LIB.BASEBOARD_FAB2(SCH_1):SMB_DEBUG_STBY_LVC3_SCL_R
 U25W4  C12 GPIOC0_SD1CLK_SCL10 AST2520A1-GP-GP_ASIC2-GB1-AST2A   I117 @BASEBOARD_FAB2_LIB.BASEBOARD_FAB2(SCH_1):PAGE145
 R6W17    2      B RES_0402-0.0,5%,1/16W,CHIP,G21A   I120 @BASEBOARD_FAB2_LIB.BASEBOARD_FAB2(SCH_1):PAGE145

SMB_DEBUG_STBY_LVC3_SCL_R1 @BASEBOARD_FAB2_LIB.BASEBOARD_FAB2(SCH_1):SMB_DEBUG_STBY_LVC3_SCL_R1
 R1W33    1      A RES_0402-0.0,5%,1/16W,CHIP,G21A   I142 @BASEBOARD_FAB2_LIB.BASEBOARD_FAB2(SCH_1):PAGE176
  U1W3    7   SCLB PCA9617_SSOP-IC,G81764-001-GNDA   I162 @BASEBOARD_FAB2_LIB.BASEBOARD_FAB2(SCH_1):PAGE176
 R1W38    2      B RES_0402-0.0,5%,1/16W,CHIP,G21A   I176 @BASEBOARD_FAB2_LIB.BASEBOARD_FAB2(SCH_1):PAGE176

SMB_DEBUG_STBY_LVC3_SDA @BASEBOARD_FAB2_LIB.BASEBOARD_FAB2(SCH_1):SMB_DEBUG_STBY_LVC3_SDA
 R6W18    1      A RES_0402-0.0,5%,1/16W,CHIP,G21A   I119 @BASEBOARD_FAB2_LIB.BASEBOARD_FAB2(SCH_1):PAGE145
 R6W12    1      A RES_0402-4.75K,1%,1/16W,CHIP,GA    I99 @BASEBOARD_FAB2_LIB.BASEBOARD_FAB2(SCH_1):PAGE247
  U6W1   23    SDA TCA9555PWR-GP_DISCRET-GC1-TCA9A   I120 @BASEBOARD_FAB2_LIB.BASEBOARD_FAB2(SCH_1):PAGE247
 R1W34    2      B RES_0402-0.0,5%,1/16W,CHIP,G21A   I143 @BASEBOARD_FAB2_LIB.BASEBOARD_FAB2(SCH_1):PAGE176

SMB_DEBUG_STBY_LVC3_SDA_CONN @BASEBOARD_FAB2_LIB.BASEBOARD_FAB2(SCH_1):SMB_DEBUG_STBY_LVC3_SDA_CONN
  J9B1    6 STDA_SSRXP CONN9_H51826001_PIP2-CONN,H518A    I69 @BASEBOARD_FAB2_LIB.BASEBOARD_FAB2(SCH_1):PAGE176
  U1W3    3   SDAA PCA9617_SSOP-IC,G81764-001-GNDA   I162 @BASEBOARD_FAB2_LIB.BASEBOARD_FAB2(SCH_1):PAGE176
 R1W37    2      B RES_0402-4.75K,1%,1/16W,CHIP,GA   I173 @BASEBOARD_FAB2_LIB.BASEBOARD_FAB2(SCH_1):PAGE176
 R1W39    1      A RES_0402-0.0,5%,1/16W,CHIP,G21A   I175 @BASEBOARD_FAB2_LIB.BASEBOARD_FAB2(SCH_1):PAGE176

SMB_DEBUG_STBY_LVC3_SDA_R @BASEBOARD_FAB2_LIB.BASEBOARD_FAB2(SCH_1):SMB_DEBUG_STBY_LVC3_SDA_R
 U25W4  A12 GPIOC1_SD1CMD_SDA10 AST2520A1-GP-GP_ASIC2-GB1-AST2A   I117 @BASEBOARD_FAB2_LIB.BASEBOARD_FAB2(SCH_1):PAGE145
 R6W18    2      B RES_0402-0.0,5%,1/16W,CHIP,G21A   I119 @BASEBOARD_FAB2_LIB.BASEBOARD_FAB2(SCH_1):PAGE145

SMB_DEBUG_STBY_LVC3_SDA_R1 @BASEBOARD_FAB2_LIB.BASEBOARD_FAB2(SCH_1):SMB_DEBUG_STBY_LVC3_SDA_R1
 R1W34    1      A RES_0402-0.0,5%,1/16W,CHIP,G21A   I143 @BASEBOARD_FAB2_LIB.BASEBOARD_FAB2(SCH_1):PAGE176
  U1W3    6   SDAB PCA9617_SSOP-IC,G81764-001-GNDA   I162 @BASEBOARD_FAB2_LIB.BASEBOARD_FAB2(SCH_1):PAGE176
 R1W39    2      B RES_0402-0.0,5%,1/16W,CHIP,G21A   I175 @BASEBOARD_FAB2_LIB.BASEBOARD_FAB2(SCH_1):PAGE176

SMB_HFI0_CPU0_LVC2_SCL @BASEBOARD_FAB2_LIB.BASEBOARD_FAB2(SCH_1):SMB_HFI0_CPU0_LVC2_SCL
  U5D1 BN22 CD_HFI0_I2CCLK SKX_EXT_B_BGA1-IC,TBD    I61 @BASEBOARD_FAB2_LIB.BASEBOARD_FAB2(SCH_1):PAGE29
  J8B1    2    IO2 SCONN24_H46321001_SM-SCONN,H46A     I1 @BASEBOARD_FAB2_LIB.BASEBOARD_FAB2(SCH_1):PAGE91
  R8B6    2      B RES_0402-1.8K,1%,1/16W,CHIP,G2A    I37 @BASEBOARD_FAB2_LIB.BASEBOARD_FAB2(SCH_1):PAGE91

SMB_HFI0_CPU0_LVC2_SDA @BASEBOARD_FAB2_LIB.BASEBOARD_FAB2(SCH_1):SMB_HFI0_CPU0_LVC2_SDA
  U5D1 BP23 CD_HFI0_I2CDAT SKX_EXT_B_BGA1-IC,TBD    I61 @BASEBOARD_FAB2_LIB.BASEBOARD_FAB2(SCH_1):PAGE29
  J8B1    4    IO4 SCONN24_H46321001_SM-SCONN,H46A     I1 @BASEBOARD_FAB2_LIB.BASEBOARD_FAB2(SCH_1):PAGE91
  R8B7    2      B RES_0402-1.8K,1%,1/16W,CHIP,G2A    I36 @BASEBOARD_FAB2_LIB.BASEBOARD_FAB2(SCH_1):PAGE91

SMB_HFI1_CPU0_LVC2_SCL @BASEBOARD_FAB2_LIB.BASEBOARD_FAB2(SCH_1):SMB_HFI1_CPU0_LVC2_SCL
  U5D1 BJ22 CD_HFI1_I2CCLK SKX_EXT_B_BGA1-IC,TBD    I61 @BASEBOARD_FAB2_LIB.BASEBOARD_FAB2(SCH_1):PAGE29
  J8B1   10   IO10 SCONN24_H46321001_SM-SCONN,H46A     I1 @BASEBOARD_FAB2_LIB.BASEBOARD_FAB2(SCH_1):PAGE91
 R8B11    2      B RES_0402-1.8K,1%,1/16W,CHIP,G2A    I35 @BASEBOARD_FAB2_LIB.BASEBOARD_FAB2(SCH_1):PAGE91

SMB_HFI1_CPU0_LVC2_SDA @BASEBOARD_FAB2_LIB.BASEBOARD_FAB2(SCH_1):SMB_HFI1_CPU0_LVC2_SDA
  U5D1 BH23 CD_HFI1_I2CDAT SKX_EXT_B_BGA1-IC,TBD    I61 @BASEBOARD_FAB2_LIB.BASEBOARD_FAB2(SCH_1):PAGE29
  J8B1   12   IO12 SCONN24_H46321001_SM-SCONN,H46A     I1 @BASEBOARD_FAB2_LIB.BASEBOARD_FAB2(SCH_1):PAGE91
 R8B13    2      B RES_0402-1.8K,1%,1/16W,CHIP,G2A    I34 @BASEBOARD_FAB2_LIB.BASEBOARD_FAB2(SCH_1):PAGE91

SMB_HOST_STBY_LVC3_SCL @BASEBOARD_FAB2_LIB.BASEBOARD_FAB2(SCH_1):SMB_HOST_STBY_LVC3_SCL
  J9A3   53   IO53 SCONN60_C21100002_SMLF-CONN,C2A    I26 @BASEBOARD_FAB2_LIB.BASEBOARD_FAB2(SCH_1):PAGE111
 R8C14    2      B RES_0402-20.0,1%,1/16W,CHIP,G2A   I168 @BASEBOARD_FAB2_LIB.BASEBOARD_FAB2(SCH_1):PAGE138
  J8C1    3    IO3 CONN3_C95678002_PIP-CONN,C9567A   I285 @BASEBOARD_FAB2_LIB.BASEBOARD_FAB2(SCH_1):PAGE156
 R2U34    2      B RES_0402-20.0,1%,1/16W,CHIP,G2A   I230 @BASEBOARD_FAB2_LIB.BASEBOARD_FAB2(SCH_1):PAGE159
 R6W22    1      A RES_0402-20.0,1%,1/16W,CHIP,G2A    I94 @BASEBOARD_FAB2_LIB.BASEBOARD_FAB2(SCH_1):PAGE247
 R1W22    1      A RES_0402-0.0,5%,1/16W,CHIP,G21A   I134 @BASEBOARD_FAB2_LIB.BASEBOARD_FAB2(SCH_1):PAGE101
  R8W5    1      A RES_0402-20.0,1%,1/16W,CHIP,G2A   I194 @BASEBOARD_FAB2_LIB.BASEBOARD_FAB2(SCH_1):PAGE138
  Q4W1    3 DRAIN<0> FET_N_DUAL_SMLF-2N7002DW,FET,DA   I101 @BASEBOARD_FAB2_LIB.BASEBOARD_FAB2(SCH_1):PAGE102

SMB_HOST_STBY_LVC3_SCL_R @BASEBOARD_FAB2_LIB.BASEBOARD_FAB2(SCH_1):SMB_HOST_STBY_LVC3_SCL_R
 R2U34    1      A RES_0402-20.0,1%,1/16W,CHIP,G2A   I230 @BASEBOARD_FAB2_LIB.BASEBOARD_FAB2(SCH_1):PAGE159
 U25W4   A9 GPIOQ2_SCL4 AST2520A1-GP-GP_ASIC2-GB1-AST2A    I95 @BASEBOARD_FAB2_LIB.BASEBOARD_FAB2(SCH_1):PAGE144
 R8C15    2      B RES_0402-2.0K,1%,1/16W,CHIP,G2A   I235 @BASEBOARD_FAB2_LIB.BASEBOARD_FAB2(SCH_1):PAGE159

SMB_HOST_STBY_LVC3_SCL_R1 @BASEBOARD_FAB2_LIB.BASEBOARD_FAB2(SCH_1):SMB_HOST_STBY_LVC3_SCL_R1
  U7C1 BW28 GPP_C0_SMBCLK LBG_CORE_QAT_EXT_D_BGA1-IC,H91A   I115 @BASEBOARD_FAB2_LIB.BASEBOARD_FAB2(SCH_1):PAGE119
 R8C14    1      A RES_0402-20.0,1%,1/16W,CHIP,G2A   I168 @BASEBOARD_FAB2_LIB.BASEBOARD_FAB2(SCH_1):PAGE138

SMB_HOST_STBY_LVC3_SCL_R2 @BASEBOARD_FAB2_LIB.BASEBOARD_FAB2(SCH_1):SMB_HOST_STBY_LVC3_SCL_R2
 EU4D2   13    SCL NB3W1200L_LCC-IC,H13585-001     I1 @BASEBOARD_FAB2_LIB.BASEBOARD_FAB2(SCH_1):PAGE102
  Q4W1    4 SOURCE<0> FET_N_DUAL_SMLF-2N7002DW,FET,DA   I101 @BASEBOARD_FAB2_LIB.BASEBOARD_FAB2(SCH_1):PAGE102
  R4W4    2      B RES_0402-3.3K,5%,1/16W,CHIP,G2A   I106 @BASEBOARD_FAB2_LIB.BASEBOARD_FAB2(SCH_1):PAGE102

SMB_HOST_STBY_LVC3_SCL_R3 @BASEBOARD_FAB2_LIB.BASEBOARD_FAB2(SCH_1):SMB_HOST_STBY_LVC3_SCL_R3
  U6W3    6    SCL AT24C64_SOICLF-IC,C47049-001-GA    I89 @BASEBOARD_FAB2_LIB.BASEBOARD_FAB2(SCH_1):PAGE247
 R6W22    2      B RES_0402-20.0,1%,1/16W,CHIP,G2A    I94 @BASEBOARD_FAB2_LIB.BASEBOARD_FAB2(SCH_1):PAGE247

SMB_HOST_STBY_LVC3_SCL_R4 @BASEBOARD_FAB2_LIB.BASEBOARD_FAB2(SCH_1):SMB_HOST_STBY_LVC3_SCL_R4
 EU8F2   38 SMBCLK ICS9FGP204_MLFP-IC,E95226-001    I34 @BASEBOARD_FAB2_LIB.BASEBOARD_FAB2(SCH_1):PAGE101
 R1W22    2      B RES_0402-0.0,5%,1/16W,CHIP,G21A   I134 @BASEBOARD_FAB2_LIB.BASEBOARD_FAB2(SCH_1):PAGE101

SMB_HOST_STBY_LVC3_SCL_R5 @BASEBOARD_FAB2_LIB.BASEBOARD_FAB2(SCH_1):SMB_HOST_STBY_LVC3_SCL_R5
  J8G1   32   IO32 SCONN200_H68296001_SM-CONN,H68A   I258 @BASEBOARD_FAB2_LIB.BASEBOARD_FAB2(SCH_1):PAGE108
 R8B26    2      B RES_0402-3.3K,5%,1/16W,CHIP,G2A   I187 @BASEBOARD_FAB2_LIB.BASEBOARD_FAB2(SCH_1):PAGE138
  R8W5    2      B RES_0402-20.0,1%,1/16W,CHIP,G2A   I194 @BASEBOARD_FAB2_LIB.BASEBOARD_FAB2(SCH_1):PAGE138

SMB_HOST_STBY_LVC3_SDA @BASEBOARD_FAB2_LIB.BASEBOARD_FAB2(SCH_1):SMB_HOST_STBY_LVC3_SDA
  J9A3   51   IO51 SCONN60_C21100002_SMLF-CONN,C2A    I26 @BASEBOARD_FAB2_LIB.BASEBOARD_FAB2(SCH_1):PAGE111
 R8C20    2      B RES_0402-20.0,1%,1/16W,CHIP,G2A   I167 @BASEBOARD_FAB2_LIB.BASEBOARD_FAB2(SCH_1):PAGE138
  J8C1    1    IO1 CONN3_C95678002_PIP-CONN,C9567A   I285 @BASEBOARD_FAB2_LIB.BASEBOARD_FAB2(SCH_1):PAGE156
 R2U33    2      B RES_0402-20.0,1%,1/16W,CHIP,G2A   I231 @BASEBOARD_FAB2_LIB.BASEBOARD_FAB2(SCH_1):PAGE159
 R6W20    2      B RES_0402-20.0,1%,1/16W,CHIP,G2A    I87 @BASEBOARD_FAB2_LIB.BASEBOARD_FAB2(SCH_1):PAGE247
 R1W23    1      A RES_0402-0.0,5%,1/16W,CHIP,G21A   I135 @BASEBOARD_FAB2_LIB.BASEBOARD_FAB2(SCH_1):PAGE101
  R8W4    1      A RES_0402-20.0,1%,1/16W,CHIP,G2A   I195 @BASEBOARD_FAB2_LIB.BASEBOARD_FAB2(SCH_1):PAGE138
  Q4W1    6 DRAIN<0> FET_N_DUAL_SMLF-2N7002DW,FET,DA   I102 @BASEBOARD_FAB2_LIB.BASEBOARD_FAB2(SCH_1):PAGE102

SMB_HOST_STBY_LVC3_SDA_R @BASEBOARD_FAB2_LIB.BASEBOARD_FAB2(SCH_1):SMB_HOST_STBY_LVC3_SDA_R
 R2U33    1      A RES_0402-20.0,1%,1/16W,CHIP,G2A   I231 @BASEBOARD_FAB2_LIB.BASEBOARD_FAB2(SCH_1):PAGE159
 U25W4   B9 GPIOQ3_SDA4 AST2520A1-GP-GP_ASIC2-GB1-AST2A    I95 @BASEBOARD_FAB2_LIB.BASEBOARD_FAB2(SCH_1):PAGE144
 R8C16    2      B RES_0402-2.0K,1%,1/16W,CHIP,G2A   I237 @BASEBOARD_FAB2_LIB.BASEBOARD_FAB2(SCH_1):PAGE159

SMB_HOST_STBY_LVC3_SDA_R1 @BASEBOARD_FAB2_LIB.BASEBOARD_FAB2(SCH_1):SMB_HOST_STBY_LVC3_SDA_R1
  U7C1 BV27 GPP_C1_SMBDATA LBG_CORE_QAT_EXT_D_BGA1-IC,H91A   I115 @BASEBOARD_FAB2_LIB.BASEBOARD_FAB2(SCH_1):PAGE119
 R8C20    1      A RES_0402-20.0,1%,1/16W,CHIP,G2A   I167 @BASEBOARD_FAB2_LIB.BASEBOARD_FAB2(SCH_1):PAGE138

SMB_HOST_STBY_LVC3_SDA_R2 @BASEBOARD_FAB2_LIB.BASEBOARD_FAB2(SCH_1):SMB_HOST_STBY_LVC3_SDA_R2
 EU4D2   12    SDA NB3W1200L_LCC-IC,H13585-001     I1 @BASEBOARD_FAB2_LIB.BASEBOARD_FAB2(SCH_1):PAGE102
  Q4W1    1 SOURCE<0> FET_N_DUAL_SMLF-2N7002DW,FET,DA   I102 @BASEBOARD_FAB2_LIB.BASEBOARD_FAB2(SCH_1):PAGE102
  R4W3    2      B RES_0402-3.3K,5%,1/16W,CHIP,G2A   I105 @BASEBOARD_FAB2_LIB.BASEBOARD_FAB2(SCH_1):PAGE102

SMB_HOST_STBY_LVC3_SDA_R3 @BASEBOARD_FAB2_LIB.BASEBOARD_FAB2(SCH_1):SMB_HOST_STBY_LVC3_SDA_R3
 R6W20    1      A RES_0402-20.0,1%,1/16W,CHIP,G2A    I87 @BASEBOARD_FAB2_LIB.BASEBOARD_FAB2(SCH_1):PAGE247
  U6W3    5    SDA AT24C64_SOICLF-IC,C47049-001-GA    I89 @BASEBOARD_FAB2_LIB.BASEBOARD_FAB2(SCH_1):PAGE247

SMB_HOST_STBY_LVC3_SDA_R4 @BASEBOARD_FAB2_LIB.BASEBOARD_FAB2(SCH_1):SMB_HOST_STBY_LVC3_SDA_R4
 EU8F2   39 SMBDAT ICS9FGP204_MLFP-IC,E95226-001    I34 @BASEBOARD_FAB2_LIB.BASEBOARD_FAB2(SCH_1):PAGE101
 R1W23    2      B RES_0402-0.0,5%,1/16W,CHIP,G21A   I135 @BASEBOARD_FAB2_LIB.BASEBOARD_FAB2(SCH_1):PAGE101

SMB_HOST_STBY_LVC3_SDA_R5 @BASEBOARD_FAB2_LIB.BASEBOARD_FAB2(SCH_1):SMB_HOST_STBY_LVC3_SDA_R5
  J8G1   30   IO30 SCONN200_H68296001_SM-CONN,H68A   I258 @BASEBOARD_FAB2_LIB.BASEBOARD_FAB2(SCH_1):PAGE108
 R8B24    2      B RES_0402-3.3K,5%,1/16W,CHIP,G2A   I186 @BASEBOARD_FAB2_LIB.BASEBOARD_FAB2(SCH_1):PAGE138
  R8W4    2      B RES_0402-20.0,1%,1/16W,CHIP,G2A   I195 @BASEBOARD_FAB2_LIB.BASEBOARD_FAB2(SCH_1):PAGE138

SMB_LAN_STBY_LVC3_SCL @BASEBOARD_FAB2_LIB.BASEBOARD_FAB2(SCH_1):SMB_LAN_STBY_LVC3_SCL
  R2U3    2      B RES_0402-665,1.0%,1/16W,CHIP,GA    I98 @BASEBOARD_FAB2_LIB.BASEBOARD_FAB2(SCH_1):PAGE138
  R2U8    1      A RES_0402-20.0,1%,1/16W,EMPTY,GA   I158 @BASEBOARD_FAB2_LIB.BASEBOARD_FAB2(SCH_1):PAGE138
  R2U6    2      B RES_0402-20.0,1%,1/16W,CHIP,G2A   I166 @BASEBOARD_FAB2_LIB.BASEBOARD_FAB2(SCH_1):PAGE138
 R2N21    2      B RES_0402-0.0,5%,1/16W,CHIP,G21A   I175 @BASEBOARD_FAB2_LIB.BASEBOARD_FAB2(SCH_1):PAGE138
 R9M20    1      A RES_0402-0.0,5%,1/16W,CHIP,G21A   I323 @BASEBOARD_FAB2_LIB.BASEBOARD_FAB2(SCH_1):PAGE156
  R4A9    1      A RES_0402-0.0,5%,1/16W,CHIP,G21A   I324 @BASEBOARD_FAB2_LIB.BASEBOARD_FAB2(SCH_1):PAGE156
 R9F22    2      B RES_0402-20.0,1%,1/16W,CHIP,G2A    I52 @BASEBOARD_FAB2_LIB.BASEBOARD_FAB2(SCH_1):PAGE160
 R1C11    1      A RES_0402-0.0,5%,1/16W,EMPTY,G2A    I10 @BASEBOARD_FAB2_LIB.BASEBOARD_FAB2(SCH_1):PAGE182
  J1C1   E5 MNG_RX_DN DM-FCI-CONN76-8R-GP-U-01_CONN-A    I79 @BASEBOARD_FAB2_LIB.BASEBOARD_FAB2(SCH_1):PAGE182

SMB_LAN_STBY_LVC3_SCL_R @BASEBOARD_FAB2_LIB.BASEBOARD_FAB2(SCH_1):SMB_LAN_STBY_LVC3_SCL_R
 R9F22    1      A RES_0402-20.0,1%,1/16W,CHIP,G2A    I52 @BASEBOARD_FAB2_LIB.BASEBOARD_FAB2(SCH_1):PAGE160
 U25W4  M18 GPIOY4_SCL1 AST2520A1-GP-GP_ASIC2-GB1-AST2A    I95 @BASEBOARD_FAB2_LIB.BASEBOARD_FAB2(SCH_1):PAGE144

SMB_LAN_STBY_LVC3_SCL_R1 @BASEBOARD_FAB2_LIB.BASEBOARD_FAB2(SCH_1):SMB_LAN_STBY_LVC3_SCL_R1
  U7C1  BF1 GPP_H16_SML4CLK_IE LBG_CORE_QAT_EXT_D_BGA1-IC,H91A   I147 @BASEBOARD_FAB2_LIB.BASEBOARD_FAB2(SCH_1):PAGE120
  R2U6    1      A RES_0402-20.0,1%,1/16W,CHIP,G2A   I166 @BASEBOARD_FAB2_LIB.BASEBOARD_FAB2(SCH_1):PAGE138

SMB_LAN_STBY_LVC3_SCL_R2 @BASEBOARD_FAB2_LIB.BASEBOARD_FAB2(SCH_1):SMB_LAN_STBY_LVC3_SCL_R2
  U7C1  AU9 GPP_F19_LAN_SMBCLK LBG_CORE_QAT_EXT_D_BGA1-IC,H91A   I147 @BASEBOARD_FAB2_LIB.BASEBOARD_FAB2(SCH_1):PAGE120
 R2N21    1      A RES_0402-0.0,5%,1/16W,CHIP,G21A   I175 @BASEBOARD_FAB2_LIB.BASEBOARD_FAB2(SCH_1):PAGE138

SMB_LAN_STBY_LVC3_SDA @BASEBOARD_FAB2_LIB.BASEBOARD_FAB2(SCH_1):SMB_LAN_STBY_LVC3_SDA
 R2U11    2      B RES_0402-665,1.0%,1/16W,CHIP,GA    I97 @BASEBOARD_FAB2_LIB.BASEBOARD_FAB2(SCH_1):PAGE138
 R2U12    1      A RES_0402-20.0,1%,1/16W,EMPTY,GA   I159 @BASEBOARD_FAB2_LIB.BASEBOARD_FAB2(SCH_1):PAGE138
  R2U9    2      B RES_0402-20.0,1%,1/16W,CHIP,G2A   I165 @BASEBOARD_FAB2_LIB.BASEBOARD_FAB2(SCH_1):PAGE138
 R2N20    2      B RES_0402-0.0,5%,1/16W,CHIP,G21A   I171 @BASEBOARD_FAB2_LIB.BASEBOARD_FAB2(SCH_1):PAGE138
 R9M21    1      A RES_0402-0.0,5%,1/16W,CHIP,G21A   I321 @BASEBOARD_FAB2_LIB.BASEBOARD_FAB2(SCH_1):PAGE156
  R4A8    1      A RES_0402-0.0,5%,1/16W,CHIP,G21A   I322 @BASEBOARD_FAB2_LIB.BASEBOARD_FAB2(SCH_1):PAGE156
 R9F23    2      B RES_0402-20.0,1%,1/16W,CHIP,G2A    I51 @BASEBOARD_FAB2_LIB.BASEBOARD_FAB2(SCH_1):PAGE160
 R1C10    1      A RES_0402-0.0,5%,1/16W,EMPTY,G2A     I9 @BASEBOARD_FAB2_LIB.BASEBOARD_FAB2(SCH_1):PAGE182
  J1C1   D5 MNG_RX_DP DM-FCI-CONN76-8R-GP-U-01_CONN-A    I79 @BASEBOARD_FAB2_LIB.BASEBOARD_FAB2(SCH_1):PAGE182

SMB_LAN_STBY_LVC3_SDA_R @BASEBOARD_FAB2_LIB.BASEBOARD_FAB2(SCH_1):SMB_LAN_STBY_LVC3_SDA_R
 R9F23    1      A RES_0402-20.0,1%,1/16W,CHIP,G2A    I51 @BASEBOARD_FAB2_LIB.BASEBOARD_FAB2(SCH_1):PAGE160
 U25W4  M19 GPIOY5_SDA1 AST2520A1-GP-GP_ASIC2-GB1-AST2A    I95 @BASEBOARD_FAB2_LIB.BASEBOARD_FAB2(SCH_1):PAGE144

SMB_LAN_STBY_LVC3_SDA_R1 @BASEBOARD_FAB2_LIB.BASEBOARD_FAB2(SCH_1):SMB_LAN_STBY_LVC3_SDA_R1
  U7C1  BE4 GPP_H17_SML4DATA_IE LBG_CORE_QAT_EXT_D_BGA1-IC,H91A   I147 @BASEBOARD_FAB2_LIB.BASEBOARD_FAB2(SCH_1):PAGE120
  R2U9    1      A RES_0402-20.0,1%,1/16W,CHIP,G2A   I165 @BASEBOARD_FAB2_LIB.BASEBOARD_FAB2(SCH_1):PAGE138

SMB_LAN_STBY_LVC3_SDA_R2 @BASEBOARD_FAB2_LIB.BASEBOARD_FAB2(SCH_1):SMB_LAN_STBY_LVC3_SDA_R2
  U7C1 AU20 GPP_F20_LAN_SMBDATA LBG_CORE_QAT_EXT_D_BGA1-IC,H91A   I147 @BASEBOARD_FAB2_LIB.BASEBOARD_FAB2(SCH_1):PAGE120
 R2N20    1      A RES_0402-0.0,5%,1/16W,CHIP,G21A   I171 @BASEBOARD_FAB2_LIB.BASEBOARD_FAB2(SCH_1):PAGE138

SMB_M2_ALT_N @BASEBOARD_FAB2_LIB.BASEBOARD_FAB2(SCH_1):SMB_M2_ALT_N
  J8F1   44     44 SKT-MINI67P-41-GP_SOCKET-G4-SKA   I143 @BASEBOARD_FAB2_LIB.BASEBOARD_FAB2(SCH_1):PAGE185
R32W12    1      A RES_0402-0.0,5%,1/16W,CHIP,G21A   I187 @BASEBOARD_FAB2_LIB.BASEBOARD_FAB2(SCH_1):PAGE185
 R32W7    2      B RES_0402-2.0K,1%,1/16W,CHIP,G2A   I215 @BASEBOARD_FAB2_LIB.BASEBOARD_FAB2(SCH_1):PAGE185

SMB_M2_ALT_R_N @BASEBOARD_FAB2_LIB.BASEBOARD_FAB2(SCH_1):SMB_M2_ALT_R_N
R32W12    2      B RES_0402-0.0,5%,1/16W,CHIP,G21A   I187 @BASEBOARD_FAB2_LIB.BASEBOARD_FAB2(SCH_1):PAGE185
 U32W2    2   SCLA TCA9517DGKR-GP_DISCRET-G8-TCA9A   I204 @BASEBOARD_FAB2_LIB.BASEBOARD_FAB2(SCH_1):PAGE185

SMB_M2_SCL @BASEBOARD_FAB2_LIB.BASEBOARD_FAB2(SCH_1):SMB_M2_SCL
  J8F1   40     40 SKT-MINI67P-41-GP_SOCKET-G4-SKA   I143 @BASEBOARD_FAB2_LIB.BASEBOARD_FAB2(SCH_1):PAGE185
R32W10    1      A RES_0402-0.0,5%,1/16W,CHIP,G21A   I183 @BASEBOARD_FAB2_LIB.BASEBOARD_FAB2(SCH_1):PAGE185
 R32W5    2      B RES_0402-2.0K,1%,1/16W,CHIP,G2A   I216 @BASEBOARD_FAB2_LIB.BASEBOARD_FAB2(SCH_1):PAGE185

SMB_M2_SCL_R @BASEBOARD_FAB2_LIB.BASEBOARD_FAB2(SCH_1):SMB_M2_SCL_R
R32W10    2      B RES_0402-0.0,5%,1/16W,CHIP,G21A   I183 @BASEBOARD_FAB2_LIB.BASEBOARD_FAB2(SCH_1):PAGE185
 U32W1    2   SCLA TCA9517DGKR-GP_DISCRET-G8-TCA9A   I191 @BASEBOARD_FAB2_LIB.BASEBOARD_FAB2(SCH_1):PAGE185

SMB_M2_SDA @BASEBOARD_FAB2_LIB.BASEBOARD_FAB2(SCH_1):SMB_M2_SDA
  J8F1   42     42 SKT-MINI67P-41-GP_SOCKET-G4-SKA   I143 @BASEBOARD_FAB2_LIB.BASEBOARD_FAB2(SCH_1):PAGE185
R32W11    1      A RES_0402-0.0,5%,1/16W,CHIP,G21A   I184 @BASEBOARD_FAB2_LIB.BASEBOARD_FAB2(SCH_1):PAGE185
 R32W6    2      B RES_0402-2.0K,1%,1/16W,CHIP,G2A   I214 @BASEBOARD_FAB2_LIB.BASEBOARD_FAB2(SCH_1):PAGE185

SMB_M2_SDA_R @BASEBOARD_FAB2_LIB.BASEBOARD_FAB2(SCH_1):SMB_M2_SDA_R
R32W11    2      B RES_0402-0.0,5%,1/16W,CHIP,G21A   I184 @BASEBOARD_FAB2_LIB.BASEBOARD_FAB2(SCH_1):PAGE185
 U32W1    3   SDAA TCA9517DGKR-GP_DISCRET-G8-TCA9A   I191 @BASEBOARD_FAB2_LIB.BASEBOARD_FAB2(SCH_1):PAGE185

SMB_OCP_FRU_STBY_LVC3_SCL @BASEBOARD_FAB2_LIB.BASEBOARD_FAB2(SCH_1):SMB_OCP_FRU_STBY_LVC3_SCL
  J8B1   22   IO22 SCONN24_H46321001_SM-SCONN,H46A     I1 @BASEBOARD_FAB2_LIB.BASEBOARD_FAB2(SCH_1):PAGE91
  R2U8    2      B RES_0402-20.0,1%,1/16W,EMPTY,GA   I158 @BASEBOARD_FAB2_LIB.BASEBOARD_FAB2(SCH_1):PAGE138
  R2U7    2      B RES_0402-20.0,1%,1/16W,CHIP,G2A   I220 @BASEBOARD_FAB2_LIB.BASEBOARD_FAB2(SCH_1):PAGE159
  J9B3   30   IO30 SCONN120_A28699018_SM-SCONN,A2A   I336 @BASEBOARD_FAB2_LIB.BASEBOARD_FAB2(SCH_1):PAGE186
  J8E4    1    IO1 SCONN64_H87568002_A_SMT-CONN,HA    I27 @BASEBOARD_FAB2_LIB.BASEBOARD_FAB2(SCH_1):PAGE188

SMB_OCP_FRU_STBY_LVC3_SCL_R @BASEBOARD_FAB2_LIB.BASEBOARD_FAB2(SCH_1):SMB_OCP_FRU_STBY_LVC3_SCL_R
  R2U5    2      B RES_0402-2.26K,1.0%,1/16W,CHIPA   I214 @BASEBOARD_FAB2_LIB.BASEBOARD_FAB2(SCH_1):PAGE159
  R2U7    1      A RES_0402-20.0,1%,1/16W,CHIP,G2A   I220 @BASEBOARD_FAB2_LIB.BASEBOARD_FAB2(SCH_1):PAGE159
 U25W4  C14 GPIOA4_TIMER5_SCL9 AST2520A1-GP-GP_ASIC2-GB1-AST2A    I95 @BASEBOARD_FAB2_LIB.BASEBOARD_FAB2(SCH_1):PAGE144

SMB_OCP_FRU_STBY_LVC3_SDA @BASEBOARD_FAB2_LIB.BASEBOARD_FAB2(SCH_1):SMB_OCP_FRU_STBY_LVC3_SDA
  J8B1   24   IO24 SCONN24_H46321001_SM-SCONN,H46A     I1 @BASEBOARD_FAB2_LIB.BASEBOARD_FAB2(SCH_1):PAGE91
 R2U12    2      B RES_0402-20.0,1%,1/16W,EMPTY,GA   I159 @BASEBOARD_FAB2_LIB.BASEBOARD_FAB2(SCH_1):PAGE138
 R2U10    2      B RES_0402-20.0,1%,1/16W,CHIP,G2A   I221 @BASEBOARD_FAB2_LIB.BASEBOARD_FAB2(SCH_1):PAGE159
  J9B3   32   IO32 SCONN120_A28699018_SM-SCONN,A2A   I336 @BASEBOARD_FAB2_LIB.BASEBOARD_FAB2(SCH_1):PAGE186
  J8E4    2    IO2 SCONN64_H87568002_A_SMT-CONN,HA    I27 @BASEBOARD_FAB2_LIB.BASEBOARD_FAB2(SCH_1):PAGE188

SMB_OCP_FRU_STBY_LVC3_SDA_R @BASEBOARD_FAB2_LIB.BASEBOARD_FAB2(SCH_1):SMB_OCP_FRU_STBY_LVC3_SDA_R
 R2U13    2      B RES_0402-2.26K,1.0%,1/16W,CHIPA   I216 @BASEBOARD_FAB2_LIB.BASEBOARD_FAB2(SCH_1):PAGE159
 R2U10    1      A RES_0402-20.0,1%,1/16W,CHIP,G2A   I221 @BASEBOARD_FAB2_LIB.BASEBOARD_FAB2(SCH_1):PAGE159
 U25W4  A13 GPIOA5_TIMER6_SDA9 AST2520A1-GP-GP_ASIC2-GB1-AST2A    I95 @BASEBOARD_FAB2_LIB.BASEBOARD_FAB2(SCH_1):PAGE144

SMB_OCP_LAN_STBY_LVC3_SCL @BASEBOARD_FAB2_LIB.BASEBOARD_FAB2(SCH_1):SMB_OCP_LAN_STBY_LVC3_SCL
 R9G13    1      A RES_0402-20.0,1%,1/16W,CHIP,G2A   I227 @BASEBOARD_FAB2_LIB.BASEBOARD_FAB2(SCH_1):PAGE159
  R8G4    2      B RES_0402-20.0,1%,1/16W,CHIP,G2A   I229 @BASEBOARD_FAB2_LIB.BASEBOARD_FAB2(SCH_1):PAGE159
  J9B3   35   IO35 SCONN120_A28699018_SM-SCONN,A2A   I336 @BASEBOARD_FAB2_LIB.BASEBOARD_FAB2(SCH_1):PAGE186
 U32W1    7   SCLB TCA9517DGKR-GP_DISCRET-G8-TCA9A   I191 @BASEBOARD_FAB2_LIB.BASEBOARD_FAB2(SCH_1):PAGE185

SMB_OCP_LAN_STBY_LVC3_SCL_R @BASEBOARD_FAB2_LIB.BASEBOARD_FAB2(SCH_1):SMB_OCP_LAN_STBY_LVC3_SCL_R
  R8G3    2      B RES_0402-2.26K,1.0%,1/16W,EMPTA   I210 @BASEBOARD_FAB2_LIB.BASEBOARD_FAB2(SCH_1):PAGE159
  R8G4    1      A RES_0402-20.0,1%,1/16W,CHIP,G2A   I229 @BASEBOARD_FAB2_LIB.BASEBOARD_FAB2(SCH_1):PAGE159
 U25W4  A11 GPIOQ0_SCL3 AST2520A1-GP-GP_ASIC2-GB1-AST2A    I95 @BASEBOARD_FAB2_LIB.BASEBOARD_FAB2(SCH_1):PAGE144

SMB_OCP_LAN_STBY_LVC3_SDA @BASEBOARD_FAB2_LIB.BASEBOARD_FAB2(SCH_1):SMB_OCP_LAN_STBY_LVC3_SDA
 R9G12    1      A RES_0402-20.0,1%,1/16W,CHIP,G2A   I224 @BASEBOARD_FAB2_LIB.BASEBOARD_FAB2(SCH_1):PAGE159
  R8G5    2      B RES_0402-20.0,1%,1/16W,CHIP,G2A   I228 @BASEBOARD_FAB2_LIB.BASEBOARD_FAB2(SCH_1):PAGE159
  J9B3   37   IO37 SCONN120_A28699018_SM-SCONN,A2A   I336 @BASEBOARD_FAB2_LIB.BASEBOARD_FAB2(SCH_1):PAGE186
 U32W1    6   SDAB TCA9517DGKR-GP_DISCRET-G8-TCA9A   I191 @BASEBOARD_FAB2_LIB.BASEBOARD_FAB2(SCH_1):PAGE185

SMB_OCP_LAN_STBY_LVC3_SDA_R @BASEBOARD_FAB2_LIB.BASEBOARD_FAB2(SCH_1):SMB_OCP_LAN_STBY_LVC3_SDA_R
  R8G6    2      B RES_0402-2.26K,1.0%,1/16W,EMPTA   I212 @BASEBOARD_FAB2_LIB.BASEBOARD_FAB2(SCH_1):PAGE159
  R8G5    1      A RES_0402-20.0,1%,1/16W,CHIP,G2A   I228 @BASEBOARD_FAB2_LIB.BASEBOARD_FAB2(SCH_1):PAGE159
 U25W4  A10 GPIOQ1_SDA3 AST2520A1-GP-GP_ASIC2-GB1-AST2A    I95 @BASEBOARD_FAB2_LIB.BASEBOARD_FAB2(SCH_1):PAGE144

SMB_PCH_MEZZ_LOM0_SCL @BASEBOARD_FAB2_LIB.BASEBOARD_FAB2(SCH_1):SMB_PCH_MEZZ_LOM0_SCL
  U7C1  BM4 GPP_J8_LAN_I2C_SCL_MDC_P0 LBG_CORE_QAT_EXT_D_BGA1-IC,H91A   I147 @BASEBOARD_FAB2_LIB.BASEBOARD_FAB2(SCH_1):PAGE120
  J8E4   20   IO20 SCONN64_H87568002_A_SMT-CONN,HA    I27 @BASEBOARD_FAB2_LIB.BASEBOARD_FAB2(SCH_1):PAGE188
 R1R18    2      B RES_0402-2.21K,1%,1/16W,CHIP,GA    I88 @BASEBOARD_FAB2_LIB.BASEBOARD_FAB2(SCH_1):PAGE188

SMB_PCH_MEZZ_LOM0_SDA @BASEBOARD_FAB2_LIB.BASEBOARD_FAB2(SCH_1):SMB_PCH_MEZZ_LOM0_SDA
  U7C1  BN3 GPP_J9_LAN_I2C_SDA_MDIO_P0 LBG_CORE_QAT_EXT_D_BGA1-IC,H91A   I147 @BASEBOARD_FAB2_LIB.BASEBOARD_FAB2(SCH_1):PAGE120
  J8E4   21   IO21 SCONN64_H87568002_A_SMT-CONN,HA    I27 @BASEBOARD_FAB2_LIB.BASEBOARD_FAB2(SCH_1):PAGE188
 R1R19    2      B RES_0402-2.21K,1%,1/16W,CHIP,GA    I89 @BASEBOARD_FAB2_LIB.BASEBOARD_FAB2(SCH_1):PAGE188

SMB_PCH_MEZZ_LOM1_SCL @BASEBOARD_FAB2_LIB.BASEBOARD_FAB2(SCH_1):SMB_PCH_MEZZ_LOM1_SCL
  U7C1  BW5 GPP_J10_LAN_I2C_SCL_MDC_P1 LBG_CORE_QAT_EXT_D_BGA1-IC,H91A   I147 @BASEBOARD_FAB2_LIB.BASEBOARD_FAB2(SCH_1):PAGE120
  J8E4   26   IO26 SCONN64_H87568002_A_SMT-CONN,HA    I27 @BASEBOARD_FAB2_LIB.BASEBOARD_FAB2(SCH_1):PAGE188
 R1R20    2      B RES_0402-2.21K,1%,1/16W,CHIP,GA    I91 @BASEBOARD_FAB2_LIB.BASEBOARD_FAB2(SCH_1):PAGE188

SMB_PCH_MEZZ_LOM1_SDA @BASEBOARD_FAB2_LIB.BASEBOARD_FAB2(SCH_1):SMB_PCH_MEZZ_LOM1_SDA
  U7C1  BV8 GPP_J11_LAN_I2C_SDA_MDIO_P1 LBG_CORE_QAT_EXT_D_BGA1-IC,H91A   I147 @BASEBOARD_FAB2_LIB.BASEBOARD_FAB2(SCH_1):PAGE120
  J8E4   27   IO27 SCONN64_H87568002_A_SMT-CONN,HA    I27 @BASEBOARD_FAB2_LIB.BASEBOARD_FAB2(SCH_1):PAGE188
 R1R21    2      B RES_0402-2.21K,1%,1/16W,CHIP,GA    I90 @BASEBOARD_FAB2_LIB.BASEBOARD_FAB2(SCH_1):PAGE188

SMB_PCH_MEZZ_LOM2_SCL @BASEBOARD_FAB2_LIB.BASEBOARD_FAB2(SCH_1):SMB_PCH_MEZZ_LOM2_SCL
  U7C1  BT5 GPP_J12_LAN_I2C_SCL_MDC_P2 LBG_CORE_QAT_EXT_D_BGA1-IC,H91A   I147 @BASEBOARD_FAB2_LIB.BASEBOARD_FAB2(SCH_1):PAGE120
  J8E4   61   IO61 SCONN64_H87568002_A_SMT-CONN,HA    I27 @BASEBOARD_FAB2_LIB.BASEBOARD_FAB2(SCH_1):PAGE188
 R1R16    2      B RES_0402-2.21K,1%,1/16W,CHIP,GA    I93 @BASEBOARD_FAB2_LIB.BASEBOARD_FAB2(SCH_1):PAGE188

SMB_PCH_MEZZ_LOM2_SDA @BASEBOARD_FAB2_LIB.BASEBOARD_FAB2(SCH_1):SMB_PCH_MEZZ_LOM2_SDA
  U7C1 BW11 GPP_J13_LAN_I2C_SDA_MDIO_P2 LBG_CORE_QAT_EXT_D_BGA1-IC,H91A   I147 @BASEBOARD_FAB2_LIB.BASEBOARD_FAB2(SCH_1):PAGE120
  J8E4   62   IO62 SCONN64_H87568002_A_SMT-CONN,HA    I27 @BASEBOARD_FAB2_LIB.BASEBOARD_FAB2(SCH_1):PAGE188
 R1R17    2      B RES_0402-2.21K,1%,1/16W,CHIP,GA    I94 @BASEBOARD_FAB2_LIB.BASEBOARD_FAB2(SCH_1):PAGE188

SMB_PCH_MEZZ_LOM3_SCL @BASEBOARD_FAB2_LIB.BASEBOARD_FAB2(SCH_1):SMB_PCH_MEZZ_LOM3_SCL
  U7C1  BW6 GPP_J14_LAN_I2C_SCL_MDC_P3 LBG_CORE_QAT_EXT_D_BGA1-IC,H91A   I147 @BASEBOARD_FAB2_LIB.BASEBOARD_FAB2(SCH_1):PAGE120
  J8E4   29   IO29 SCONN64_H87568002_A_SMT-CONN,HA    I27 @BASEBOARD_FAB2_LIB.BASEBOARD_FAB2(SCH_1):PAGE188
 R1R23    2      B RES_0402-2.21K,1%,1/16W,CHIP,GA    I95 @BASEBOARD_FAB2_LIB.BASEBOARD_FAB2(SCH_1):PAGE188

SMB_PCH_MEZZ_LOM3_SDA @BASEBOARD_FAB2_LIB.BASEBOARD_FAB2(SCH_1):SMB_PCH_MEZZ_LOM3_SDA
  U7C1  BW9 GPP_J15_LAN_I2C_SDA_MDIO_P3 LBG_CORE_QAT_EXT_D_BGA1-IC,H91A   I147 @BASEBOARD_FAB2_LIB.BASEBOARD_FAB2(SCH_1):PAGE120
  J8E4   30   IO30 SCONN64_H87568002_A_SMT-CONN,HA    I27 @BASEBOARD_FAB2_LIB.BASEBOARD_FAB2(SCH_1):PAGE188
 R1R22    2      B RES_0402-2.21K,1%,1/16W,CHIP,GA    I92 @BASEBOARD_FAB2_LIB.BASEBOARD_FAB2(SCH_1):PAGE188

SMB_PEHPCPU0_STBY_LVC3_R2_SCL @BASEBOARD_FAB2_LIB.BASEBOARD_FAB2(SCH_1):SMB_PEHPCPU0_STBY_LVC3_R2_SCL
 U25W4  C11 GPIOC6_SD1CD#_SCL13 AST2520A1-GP-GP_ASIC2-GB1-AST2A   I117 @BASEBOARD_FAB2_LIB.BASEBOARD_FAB2(SCH_1):PAGE145
R25W122    2      B RES_0402-20.0,1%,1/16W,CHIP,G2A   I164 @BASEBOARD_FAB2_LIB.BASEBOARD_FAB2(SCH_1):PAGE145

SMB_PEHPCPU0_STBY_LVC3_R2_SDA @BASEBOARD_FAB2_LIB.BASEBOARD_FAB2(SCH_1):SMB_PEHPCPU0_STBY_LVC3_R2_SDA
 U25W4  B11 GPIOC7_SD1WP#_SDA13 AST2520A1-GP-GP_ASIC2-GB1-AST2A   I117 @BASEBOARD_FAB2_LIB.BASEBOARD_FAB2(SCH_1):PAGE145
R25W121    2      B RES_0402-20.0,1%,1/16W,CHIP,G2A   I163 @BASEBOARD_FAB2_LIB.BASEBOARD_FAB2(SCH_1):PAGE145

SMB_PEHPCPU0_STBY_LVC3_R_SCL @BASEBOARD_FAB2_LIB.BASEBOARD_FAB2(SCH_1):SMB_PEHPCPU0_STBY_LVC3_R_SCL
 R9W17    2      B RES_0402-2.0K,1%,1/16W,CHIP,G2A    I35 @BASEBOARD_FAB2_LIB.BASEBOARD_FAB2(SCH_1):PAGE248
 R9W14    1      A RES_0402-20.0,1%,1/16W,CHIP,G2A    I37 @BASEBOARD_FAB2_LIB.BASEBOARD_FAB2(SCH_1):PAGE248
  U1W2    7   SCLB TCA9517DGKR-GP_DISCRET-G8-TCA9A    I49 @BASEBOARD_FAB2_LIB.BASEBOARD_FAB2(SCH_1):PAGE248
R25W122    1      A RES_0402-20.0,1%,1/16W,CHIP,G2A   I164 @BASEBOARD_FAB2_LIB.BASEBOARD_FAB2(SCH_1):PAGE145

SMB_PEHPCPU0_STBY_LVC3_R_SDA @BASEBOARD_FAB2_LIB.BASEBOARD_FAB2(SCH_1):SMB_PEHPCPU0_STBY_LVC3_R_SDA
 R9W16    2      B RES_0402-2.0K,1%,1/16W,CHIP,G2A    I34 @BASEBOARD_FAB2_LIB.BASEBOARD_FAB2(SCH_1):PAGE248
 R9W13    1      A RES_0402-20.0,1%,1/16W,CHIP,G2A    I38 @BASEBOARD_FAB2_LIB.BASEBOARD_FAB2(SCH_1):PAGE248
  U1W2    6   SDAB TCA9517DGKR-GP_DISCRET-G8-TCA9A    I49 @BASEBOARD_FAB2_LIB.BASEBOARD_FAB2(SCH_1):PAGE248
R25W121    1      A RES_0402-20.0,1%,1/16W,CHIP,G2A   I163 @BASEBOARD_FAB2_LIB.BASEBOARD_FAB2(SCH_1):PAGE145

SMB_PEHPCPU0_STBY_LVC3_SCL @BASEBOARD_FAB2_LIB.BASEBOARD_FAB2(SCH_1):SMB_PEHPCPU0_STBY_LVC3_SCL
 U25W4  B12 GPIOC2_SD1DAT0_SCL11 AST2520A1-GP-GP_ASIC2-GB1-AST2A   I117 @BASEBOARD_FAB2_LIB.BASEBOARD_FAB2(SCH_1):PAGE145
 R9W14    2      B RES_0402-20.0,1%,1/16W,CHIP,G2A    I37 @BASEBOARD_FAB2_LIB.BASEBOARD_FAB2(SCH_1):PAGE248

SMB_PEHPCPU0_STBY_LVC3_SDA @BASEBOARD_FAB2_LIB.BASEBOARD_FAB2(SCH_1):SMB_PEHPCPU0_STBY_LVC3_SDA
 U25W4   D9 GPIOC3_SD1DAT1_SDA11 AST2520A1-GP-GP_ASIC2-GB1-AST2A   I117 @BASEBOARD_FAB2_LIB.BASEBOARD_FAB2(SCH_1):PAGE145
 R9W13    2      B RES_0402-20.0,1%,1/16W,CHIP,G2A    I38 @BASEBOARD_FAB2_LIB.BASEBOARD_FAB2(SCH_1):PAGE248

SMB_PEHPCPU1_STBY_LVC3_R_SCL @BASEBOARD_FAB2_LIB.BASEBOARD_FAB2(SCH_1):SMB_PEHPCPU1_STBY_LVC3_R_SCL
 R9M17    2      B RES_0402-2.0K,1%,1/16W,CHIP,G2A    I15 @BASEBOARD_FAB2_LIB.BASEBOARD_FAB2(SCH_1):PAGE163
 R9M14    1      A RES_0402-20.0,1%,1/16W,CHIP,G2A    I20 @BASEBOARD_FAB2_LIB.BASEBOARD_FAB2(SCH_1):PAGE163
  U1B2    7   SCLB TCA9517DGKR-GP_DISCRET-G8-TCA9A    I28 @BASEBOARD_FAB2_LIB.BASEBOARD_FAB2(SCH_1):PAGE163

SMB_PEHPCPU1_STBY_LVC3_R_SDA @BASEBOARD_FAB2_LIB.BASEBOARD_FAB2(SCH_1):SMB_PEHPCPU1_STBY_LVC3_R_SDA
 R9M16    2      B RES_0402-2.0K,1%,1/16W,CHIP,G2A    I16 @BASEBOARD_FAB2_LIB.BASEBOARD_FAB2(SCH_1):PAGE163
 R9M13    1      A RES_0402-20.0,1%,1/16W,CHIP,G2A    I21 @BASEBOARD_FAB2_LIB.BASEBOARD_FAB2(SCH_1):PAGE163
  U1B2    6   SDAB TCA9517DGKR-GP_DISCRET-G8-TCA9A    I28 @BASEBOARD_FAB2_LIB.BASEBOARD_FAB2(SCH_1):PAGE163

SMB_PEHPCPU1_STBY_LVC3_SCL @BASEBOARD_FAB2_LIB.BASEBOARD_FAB2(SCH_1):SMB_PEHPCPU1_STBY_LVC3_SCL
 R9M14    2      B RES_0402-20.0,1%,1/16W,CHIP,G2A    I20 @BASEBOARD_FAB2_LIB.BASEBOARD_FAB2(SCH_1):PAGE163
 U25W4  D10 GPIOC4_SD1DAT2_SCL12 AST2520A1-GP-GP_ASIC2-GB1-AST2A   I117 @BASEBOARD_FAB2_LIB.BASEBOARD_FAB2(SCH_1):PAGE145
  J1C1   C6 PMBUS_CLK DM-FCI-CONN76-8R-GP-U-01_CONN-A    I79 @BASEBOARD_FAB2_LIB.BASEBOARD_FAB2(SCH_1):PAGE182

SMB_PEHPCPU1_STBY_LVC3_SDA @BASEBOARD_FAB2_LIB.BASEBOARD_FAB2(SCH_1):SMB_PEHPCPU1_STBY_LVC3_SDA
 R9M13    2      B RES_0402-20.0,1%,1/16W,CHIP,G2A    I21 @BASEBOARD_FAB2_LIB.BASEBOARD_FAB2(SCH_1):PAGE163
 U25W4  E12 GPIOC5_SD1DAT3_SDA12 AST2520A1-GP-GP_ASIC2-GB1-AST2A   I117 @BASEBOARD_FAB2_LIB.BASEBOARD_FAB2(SCH_1):PAGE145
  J1C1   B6 PMBUS_DATA DM-FCI-CONN76-8R-GP-U-01_CONN-A    I79 @BASEBOARD_FAB2_LIB.BASEBOARD_FAB2(SCH_1):PAGE182

SMB_PIROM_CPU0_SCL @BASEBOARD_FAB2_LIB.BASEBOARD_FAB2(SCH_1):SMB_PIROM_CPU0_SCL
  U5D1 CT59 SMBCLK SKX_EXT_B_BGA1-IC,TBD   I259 @BASEBOARD_FAB2_LIB.BASEBOARD_FAB2(SCH_1):PAGE21
  R4A9    2      B RES_0402-0.0,5%,1/16W,CHIP,G21A   I324 @BASEBOARD_FAB2_LIB.BASEBOARD_FAB2(SCH_1):PAGE156

SMB_PIROM_CPU0_SDA @BASEBOARD_FAB2_LIB.BASEBOARD_FAB2(SCH_1):SMB_PIROM_CPU0_SDA
  U5D1 CW58 SMBDAT SKX_EXT_B_BGA1-IC,TBD   I259 @BASEBOARD_FAB2_LIB.BASEBOARD_FAB2(SCH_1):PAGE21
  R4A8    2      B RES_0402-0.0,5%,1/16W,CHIP,G21A   I322 @BASEBOARD_FAB2_LIB.BASEBOARD_FAB2(SCH_1):PAGE156

SMB_PIROM_CPU1_SCL @BASEBOARD_FAB2_LIB.BASEBOARD_FAB2(SCH_1):SMB_PIROM_CPU1_SCL
  U2D1 CT59 SMBCLK SKX_EXT_B_BGA1-IC,TBD   I172 @BASEBOARD_FAB2_LIB.BASEBOARD_FAB2(SCH_1):PAGE55
 R9M20    2      B RES_0402-0.0,5%,1/16W,CHIP,G21A   I323 @BASEBOARD_FAB2_LIB.BASEBOARD_FAB2(SCH_1):PAGE156

SMB_PIROM_CPU1_SDA @BASEBOARD_FAB2_LIB.BASEBOARD_FAB2(SCH_1):SMB_PIROM_CPU1_SDA
  U2D1 CW58 SMBDAT SKX_EXT_B_BGA1-IC,TBD   I172 @BASEBOARD_FAB2_LIB.BASEBOARD_FAB2(SCH_1):PAGE55
 R9M21    2      B RES_0402-0.0,5%,1/16W,CHIP,G21A   I321 @BASEBOARD_FAB2_LIB.BASEBOARD_FAB2(SCH_1):PAGE156

SMB_PMBUS_BMC_STBY_LVC3_SCL_R1 @BASEBOARD_FAB2_LIB.BASEBOARD_FAB2(SCH_1):SMB_PMBUS_BMC_STBY_LVC3_SCL_R1
  U7C1 CA28 GPP_C6_SML1CLK_IE LBG_CORE_QAT_EXT_D_BGA1-IC,H91A   I115 @BASEBOARD_FAB2_LIB.BASEBOARD_FAB2(SCH_1):PAGE119
 R6W25    2      B RES_0402-4.75K,1%,1/16W,CHIP,GA   I101 @BASEBOARD_FAB2_LIB.BASEBOARD_FAB2(SCH_1):PAGE247
  U6W2    2   SCLA TCA9517DGKR-GP_DISCRET-G8-TCA9A   I118 @BASEBOARD_FAB2_LIB.BASEBOARD_FAB2(SCH_1):PAGE247

SMB_PMBUS_BMC_STBY_LVC3_SDA_R1 @BASEBOARD_FAB2_LIB.BASEBOARD_FAB2(SCH_1):SMB_PMBUS_BMC_STBY_LVC3_SDA_R1
  U7C1 BV35 GPP_C7_SML1DATA_IE LBG_CORE_QAT_EXT_D_BGA1-IC,H91A   I115 @BASEBOARD_FAB2_LIB.BASEBOARD_FAB2(SCH_1):PAGE119
 R6W24    2      B RES_0402-4.75K,1%,1/16W,CHIP,GA   I100 @BASEBOARD_FAB2_LIB.BASEBOARD_FAB2(SCH_1):PAGE247
  U6W2    3   SDAA TCA9517DGKR-GP_DISCRET-G8-TCA9A   I118 @BASEBOARD_FAB2_LIB.BASEBOARD_FAB2(SCH_1):PAGE247

SMB_SENSOR_BMC_STBY_LVC3_SCL @BASEBOARD_FAB2_LIB.BASEBOARD_FAB2(SCH_1):SMB_SENSOR_BMC_STBY_LVC3_SCL
 R9G14    1      A RES_0402-20.0,1%,1/16W,CHIP,G2A    I77 @BASEBOARD_FAB2_LIB.BASEBOARD_FAB2(SCH_1):PAGE167
 U25W4   N1 GPIOK4_SCL7 AST2520A1-GP-GP_ASIC2-GB1-AST2A    I95 @BASEBOARD_FAB2_LIB.BASEBOARD_FAB2(SCH_1):PAGE144

SMB_SENSOR_BMC_STBY_LVC3_SDA @BASEBOARD_FAB2_LIB.BASEBOARD_FAB2(SCH_1):SMB_SENSOR_BMC_STBY_LVC3_SDA
 R9G15    1      A RES_0402-20.0,1%,1/16W,CHIP,G2A    I58 @BASEBOARD_FAB2_LIB.BASEBOARD_FAB2(SCH_1):PAGE167
 U25W4   P1 GPIOK5_SDA7 AST2520A1-GP-GP_ASIC2-GB1-AST2A    I95 @BASEBOARD_FAB2_LIB.BASEBOARD_FAB2(SCH_1):PAGE144

SMB_SENSOR_STBY_LVC3_SCL @BASEBOARD_FAB2_LIB.BASEBOARD_FAB2(SCH_1):SMB_SENSOR_STBY_LVC3_SCL
  R1M8    2      B RES_0402-20.0,1%,1/16W,CHIP,G2A    I74 @BASEBOARD_FAB2_LIB.BASEBOARD_FAB2(SCH_1):PAGE167
  R9R7    2      B RES_0402-20.0,1%,1/16W,CHIP,G2A    I75 @BASEBOARD_FAB2_LIB.BASEBOARD_FAB2(SCH_1):PAGE167
 R9G14    2      B RES_0402-20.0,1%,1/16W,CHIP,G2A    I77 @BASEBOARD_FAB2_LIB.BASEBOARD_FAB2(SCH_1):PAGE167
 R2U38    2      B RES_0402-665,1.0%,1/16W,CHIP,GA    I80 @BASEBOARD_FAB2_LIB.BASEBOARD_FAB2(SCH_1):PAGE167
 R8D24    1      A RES_0402-20.0,1%,1/16W,CHIP,G2A    I84 @BASEBOARD_FAB2_LIB.BASEBOARD_FAB2(SCH_1):PAGE167
  J8E1   10   IO10 SCONN11_H67026001_SM-CONN,H670A    I87 @BASEBOARD_FAB2_LIB.BASEBOARD_FAB2(SCH_1):PAGE184
  U8D7   A9 PT18C_SCL_PCLKT0_0 LCMXO2_A_256BGA-IC,H63395-001    I59 @BASEBOARD_FAB2_LIB.BASEBOARD_FAB2(SCH_1):PAGE191
 U6W11   14    SCL PCA9554PWR-GP_DISCRET-G1-PCA95A    I97 @BASEBOARD_FAB2_LIB.BASEBOARD_FAB2(SCH_1):PAGE164

SMB_SENSOR_STBY_LVC3_SCL_R2 @BASEBOARD_FAB2_LIB.BASEBOARD_FAB2(SCH_1):SMB_SENSOR_STBY_LVC3_SCL_R2
  U8D4    6    SCL AT24C64_SOICLF-IC,C47049-001-GA    I49 @BASEBOARD_FAB2_LIB.BASEBOARD_FAB2(SCH_1):PAGE167
 R8D24    2      B RES_0402-20.0,1%,1/16W,CHIP,G2A    I84 @BASEBOARD_FAB2_LIB.BASEBOARD_FAB2(SCH_1):PAGE167

SMB_SENSOR_STBY_LVC3_SDA @BASEBOARD_FAB2_LIB.BASEBOARD_FAB2(SCH_1):SMB_SENSOR_STBY_LVC3_SDA
  R1M9    2      B RES_0402-20.0,1%,1/16W,CHIP,G2A     I8 @BASEBOARD_FAB2_LIB.BASEBOARD_FAB2(SCH_1):PAGE167
 R9G15    2      B RES_0402-20.0,1%,1/16W,CHIP,G2A    I58 @BASEBOARD_FAB2_LIB.BASEBOARD_FAB2(SCH_1):PAGE167
  R9R8    2      B RES_0402-20.0,1%,1/16W,CHIP,G2A    I76 @BASEBOARD_FAB2_LIB.BASEBOARD_FAB2(SCH_1):PAGE167
 R2U39    2      B RES_0402-665,1.0%,1/16W,CHIP,GA    I83 @BASEBOARD_FAB2_LIB.BASEBOARD_FAB2(SCH_1):PAGE167
 R8D23    2      B RES_0402-20.0,1%,1/16W,CHIP,G2A    I85 @BASEBOARD_FAB2_LIB.BASEBOARD_FAB2(SCH_1):PAGE167
  J8E1    6    IO6 SCONN11_H67026001_SM-CONN,H670A    I87 @BASEBOARD_FAB2_LIB.BASEBOARD_FAB2(SCH_1):PAGE184
  U8D7   C9 PT18D_SDA_PCLKC0_0 LCMXO2_A_256BGA-IC,H63395-001    I59 @BASEBOARD_FAB2_LIB.BASEBOARD_FAB2(SCH_1):PAGE191
 U6W11   15    SDA PCA9554PWR-GP_DISCRET-G1-PCA95A    I97 @BASEBOARD_FAB2_LIB.BASEBOARD_FAB2(SCH_1):PAGE164

SMB_SENSOR_STBY_LVC3_SDA_R2 @BASEBOARD_FAB2_LIB.BASEBOARD_FAB2(SCH_1):SMB_SENSOR_STBY_LVC3_SDA_R2
  U8D4    5    SDA AT24C64_SOICLF-IC,C47049-001-GA    I49 @BASEBOARD_FAB2_LIB.BASEBOARD_FAB2(SCH_1):PAGE167
 R8D23    1      A RES_0402-20.0,1%,1/16W,CHIP,G2A    I85 @BASEBOARD_FAB2_LIB.BASEBOARD_FAB2(SCH_1):PAGE167

SMB_SENSOR_TMP421_1_SCL @BASEBOARD_FAB2_LIB.BASEBOARD_FAB2(SCH_1):SMB_SENSOR_TMP421_1_SCL
  U9B4    7    SCL TMP421_TSSOP-IC,G62962-001     I1 @BASEBOARD_FAB2_LIB.BASEBOARD_FAB2(SCH_1):PAGE167
  R1M8    1      A RES_0402-20.0,1%,1/16W,CHIP,G2A    I74 @BASEBOARD_FAB2_LIB.BASEBOARD_FAB2(SCH_1):PAGE167

SMB_SENSOR_TMP421_1_SDA @BASEBOARD_FAB2_LIB.BASEBOARD_FAB2(SCH_1):SMB_SENSOR_TMP421_1_SDA
  U9B4    6    SDA TMP421_TSSOP-IC,G62962-001     I1 @BASEBOARD_FAB2_LIB.BASEBOARD_FAB2(SCH_1):PAGE167
  R1M9    1      A RES_0402-20.0,1%,1/16W,CHIP,G2A     I8 @BASEBOARD_FAB2_LIB.BASEBOARD_FAB2(SCH_1):PAGE167

SMB_SENSOR_TMP421_2_SCL @BASEBOARD_FAB2_LIB.BASEBOARD_FAB2(SCH_1):SMB_SENSOR_TMP421_2_SCL
  U1E1    7    SCL TMP421_TSSOP-IC,G62962-001    I30 @BASEBOARD_FAB2_LIB.BASEBOARD_FAB2(SCH_1):PAGE167
  R9R7    1      A RES_0402-20.0,1%,1/16W,CHIP,G2A    I75 @BASEBOARD_FAB2_LIB.BASEBOARD_FAB2(SCH_1):PAGE167

SMB_SENSOR_TMP421_2_SDA @BASEBOARD_FAB2_LIB.BASEBOARD_FAB2(SCH_1):SMB_SENSOR_TMP421_2_SDA
  U1E1    6    SDA TMP421_TSSOP-IC,G62962-001    I30 @BASEBOARD_FAB2_LIB.BASEBOARD_FAB2(SCH_1):PAGE167
  R9R8    1      A RES_0402-20.0,1%,1/16W,CHIP,G2A    I76 @BASEBOARD_FAB2_LIB.BASEBOARD_FAB2(SCH_1):PAGE167

SMB_SLOTX24_BMC_STBY_LVC3_SCL @BASEBOARD_FAB2_LIB.BASEBOARD_FAB2(SCH_1):SMB_SLOTX24_BMC_STBY_LVC3_SCL
 R2U32    1      A RES_0402-20.0,1%,1/16W,CHIP,G2A   I339 @BASEBOARD_FAB2_LIB.BASEBOARD_FAB2(SCH_1):PAGE108
  R1T7    2      B RES_0402-20.0,1%,1/16W,CHIP,G2A    I50 @BASEBOARD_FAB2_LIB.BASEBOARD_FAB2(SCH_1):PAGE160

SMB_SLOTX24_BMC_STBY_LVC3_SDA @BASEBOARD_FAB2_LIB.BASEBOARD_FAB2(SCH_1):SMB_SLOTX24_BMC_STBY_LVC3_SDA
 R2U31    1      A RES_0402-20.0,1%,1/16W,CHIP,G2A   I330 @BASEBOARD_FAB2_LIB.BASEBOARD_FAB2(SCH_1):PAGE108
  R1T8    2      B RES_0402-20.0,1%,1/16W,CHIP,G2A     I4 @BASEBOARD_FAB2_LIB.BASEBOARD_FAB2(SCH_1):PAGE160

SMB_SLOTX24_PCH_STBY_LVC3_SCL @BASEBOARD_FAB2_LIB.BASEBOARD_FAB2(SCH_1):SMB_SLOTX24_PCH_STBY_LVC3_SCL
  U7C1 BY44 GPP_D13_SML0BCLK_IE LBG_CORE_QAT_EXT_D_BGA1-IC,H91A   I115 @BASEBOARD_FAB2_LIB.BASEBOARD_FAB2(SCH_1):PAGE119
 R2U36    1      A RES_0402-20.0,1%,1/16W,EMPTY,GA   I351 @BASEBOARD_FAB2_LIB.BASEBOARD_FAB2(SCH_1):PAGE108
 R24W2    2      B RES_0402-3.3K,5%,1/16W,CHIP,G2A   I199 @BASEBOARD_FAB2_LIB.BASEBOARD_FAB2(SCH_1):PAGE138

SMB_SLOTX24_PCH_STBY_LVC3_SDA @BASEBOARD_FAB2_LIB.BASEBOARD_FAB2(SCH_1):SMB_SLOTX24_PCH_STBY_LVC3_SDA
  U7C1 BL44 GPP_D14_SML0BDATA_IE LBG_CORE_QAT_EXT_D_BGA1-IC,H91A   I115 @BASEBOARD_FAB2_LIB.BASEBOARD_FAB2(SCH_1):PAGE119
 R2U35    1      A RES_0402-20.0,1%,1/16W,EMPTY,GA   I350 @BASEBOARD_FAB2_LIB.BASEBOARD_FAB2(SCH_1):PAGE108
 R24W1    2      B RES_0402-3.3K,5%,1/16W,CHIP,G2A   I198 @BASEBOARD_FAB2_LIB.BASEBOARD_FAB2(SCH_1):PAGE138

SMB_SLOTX24_STBY_LVC3_SCL_R @BASEBOARD_FAB2_LIB.BASEBOARD_FAB2(SCH_1):SMB_SLOTX24_STBY_LVC3_SCL_R
  R1T2    2      B RES_0402-665,1.0%,1/16W,CHIP,GA    I49 @BASEBOARD_FAB2_LIB.BASEBOARD_FAB2(SCH_1):PAGE160
  R1T7    1      A RES_0402-20.0,1%,1/16W,CHIP,G2A    I50 @BASEBOARD_FAB2_LIB.BASEBOARD_FAB2(SCH_1):PAGE160
 U25W4  M20 GPIOY6_SCL2 AST2520A1-GP-GP_ASIC2-GB1-AST2A    I95 @BASEBOARD_FAB2_LIB.BASEBOARD_FAB2(SCH_1):PAGE144

SMB_SLOTX24_STBY_LVC3_SCL_R2 @BASEBOARD_FAB2_LIB.BASEBOARD_FAB2(SCH_1):SMB_SLOTX24_STBY_LVC3_SCL_R2
  J8G1   17   IO17 SCONN200_H68296001_SM-CONN,H68A   I258 @BASEBOARD_FAB2_LIB.BASEBOARD_FAB2(SCH_1):PAGE108
 R2U32    2      B RES_0402-20.0,1%,1/16W,CHIP,G2A   I339 @BASEBOARD_FAB2_LIB.BASEBOARD_FAB2(SCH_1):PAGE108
 R2U36    2      B RES_0402-20.0,1%,1/16W,EMPTY,GA   I351 @BASEBOARD_FAB2_LIB.BASEBOARD_FAB2(SCH_1):PAGE108

SMB_SLOTX24_STBY_LVC3_SDA_R @BASEBOARD_FAB2_LIB.BASEBOARD_FAB2(SCH_1):SMB_SLOTX24_STBY_LVC3_SDA_R
  R1T8    1      A RES_0402-20.0,1%,1/16W,CHIP,G2A     I4 @BASEBOARD_FAB2_LIB.BASEBOARD_FAB2(SCH_1):PAGE160
  R1T3    2      B RES_0402-665,1.0%,1/16W,CHIP,GA    I46 @BASEBOARD_FAB2_LIB.BASEBOARD_FAB2(SCH_1):PAGE160
 U25W4  P20 GPIOY7_SDA2 AST2520A1-GP-GP_ASIC2-GB1-AST2A    I95 @BASEBOARD_FAB2_LIB.BASEBOARD_FAB2(SCH_1):PAGE144

SMB_SLOTX24_STBY_LVC3_SDA_R2 @BASEBOARD_FAB2_LIB.BASEBOARD_FAB2(SCH_1):SMB_SLOTX24_STBY_LVC3_SDA_R2
  J8G1   15   IO15 SCONN200_H68296001_SM-CONN,H68A   I258 @BASEBOARD_FAB2_LIB.BASEBOARD_FAB2(SCH_1):PAGE108
 R2U31    2      B RES_0402-20.0,1%,1/16W,CHIP,G2A   I330 @BASEBOARD_FAB2_LIB.BASEBOARD_FAB2(SCH_1):PAGE108
 R2U35    2      B RES_0402-20.0,1%,1/16W,EMPTY,GA   I350 @BASEBOARD_FAB2_LIB.BASEBOARD_FAB2(SCH_1):PAGE108

SMB_SMLINK0_STBY_LVC3_SCL @BASEBOARD_FAB2_LIB.BASEBOARD_FAB2(SCH_1):SMB_SMLINK0_STBY_LVC3_SCL
  R2N5    2      B RES_0402-665,1.0%,1/16W,CHIP,GA    I90 @BASEBOARD_FAB2_LIB.BASEBOARD_FAB2(SCH_1):PAGE138
 R8C12    2      B RES_0402-20.0,1%,1/16W,CHIP,G2A   I170 @BASEBOARD_FAB2_LIB.BASEBOARD_FAB2(SCH_1):PAGE138
  J9B2    3    IO3 CONN3_C95678002_PIP-CONN,C9567A   I281 @BASEBOARD_FAB2_LIB.BASEBOARD_FAB2(SCH_1):PAGE156
 R1U19    1      A RES_0402-20.0,1%,1/16W,CHIP,G2A   I226 @BASEBOARD_FAB2_LIB.BASEBOARD_FAB2(SCH_1):PAGE159
  R1U9    2      B RES_0402-20.0,1%,1/16W,CHIP,G2A   I232 @BASEBOARD_FAB2_LIB.BASEBOARD_FAB2(SCH_1):PAGE159

SMB_SMLINK0_STBY_LVC3_SCL_R @BASEBOARD_FAB2_LIB.BASEBOARD_FAB2(SCH_1):SMB_SMLINK0_STBY_LVC3_SCL_R
  R1U9    1      A RES_0402-20.0,1%,1/16W,CHIP,G2A   I232 @BASEBOARD_FAB2_LIB.BASEBOARD_FAB2(SCH_1):PAGE159
 U25W4   L3 GPIOK0_SCL5 AST2520A1-GP-GP_ASIC2-GB1-AST2A    I95 @BASEBOARD_FAB2_LIB.BASEBOARD_FAB2(SCH_1):PAGE144

SMB_SMLINK0_STBY_LVC3_SCL_R1 @BASEBOARD_FAB2_LIB.BASEBOARD_FAB2(SCH_1):SMB_SMLINK0_STBY_LVC3_SCL_R1
  U7C1 BV29 GPP_C3_SML0CLK_IE LBG_CORE_QAT_EXT_D_BGA1-IC,H91A   I115 @BASEBOARD_FAB2_LIB.BASEBOARD_FAB2(SCH_1):PAGE119
 R8C12    1      A RES_0402-20.0,1%,1/16W,CHIP,G2A   I170 @BASEBOARD_FAB2_LIB.BASEBOARD_FAB2(SCH_1):PAGE138

SMB_SMLINK0_STBY_LVC3_SDA @BASEBOARD_FAB2_LIB.BASEBOARD_FAB2(SCH_1):SMB_SMLINK0_STBY_LVC3_SDA
  R2N8    2      B RES_0402-665,1.0%,1/16W,CHIP,GA    I89 @BASEBOARD_FAB2_LIB.BASEBOARD_FAB2(SCH_1):PAGE138
 R8C11    2      B RES_0402-20.0,1%,1/16W,CHIP,G2A   I169 @BASEBOARD_FAB2_LIB.BASEBOARD_FAB2(SCH_1):PAGE138
  J9B2    1    IO1 CONN3_C95678002_PIP-CONN,C9567A   I281 @BASEBOARD_FAB2_LIB.BASEBOARD_FAB2(SCH_1):PAGE156
 R1U20    1      A RES_0402-20.0,1%,1/16W,CHIP,G2A   I225 @BASEBOARD_FAB2_LIB.BASEBOARD_FAB2(SCH_1):PAGE159
 R1U10    2      B RES_0402-20.0,1%,1/16W,CHIP,G2A   I233 @BASEBOARD_FAB2_LIB.BASEBOARD_FAB2(SCH_1):PAGE159

SMB_SMLINK0_STBY_LVC3_SDA_R @BASEBOARD_FAB2_LIB.BASEBOARD_FAB2(SCH_1):SMB_SMLINK0_STBY_LVC3_SDA_R
 R1U10    1      A RES_0402-20.0,1%,1/16W,CHIP,G2A   I233 @BASEBOARD_FAB2_LIB.BASEBOARD_FAB2(SCH_1):PAGE159
 U25W4   L4 GPIOK1_SDA5 AST2520A1-GP-GP_ASIC2-GB1-AST2A    I95 @BASEBOARD_FAB2_LIB.BASEBOARD_FAB2(SCH_1):PAGE144

SMB_SMLINK0_STBY_LVC3_SDA_R1 @BASEBOARD_FAB2_LIB.BASEBOARD_FAB2(SCH_1):SMB_SMLINK0_STBY_LVC3_SDA_R1
  U7C1 BW30 GPP_C4_SML0DATA_IE LBG_CORE_QAT_EXT_D_BGA1-IC,H91A   I115 @BASEBOARD_FAB2_LIB.BASEBOARD_FAB2(SCH_1):PAGE119
 R8C11    1      A RES_0402-20.0,1%,1/16W,CHIP,G2A   I169 @BASEBOARD_FAB2_LIB.BASEBOARD_FAB2(SCH_1):PAGE138

SMB_SPRINGVILLE_STBY_LVC3_SCL @BASEBOARD_FAB2_LIB.BASEBOARD_FAB2(SCH_1):SMB_SPRINGVILLE_STBY_LVC3_SCL
 EU9E1   34 SMB_CLK SPRINGVILLE_SM1-IC,G47144-004    I72 @BASEBOARD_FAB2_LIB.BASEBOARD_FAB2(SCH_1):PAGE139
 R1U19    2      B RES_0402-20.0,1%,1/16W,CHIP,G2A   I226 @BASEBOARD_FAB2_LIB.BASEBOARD_FAB2(SCH_1):PAGE159
 R9G13    2      B RES_0402-20.0,1%,1/16W,CHIP,G2A   I227 @BASEBOARD_FAB2_LIB.BASEBOARD_FAB2(SCH_1):PAGE159

SMB_SPRINGVILLE_STBY_LVC3_SDA @BASEBOARD_FAB2_LIB.BASEBOARD_FAB2(SCH_1):SMB_SPRINGVILLE_STBY_LVC3_SDA
 EU9E1   36 SMB_DATA SPRINGVILLE_SM1-IC,G47144-004    I72 @BASEBOARD_FAB2_LIB.BASEBOARD_FAB2(SCH_1):PAGE139
 R9G12    2      B RES_0402-20.0,1%,1/16W,CHIP,G2A   I224 @BASEBOARD_FAB2_LIB.BASEBOARD_FAB2(SCH_1):PAGE159
 R1U20    2      B RES_0402-20.0,1%,1/16W,CHIP,G2A   I225 @BASEBOARD_FAB2_LIB.BASEBOARD_FAB2(SCH_1):PAGE159

SMB_VR_STBY_LVC3_SCL @BASEBOARD_FAB2_LIB.BASEBOARD_FAB2(SCH_1):SMB_VR_STBY_LVC3_SCL
 R8D15    2      B RES_0402-1.37K,1%,1/16W,CHIP,GA    I88 @BASEBOARD_FAB2_LIB.BASEBOARD_FAB2(SCH_1):PAGE138
  R8D4    2      B RES_0402-20.0,1%,1/16W,CHIP,G2A   I164 @BASEBOARD_FAB2_LIB.BASEBOARD_FAB2(SCH_1):PAGE138
 R1U11    2      B RES_0402-0.0,5%,1/16W,CHIP,G21A   I222 @BASEBOARD_FAB2_LIB.BASEBOARD_FAB2(SCH_1):PAGE159
  J4B2  A18  IOA18 SCONN120_H61426002_SM-CONN,H61A    I46 @BASEBOARD_FAB2_LIB.BASEBOARD_FAB2(SCH_1):PAGE193
  J6B1  A18  IOA18 SCONN120_H61426002_SM-CONN,H61A    I56 @BASEBOARD_FAB2_LIB.BASEBOARD_FAB2(SCH_1):PAGE194
 R6P37    2      B RES_0402-2.0K,1%,1/16W,EMPTY,GA   I103 @BASEBOARD_FAB2_LIB.BASEBOARD_FAB2(SCH_1):PAGE201
 EU4D4    9    SCL PXE1610B_QFN-IC,H79206-001   I155 @BASEBOARD_FAB2_LIB.BASEBOARD_FAB2(SCH_1):PAGE201
 EU1C2    9    SCL PXE1610B_QFN-IC,H79206-001   I130 @BASEBOARD_FAB2_LIB.BASEBOARD_FAB2(SCH_1):PAGE206
 EU3P1    7    SCL PXE1110B_QFN-IC,H89187-001    I93 @BASEBOARD_FAB2_LIB.BASEBOARD_FAB2(SCH_1):PAGE211
 EU4D5    7    SCL PXE1110B_QFN-IC,H89187-001    I96 @BASEBOARD_FAB2_LIB.BASEBOARD_FAB2(SCH_1):PAGE213
 EU8A1    7    SCL PXE1110B_QFN-IC,H89187-001   I229 @BASEBOARD_FAB2_LIB.BASEBOARD_FAB2(SCH_1):PAGE235
 EU7G1    7    SCL PXM1310B_QFN-IC,H89186-001    I69 @BASEBOARD_FAB2_LIB.BASEBOARD_FAB2(SCH_1):PAGE215
 EU7A5    7    SCL PXM1310B_QFN-IC,H89186-001    I69 @BASEBOARD_FAB2_LIB.BASEBOARD_FAB2(SCH_1):PAGE218
 EU1G2    7    SCL PXM1310B_QFN-IC,H89186-001    I69 @BASEBOARD_FAB2_LIB.BASEBOARD_FAB2(SCH_1):PAGE223
 EU1B1    7    SCL PXM1310B_QFN-IC,H89186-001    I69 @BASEBOARD_FAB2_LIB.BASEBOARD_FAB2(SCH_1):PAGE226
  J8D4    3      3 PIN-CON3-27-GP_CONN-G7-PIN-CONA   I191 @BASEBOARD_FAB2_LIB.BASEBOARD_FAB2(SCH_1):PAGE201

SMB_VR_STBY_LVC3_SCL_R @BASEBOARD_FAB2_LIB.BASEBOARD_FAB2(SCH_1):SMB_VR_STBY_LVC3_SCL_R
 R1U11    1      A RES_0402-0.0,5%,1/16W,CHIP,G21A   I222 @BASEBOARD_FAB2_LIB.BASEBOARD_FAB2(SCH_1):PAGE159
 U25W4   L1 GPIOK2_SCL6 AST2520A1-GP-GP_ASIC2-GB1-AST2A    I95 @BASEBOARD_FAB2_LIB.BASEBOARD_FAB2(SCH_1):PAGE144

SMB_VR_STBY_LVC3_SCL_R1 @BASEBOARD_FAB2_LIB.BASEBOARD_FAB2(SCH_1):SMB_VR_STBY_LVC3_SCL_R1
  U7C1  BA4 GPP_H10_SML2CLK_IE LBG_CORE_QAT_EXT_D_BGA1-IC,H91A   I147 @BASEBOARD_FAB2_LIB.BASEBOARD_FAB2(SCH_1):PAGE120
  R8D4    1      A RES_0402-20.0,1%,1/16W,CHIP,G2A   I164 @BASEBOARD_FAB2_LIB.BASEBOARD_FAB2(SCH_1):PAGE138
  R8W7    2      B RES_0402-1.37K,1%,1/16W,CHIP,GA   I202 @BASEBOARD_FAB2_LIB.BASEBOARD_FAB2(SCH_1):PAGE138

SMB_VR_STBY_LVC3_SDA @BASEBOARD_FAB2_LIB.BASEBOARD_FAB2(SCH_1):SMB_VR_STBY_LVC3_SDA
 R8D17    2      B RES_0402-1.37K,1%,1/16W,CHIP,GA    I87 @BASEBOARD_FAB2_LIB.BASEBOARD_FAB2(SCH_1):PAGE138
  R8D7    2      B RES_0402-20.0,1%,1/16W,CHIP,G2A   I163 @BASEBOARD_FAB2_LIB.BASEBOARD_FAB2(SCH_1):PAGE138
  R1U8    2      B RES_0402-0.0,5%,1/16W,CHIP,G21A   I223 @BASEBOARD_FAB2_LIB.BASEBOARD_FAB2(SCH_1):PAGE159
  J4B2  B18  IOB18 SCONN120_H61426002_SM-CONN,H61A    I46 @BASEBOARD_FAB2_LIB.BASEBOARD_FAB2(SCH_1):PAGE193
  J6B1  B18  IOB18 SCONN120_H61426002_SM-CONN,H61A    I56 @BASEBOARD_FAB2_LIB.BASEBOARD_FAB2(SCH_1):PAGE194
 R6P32    2      B RES_0402-2.0K,1%,1/16W,EMPTY,GA   I102 @BASEBOARD_FAB2_LIB.BASEBOARD_FAB2(SCH_1):PAGE201
 EU4D4    8    SDA PXE1610B_QFN-IC,H79206-001   I155 @BASEBOARD_FAB2_LIB.BASEBOARD_FAB2(SCH_1):PAGE201
 EU1C2    8    SDA PXE1610B_QFN-IC,H79206-001   I130 @BASEBOARD_FAB2_LIB.BASEBOARD_FAB2(SCH_1):PAGE206
 EU3P1    6    SDA PXE1110B_QFN-IC,H89187-001    I93 @BASEBOARD_FAB2_LIB.BASEBOARD_FAB2(SCH_1):PAGE211
 EU4D5    6    SDA PXE1110B_QFN-IC,H89187-001    I96 @BASEBOARD_FAB2_LIB.BASEBOARD_FAB2(SCH_1):PAGE213
 EU8A1    6    SDA PXE1110B_QFN-IC,H89187-001   I229 @BASEBOARD_FAB2_LIB.BASEBOARD_FAB2(SCH_1):PAGE235
 EU7G1    6    SDA PXM1310B_QFN-IC,H89186-001    I69 @BASEBOARD_FAB2_LIB.BASEBOARD_FAB2(SCH_1):PAGE215
 EU7A5    6    SDA PXM1310B_QFN-IC,H89186-001    I69 @BASEBOARD_FAB2_LIB.BASEBOARD_FAB2(SCH_1):PAGE218
 EU1G2    6    SDA PXM1310B_QFN-IC,H89186-001    I69 @BASEBOARD_FAB2_LIB.BASEBOARD_FAB2(SCH_1):PAGE223
 EU1B1    6    SDA PXM1310B_QFN-IC,H89186-001    I69 @BASEBOARD_FAB2_LIB.BASEBOARD_FAB2(SCH_1):PAGE226
  J8D4    1      1 PIN-CON3-27-GP_CONN-G7-PIN-CONA   I191 @BASEBOARD_FAB2_LIB.BASEBOARD_FAB2(SCH_1):PAGE201

SMB_VR_STBY_LVC3_SDA_R @BASEBOARD_FAB2_LIB.BASEBOARD_FAB2(SCH_1):SMB_VR_STBY_LVC3_SDA_R
  R1U8    1      A RES_0402-0.0,5%,1/16W,CHIP,G21A   I223 @BASEBOARD_FAB2_LIB.BASEBOARD_FAB2(SCH_1):PAGE159
 U25W4   N2 GPIOK3_SDA6 AST2520A1-GP-GP_ASIC2-GB1-AST2A    I95 @BASEBOARD_FAB2_LIB.BASEBOARD_FAB2(SCH_1):PAGE144

SMB_VR_STBY_LVC3_SDA_R1 @BASEBOARD_FAB2_LIB.BASEBOARD_FAB2(SCH_1):SMB_VR_STBY_LVC3_SDA_R1
  U7C1  BD1 GPP_H11_SML2DATA_IE LBG_CORE_QAT_EXT_D_BGA1-IC,H91A   I147 @BASEBOARD_FAB2_LIB.BASEBOARD_FAB2(SCH_1):PAGE120
  R8D7    1      A RES_0402-20.0,1%,1/16W,CHIP,G2A   I163 @BASEBOARD_FAB2_LIB.BASEBOARD_FAB2(SCH_1):PAGE138
  R8W6    2      B RES_0402-1.37K,1%,1/16W,CHIP,GA   I205 @BASEBOARD_FAB2_LIB.BASEBOARD_FAB2(SCH_1):PAGE138

SP1_BMC_HOST_UART_RX @BASEBOARD_FAB2_LIB.BASEBOARD_FAB2(SCH_1):SP1_BMC_HOST_UART_RX
  U9F1    3     B2 FSA3357_SM-IC,C63273-001    I75 @BASEBOARD_FAB2_LIB.BASEBOARD_FAB2(SCH_1):PAGE158
  U8D7   K3  PL10A LCMXO2_A_256BGA-IC,H63395-001   I179 @BASEBOARD_FAB2_LIB.BASEBOARD_FAB2(SCH_1):PAGE190
 U25W4   W1 GPIOL7_RXD1 AST2520A1-GP-GP_ASIC2-GB1-AST2A   I117 @BASEBOARD_FAB2_LIB.BASEBOARD_FAB2(SCH_1):PAGE145
 R9W33    2      B RES_0402-4.75K,1%,1/16W,CHIP,GA   I153 @BASEBOARD_FAB2_LIB.BASEBOARD_FAB2(SCH_1):PAGE158

SP1_BMC_HOST_UART_TX @BASEBOARD_FAB2_LIB.BASEBOARD_FAB2(SCH_1):SP1_BMC_HOST_UART_TX
  U9F2    3     B2 FSA3357_SM-IC,C63273-001    I74 @BASEBOARD_FAB2_LIB.BASEBOARD_FAB2(SCH_1):PAGE158
  U8D7   K2  PL10B LCMXO2_A_256BGA-IC,H63395-001   I179 @BASEBOARD_FAB2_LIB.BASEBOARD_FAB2(SCH_1):PAGE190
 U25W4   V1 GPIOL6_TXD1 AST2520A1-GP-GP_ASIC2-GB1-AST2A   I117 @BASEBOARD_FAB2_LIB.BASEBOARD_FAB2(SCH_1):PAGE145

SP2_BMC_CM_UART_RX @BASEBOARD_FAB2_LIB.BASEBOARD_FAB2(SCH_1):SP2_BMC_CM_UART_RX
 R9F24    2      B RES_0402-0.0,5%,1/16W,EMPTY,G2A   I100 @BASEBOARD_FAB2_LIB.BASEBOARD_FAB2(SCH_1):PAGE158
 R9F68    2      B RES_0402-0.0,5%,1/16W,EMPTY,G2A   I149 @BASEBOARD_FAB2_LIB.BASEBOARD_FAB2(SCH_1):PAGE158
 U25W4   T5 GPIOM7_RXD2_VPIB9 AST2520A1-GP-GP_ASIC2-GB1-AST2A   I117 @BASEBOARD_FAB2_LIB.BASEBOARD_FAB2(SCH_1):PAGE145

SP2_BMC_CM_UART_RX_R @BASEBOARD_FAB2_LIB.BASEBOARD_FAB2(SCH_1):SP2_BMC_CM_UART_RX_R
  U9F1    1     B0 FSA3357_SM-IC,C63273-001    I75 @BASEBOARD_FAB2_LIB.BASEBOARD_FAB2(SCH_1):PAGE158
 R9F68    1      A RES_0402-0.0,5%,1/16W,EMPTY,G2A   I149 @BASEBOARD_FAB2_LIB.BASEBOARD_FAB2(SCH_1):PAGE158
 R9F69    1      A RES_0402-0.0,5%,1/16W,CHIP,G21A   I150 @BASEBOARD_FAB2_LIB.BASEBOARD_FAB2(SCH_1):PAGE158
 R9W35    2      B RES_0402-4.75K,1%,1/16W,CHIP,GA   I155 @BASEBOARD_FAB2_LIB.BASEBOARD_FAB2(SCH_1):PAGE158

SP2_BMC_CM_UART_RX_R1 @BASEBOARD_FAB2_LIB.BASEBOARD_FAB2(SCH_1):SP2_BMC_CM_UART_RX_R1
 R9F69    2      B RES_0402-0.0,5%,1/16W,CHIP,G21A   I150 @BASEBOARD_FAB2_LIB.BASEBOARD_FAB2(SCH_1):PAGE158
 R9F67    1      A RES_0402-0.0,5%,1/16W,CHIP,G21A    I33 @BASEBOARD_FAB2_LIB.BASEBOARD_FAB2(SCH_1):PAGE181

SP2_BMC_CM_UART_TX @BASEBOARD_FAB2_LIB.BASEBOARD_FAB2(SCH_1):SP2_BMC_CM_UART_TX
 R9F26    1      A RES_0402-0.0,5%,1/16W,EMPTY,G2A    I99 @BASEBOARD_FAB2_LIB.BASEBOARD_FAB2(SCH_1):PAGE158
 R9F66    1      A RES_0402-0.0,5%,1/16W,EMPTY,G2A   I152 @BASEBOARD_FAB2_LIB.BASEBOARD_FAB2(SCH_1):PAGE158
 U25W4   R5 GPIOM6_TXD2_VPIB8 AST2520A1-GP-GP_ASIC2-GB1-AST2A   I117 @BASEBOARD_FAB2_LIB.BASEBOARD_FAB2(SCH_1):PAGE145

SP2_BMC_CM_UART_TX_R @BASEBOARD_FAB2_LIB.BASEBOARD_FAB2(SCH_1):SP2_BMC_CM_UART_TX_R
  U9F2    1     B0 FSA3357_SM-IC,C63273-001    I74 @BASEBOARD_FAB2_LIB.BASEBOARD_FAB2(SCH_1):PAGE158
 R9F65    2      B RES_0402-0.0,5%,1/16W,CHIP,G21A   I148 @BASEBOARD_FAB2_LIB.BASEBOARD_FAB2(SCH_1):PAGE158
 R9F66    2      B RES_0402-0.0,5%,1/16W,EMPTY,G2A   I152 @BASEBOARD_FAB2_LIB.BASEBOARD_FAB2(SCH_1):PAGE158

SP2_BMC_CM_UART_TX_R1 @BASEBOARD_FAB2_LIB.BASEBOARD_FAB2(SCH_1):SP2_BMC_CM_UART_TX_R1
 R9F65    1      A RES_0402-0.0,5%,1/16W,CHIP,G21A   I148 @BASEBOARD_FAB2_LIB.BASEBOARD_FAB2(SCH_1):PAGE158
 R9F64    1      A RES_0402-0.0,5%,1/16W,CHIP,G21A    I29 @BASEBOARD_FAB2_LIB.BASEBOARD_FAB2(SCH_1):PAGE181

SPA_5V_SIN_SW @BASEBOARD_FAB2_LIB.BASEBOARD_FAB2(SCH_1):SPA_5V_SIN_SW
  J9A2   10   IO10 CONN14_H54902001_PIP-CONN,H549A   I171 @BASEBOARD_FAB2_LIB.BASEBOARD_FAB2(SCH_1):PAGE155
 CR9W1    1      C DIODE_SMLF-BAT54WS,IC,C73510-0A   I202 @BASEBOARD_FAB2_LIB.BASEBOARD_FAB2(SCH_1):PAGE155

SPA_5V_SIN_SW_D @BASEBOARD_FAB2_LIB.BASEBOARD_FAB2(SCH_1):SPA_5V_SIN_SW_D
  U9A1    2      A TTL1G07_A_SOP-74LVC1G07,IC,C88B   I178 @BASEBOARD_FAB2_LIB.BASEBOARD_FAB2(SCH_1):PAGE155
 R6W19    1      A RES_0402-0.0,5%,1/16W,CHIP,G21A   I196 @BASEBOARD_FAB2_LIB.BASEBOARD_FAB2(SCH_1):PAGE155
 R6W40    2      B RES_0402-10.0K,1%,1/16W,CHIP,GA   I201 @BASEBOARD_FAB2_LIB.BASEBOARD_FAB2(SCH_1):PAGE155
 CR9W1    2      A DIODE_SMLF-BAT54WS,IC,C73510-0A   I202 @BASEBOARD_FAB2_LIB.BASEBOARD_FAB2(SCH_1):PAGE155

SPA_MID_DBG1_RX @BASEBOARD_FAB2_LIB.BASEBOARD_FAB2(SCH_1):SPA_MID_DBG1_RX
  R9A8    2      B RES_0402-0.0,5%,1/16W,CHIP,G21A    I53 @BASEBOARD_FAB2_LIB.BASEBOARD_FAB2(SCH_1):PAGE155
 U6W12    3     B0 NC7SB3157_SMLF-IC,C99406-001   I182 @BASEBOARD_FAB2_LIB.BASEBOARD_FAB2(SCH_1):PAGE176

SPA_MID_DBG1_TX @BASEBOARD_FAB2_LIB.BASEBOARD_FAB2(SCH_1):SPA_MID_DBG1_TX
  J9A2    9    IO9 CONN14_H54902001_PIP-CONN,H549A   I171 @BASEBOARD_FAB2_LIB.BASEBOARD_FAB2(SCH_1):PAGE155
 R6W36    2      B RES_0402-10.0,1%,1/16W,CHIP,G2A   I161 @BASEBOARD_FAB2_LIB.BASEBOARD_FAB2(SCH_1):PAGE176

SPA_MID_DBG1_TX_EN @BASEBOARD_FAB2_LIB.BASEBOARD_FAB2(SCH_1):SPA_MID_DBG1_TX_EN
  U6W6    1     OE TTL1G126_A_SOT-74HC1G126,IC,A7B   I157 @BASEBOARD_FAB2_LIB.BASEBOARD_FAB2(SCH_1):PAGE176
 R6W39    1      A RES_0402-10.0K,1%,1/16W,CHIP,GA   I158 @BASEBOARD_FAB2_LIB.BASEBOARD_FAB2(SCH_1):PAGE176

SPA_MID_DBG1_TX_R @BASEBOARD_FAB2_LIB.BASEBOARD_FAB2(SCH_1):SPA_MID_DBG1_TX_R
  U6W6    4      Y TTL1G126_A_SOT-74HC1G126,IC,A7B   I157 @BASEBOARD_FAB2_LIB.BASEBOARD_FAB2(SCH_1):PAGE176
 R6W36    1      A RES_0402-10.0,1%,1/16W,CHIP,G2A   I161 @BASEBOARD_FAB2_LIB.BASEBOARD_FAB2(SCH_1):PAGE176

SPA_MID_DBG2_RX @BASEBOARD_FAB2_LIB.BASEBOARD_FAB2(SCH_1):SPA_MID_DBG2_RX
  J9B1    9 STDA_SSTXP CONN9_H51826001_PIP2-CONN,H518A    I69 @BASEBOARD_FAB2_LIB.BASEBOARD_FAB2(SCH_1):PAGE176
  U6W4    2      A TTL1G126_A_SOT-74HC1G126,IC,A7B   I146 @BASEBOARD_FAB2_LIB.BASEBOARD_FAB2(SCH_1):PAGE176
 R6W50    2      B RES_0402-4.75K,1%,1/16W,CHIP,GA   I178 @BASEBOARD_FAB2_LIB.BASEBOARD_FAB2(SCH_1):PAGE176

SPA_MID_DBG2_RX_BUF @BASEBOARD_FAB2_LIB.BASEBOARD_FAB2(SCH_1):SPA_MID_DBG2_RX_BUF
  U6W4    4      Y TTL1G126_A_SOT-74HC1G126,IC,A7B   I146 @BASEBOARD_FAB2_LIB.BASEBOARD_FAB2(SCH_1):PAGE176
 R6W30    2      B RES_0603-100.0K,1%,1/10W,CHIP,A   I147 @BASEBOARD_FAB2_LIB.BASEBOARD_FAB2(SCH_1):PAGE176
 U6W12    1     B1 NC7SB3157_SMLF-IC,C99406-001   I182 @BASEBOARD_FAB2_LIB.BASEBOARD_FAB2(SCH_1):PAGE176

SPA_MID_DBG2_TX @BASEBOARD_FAB2_LIB.BASEBOARD_FAB2(SCH_1):SPA_MID_DBG2_TX
  J9B1    8 STDA_SSTXN CONN9_H51826001_PIP2-CONN,H518A    I69 @BASEBOARD_FAB2_LIB.BASEBOARD_FAB2(SCH_1):PAGE176
 R6W37    2      B RES_0402-10.0,1%,1/16W,CHIP,G2A   I160 @BASEBOARD_FAB2_LIB.BASEBOARD_FAB2(SCH_1):PAGE176

SPA_MID_DBG2_TX_R @BASEBOARD_FAB2_LIB.BASEBOARD_FAB2(SCH_1):SPA_MID_DBG2_TX_R
  U6W5    4      Y TTL1G126_A_SOT-74HC1G126,IC,A7B   I148 @BASEBOARD_FAB2_LIB.BASEBOARD_FAB2(SCH_1):PAGE176
 R6W37    1      A RES_0402-10.0,1%,1/16W,CHIP,G2A   I160 @BASEBOARD_FAB2_LIB.BASEBOARD_FAB2(SCH_1):PAGE176

SPA_MID_DBG_RX @BASEBOARD_FAB2_LIB.BASEBOARD_FAB2(SCH_1):SPA_MID_DBG_RX
 R9F25    1      A RES_0402-100.0,1%,1/16W,CHIP,GA    I86 @BASEBOARD_FAB2_LIB.BASEBOARD_FAB2(SCH_1):PAGE158
 R9F24    1      A RES_0402-0.0,5%,1/16W,EMPTY,G2A   I100 @BASEBOARD_FAB2_LIB.BASEBOARD_FAB2(SCH_1):PAGE158
 R9F63    1      A RES_0402-0.0,5%,1/16W,EMPTY,G2A    I28 @BASEBOARD_FAB2_LIB.BASEBOARD_FAB2(SCH_1):PAGE181
 U6W12    4      A NC7SB3157_SMLF-IC,C99406-001   I182 @BASEBOARD_FAB2_LIB.BASEBOARD_FAB2(SCH_1):PAGE176

SPA_MID_DBG_RX_R @BASEBOARD_FAB2_LIB.BASEBOARD_FAB2(SCH_1):SPA_MID_DBG_RX_R
 R9F63    2      B RES_0402-0.0,5%,1/16W,EMPTY,G2A    I28 @BASEBOARD_FAB2_LIB.BASEBOARD_FAB2(SCH_1):PAGE181
 R9F64    2      B RES_0402-0.0,5%,1/16W,CHIP,G21A    I29 @BASEBOARD_FAB2_LIB.BASEBOARD_FAB2(SCH_1):PAGE181
  J1F1   H3 COM_RX DM-FCI-CONN76-8R-GP-U-01_CONN-A   I134 @BASEBOARD_FAB2_LIB.BASEBOARD_FAB2(SCH_1):PAGE181

SPA_MID_DBG_TX @BASEBOARD_FAB2_LIB.BASEBOARD_FAB2(SCH_1):SPA_MID_DBG_TX
 R9F27    2      B RES_0402-0.0,5%,1/16W,CHIP,G21A    I91 @BASEBOARD_FAB2_LIB.BASEBOARD_FAB2(SCH_1):PAGE158
 R9F26    2      B RES_0402-0.0,5%,1/16W,EMPTY,G2A    I99 @BASEBOARD_FAB2_LIB.BASEBOARD_FAB2(SCH_1):PAGE158
 R9F70    1      A RES_0402-0.0,5%,1/16W,EMPTY,G2A    I30 @BASEBOARD_FAB2_LIB.BASEBOARD_FAB2(SCH_1):PAGE181
  U6W5    2      A TTL1G126_A_SOT-74HC1G126,IC,A7B   I148 @BASEBOARD_FAB2_LIB.BASEBOARD_FAB2(SCH_1):PAGE176
  U6W6    2      A TTL1G126_A_SOT-74HC1G126,IC,A7B   I157 @BASEBOARD_FAB2_LIB.BASEBOARD_FAB2(SCH_1):PAGE176

SPA_MID_DBG_TX_R @BASEBOARD_FAB2_LIB.BASEBOARD_FAB2(SCH_1):SPA_MID_DBG_TX_R
 R9F70    2      B RES_0402-0.0,5%,1/16W,EMPTY,G2A    I30 @BASEBOARD_FAB2_LIB.BASEBOARD_FAB2(SCH_1):PAGE181
 R9F67    2      B RES_0402-0.0,5%,1/16W,CHIP,G21A    I33 @BASEBOARD_FAB2_LIB.BASEBOARD_FAB2(SCH_1):PAGE181
  J1F1   G3 COM_TX DM-FCI-CONN76-8R-GP-U-01_CONN-A   I134 @BASEBOARD_FAB2_LIB.BASEBOARD_FAB2(SCH_1):PAGE181

SPA_SIN_SW_R @BASEBOARD_FAB2_LIB.BASEBOARD_FAB2(SCH_1):SPA_SIN_SW_R
  R9A8    1      A RES_0402-0.0,5%,1/16W,CHIP,G21A    I53 @BASEBOARD_FAB2_LIB.BASEBOARD_FAB2(SCH_1):PAGE155
  R9A7    2      B RES_0402-2.21K,1%,1/16W,CHIP,GA    I80 @BASEBOARD_FAB2_LIB.BASEBOARD_FAB2(SCH_1):PAGE155
  U9A1    4      Y TTL1G07_A_SOP-74LVC1G07,IC,C88B   I178 @BASEBOARD_FAB2_LIB.BASEBOARD_FAB2(SCH_1):PAGE155
 R6W19    2      B RES_0402-0.0,5%,1/16W,CHIP,G21A   I196 @BASEBOARD_FAB2_LIB.BASEBOARD_FAB2(SCH_1):PAGE155

SPI_BIOS_SOCKET_IO2 @BASEBOARD_FAB2_LIB.BASEBOARD_FAB2(SCH_1):SPI_BIOS_SOCKET_IO2
 R7F37    1      A RES_0402-33.2,1%,1/16W,CHIP,G2A   I108 @BASEBOARD_FAB2_LIB.BASEBOARD_FAB2(SCH_1):PAGE153
  R3U1    1      A RES_0402-33.2,1%,1/16W,CHIP,G2A   I156 @BASEBOARD_FAB2_LIB.BASEBOARD_FAB2(SCH_1):PAGE153
  U2T1    4     YA PI3B3257A_TSSOPLF-IC,E16801-001    I75 @BASEBOARD_FAB2_LIB.BASEBOARD_FAB2(SCH_1):PAGE154

SPI_BIOS_SOCKET_IO3 @BASEBOARD_FAB2_LIB.BASEBOARD_FAB2(SCH_1):SPI_BIOS_SOCKET_IO3
  R7F3    1      A RES_0402-33.2,1%,1/16W,CHIP,G2A   I109 @BASEBOARD_FAB2_LIB.BASEBOARD_FAB2(SCH_1):PAGE153
  R3T1    1      A RES_0402-33.2,1%,1/16W,CHIP,G2A   I157 @BASEBOARD_FAB2_LIB.BASEBOARD_FAB2(SCH_1):PAGE153
  U2T1    7     YB PI3B3257A_TSSOPLF-IC,E16801-001    I75 @BASEBOARD_FAB2_LIB.BASEBOARD_FAB2(SCH_1):PAGE154

SPI_BMC_BT_CLK @BASEBOARD_FAB2_LIB.BASEBOARD_FAB2(SCH_1):SPI_BMC_BT_CLK
  U8F2   16    CLK W25Q128_SKT16-IC,H12709-001    I32 @BASEBOARD_FAB2_LIB.BASEBOARD_FAB2(SCH_1):PAGE162
 UN8F2   16    CLK W25Q256_XSOI-IC,H25002-001    I17 @BASEBOARD_FAB2_LIB.BASEBOARD_FAB2(SCH_1):PAGE246
R25W81    1      A RES_0402-33.2,1%,1/16W,CHIP,G2A    I67 @BASEBOARD_FAB2_LIB.BASEBOARD_FAB2(SCH_1):PAGE146
R25W95    2      B RES_0402-4.75K,1%,1/16W,CHIP,GA   I144 @BASEBOARD_FAB2_LIB.BASEBOARD_FAB2(SCH_1):PAGE150

SPI_BMC_BT_CLK_R @BASEBOARD_FAB2_LIB.BASEBOARD_FAB2(SCH_1):SPI_BMC_BT_CLK_R
R25W81    2      B RES_0402-33.2,1%,1/16W,CHIP,G2A    I67 @BASEBOARD_FAB2_LIB.BASEBOARD_FAB2(SCH_1):PAGE146
 U25W4 AA18 FWSPICK AST2520A1-GP-GP_ASIC2-GB1-AST2A   I105 @BASEBOARD_FAB2_LIB.BASEBOARD_FAB2(SCH_1):PAGE146

SPI_BMC_BT_CS0_N @BASEBOARD_FAB2_LIB.BASEBOARD_FAB2(SCH_1):SPI_BMC_BT_CS0_N
  J9G1   10   IO10 CONN12_C73564003_PIP-CONN,C735A   I128 @BASEBOARD_FAB2_LIB.BASEBOARD_FAB2(SCH_1):PAGE137
 UN8F2    7   CS_N W25Q256_XSOI-IC,H25002-001    I17 @BASEBOARD_FAB2_LIB.BASEBOARD_FAB2(SCH_1):PAGE246
 U25W4 AB19 FWSPICS0# AST2520A1-GP-GP_ASIC2-GB1-AST2A   I105 @BASEBOARD_FAB2_LIB.BASEBOARD_FAB2(SCH_1):PAGE146

SPI_BMC_BT_CS_N @BASEBOARD_FAB2_LIB.BASEBOARD_FAB2(SCH_1):SPI_BMC_BT_CS_N
  U8F2    7   CS_N W25Q128_SKT16-IC,H12709-001    I32 @BASEBOARD_FAB2_LIB.BASEBOARD_FAB2(SCH_1):PAGE162
R25W78    2      B RES_0402-22.1,1.0%,1/16W,CHIP,A   I123 @BASEBOARD_FAB2_LIB.BASEBOARD_FAB2(SCH_1):PAGE146
 R8F13    2      B RES_0402-4.75K,1%,1/16W,CHIP,GA    I35 @BASEBOARD_FAB2_LIB.BASEBOARD_FAB2(SCH_1):PAGE162

SPI_BMC_BT_CS_R_N @BASEBOARD_FAB2_LIB.BASEBOARD_FAB2(SCH_1):SPI_BMC_BT_CS_R_N
 U25W4 AA19 GPIOR0_FWSPICS1# AST2520A1-GP-GP_ASIC2-GB1-AST2A   I105 @BASEBOARD_FAB2_LIB.BASEBOARD_FAB2(SCH_1):PAGE146
R25W78    1      A RES_0402-22.1,1.0%,1/16W,CHIP,A   I123 @BASEBOARD_FAB2_LIB.BASEBOARD_FAB2(SCH_1):PAGE146

SPI_BMC_BT_DI @BASEBOARD_FAB2_LIB.BASEBOARD_FAB2(SCH_1):SPI_BMC_BT_DI
 R8F12    1      A RES_0402-33.2,1%,1/16W,CHIP,G2A    I13 @BASEBOARD_FAB2_LIB.BASEBOARD_FAB2(SCH_1):PAGE162
 RN8F5    1      A RES_0402-33.2,1%,1/16W,CHIP,G2A     I9 @BASEBOARD_FAB2_LIB.BASEBOARD_FAB2(SCH_1):PAGE246
 U25W4  T18 FWSPIMISO AST2520A1-GP-GP_ASIC2-GB1-AST2A   I105 @BASEBOARD_FAB2_LIB.BASEBOARD_FAB2(SCH_1):PAGE146
R25W97    2      B RES_0402-4.75K,1%,1/16W,EMPTY,A   I146 @BASEBOARD_FAB2_LIB.BASEBOARD_FAB2(SCH_1):PAGE150

SPI_BMC_BT_DI_R @BASEBOARD_FAB2_LIB.BASEBOARD_FAB2(SCH_1):SPI_BMC_BT_DI_R
 R8F12    2      B RES_0402-33.2,1%,1/16W,CHIP,G2A    I13 @BASEBOARD_FAB2_LIB.BASEBOARD_FAB2(SCH_1):PAGE162
  U8F2    8 DO_IO<1> W25Q128_SKT16-IC,H12709-001    I32 @BASEBOARD_FAB2_LIB.BASEBOARD_FAB2(SCH_1):PAGE162

SPI_BMC_BT_DO @BASEBOARD_FAB2_LIB.BASEBOARD_FAB2(SCH_1):SPI_BMC_BT_DO
  U8F2   15 DI_IO<0> W25Q128_SKT16-IC,H12709-001    I32 @BASEBOARD_FAB2_LIB.BASEBOARD_FAB2(SCH_1):PAGE162
 UN8F2   15 DI_IO<0> W25Q256_XSOI-IC,H25002-001    I17 @BASEBOARD_FAB2_LIB.BASEBOARD_FAB2(SCH_1):PAGE246
R25W82    1      A RES_0402-33.2,1%,1/16W,CHIP,G2A    I68 @BASEBOARD_FAB2_LIB.BASEBOARD_FAB2(SCH_1):PAGE146
R25W96    2      B RES_0402-4.75K,1%,1/16W,CHIP,GA   I145 @BASEBOARD_FAB2_LIB.BASEBOARD_FAB2(SCH_1):PAGE150

SPI_BMC_BT_DO_R @BASEBOARD_FAB2_LIB.BASEBOARD_FAB2(SCH_1):SPI_BMC_BT_DO_R
R25W82    2      B RES_0402-33.2,1%,1/16W,CHIP,G2A    I68 @BASEBOARD_FAB2_LIB.BASEBOARD_FAB2(SCH_1):PAGE146
 U25W4  U17 FWSPIMOSI AST2520A1-GP-GP_ASIC2-GB1-AST2A   I105 @BASEBOARD_FAB2_LIB.BASEBOARD_FAB2(SCH_1):PAGE146

SPI_BMC_BT_WP0_N @BASEBOARD_FAB2_LIB.BASEBOARD_FAB2(SCH_1):SPI_BMC_BT_WP0_N
 U25W4  J18 GPIOF1_NDCD4_LHAD1 AST2520A1-GP-GP_ASIC2-GB1-AST2A   I117 @BASEBOARD_FAB2_LIB.BASEBOARD_FAB2(SCH_1):PAGE145
R25W154    1      A RES_0402-0.0,5%,1/16W,CHIP,G21A   I133 @BASEBOARD_FAB2_LIB.BASEBOARD_FAB2(SCH_1):PAGE137

SPI_BMC_CLK @BASEBOARD_FAB2_LIB.BASEBOARD_FAB2(SCH_1):SPI_BMC_CLK
  U8F1    3    IA1 PI3B3257A_TSSOPLF-IC,E16801-001    I74 @BASEBOARD_FAB2_LIB.BASEBOARD_FAB2(SCH_1):PAGE154
 U25W4  C15 GPIOI5_SPI1CK_VBCK AST2520A1-GP-GP_ASIC2-GB1-AST2A    I95 @BASEBOARD_FAB2_LIB.BASEBOARD_FAB2(SCH_1):PAGE144

SPI_BMC_CS0_N @BASEBOARD_FAB2_LIB.BASEBOARD_FAB2(SCH_1):SPI_BMC_CS0_N
  U8F1   10    IC1 PI3B3257A_TSSOPLF-IC,E16801-001    I74 @BASEBOARD_FAB2_LIB.BASEBOARD_FAB2(SCH_1):PAGE154
 U25W4  B15 GPIOI4_SPI1CS0#_VBCS# AST2520A1-GP-GP_ASIC2-GB1-AST2A    I95 @BASEBOARD_FAB2_LIB.BASEBOARD_FAB2(SCH_1):PAGE144

SPI_BMC_DI @BASEBOARD_FAB2_LIB.BASEBOARD_FAB2(SCH_1):SPI_BMC_DI
  U8F1   13    ID1 PI3B3257A_TSSOPLF-IC,E16801-001    I74 @BASEBOARD_FAB2_LIB.BASEBOARD_FAB2(SCH_1):PAGE154
 U25W4  A15 GPIOI7_SPI1MISO_VBMISO AST2520A1-GP-GP_ASIC2-GB1-AST2A    I95 @BASEBOARD_FAB2_LIB.BASEBOARD_FAB2(SCH_1):PAGE144

SPI_BMC_DO @BASEBOARD_FAB2_LIB.BASEBOARD_FAB2(SCH_1):SPI_BMC_DO
  U8F1    6    IB1 PI3B3257A_TSSOPLF-IC,E16801-001    I74 @BASEBOARD_FAB2_LIB.BASEBOARD_FAB2(SCH_1):PAGE154
 U25W4  A14 GPIOI6_SPI1MOSI_VBMOSI AST2520A1-GP-GP_ASIC2-GB1-AST2A    I95 @BASEBOARD_FAB2_LIB.BASEBOARD_FAB2(SCH_1):PAGE144

SPI_CLK_R0 @BASEBOARD_FAB2_LIB.BASEBOARD_FAB2(SCH_1):SPI_CLK_R0
  U7F1   16    CLK W25Q256_XSOI-IC,H25002-001   I146 @BASEBOARD_FAB2_LIB.BASEBOARD_FAB2(SCH_1):PAGE153
  R8F8    2      B RES_0402-33.2,1%,1/16W,CHIP,G2A   I166 @BASEBOARD_FAB2_LIB.BASEBOARD_FAB2(SCH_1):PAGE153

SPI_CLK_R1 @BASEBOARD_FAB2_LIB.BASEBOARD_FAB2(SCH_1):SPI_CLK_R1
  R8F7    2      B RES_0402-33.2,1%,1/16W,CHIP,G2A   I167 @BASEBOARD_FAB2_LIB.BASEBOARD_FAB2(SCH_1):PAGE153
  U3T1   16    CLK W25Q256FVFIG-GP_MEMORY-G4-W25QA   I185 @BASEBOARD_FAB2_LIB.BASEBOARD_FAB2(SCH_1):PAGE153

SPI_CS0_PRIMARY_N @BASEBOARD_FAB2_LIB.BASEBOARD_FAB2(SCH_1):SPI_CS0_PRIMARY_N
  U2T3    4      Y TTL1G32_A_SOT-74LVC1G32,IC,E60B    I99 @BASEBOARD_FAB2_LIB.BASEBOARD_FAB2(SCH_1):PAGE154
 R2T13    1      A RES_0402-200.0,1%,1/16W,CHIP,GA   I101 @BASEBOARD_FAB2_LIB.BASEBOARD_FAB2(SCH_1):PAGE154

SPI_CS0_PRIMARY_R_N @BASEBOARD_FAB2_LIB.BASEBOARD_FAB2(SCH_1):SPI_CS0_PRIMARY_R_N
  R7F5    2      B RES_0402-4.75K,1%,1/16W,CHIP,GA    I94 @BASEBOARD_FAB2_LIB.BASEBOARD_FAB2(SCH_1):PAGE153
  U7F1    7   CS_N W25Q256_XSOI-IC,H25002-001   I146 @BASEBOARD_FAB2_LIB.BASEBOARD_FAB2(SCH_1):PAGE153
 R2T13    2      B RES_0402-200.0,1%,1/16W,CHIP,GA   I101 @BASEBOARD_FAB2_LIB.BASEBOARD_FAB2(SCH_1):PAGE154
  R7W5    2      B RES_0402-0.0,5%,1/16W,CHIP,G21A   I187 @BASEBOARD_FAB2_LIB.BASEBOARD_FAB2(SCH_1):PAGE153

SPI_CS0_SECONDARY_N @BASEBOARD_FAB2_LIB.BASEBOARD_FAB2(SCH_1):SPI_CS0_SECONDARY_N
  R2T9    1      A RES_0402-75,1.0%,1/16W,CHIP,G2A    I62 @BASEBOARD_FAB2_LIB.BASEBOARD_FAB2(SCH_1):PAGE154
  U2T2    4      Y TTL1G32_A_SOT-74LVC1G32,IC,E60B   I100 @BASEBOARD_FAB2_LIB.BASEBOARD_FAB2(SCH_1):PAGE154

SPI_CS0_SECONDARY_R_N @BASEBOARD_FAB2_LIB.BASEBOARD_FAB2(SCH_1):SPI_CS0_SECONDARY_R_N
  R3T5    2      B RES_0402-4.75K,1%,1/16W,CHIP,GA   I152 @BASEBOARD_FAB2_LIB.BASEBOARD_FAB2(SCH_1):PAGE153
  R2T9    2      B RES_0402-75,1.0%,1/16W,CHIP,G2A    I62 @BASEBOARD_FAB2_LIB.BASEBOARD_FAB2(SCH_1):PAGE154
  U3T1    7    CS# W25Q256FVFIG-GP_MEMORY-G4-W25QA   I185 @BASEBOARD_FAB2_LIB.BASEBOARD_FAB2(SCH_1):PAGE153

SPI_MISO_R0 @BASEBOARD_FAB2_LIB.BASEBOARD_FAB2(SCH_1):SPI_MISO_R0
  R7F4    2      B RES_0402-33.2,1%,1/16W,CHIP,G2A    I98 @BASEBOARD_FAB2_LIB.BASEBOARD_FAB2(SCH_1):PAGE153
  U7F1    8 DO_IO<1> W25Q256_XSOI-IC,H25002-001   I146 @BASEBOARD_FAB2_LIB.BASEBOARD_FAB2(SCH_1):PAGE153

SPI_MISO_R1 @BASEBOARD_FAB2_LIB.BASEBOARD_FAB2(SCH_1):SPI_MISO_R1
  R3T2    2      B RES_0402-33.2,1%,1/16W,CHIP,G2A   I155 @BASEBOARD_FAB2_LIB.BASEBOARD_FAB2(SCH_1):PAGE153
  U3T1    8 DO/IO1 W25Q256FVFIG-GP_MEMORY-G4-W25QA   I185 @BASEBOARD_FAB2_LIB.BASEBOARD_FAB2(SCH_1):PAGE153

SPI_NIC_CS_N @BASEBOARD_FAB2_LIB.BASEBOARD_FAB2(SCH_1):SPI_NIC_CS_N
  R9E5    2      B RES_0402-33.2,1%,1/16W,CHIP,G2A   I129 @BASEBOARD_FAB2_LIB.BASEBOARD_FAB2(SCH_1):PAGE139
  U9E1    1    S_N M25PE16_SM-IC,H77797-001     I1 @BASEBOARD_FAB2_LIB.BASEBOARD_FAB2(SCH_1):PAGE140

SPI_NIC_CS_R_N @BASEBOARD_FAB2_LIB.BASEBOARD_FAB2(SCH_1):SPI_NIC_CS_R_N
 EU9E1   15 NVM_CS_N SPRINGVILLE_SM1-IC,G47144-004    I72 @BASEBOARD_FAB2_LIB.BASEBOARD_FAB2(SCH_1):PAGE139
  R9E5    1      A RES_0402-33.2,1%,1/16W,CHIP,G2A   I129 @BASEBOARD_FAB2_LIB.BASEBOARD_FAB2(SCH_1):PAGE139

SPI_NIC_MISO @BASEBOARD_FAB2_LIB.BASEBOARD_FAB2(SCH_1):SPI_NIC_MISO
 EU9E1   14 NVM_SO SPRINGVILLE_SM1-IC,G47144-004    I72 @BASEBOARD_FAB2_LIB.BASEBOARD_FAB2(SCH_1):PAGE139
  R9E6    2      B RES_0402-33.2,1%,1/16W,CHIP,G2A    I17 @BASEBOARD_FAB2_LIB.BASEBOARD_FAB2(SCH_1):PAGE140

SPI_NIC_MISO_R @BASEBOARD_FAB2_LIB.BASEBOARD_FAB2(SCH_1):SPI_NIC_MISO_R
  U9E1    2    DQ1 M25PE16_SM-IC,H77797-001     I1 @BASEBOARD_FAB2_LIB.BASEBOARD_FAB2(SCH_1):PAGE140
  R9E6    1      A RES_0402-33.2,1%,1/16W,CHIP,G2A    I17 @BASEBOARD_FAB2_LIB.BASEBOARD_FAB2(SCH_1):PAGE140

SPI_NIC_MOSI @BASEBOARD_FAB2_LIB.BASEBOARD_FAB2(SCH_1):SPI_NIC_MOSI
  R9E9    2      B RES_0402-33.2,1%,1/16W,CHIP,G2A   I128 @BASEBOARD_FAB2_LIB.BASEBOARD_FAB2(SCH_1):PAGE139
  U9E1    5    DQ0 M25PE16_SM-IC,H77797-001     I1 @BASEBOARD_FAB2_LIB.BASEBOARD_FAB2(SCH_1):PAGE140
  R1R7    2      B RES_0402-20.0K,1%,1/16W,CHIP,GA    I12 @BASEBOARD_FAB2_LIB.BASEBOARD_FAB2(SCH_1):PAGE140
  R1R6    1      A RES_0402-3.32K,1%,1/16W,EMPTY,A    I14 @BASEBOARD_FAB2_LIB.BASEBOARD_FAB2(SCH_1):PAGE140

SPI_NIC_MOSI_R @BASEBOARD_FAB2_LIB.BASEBOARD_FAB2(SCH_1):SPI_NIC_MOSI_R
 EU9E1   12 NVM_SI SPRINGVILLE_SM1-IC,G47144-004    I72 @BASEBOARD_FAB2_LIB.BASEBOARD_FAB2(SCH_1):PAGE139
  R9E9    1      A RES_0402-33.2,1%,1/16W,CHIP,G2A   I128 @BASEBOARD_FAB2_LIB.BASEBOARD_FAB2(SCH_1):PAGE139

SPI_NIC_SCLK @BASEBOARD_FAB2_LIB.BASEBOARD_FAB2(SCH_1):SPI_NIC_SCLK
  R9E8    2      B RES_0402-33.2,1%,1/16W,CHIP,G2A   I130 @BASEBOARD_FAB2_LIB.BASEBOARD_FAB2(SCH_1):PAGE139
  U9E1    6      C M25PE16_SM-IC,H77797-001     I1 @BASEBOARD_FAB2_LIB.BASEBOARD_FAB2(SCH_1):PAGE140

SPI_NIC_SCLK_R @BASEBOARD_FAB2_LIB.BASEBOARD_FAB2(SCH_1):SPI_NIC_SCLK_R
 EU9E1   13 NVM_SK SPRINGVILLE_SM1-IC,G47144-004    I72 @BASEBOARD_FAB2_LIB.BASEBOARD_FAB2(SCH_1):PAGE139
  R9E8    1      A RES_0402-33.2,1%,1/16W,CHIP,G2A   I130 @BASEBOARD_FAB2_LIB.BASEBOARD_FAB2(SCH_1):PAGE139

SPI_PCH_CLK @BASEBOARD_FAB2_LIB.BASEBOARD_FAB2(SCH_1):SPI_PCH_CLK
  U7C1   K2 SPI0_CLK LBG_CORE_QAT_EXT_D_BGA1-IC,H91A    I34 @BASEBOARD_FAB2_LIB.BASEBOARD_FAB2(SCH_1):PAGE121
  U8F1    2    IA0 PI3B3257A_TSSOPLF-IC,E16801-001    I74 @BASEBOARD_FAB2_LIB.BASEBOARD_FAB2(SCH_1):PAGE154
  R8E9    1      A RES_0402-33.2,1%,1/16W,CHIP,G2A    I88 @BASEBOARD_FAB2_LIB.BASEBOARD_FAB2(SCH_1):PAGE184

SPI_PCH_CS0_N @BASEBOARD_FAB2_LIB.BASEBOARD_FAB2(SCH_1):SPI_PCH_CS0_N
 R7C16    2      B RES_0402-33.2,1%,1/16W,CHIP,G2A    I33 @BASEBOARD_FAB2_LIB.BASEBOARD_FAB2(SCH_1):PAGE121
  U8F1   11    IC0 PI3B3257A_TSSOPLF-IC,E16801-001    I74 @BASEBOARD_FAB2_LIB.BASEBOARD_FAB2(SCH_1):PAGE154

SPI_PCH_CS0_R_N @BASEBOARD_FAB2_LIB.BASEBOARD_FAB2(SCH_1):SPI_PCH_CS0_R_N
 R7C16    1      A RES_0402-33.2,1%,1/16W,CHIP,G2A    I33 @BASEBOARD_FAB2_LIB.BASEBOARD_FAB2(SCH_1):PAGE121
  U7C1   J3 SPI0_FLASH_CS0_N LBG_CORE_QAT_EXT_D_BGA1-IC,H91A    I34 @BASEBOARD_FAB2_LIB.BASEBOARD_FAB2(SCH_1):PAGE121

SPI_PCH_IO2 @BASEBOARD_FAB2_LIB.BASEBOARD_FAB2(SCH_1):SPI_PCH_IO2
  R2P2    1      A RES_0402-1.00K,1%,1/16W,CHIP,GA    I37 @BASEBOARD_FAB2_LIB.BASEBOARD_FAB2(SCH_1):PAGE111
  U7C1   F5 SPI0_IO2 LBG_CORE_QAT_EXT_D_BGA1-IC,H91A    I34 @BASEBOARD_FAB2_LIB.BASEBOARD_FAB2(SCH_1):PAGE121
 R2R11    1      A RES_0402-1.00K,1%,1/16W,EMPTY,A    I11 @BASEBOARD_FAB2_LIB.BASEBOARD_FAB2(SCH_1):PAGE125
 R2R12    1      A RES_0402-0.0,5%,1/16W,CHIP,G21A    I93 @BASEBOARD_FAB2_LIB.BASEBOARD_FAB2(SCH_1):PAGE154

SPI_PCH_IO2_R1 @BASEBOARD_FAB2_LIB.BASEBOARD_FAB2(SCH_1):SPI_PCH_IO2_R1
  U2T1    2    IA0 PI3B3257A_TSSOPLF-IC,E16801-001    I75 @BASEBOARD_FAB2_LIB.BASEBOARD_FAB2(SCH_1):PAGE154
 R2R12    2      B RES_0402-0.0,5%,1/16W,CHIP,G21A    I93 @BASEBOARD_FAB2_LIB.BASEBOARD_FAB2(SCH_1):PAGE154

SPI_PCH_IO3 @BASEBOARD_FAB2_LIB.BASEBOARD_FAB2(SCH_1):SPI_PCH_IO3
  U7C1   L1 SPI0_IO3 LBG_CORE_QAT_EXT_D_BGA1-IC,H91A    I34 @BASEBOARD_FAB2_LIB.BASEBOARD_FAB2(SCH_1):PAGE121
 R3N17    2      B RES_0402-1.00K,1%,1/16W,EMPTY,A    I78 @BASEBOARD_FAB2_LIB.BASEBOARD_FAB2(SCH_1):PAGE125
  R2T2    1      A RES_0402-0.0,5%,1/16W,CHIP,G21A    I92 @BASEBOARD_FAB2_LIB.BASEBOARD_FAB2(SCH_1):PAGE154
  R2T1    1      A RES_0402-1.00K,1%,1/16W,EMPTY,A    I89 @BASEBOARD_FAB2_LIB.BASEBOARD_FAB2(SCH_1):PAGE125

SPI_PCH_IO3_R1 @BASEBOARD_FAB2_LIB.BASEBOARD_FAB2(SCH_1):SPI_PCH_IO3_R1
  U2T1    5    IB0 PI3B3257A_TSSOPLF-IC,E16801-001    I75 @BASEBOARD_FAB2_LIB.BASEBOARD_FAB2(SCH_1):PAGE154
  R2T2    2      B RES_0402-0.0,5%,1/16W,CHIP,G21A    I92 @BASEBOARD_FAB2_LIB.BASEBOARD_FAB2(SCH_1):PAGE154

SPI_PCH_MISO @BASEBOARD_FAB2_LIB.BASEBOARD_FAB2(SCH_1):SPI_PCH_MISO
  U7C1   L3 SPI0_MISO_IO1 LBG_CORE_QAT_EXT_D_BGA1-IC,H91A    I34 @BASEBOARD_FAB2_LIB.BASEBOARD_FAB2(SCH_1):PAGE121
  R8F6    1      A RES_0402-0.0,5%,1/16W,CHIP,G21A   I119 @BASEBOARD_FAB2_LIB.BASEBOARD_FAB2(SCH_1):PAGE154
 R8E13    1      A RES_0402-33.2,1%,1/16W,CHIP,G2A    I93 @BASEBOARD_FAB2_LIB.BASEBOARD_FAB2(SCH_1):PAGE184

SPI_PCH_MISO_R @BASEBOARD_FAB2_LIB.BASEBOARD_FAB2(SCH_1):SPI_PCH_MISO_R
  U8F1   14    ID0 PI3B3257A_TSSOPLF-IC,E16801-001    I74 @BASEBOARD_FAB2_LIB.BASEBOARD_FAB2(SCH_1):PAGE154
  R8F6    2      B RES_0402-0.0,5%,1/16W,CHIP,G21A   I119 @BASEBOARD_FAB2_LIB.BASEBOARD_FAB2(SCH_1):PAGE154

SPI_PCH_MOSI @BASEBOARD_FAB2_LIB.BASEBOARD_FAB2(SCH_1):SPI_PCH_MOSI
  R8E2    2      B RES_0402-1.00K,1%,1/16W,CHIP,GA    I89 @BASEBOARD_FAB2_LIB.BASEBOARD_FAB2(SCH_1):PAGE111
 R7C15    2      B RES_0402-0.0,5%,1/16W,CHIP,G21A    I31 @BASEBOARD_FAB2_LIB.BASEBOARD_FAB2(SCH_1):PAGE121
  R8E6    2      B RES_0402-1.00K,1%,1/16W,EMPTY,A    I21 @BASEBOARD_FAB2_LIB.BASEBOARD_FAB2(SCH_1):PAGE125
  R8E4    1      A RES_0402-1.00K,1%,1/16W,EMPTY,A    I24 @BASEBOARD_FAB2_LIB.BASEBOARD_FAB2(SCH_1):PAGE125
  U8F1    5    IB0 PI3B3257A_TSSOPLF-IC,E16801-001    I74 @BASEBOARD_FAB2_LIB.BASEBOARD_FAB2(SCH_1):PAGE154
 R8E10    1      A RES_0402-33.2,1%,1/16W,CHIP,G2A    I95 @BASEBOARD_FAB2_LIB.BASEBOARD_FAB2(SCH_1):PAGE184

SPI_PCH_MOSI_R @BASEBOARD_FAB2_LIB.BASEBOARD_FAB2(SCH_1):SPI_PCH_MOSI_R
 R7C15    1      A RES_0402-0.0,5%,1/16W,CHIP,G21A    I31 @BASEBOARD_FAB2_LIB.BASEBOARD_FAB2(SCH_1):PAGE121
  U7C1   H4 SPI0_MOSI_IO0 LBG_CORE_QAT_EXT_D_BGA1-IC,H91A    I34 @BASEBOARD_FAB2_LIB.BASEBOARD_FAB2(SCH_1):PAGE121

SPI_PCH_TPM_CLK_R @BASEBOARD_FAB2_LIB.BASEBOARD_FAB2(SCH_1):SPI_PCH_TPM_CLK_R
  J8E1    1    IO1 SCONN11_H67026001_SM-CONN,H670A    I87 @BASEBOARD_FAB2_LIB.BASEBOARD_FAB2(SCH_1):PAGE184
  R8E9    2      B RES_0402-33.2,1%,1/16W,CHIP,G2A    I88 @BASEBOARD_FAB2_LIB.BASEBOARD_FAB2(SCH_1):PAGE184

SPI_PCH_TPM_CS_N @BASEBOARD_FAB2_LIB.BASEBOARD_FAB2(SCH_1):SPI_PCH_TPM_CS_N
  U7C1   K4 SPI0_TPM_CS_N LBG_CORE_QAT_EXT_D_BGA1-IC,H91A    I34 @BASEBOARD_FAB2_LIB.BASEBOARD_FAB2(SCH_1):PAGE121
 R8D35    1      A RES_0402-0.0,5%,1/16W,CHIP,G21A    I92 @BASEBOARD_FAB2_LIB.BASEBOARD_FAB2(SCH_1):PAGE184

SPI_PCH_TPM_CS_R_N @BASEBOARD_FAB2_LIB.BASEBOARD_FAB2(SCH_1):SPI_PCH_TPM_CS_R_N
  J8E1    5    IO5 SCONN11_H67026001_SM-CONN,H670A    I87 @BASEBOARD_FAB2_LIB.BASEBOARD_FAB2(SCH_1):PAGE184
 R8D35    2      B RES_0402-0.0,5%,1/16W,CHIP,G21A    I92 @BASEBOARD_FAB2_LIB.BASEBOARD_FAB2(SCH_1):PAGE184

SPI_PCH_TPM_MISO_R @BASEBOARD_FAB2_LIB.BASEBOARD_FAB2(SCH_1):SPI_PCH_TPM_MISO_R
  J8E1    4    IO4 SCONN11_H67026001_SM-CONN,H670A    I87 @BASEBOARD_FAB2_LIB.BASEBOARD_FAB2(SCH_1):PAGE184
 R8E13    2      B RES_0402-33.2,1%,1/16W,CHIP,G2A    I93 @BASEBOARD_FAB2_LIB.BASEBOARD_FAB2(SCH_1):PAGE184

SPI_PCH_TPM_MOSI_R @BASEBOARD_FAB2_LIB.BASEBOARD_FAB2(SCH_1):SPI_PCH_TPM_MOSI_R
  J8E1    3    IO3 SCONN11_H67026001_SM-CONN,H670A    I87 @BASEBOARD_FAB2_LIB.BASEBOARD_FAB2(SCH_1):PAGE184
 R8E10    2      B RES_0402-33.2,1%,1/16W,CHIP,G2A    I95 @BASEBOARD_FAB2_LIB.BASEBOARD_FAB2(SCH_1):PAGE184

SPI_SWITCH_CLK @BASEBOARD_FAB2_LIB.BASEBOARD_FAB2(SCH_1):SPI_SWITCH_CLK
  R8F8    1      A RES_0402-33.2,1%,1/16W,CHIP,G2A   I166 @BASEBOARD_FAB2_LIB.BASEBOARD_FAB2(SCH_1):PAGE153
  R8F7    1      A RES_0402-33.2,1%,1/16W,CHIP,G2A   I167 @BASEBOARD_FAB2_LIB.BASEBOARD_FAB2(SCH_1):PAGE153
  U8F1    4     YA PI3B3257A_TSSOPLF-IC,E16801-001    I74 @BASEBOARD_FAB2_LIB.BASEBOARD_FAB2(SCH_1):PAGE154

SPI_SWITCH_CS0_N @BASEBOARD_FAB2_LIB.BASEBOARD_FAB2(SCH_1):SPI_SWITCH_CS0_N
  U8F1    9     YC PI3B3257A_TSSOPLF-IC,E16801-001    I74 @BASEBOARD_FAB2_LIB.BASEBOARD_FAB2(SCH_1):PAGE154
  U2T3    2      B TTL1G32_A_SOT-74LVC1G32,IC,E60B    I99 @BASEBOARD_FAB2_LIB.BASEBOARD_FAB2(SCH_1):PAGE154
  U2T2    2      B TTL1G32_A_SOT-74LVC1G32,IC,E60B   I100 @BASEBOARD_FAB2_LIB.BASEBOARD_FAB2(SCH_1):PAGE154
  R2T8    2      B RES_0402-10.0K,1%,1/16W,CHIP,GA   I106 @BASEBOARD_FAB2_LIB.BASEBOARD_FAB2(SCH_1):PAGE154
  R7W5    1      A RES_0402-0.0,5%,1/16W,CHIP,G21A   I187 @BASEBOARD_FAB2_LIB.BASEBOARD_FAB2(SCH_1):PAGE153

SPI_SWITCH_MISO @BASEBOARD_FAB2_LIB.BASEBOARD_FAB2(SCH_1):SPI_SWITCH_MISO
  R7F4    1      A RES_0402-33.2,1%,1/16W,CHIP,G2A    I98 @BASEBOARD_FAB2_LIB.BASEBOARD_FAB2(SCH_1):PAGE153
  R3T2    1      A RES_0402-33.2,1%,1/16W,CHIP,G2A   I155 @BASEBOARD_FAB2_LIB.BASEBOARD_FAB2(SCH_1):PAGE153
  U8F1   12     YD PI3B3257A_TSSOPLF-IC,E16801-001    I74 @BASEBOARD_FAB2_LIB.BASEBOARD_FAB2(SCH_1):PAGE154

SPI_SWITCH_MOSI @BASEBOARD_FAB2_LIB.BASEBOARD_FAB2(SCH_1):SPI_SWITCH_MOSI
 R7F29    1      A RES_0402-33.2,1%,1/16W,CHIP,G2A   I181 @BASEBOARD_FAB2_LIB.BASEBOARD_FAB2(SCH_1):PAGE153
 R3T10    1      A RES_0402-33.2,1%,1/16W,CHIP,G2A   I184 @BASEBOARD_FAB2_LIB.BASEBOARD_FAB2(SCH_1):PAGE153
  U8F1    7     YB PI3B3257A_TSSOPLF-IC,E16801-001    I74 @BASEBOARD_FAB2_LIB.BASEBOARD_FAB2(SCH_1):PAGE154

SPI_SWITCH_MOSI_R0 @BASEBOARD_FAB2_LIB.BASEBOARD_FAB2(SCH_1):SPI_SWITCH_MOSI_R0
  U7F1   15 DI_IO<0> W25Q256_XSOI-IC,H25002-001   I146 @BASEBOARD_FAB2_LIB.BASEBOARD_FAB2(SCH_1):PAGE153
 R7F29    2      B RES_0402-33.2,1%,1/16W,CHIP,G2A   I181 @BASEBOARD_FAB2_LIB.BASEBOARD_FAB2(SCH_1):PAGE153

SPI_SWITCH_MOSI_R1 @BASEBOARD_FAB2_LIB.BASEBOARD_FAB2(SCH_1):SPI_SWITCH_MOSI_R1
 R3T10    2      B RES_0402-33.2,1%,1/16W,CHIP,G2A   I184 @BASEBOARD_FAB2_LIB.BASEBOARD_FAB2(SCH_1):PAGE153
  U3T1   15 DI/IO0 W25Q256FVFIG-GP_MEMORY-G4-W25QA   I185 @BASEBOARD_FAB2_LIB.BASEBOARD_FAB2(SCH_1):PAGE153

SPI_TPM_BMC_DI_R @BASEBOARD_FAB2_LIB.BASEBOARD_FAB2(SCH_1):SPI_TPM_BMC_DI_R
 RN8F5    2      B RES_0402-33.2,1%,1/16W,CHIP,G2A     I9 @BASEBOARD_FAB2_LIB.BASEBOARD_FAB2(SCH_1):PAGE246
 UN8F2    8 DO_IO<1> W25Q256_XSOI-IC,H25002-001    I17 @BASEBOARD_FAB2_LIB.BASEBOARD_FAB2(SCH_1):PAGE246

SVID_ALERT0_CPU0_N @BASEBOARD_FAB2_LIB.BASEBOARD_FAB2(SCH_1):SVID_ALERT0_CPU0_N
 R6N10    1      A RES_0402-221,1.0%,1/16W,CHIP,GA   I149 @BASEBOARD_FAB2_LIB.BASEBOARD_FAB2(SCH_1):PAGE21
  U5D1 DE44 SVIDALERT_N<0> SKX_EXT_B_BGA1-IC,TBD   I259 @BASEBOARD_FAB2_LIB.BASEBOARD_FAB2(SCH_1):PAGE21

SVID_ALERT0_CPU0_R_N @BASEBOARD_FAB2_LIB.BASEBOARD_FAB2(SCH_1):SVID_ALERT0_CPU0_R_N
 R6N10    2      B RES_0402-221,1.0%,1/16W,CHIP,GA   I149 @BASEBOARD_FAB2_LIB.BASEBOARD_FAB2(SCH_1):PAGE21
  R6N1    1      A RES_0402-49.9,1%,1/16W,CHIP,G2A   I164 @BASEBOARD_FAB2_LIB.BASEBOARD_FAB2(SCH_1):PAGE21
  J6B1  A19  IOA19 SCONN120_H61426002_SM-CONN,H61A    I56 @BASEBOARD_FAB2_LIB.BASEBOARD_FAB2(SCH_1):PAGE194
 R4D67    2      B RES_0402-0.0,5%,1/16W,CHIP,G21A    I26 @BASEBOARD_FAB2_LIB.BASEBOARD_FAB2(SCH_1):PAGE201
  R3P1    2      B RES_0402-0.0,5%,1/16W,CHIP,G21A    I61 @BASEBOARD_FAB2_LIB.BASEBOARD_FAB2(SCH_1):PAGE211

SVID_ALERT0_CPU1_N @BASEBOARD_FAB2_LIB.BASEBOARD_FAB2(SCH_1):SVID_ALERT0_CPU1_N
  R3B1    1      A RES_0402-221,1.0%,1/16W,CHIP,GA    I27 @BASEBOARD_FAB2_LIB.BASEBOARD_FAB2(SCH_1):PAGE55
  U2D1 DE44 SVIDALERT_N<0> SKX_EXT_B_BGA1-IC,TBD   I172 @BASEBOARD_FAB2_LIB.BASEBOARD_FAB2(SCH_1):PAGE55

SVID_ALERT0_CPU1_R_N @BASEBOARD_FAB2_LIB.BASEBOARD_FAB2(SCH_1):SVID_ALERT0_CPU1_R_N
  R3B2    1      A RES_0402-49.9,1%,1/16W,CHIP,G2A    I19 @BASEBOARD_FAB2_LIB.BASEBOARD_FAB2(SCH_1):PAGE55
  R3B1    2      B RES_0402-221,1.0%,1/16W,CHIP,GA    I27 @BASEBOARD_FAB2_LIB.BASEBOARD_FAB2(SCH_1):PAGE55
  J4B2  A19  IOA19 SCONN120_H61426002_SM-CONN,H61A    I46 @BASEBOARD_FAB2_LIB.BASEBOARD_FAB2(SCH_1):PAGE193
  R1D3    2      B RES_0402-0.0,5%,1/16W,CHIP,G21A    I37 @BASEBOARD_FAB2_LIB.BASEBOARD_FAB2(SCH_1):PAGE206
 R4D56    2      B RES_0402-0.0,5%,1/16W,CHIP,G21A    I16 @BASEBOARD_FAB2_LIB.BASEBOARD_FAB2(SCH_1):PAGE213

SVID_ALERT1_CPU0_N @BASEBOARD_FAB2_LIB.BASEBOARD_FAB2(SCH_1):SVID_ALERT1_CPU0_N
  R6B3    1      A RES_0402-221,1.0%,1/16W,CHIP,GA   I152 @BASEBOARD_FAB2_LIB.BASEBOARD_FAB2(SCH_1):PAGE21
  U5D1 DL44 SVIDALERT_N<1> SKX_EXT_B_BGA1-IC,TBD   I259 @BASEBOARD_FAB2_LIB.BASEBOARD_FAB2(SCH_1):PAGE21

SVID_ALERT1_CPU0_R_N @BASEBOARD_FAB2_LIB.BASEBOARD_FAB2(SCH_1):SVID_ALERT1_CPU0_R_N
  R6B3    2      B RES_0402-221,1.0%,1/16W,CHIP,GA   I152 @BASEBOARD_FAB2_LIB.BASEBOARD_FAB2(SCH_1):PAGE21
  R6B1    2      B RES_0402-49.9,1%,1/16W,CHIP,G2A   I161 @BASEBOARD_FAB2_LIB.BASEBOARD_FAB2(SCH_1):PAGE21
  J6B1  B19  IOB19 SCONN120_H61426002_SM-CONN,H61A    I56 @BASEBOARD_FAB2_LIB.BASEBOARD_FAB2(SCH_1):PAGE194
  R7G4    2      B RES_0402-0.0,5%,1/16W,CHIP,G21A    I49 @BASEBOARD_FAB2_LIB.BASEBOARD_FAB2(SCH_1):PAGE215
 R7A11    2      B RES_0402-0.0,5%,1/16W,CHIP,G21A    I56 @BASEBOARD_FAB2_LIB.BASEBOARD_FAB2(SCH_1):PAGE218

SVID_ALERT1_CPU1_N @BASEBOARD_FAB2_LIB.BASEBOARD_FAB2(SCH_1):SVID_ALERT1_CPU1_N
  R1C1    1      A RES_0402-221,1.0%,1/16W,CHIP,GA    I26 @BASEBOARD_FAB2_LIB.BASEBOARD_FAB2(SCH_1):PAGE55
  U2D1 DL44 SVIDALERT_N<1> SKX_EXT_B_BGA1-IC,TBD   I172 @BASEBOARD_FAB2_LIB.BASEBOARD_FAB2(SCH_1):PAGE55

SVID_ALERT1_CPU1_R_N @BASEBOARD_FAB2_LIB.BASEBOARD_FAB2(SCH_1):SVID_ALERT1_CPU1_R_N
  R9N1    2      B RES_0402-49.9,1%,1/16W,CHIP,G2A     I4 @BASEBOARD_FAB2_LIB.BASEBOARD_FAB2(SCH_1):PAGE55
  R1C1    2      B RES_0402-221,1.0%,1/16W,CHIP,GA    I26 @BASEBOARD_FAB2_LIB.BASEBOARD_FAB2(SCH_1):PAGE55
  J4B2  B19  IOB19 SCONN120_H61426002_SM-CONN,H61A    I46 @BASEBOARD_FAB2_LIB.BASEBOARD_FAB2(SCH_1):PAGE193
  R1G9    2      B RES_0402-0.0,5%,1/16W,CHIP,G21A    I50 @BASEBOARD_FAB2_LIB.BASEBOARD_FAB2(SCH_1):PAGE223
 R1B11    2      B RES_0402-0.0,5%,1/16W,CHIP,G21A    I48 @BASEBOARD_FAB2_LIB.BASEBOARD_FAB2(SCH_1):PAGE226

SVID_ALERT_PVCCIO_CPU0 @BASEBOARD_FAB2_LIB.BASEBOARD_FAB2(SCH_1):SVID_ALERT_PVCCIO_CPU0
  R3P1    1      A RES_0402-0.0,5%,1/16W,CHIP,G21A    I61 @BASEBOARD_FAB2_LIB.BASEBOARD_FAB2(SCH_1):PAGE211
 EU3P1   17 VALRT_N PXE1110B_QFN-IC,H89187-001    I93 @BASEBOARD_FAB2_LIB.BASEBOARD_FAB2(SCH_1):PAGE211

SVID_ALERT_PVCCIO_CPU1 @BASEBOARD_FAB2_LIB.BASEBOARD_FAB2(SCH_1):SVID_ALERT_PVCCIO_CPU1
 R4D56    1      A RES_0402-0.0,5%,1/16W,CHIP,G21A    I16 @BASEBOARD_FAB2_LIB.BASEBOARD_FAB2(SCH_1):PAGE213
 EU4D5   17 VALRT_N PXE1110B_QFN-IC,H89187-001    I96 @BASEBOARD_FAB2_LIB.BASEBOARD_FAB2(SCH_1):PAGE213

SVID_ALERT_PVDDQ_ABC @BASEBOARD_FAB2_LIB.BASEBOARD_FAB2(SCH_1):SVID_ALERT_PVDDQ_ABC
  R7G4    1      A RES_0402-0.0,5%,1/16W,CHIP,G21A    I49 @BASEBOARD_FAB2_LIB.BASEBOARD_FAB2(SCH_1):PAGE215
 EU7G1   17 VALRT_N PXM1310B_QFN-IC,H89186-001    I69 @BASEBOARD_FAB2_LIB.BASEBOARD_FAB2(SCH_1):PAGE215

SVID_ALERT_PVDDQ_DEF @BASEBOARD_FAB2_LIB.BASEBOARD_FAB2(SCH_1):SVID_ALERT_PVDDQ_DEF
 R7A11    1      A RES_0402-0.0,5%,1/16W,CHIP,G21A    I56 @BASEBOARD_FAB2_LIB.BASEBOARD_FAB2(SCH_1):PAGE218
 EU7A5   17 VALRT_N PXM1310B_QFN-IC,H89186-001    I69 @BASEBOARD_FAB2_LIB.BASEBOARD_FAB2(SCH_1):PAGE218

SVID_ALERT_PVDDQ_GHJ @BASEBOARD_FAB2_LIB.BASEBOARD_FAB2(SCH_1):SVID_ALERT_PVDDQ_GHJ
 EU1G2   17 VALRT_N PXM1310B_QFN-IC,H89186-001    I69 @BASEBOARD_FAB2_LIB.BASEBOARD_FAB2(SCH_1):PAGE223
  R1G9    1      A RES_0402-0.0,5%,1/16W,CHIP,G21A    I50 @BASEBOARD_FAB2_LIB.BASEBOARD_FAB2(SCH_1):PAGE223

SVID_ALERT_PVDDQ_KLM @BASEBOARD_FAB2_LIB.BASEBOARD_FAB2(SCH_1):SVID_ALERT_PVDDQ_KLM
 R1B11    1      A RES_0402-0.0,5%,1/16W,CHIP,G21A    I48 @BASEBOARD_FAB2_LIB.BASEBOARD_FAB2(SCH_1):PAGE226
 EU1B1   17 VALRT_N PXM1310B_QFN-IC,H89186-001    I69 @BASEBOARD_FAB2_LIB.BASEBOARD_FAB2(SCH_1):PAGE226

SVID_CLK0_CPU0 @BASEBOARD_FAB2_LIB.BASEBOARD_FAB2(SCH_1):SVID_CLK0_CPU0
 R6N12    1      A RES_0402-0.0,5%,1/16W,CHIP,G21A   I150 @BASEBOARD_FAB2_LIB.BASEBOARD_FAB2(SCH_1):PAGE21
  U5D1 DC44 SVIDCLK<0> SKX_EXT_B_BGA1-IC,TBD   I259 @BASEBOARD_FAB2_LIB.BASEBOARD_FAB2(SCH_1):PAGE21

SVID_CLK0_CPU0_R @BASEBOARD_FAB2_LIB.BASEBOARD_FAB2(SCH_1):SVID_CLK0_CPU0_R
 R6N12    2      B RES_0402-0.0,5%,1/16W,CHIP,G21A   I150 @BASEBOARD_FAB2_LIB.BASEBOARD_FAB2(SCH_1):PAGE21
  J6B1  A20  IOA20 SCONN120_H61426002_SM-CONN,H61A    I56 @BASEBOARD_FAB2_LIB.BASEBOARD_FAB2(SCH_1):PAGE194
  R4E6    1      A RES_0402-150.0,1%,1/16W,CHIP,GA    I56 @BASEBOARD_FAB2_LIB.BASEBOARD_FAB2(SCH_1):PAGE201
 R3P15    1      A RES_0402-150.0,1%,1/16W,CHIP,GA    I29 @BASEBOARD_FAB2_LIB.BASEBOARD_FAB2(SCH_1):PAGE211
  R4E9    2      B RES_0402-49.9,1%,1/16W,EMPTY,GA   I189 @BASEBOARD_FAB2_LIB.BASEBOARD_FAB2(SCH_1):PAGE201
 R3P17    2      B RES_0402-49.9,1%,1/16W,CHIP,G2A    I99 @BASEBOARD_FAB2_LIB.BASEBOARD_FAB2(SCH_1):PAGE211

SVID_CLK0_CPU1 @BASEBOARD_FAB2_LIB.BASEBOARD_FAB2(SCH_1):SVID_CLK0_CPU1
  R3B5    1      A RES_0402-0.0,5%,1/16W,CHIP,G21A    I28 @BASEBOARD_FAB2_LIB.BASEBOARD_FAB2(SCH_1):PAGE55
  U2D1 DC44 SVIDCLK<0> SKX_EXT_B_BGA1-IC,TBD   I172 @BASEBOARD_FAB2_LIB.BASEBOARD_FAB2(SCH_1):PAGE55

SVID_CLK0_CPU1_R @BASEBOARD_FAB2_LIB.BASEBOARD_FAB2(SCH_1):SVID_CLK0_CPU1_R
  R3B5    2      B RES_0402-0.0,5%,1/16W,CHIP,G21A    I28 @BASEBOARD_FAB2_LIB.BASEBOARD_FAB2(SCH_1):PAGE55
  J4B2  A20  IOA20 SCONN120_H61426002_SM-CONN,H61A    I46 @BASEBOARD_FAB2_LIB.BASEBOARD_FAB2(SCH_1):PAGE193
  R9P2    2      B RES_0402-49.9,1%,1/16W,CHIP,G2A    I53 @BASEBOARD_FAB2_LIB.BASEBOARD_FAB2(SCH_1):PAGE206
  R1D9    1      A RES_0402-150.0,1%,1/16W,CHIP,GA    I54 @BASEBOARD_FAB2_LIB.BASEBOARD_FAB2(SCH_1):PAGE206
 R6P33    2      B RES_0402-110,1%,1/16W,EMPTY,G2A    I30 @BASEBOARD_FAB2_LIB.BASEBOARD_FAB2(SCH_1):PAGE213
 R4D51    1      A RES_0402-150.0,1%,1/16W,CHIP,GA    I46 @BASEBOARD_FAB2_LIB.BASEBOARD_FAB2(SCH_1):PAGE213

SVID_CLK1_CPU0 @BASEBOARD_FAB2_LIB.BASEBOARD_FAB2(SCH_1):SVID_CLK1_CPU0
  R6B5    1      A RES_0402-0.0,5%,1/16W,CHIP,G21A   I153 @BASEBOARD_FAB2_LIB.BASEBOARD_FAB2(SCH_1):PAGE21
  U5D1 DG44 SVIDCLK<1> SKX_EXT_B_BGA1-IC,TBD   I259 @BASEBOARD_FAB2_LIB.BASEBOARD_FAB2(SCH_1):PAGE21

SVID_CLK1_CPU0_R @BASEBOARD_FAB2_LIB.BASEBOARD_FAB2(SCH_1):SVID_CLK1_CPU0_R
  R6B5    2      B RES_0402-0.0,5%,1/16W,CHIP,G21A   I153 @BASEBOARD_FAB2_LIB.BASEBOARD_FAB2(SCH_1):PAGE21
  J6B1  E20  IOE20 SCONN120_H61426002_SM-CONN,H61A    I56 @BASEBOARD_FAB2_LIB.BASEBOARD_FAB2(SCH_1):PAGE194
 R7A17    1      A RES_0402-150.0,1%,1/16W,CHIP,GA    I21 @BASEBOARD_FAB2_LIB.BASEBOARD_FAB2(SCH_1):PAGE218
 R7G24    1      A RES_0402-150.0,1%,1/16W,CHIP,GA    I28 @BASEBOARD_FAB2_LIB.BASEBOARD_FAB2(SCH_1):PAGE215
 R3T11    2      B RES_0402-49.9,1%,1/16W,CHIP,G2A    I70 @BASEBOARD_FAB2_LIB.BASEBOARD_FAB2(SCH_1):PAGE215
 R3L13    2      B RES_0402-49.9,1%,1/16W,EMPTY,GA    I70 @BASEBOARD_FAB2_LIB.BASEBOARD_FAB2(SCH_1):PAGE218

SVID_CLK1_CPU1 @BASEBOARD_FAB2_LIB.BASEBOARD_FAB2(SCH_1):SVID_CLK1_CPU1
  R1C3    1      A RES_0402-0.0,5%,1/16W,CHIP,G21A    I25 @BASEBOARD_FAB2_LIB.BASEBOARD_FAB2(SCH_1):PAGE55
  U2D1 DG44 SVIDCLK<1> SKX_EXT_B_BGA1-IC,TBD   I172 @BASEBOARD_FAB2_LIB.BASEBOARD_FAB2(SCH_1):PAGE55

SVID_CLK1_CPU1_R @BASEBOARD_FAB2_LIB.BASEBOARD_FAB2(SCH_1):SVID_CLK1_CPU1_R
  R1C3    2      B RES_0402-0.0,5%,1/16W,CHIP,G21A    I25 @BASEBOARD_FAB2_LIB.BASEBOARD_FAB2(SCH_1):PAGE55
  J4B2  E20  IOE20 SCONN120_H61426002_SM-CONN,H61A    I46 @BASEBOARD_FAB2_LIB.BASEBOARD_FAB2(SCH_1):PAGE193
  R1G7    1      A RES_0402-150.0,1%,1/16W,CHIP,GA    I18 @BASEBOARD_FAB2_LIB.BASEBOARD_FAB2(SCH_1):PAGE223
  R1B8    1      A RES_0402-150.0,1%,1/16W,CHIP,GA    I19 @BASEBOARD_FAB2_LIB.BASEBOARD_FAB2(SCH_1):PAGE226
  R9M6    2      B RES_0402-49.9,1%,1/16W,EMPTY,GA    I70 @BASEBOARD_FAB2_LIB.BASEBOARD_FAB2(SCH_1):PAGE226
  R9U4    2      B RES_0402-49.9,1%,1/16W,CHIP,G2A    I70 @BASEBOARD_FAB2_LIB.BASEBOARD_FAB2(SCH_1):PAGE223

SVID_CLK_PVCCIO_CPU0 @BASEBOARD_FAB2_LIB.BASEBOARD_FAB2(SCH_1):SVID_CLK_PVCCIO_CPU0
 R3P15    2      B RES_0402-150.0,1%,1/16W,CHIP,GA    I29 @BASEBOARD_FAB2_LIB.BASEBOARD_FAB2(SCH_1):PAGE211
 EU3P1   15   VCLK PXE1110B_QFN-IC,H89187-001    I93 @BASEBOARD_FAB2_LIB.BASEBOARD_FAB2(SCH_1):PAGE211

SVID_CLK_PVCCIO_CPU1 @BASEBOARD_FAB2_LIB.BASEBOARD_FAB2(SCH_1):SVID_CLK_PVCCIO_CPU1
 R4D51    2      B RES_0402-150.0,1%,1/16W,CHIP,GA    I46 @BASEBOARD_FAB2_LIB.BASEBOARD_FAB2(SCH_1):PAGE213
 EU4D5   15   VCLK PXE1110B_QFN-IC,H89187-001    I96 @BASEBOARD_FAB2_LIB.BASEBOARD_FAB2(SCH_1):PAGE213

SVID_CLK_PVDDQ_ABC @BASEBOARD_FAB2_LIB.BASEBOARD_FAB2(SCH_1):SVID_CLK_PVDDQ_ABC
 R7G24    2      B RES_0402-150.0,1%,1/16W,CHIP,GA    I28 @BASEBOARD_FAB2_LIB.BASEBOARD_FAB2(SCH_1):PAGE215
 EU7G1   15   VCLK PXM1310B_QFN-IC,H89186-001    I69 @BASEBOARD_FAB2_LIB.BASEBOARD_FAB2(SCH_1):PAGE215

SVID_CLK_PVDDQ_DEF @BASEBOARD_FAB2_LIB.BASEBOARD_FAB2(SCH_1):SVID_CLK_PVDDQ_DEF
 R7A17    2      B RES_0402-150.0,1%,1/16W,CHIP,GA    I21 @BASEBOARD_FAB2_LIB.BASEBOARD_FAB2(SCH_1):PAGE218
 EU7A5   15   VCLK PXM1310B_QFN-IC,H89186-001    I69 @BASEBOARD_FAB2_LIB.BASEBOARD_FAB2(SCH_1):PAGE218

SVID_CLK_PVDDQ_GHJ @BASEBOARD_FAB2_LIB.BASEBOARD_FAB2(SCH_1):SVID_CLK_PVDDQ_GHJ
  R1G7    2      B RES_0402-150.0,1%,1/16W,CHIP,GA    I18 @BASEBOARD_FAB2_LIB.BASEBOARD_FAB2(SCH_1):PAGE223
 EU1G2   15   VCLK PXM1310B_QFN-IC,H89186-001    I69 @BASEBOARD_FAB2_LIB.BASEBOARD_FAB2(SCH_1):PAGE223

SVID_CLK_PVDDQ_KLM @BASEBOARD_FAB2_LIB.BASEBOARD_FAB2(SCH_1):SVID_CLK_PVDDQ_KLM
  R1B8    2      B RES_0402-150.0,1%,1/16W,CHIP,GA    I19 @BASEBOARD_FAB2_LIB.BASEBOARD_FAB2(SCH_1):PAGE226
 EU1B1   15   VCLK PXM1310B_QFN-IC,H89186-001    I69 @BASEBOARD_FAB2_LIB.BASEBOARD_FAB2(SCH_1):PAGE226

SVID_DIO0_CPU0 @BASEBOARD_FAB2_LIB.BASEBOARD_FAB2(SCH_1):SVID_DIO0_CPU0
 R6N11    1      A RES_0402-0.0,5%,1/16W,CHIP,G21A   I151 @BASEBOARD_FAB2_LIB.BASEBOARD_FAB2(SCH_1):PAGE21
  U5D1 DB45 SVIDDATA<0> SKX_EXT_B_BGA1-IC,TBD   I259 @BASEBOARD_FAB2_LIB.BASEBOARD_FAB2(SCH_1):PAGE21

SVID_DIO0_CPU0_R @BASEBOARD_FAB2_LIB.BASEBOARD_FAB2(SCH_1):SVID_DIO0_CPU0_R
 R6N11    2      B RES_0402-0.0,5%,1/16W,CHIP,G21A   I151 @BASEBOARD_FAB2_LIB.BASEBOARD_FAB2(SCH_1):PAGE21
  R6N2    1      A RES_0402-100.0,1%,1/16W,CHIP,GA   I163 @BASEBOARD_FAB2_LIB.BASEBOARD_FAB2(SCH_1):PAGE21
  J6B1  B20  IOB20 SCONN120_H61426002_SM-CONN,H61A    I56 @BASEBOARD_FAB2_LIB.BASEBOARD_FAB2(SCH_1):PAGE194
 R4D66    2      B RES_0402-0.0,5%,1/16W,CHIP,G21A    I98 @BASEBOARD_FAB2_LIB.BASEBOARD_FAB2(SCH_1):PAGE201
 R3P11    1      A RES_0402-0.0,5%,1/16W,CHIP,G21A    I16 @BASEBOARD_FAB2_LIB.BASEBOARD_FAB2(SCH_1):PAGE211
 R4E10    2      B RES_0402-100.0,1%,1/16W,EMPTY,A   I190 @BASEBOARD_FAB2_LIB.BASEBOARD_FAB2(SCH_1):PAGE201
 R3P13    2      B RES_0402-100.0,1%,1/16W,CHIP,GA   I100 @BASEBOARD_FAB2_LIB.BASEBOARD_FAB2(SCH_1):PAGE211

SVID_DIO0_CPU1 @BASEBOARD_FAB2_LIB.BASEBOARD_FAB2(SCH_1):SVID_DIO0_CPU1
  R3B3    1      A RES_0402-0.0,5%,1/16W,CHIP,G21A    I29 @BASEBOARD_FAB2_LIB.BASEBOARD_FAB2(SCH_1):PAGE55
  U2D1 DB45 SVIDDATA<0> SKX_EXT_B_BGA1-IC,TBD   I172 @BASEBOARD_FAB2_LIB.BASEBOARD_FAB2(SCH_1):PAGE55

SVID_DIO0_CPU1_R @BASEBOARD_FAB2_LIB.BASEBOARD_FAB2(SCH_1):SVID_DIO0_CPU1_R
  R3B4    1      A RES_0402-100.0,1%,1/16W,CHIP,GA    I21 @BASEBOARD_FAB2_LIB.BASEBOARD_FAB2(SCH_1):PAGE55
  R3B3    2      B RES_0402-0.0,5%,1/16W,CHIP,G21A    I29 @BASEBOARD_FAB2_LIB.BASEBOARD_FAB2(SCH_1):PAGE55
  J4B2  B20  IOB20 SCONN120_H61426002_SM-CONN,H61A    I46 @BASEBOARD_FAB2_LIB.BASEBOARD_FAB2(SCH_1):PAGE193
  R9P1    2      B RES_0402-100.0,1%,1/16W,CHIP,GA     I4 @BASEBOARD_FAB2_LIB.BASEBOARD_FAB2(SCH_1):PAGE206
  R1D2    2      B RES_0402-0.0,5%,1/16W,CHIP,G21A    I38 @BASEBOARD_FAB2_LIB.BASEBOARD_FAB2(SCH_1):PAGE206
 R6P35    2      B RES_0402-100.0,1%,1/16W,EMPTY,A    I27 @BASEBOARD_FAB2_LIB.BASEBOARD_FAB2(SCH_1):PAGE213
 R4D54    1      A RES_0402-0.0,5%,1/16W,CHIP,G21A    I37 @BASEBOARD_FAB2_LIB.BASEBOARD_FAB2(SCH_1):PAGE213

SVID_DIO1_CPU0 @BASEBOARD_FAB2_LIB.BASEBOARD_FAB2(SCH_1):SVID_DIO1_CPU0
  R6B4    1      A RES_0402-0.0,5%,1/16W,CHIP,G21A   I154 @BASEBOARD_FAB2_LIB.BASEBOARD_FAB2(SCH_1):PAGE21
  U5D1 DJ44 SVIDDATA<1> SKX_EXT_B_BGA1-IC,TBD   I259 @BASEBOARD_FAB2_LIB.BASEBOARD_FAB2(SCH_1):PAGE21

SVID_DIO1_CPU0_R @BASEBOARD_FAB2_LIB.BASEBOARD_FAB2(SCH_1):SVID_DIO1_CPU0_R
  R6B4    2      B RES_0402-0.0,5%,1/16W,CHIP,G21A   I154 @BASEBOARD_FAB2_LIB.BASEBOARD_FAB2(SCH_1):PAGE21
  R6B2    2      B RES_0402-100.0,1%,1/16W,CHIP,GA   I159 @BASEBOARD_FAB2_LIB.BASEBOARD_FAB2(SCH_1):PAGE21
  J6B1  F20  IOF20 SCONN120_H61426002_SM-CONN,H61A    I56 @BASEBOARD_FAB2_LIB.BASEBOARD_FAB2(SCH_1):PAGE194
  R7G2    2      B RES_0402-0.0,5%,1/16W,CHIP,G21A    I41 @BASEBOARD_FAB2_LIB.BASEBOARD_FAB2(SCH_1):PAGE215
  R3U2    2      B RES_0402-100.0,1%,1/16W,CHIP,GA    I58 @BASEBOARD_FAB2_LIB.BASEBOARD_FAB2(SCH_1):PAGE215
 R7A12    2      B RES_0402-0.0,5%,1/16W,CHIP,G21A    I45 @BASEBOARD_FAB2_LIB.BASEBOARD_FAB2(SCH_1):PAGE218
 R3L11    2      B RES_0402-100.0,1%,1/16W,EMPTY,A    I67 @BASEBOARD_FAB2_LIB.BASEBOARD_FAB2(SCH_1):PAGE218

SVID_DIO1_CPU1 @BASEBOARD_FAB2_LIB.BASEBOARD_FAB2(SCH_1):SVID_DIO1_CPU1
  R1C2    1      A RES_0402-0.0,5%,1/16W,CHIP,G21A    I24 @BASEBOARD_FAB2_LIB.BASEBOARD_FAB2(SCH_1):PAGE55
  U2D1 DJ44 SVIDDATA<1> SKX_EXT_B_BGA1-IC,TBD   I172 @BASEBOARD_FAB2_LIB.BASEBOARD_FAB2(SCH_1):PAGE55

SVID_DIO1_CPU1_R @BASEBOARD_FAB2_LIB.BASEBOARD_FAB2(SCH_1):SVID_DIO1_CPU1_R
  R9N2    2      B RES_0402-100.0,1%,1/16W,CHIP,GA     I7 @BASEBOARD_FAB2_LIB.BASEBOARD_FAB2(SCH_1):PAGE55
  R1C2    2      B RES_0402-0.0,5%,1/16W,CHIP,G21A    I24 @BASEBOARD_FAB2_LIB.BASEBOARD_FAB2(SCH_1):PAGE55
  J4B2  F20  IOF20 SCONN120_H61426002_SM-CONN,H61A    I46 @BASEBOARD_FAB2_LIB.BASEBOARD_FAB2(SCH_1):PAGE193
  R9U3    2      B RES_0402-100.0,1%,1/16W,CHIP,GA    I57 @BASEBOARD_FAB2_LIB.BASEBOARD_FAB2(SCH_1):PAGE223
 R1G10    2      B RES_0402-0.0,5%,1/16W,CHIP,G21A    I41 @BASEBOARD_FAB2_LIB.BASEBOARD_FAB2(SCH_1):PAGE223
  R9M7    2      B RES_0402-100.0,1%,1/16W,EMPTY,A    I57 @BASEBOARD_FAB2_LIB.BASEBOARD_FAB2(SCH_1):PAGE226
 R1B10    2      B RES_0402-0.0,5%,1/16W,CHIP,G21A    I41 @BASEBOARD_FAB2_LIB.BASEBOARD_FAB2(SCH_1):PAGE226

SVID_VALERT_VCCIN_CPU0 @BASEBOARD_FAB2_LIB.BASEBOARD_FAB2(SCH_1):SVID_VALERT_VCCIN_CPU0
 R4D67    1      A RES_0402-0.0,5%,1/16W,CHIP,G21A    I26 @BASEBOARD_FAB2_LIB.BASEBOARD_FAB2(SCH_1):PAGE201
 EU4D4   19 VALRT_N PXE1610B_QFN-IC,H79206-001   I155 @BASEBOARD_FAB2_LIB.BASEBOARD_FAB2(SCH_1):PAGE201

SVID_VALERT_VCCIN_CPU1 @BASEBOARD_FAB2_LIB.BASEBOARD_FAB2(SCH_1):SVID_VALERT_VCCIN_CPU1
  R1D3    1      A RES_0402-0.0,5%,1/16W,CHIP,G21A    I37 @BASEBOARD_FAB2_LIB.BASEBOARD_FAB2(SCH_1):PAGE206
 EU1C2   19 VALRT_N PXE1610B_QFN-IC,H79206-001   I130 @BASEBOARD_FAB2_LIB.BASEBOARD_FAB2(SCH_1):PAGE206

SVID_VCLK_PVCCIN_CPU0 @BASEBOARD_FAB2_LIB.BASEBOARD_FAB2(SCH_1):SVID_VCLK_PVCCIN_CPU0
  R4E6    2      B RES_0402-150.0,1%,1/16W,CHIP,GA    I56 @BASEBOARD_FAB2_LIB.BASEBOARD_FAB2(SCH_1):PAGE201
 EU4D4   17   VCLK PXE1610B_QFN-IC,H79206-001   I155 @BASEBOARD_FAB2_LIB.BASEBOARD_FAB2(SCH_1):PAGE201

SVID_VCLK_PVCCIN_CPU1 @BASEBOARD_FAB2_LIB.BASEBOARD_FAB2(SCH_1):SVID_VCLK_PVCCIN_CPU1
  R1D9    2      B RES_0402-150.0,1%,1/16W,CHIP,GA    I54 @BASEBOARD_FAB2_LIB.BASEBOARD_FAB2(SCH_1):PAGE206
 EU1C2   17   VCLK PXE1610B_QFN-IC,H79206-001   I130 @BASEBOARD_FAB2_LIB.BASEBOARD_FAB2(SCH_1):PAGE206

SVID_VDIO_PVCCIN_CPU0 @BASEBOARD_FAB2_LIB.BASEBOARD_FAB2(SCH_1):SVID_VDIO_PVCCIN_CPU0
 R4D66    1      A RES_0402-0.0,5%,1/16W,CHIP,G21A    I98 @BASEBOARD_FAB2_LIB.BASEBOARD_FAB2(SCH_1):PAGE201
 EU4D4   18   VDIO PXE1610B_QFN-IC,H79206-001   I155 @BASEBOARD_FAB2_LIB.BASEBOARD_FAB2(SCH_1):PAGE201

SVID_VDIO_PVCCIN_CPU1 @BASEBOARD_FAB2_LIB.BASEBOARD_FAB2(SCH_1):SVID_VDIO_PVCCIN_CPU1
  R1D2    1      A RES_0402-0.0,5%,1/16W,CHIP,G21A    I38 @BASEBOARD_FAB2_LIB.BASEBOARD_FAB2(SCH_1):PAGE206
 EU1C2   18   VDIO PXE1610B_QFN-IC,H79206-001   I130 @BASEBOARD_FAB2_LIB.BASEBOARD_FAB2(SCH_1):PAGE206

SVID_VDIO_PVCCIO_CPU0 @BASEBOARD_FAB2_LIB.BASEBOARD_FAB2(SCH_1):SVID_VDIO_PVCCIO_CPU0
 R3P11    2      B RES_0402-0.0,5%,1/16W,CHIP,G21A    I16 @BASEBOARD_FAB2_LIB.BASEBOARD_FAB2(SCH_1):PAGE211
 EU3P1   16   VDIO PXE1110B_QFN-IC,H89187-001    I93 @BASEBOARD_FAB2_LIB.BASEBOARD_FAB2(SCH_1):PAGE211

SVID_VDIO_PVCCIO_CPU1 @BASEBOARD_FAB2_LIB.BASEBOARD_FAB2(SCH_1):SVID_VDIO_PVCCIO_CPU1
 R4D54    2      B RES_0402-0.0,5%,1/16W,CHIP,G21A    I37 @BASEBOARD_FAB2_LIB.BASEBOARD_FAB2(SCH_1):PAGE213
 EU4D5   16   VDIO PXE1110B_QFN-IC,H89187-001    I96 @BASEBOARD_FAB2_LIB.BASEBOARD_FAB2(SCH_1):PAGE213

SVID_VDIO_PVDDQ_ABC @BASEBOARD_FAB2_LIB.BASEBOARD_FAB2(SCH_1):SVID_VDIO_PVDDQ_ABC
  R7G2    1      A RES_0402-0.0,5%,1/16W,CHIP,G21A    I41 @BASEBOARD_FAB2_LIB.BASEBOARD_FAB2(SCH_1):PAGE215
 EU7G1   16   VDIO PXM1310B_QFN-IC,H89186-001    I69 @BASEBOARD_FAB2_LIB.BASEBOARD_FAB2(SCH_1):PAGE215

SVID_VDIO_PVDDQ_DEF @BASEBOARD_FAB2_LIB.BASEBOARD_FAB2(SCH_1):SVID_VDIO_PVDDQ_DEF
 R7A12    1      A RES_0402-0.0,5%,1/16W,CHIP,G21A    I45 @BASEBOARD_FAB2_LIB.BASEBOARD_FAB2(SCH_1):PAGE218
 EU7A5   16   VDIO PXM1310B_QFN-IC,H89186-001    I69 @BASEBOARD_FAB2_LIB.BASEBOARD_FAB2(SCH_1):PAGE218

SVID_VDIO_PVDDQ_GHJ @BASEBOARD_FAB2_LIB.BASEBOARD_FAB2(SCH_1):SVID_VDIO_PVDDQ_GHJ
 EU1G2   16   VDIO PXM1310B_QFN-IC,H89186-001    I69 @BASEBOARD_FAB2_LIB.BASEBOARD_FAB2(SCH_1):PAGE223
 R1G10    1      A RES_0402-0.0,5%,1/16W,CHIP,G21A    I41 @BASEBOARD_FAB2_LIB.BASEBOARD_FAB2(SCH_1):PAGE223

SVID_VDIO_PVDDQ_KLM @BASEBOARD_FAB2_LIB.BASEBOARD_FAB2(SCH_1):SVID_VDIO_PVDDQ_KLM
 EU1B1   16   VDIO PXM1310B_QFN-IC,H89186-001    I69 @BASEBOARD_FAB2_LIB.BASEBOARD_FAB2(SCH_1):PAGE226
 R1B10    1      A RES_0402-0.0,5%,1/16W,CHIP,G21A    I41 @BASEBOARD_FAB2_LIB.BASEBOARD_FAB2(SCH_1):PAGE226

TEMP_SENSOR_B @BASEBOARD_FAB2_LIB.BASEBOARD_FAB2(SCH_1):TEMP_SENSOR_B
  Q1D3    1      B NPN_SM-MMBT3904,IC,C52245-001    I58 @BASEBOARD_FAB2_LIB.BASEBOARD_FAB2(SCH_1):PAGE199
  Q1D3    3      C NPN_SM-MMBT3904,IC,C52245-001    I58 @BASEBOARD_FAB2_LIB.BASEBOARD_FAB2(SCH_1):PAGE199
 R1W20    2      B RES_0402-0.0,5%,1/16W,CHIP,G21A   I134 @BASEBOARD_FAB2_LIB.BASEBOARD_FAB2(SCH_1):PAGE199

TEMP_SENSOR_E @BASEBOARD_FAB2_LIB.BASEBOARD_FAB2(SCH_1):TEMP_SENSOR_E
  Q1D3    2      E NPN_SM-MMBT3904,IC,C52245-001    I58 @BASEBOARD_FAB2_LIB.BASEBOARD_FAB2(SCH_1):PAGE199
 R1W21    2      B RES_0402-0.0,5%,1/16W,CHIP,G21A   I135 @BASEBOARD_FAB2_LIB.BASEBOARD_FAB2(SCH_1):PAGE199

TPM_SPI_BMC_WP_N @BASEBOARD_FAB2_LIB.BASEBOARD_FAB2(SCH_1):TPM_SPI_BMC_WP_N
 UN8F2    9 WP_N_IO<2> W25Q256_XSOI-IC,H25002-001    I17 @BASEBOARD_FAB2_LIB.BASEBOARD_FAB2(SCH_1):PAGE246
 RN8F6    1      1 82KR2F-1-GP_SMD-RG-82KR2F-1-GPA    I19 @BASEBOARD_FAB2_LIB.BASEBOARD_FAB2(SCH_1):PAGE246
 RN8F2    2      B RES_0402-4.75K,1%,1/16W,EMPTY,A    I20 @BASEBOARD_FAB2_LIB.BASEBOARD_FAB2(SCH_1):PAGE246
R25W154    2      B RES_0402-0.0,5%,1/16W,CHIP,G21A   I133 @BASEBOARD_FAB2_LIB.BASEBOARD_FAB2(SCH_1):PAGE137

TP_10GBE_KR0_MON_DN @BASEBOARD_FAB2_LIB.BASEBOARD_FAB2(SCH_1):TP_10GBE_KR0_MON_DN
  U7C1 BL26 RSVD<39> LBG_CORE_QAT_EXT_D_BGA1-IC,H91A    I73 @BASEBOARD_FAB2_LIB.BASEBOARD_FAB2(SCH_1):PAGE118

TP_10GBE_KR0_MON_DP @BASEBOARD_FAB2_LIB.BASEBOARD_FAB2(SCH_1):TP_10GBE_KR0_MON_DP
  U7C1 BN26 RSVD<40> LBG_CORE_QAT_EXT_D_BGA1-IC,H91A    I73 @BASEBOARD_FAB2_LIB.BASEBOARD_FAB2(SCH_1):PAGE118

TP_10GBE_KR1_MON_DN @BASEBOARD_FAB2_LIB.BASEBOARD_FAB2(SCH_1):TP_10GBE_KR1_MON_DN
  U7C1 BL33 RSVD<43> LBG_CORE_QAT_EXT_D_BGA1-IC,H91A    I73 @BASEBOARD_FAB2_LIB.BASEBOARD_FAB2(SCH_1):PAGE118

TP_10GBE_KR1_MON_DP @BASEBOARD_FAB2_LIB.BASEBOARD_FAB2(SCH_1):TP_10GBE_KR1_MON_DP
  U7C1 BN33 RSVD<44> LBG_CORE_QAT_EXT_D_BGA1-IC,H91A    I73 @BASEBOARD_FAB2_LIB.BASEBOARD_FAB2(SCH_1):PAGE118

TP_BIOS_RECOVER_BOOT @BASEBOARD_FAB2_LIB.BASEBOARD_FAB2(SCH_1):TP_BIOS_RECOVER_BOOT
  J7G3    8    IO8 CONN12_C73564003_PIP-CONN,C735A   I174 @BASEBOARD_FAB2_LIB.BASEBOARD_FAB2(SCH_1):PAGE136

TP_BIOS_USB_RECOVERY @BASEBOARD_FAB2_LIB.BASEBOARD_FAB2(SCH_1):TP_BIOS_USB_RECOVERY
  J7G3    2    IO2 CONN12_C73564003_PIP-CONN,C735A   I174 @BASEBOARD_FAB2_LIB.BASEBOARD_FAB2(SCH_1):PAGE136

TP_BMC_GPIOA2 @BASEBOARD_FAB2_LIB.BASEBOARD_FAB2(SCH_1):TP_BMC_GPIOA2
 U25W4  D13 GPIOA2_TIMER3_SPI1CS1# AST2520A1-GP-GP_ASIC2-GB1-AST2A   I117 @BASEBOARD_FAB2_LIB.BASEBOARD_FAB2(SCH_1):PAGE145

TP_BMC_M_A15 @BASEBOARD_FAB2_LIB.BASEBOARD_FAB2(SCH_1):TP_BMC_M_A15
 U25W4  U15   MA15 AST2520A1-GP-GP_ASIC2-GB1-AST2A    I63 @BASEBOARD_FAB2_LIB.BASEBOARD_FAB2(SCH_1):PAGE143

TP_CD_HFI1_CPU1_I2CDAT @BASEBOARD_FAB2_LIB.BASEBOARD_FAB2(SCH_1):TP_CD_HFI1_CPU1_I2CDAT
  U2D1 BH23 CD_HFI1_I2CDAT SKX_EXT_B_BGA1-IC,TBD    I23 @BASEBOARD_FAB2_LIB.BASEBOARD_FAB2(SCH_1):PAGE63

TP_CD_HFI1_CPU1_I2CLK @BASEBOARD_FAB2_LIB.BASEBOARD_FAB2(SCH_1):TP_CD_HFI1_CPU1_I2CLK
  U2D1 BJ22 CD_HFI1_I2CCLK SKX_EXT_B_BGA1-IC,TBD    I23 @BASEBOARD_FAB2_LIB.BASEBOARD_FAB2(SCH_1):PAGE63

TP_CD_HFI1_CPU1_INT_N @BASEBOARD_FAB2_LIB.BASEBOARD_FAB2(SCH_1):TP_CD_HFI1_CPU1_INT_N
  U2D1 BM21 CD_HFI1_INT_N SKX_EXT_B_BGA1-IC,TBD    I23 @BASEBOARD_FAB2_LIB.BASEBOARD_FAB2(SCH_1):PAGE63

TP_CD_HFI1_CPU1_LED_N @BASEBOARD_FAB2_LIB.BASEBOARD_FAB2(SCH_1):TP_CD_HFI1_CPU1_LED_N
  U2D1 BM23 CD_HFI1_LED_N SKX_EXT_B_BGA1-IC,TBD    I23 @BASEBOARD_FAB2_LIB.BASEBOARD_FAB2(SCH_1):PAGE63

TP_CD_HFI1_CPU1_MODPRST_N @BASEBOARD_FAB2_LIB.BASEBOARD_FAB2(SCH_1):TP_CD_HFI1_CPU1_MODPRST_N
  U2D1 BT19 CD_HFI1_MODPRST_N SKX_EXT_B_BGA1-IC,TBD    I23 @BASEBOARD_FAB2_LIB.BASEBOARD_FAB2(SCH_1):PAGE63

TP_CD_HFI1_CPU1_RESET_N @BASEBOARD_FAB2_LIB.BASEBOARD_FAB2(SCH_1):TP_CD_HFI1_CPU1_RESET_N
  U2D1 BK23 CD_HFI1_RESET_N SKX_EXT_B_BGA1-IC,TBD    I23 @BASEBOARD_FAB2_LIB.BASEBOARD_FAB2(SCH_1):PAGE63

TP_CH_A_DIMM_A0_RFU_0 @BASEBOARD_FAB2_LIB.BASEBOARD_FAB2(SCH_1):TP_CH_A_DIMM_A0_RFU_0
  J4G1  205 RFU<0> SCONN288_H44441004_PIP-SCONN,HA     I1 @BASEBOARD_FAB2_LIB.BASEBOARD_FAB2(SCH_1):PAGE43

TP_CH_A_DIMM_A0_RFU_1 @BASEBOARD_FAB2_LIB.BASEBOARD_FAB2(SCH_1):TP_CH_A_DIMM_A0_RFU_1
  J4G1  227 RFU<1> SCONN288_H44441004_PIP-SCONN,HA     I1 @BASEBOARD_FAB2_LIB.BASEBOARD_FAB2(SCH_1):PAGE43

TP_CH_A_DIMM_A0_RFU_2 @BASEBOARD_FAB2_LIB.BASEBOARD_FAB2(SCH_1):TP_CH_A_DIMM_A0_RFU_2
  J4G1  144 RFU<2> SCONN288_H44441004_PIP-SCONN,HA     I1 @BASEBOARD_FAB2_LIB.BASEBOARD_FAB2(SCH_1):PAGE43

TP_CH_A_DIMM_A1_RFU_0 @BASEBOARD_FAB2_LIB.BASEBOARD_FAB2(SCH_1):TP_CH_A_DIMM_A1_RFU_0
  J6T1  205 RFU<0> SCONN288_H44441003_PIP-SCONN,HA    I13 @BASEBOARD_FAB2_LIB.BASEBOARD_FAB2(SCH_1):PAGE44

TP_CH_A_DIMM_A1_RFU_1 @BASEBOARD_FAB2_LIB.BASEBOARD_FAB2(SCH_1):TP_CH_A_DIMM_A1_RFU_1
  J6T1  227 RFU<1> SCONN288_H44441003_PIP-SCONN,HA    I13 @BASEBOARD_FAB2_LIB.BASEBOARD_FAB2(SCH_1):PAGE44

TP_CH_A_DIMM_A1_RFU_2 @BASEBOARD_FAB2_LIB.BASEBOARD_FAB2(SCH_1):TP_CH_A_DIMM_A1_RFU_2
  J6T1  144 RFU<2> SCONN288_H44441003_PIP-SCONN,HA    I13 @BASEBOARD_FAB2_LIB.BASEBOARD_FAB2(SCH_1):PAGE44

TP_CH_B_DIMM_B0_RFU_0 @BASEBOARD_FAB2_LIB.BASEBOARD_FAB2(SCH_1):TP_CH_B_DIMM_B0_RFU_0
  J4G2  205 RFU<0> SCONN288_H44441004_PIP-SCONN,HA   I111 @BASEBOARD_FAB2_LIB.BASEBOARD_FAB2(SCH_1):PAGE45

TP_CH_B_DIMM_B0_RFU_1 @BASEBOARD_FAB2_LIB.BASEBOARD_FAB2(SCH_1):TP_CH_B_DIMM_B0_RFU_1
  J4G2  227 RFU<1> SCONN288_H44441004_PIP-SCONN,HA   I111 @BASEBOARD_FAB2_LIB.BASEBOARD_FAB2(SCH_1):PAGE45

TP_CH_B_DIMM_B0_RFU_2 @BASEBOARD_FAB2_LIB.BASEBOARD_FAB2(SCH_1):TP_CH_B_DIMM_B0_RFU_2
  J4G2  144 RFU<2> SCONN288_H44441004_PIP-SCONN,HA   I111 @BASEBOARD_FAB2_LIB.BASEBOARD_FAB2(SCH_1):PAGE45

TP_CH_B_DIMM_B1_RFU_0 @BASEBOARD_FAB2_LIB.BASEBOARD_FAB2(SCH_1):TP_CH_B_DIMM_B1_RFU_0
  J6U1  205 RFU<0> SCONN288_H44441003_PIP-SCONN,HA    I14 @BASEBOARD_FAB2_LIB.BASEBOARD_FAB2(SCH_1):PAGE46

TP_CH_B_DIMM_B1_RFU_1 @BASEBOARD_FAB2_LIB.BASEBOARD_FAB2(SCH_1):TP_CH_B_DIMM_B1_RFU_1
  J6U1  227 RFU<1> SCONN288_H44441003_PIP-SCONN,HA    I14 @BASEBOARD_FAB2_LIB.BASEBOARD_FAB2(SCH_1):PAGE46

TP_CH_B_DIMM_B1_RFU_2 @BASEBOARD_FAB2_LIB.BASEBOARD_FAB2(SCH_1):TP_CH_B_DIMM_B1_RFU_2
  J6U1  144 RFU<2> SCONN288_H44441003_PIP-SCONN,HA    I14 @BASEBOARD_FAB2_LIB.BASEBOARD_FAB2(SCH_1):PAGE46

TP_CH_C_DIMM_C0_RFU_0 @BASEBOARD_FAB2_LIB.BASEBOARD_FAB2(SCH_1):TP_CH_C_DIMM_C0_RFU_0
  J4G3  205 RFU<0> SCONN288_H44441004_PIP-SCONN,HA   I111 @BASEBOARD_FAB2_LIB.BASEBOARD_FAB2(SCH_1):PAGE47

TP_CH_C_DIMM_C0_RFU_1 @BASEBOARD_FAB2_LIB.BASEBOARD_FAB2(SCH_1):TP_CH_C_DIMM_C0_RFU_1
  J4G3  227 RFU<1> SCONN288_H44441004_PIP-SCONN,HA   I111 @BASEBOARD_FAB2_LIB.BASEBOARD_FAB2(SCH_1):PAGE47

TP_CH_C_DIMM_C0_RFU_2 @BASEBOARD_FAB2_LIB.BASEBOARD_FAB2(SCH_1):TP_CH_C_DIMM_C0_RFU_2
  J4G3  144 RFU<2> SCONN288_H44441004_PIP-SCONN,HA   I111 @BASEBOARD_FAB2_LIB.BASEBOARD_FAB2(SCH_1):PAGE47

TP_CH_C_DIMM_C1_RFU_0 @BASEBOARD_FAB2_LIB.BASEBOARD_FAB2(SCH_1):TP_CH_C_DIMM_C1_RFU_0
  J6U2  205 RFU<0> SCONN288_H44441003_PIP-SCONN,HA   I111 @BASEBOARD_FAB2_LIB.BASEBOARD_FAB2(SCH_1):PAGE48

TP_CH_C_DIMM_C1_RFU_1 @BASEBOARD_FAB2_LIB.BASEBOARD_FAB2(SCH_1):TP_CH_C_DIMM_C1_RFU_1
  J6U2  227 RFU<1> SCONN288_H44441003_PIP-SCONN,HA   I111 @BASEBOARD_FAB2_LIB.BASEBOARD_FAB2(SCH_1):PAGE48

TP_CH_C_DIMM_C1_RFU_2 @BASEBOARD_FAB2_LIB.BASEBOARD_FAB2(SCH_1):TP_CH_C_DIMM_C1_RFU_2
  J6U2  144 RFU<2> SCONN288_H44441003_PIP-SCONN,HA   I111 @BASEBOARD_FAB2_LIB.BASEBOARD_FAB2(SCH_1):PAGE48

TP_CH_D_DIMM_D0_RFU_0 @BASEBOARD_FAB2_LIB.BASEBOARD_FAB2(SCH_1):TP_CH_D_DIMM_D0_RFU_0
  J4B1  205 RFU<0> SCONN288_H44441004_PIP-SCONN,HA   I111 @BASEBOARD_FAB2_LIB.BASEBOARD_FAB2(SCH_1):PAGE49

TP_CH_D_DIMM_D0_RFU_1 @BASEBOARD_FAB2_LIB.BASEBOARD_FAB2(SCH_1):TP_CH_D_DIMM_D0_RFU_1
  J4B1  227 RFU<1> SCONN288_H44441004_PIP-SCONN,HA   I111 @BASEBOARD_FAB2_LIB.BASEBOARD_FAB2(SCH_1):PAGE49

TP_CH_D_DIMM_D0_RFU_2 @BASEBOARD_FAB2_LIB.BASEBOARD_FAB2(SCH_1):TP_CH_D_DIMM_D0_RFU_2
  J4B1  144 RFU<2> SCONN288_H44441004_PIP-SCONN,HA   I111 @BASEBOARD_FAB2_LIB.BASEBOARD_FAB2(SCH_1):PAGE49

TP_CH_D_DIMM_D1_RFU_0 @BASEBOARD_FAB2_LIB.BASEBOARD_FAB2(SCH_1):TP_CH_D_DIMM_D1_RFU_0
  J6M1  205 RFU<0> SCONN288_H44441003_PIP-SCONN,HA   I158 @BASEBOARD_FAB2_LIB.BASEBOARD_FAB2(SCH_1):PAGE50

TP_CH_D_DIMM_D1_RFU_1 @BASEBOARD_FAB2_LIB.BASEBOARD_FAB2(SCH_1):TP_CH_D_DIMM_D1_RFU_1
  J6M1  227 RFU<1> SCONN288_H44441003_PIP-SCONN,HA   I158 @BASEBOARD_FAB2_LIB.BASEBOARD_FAB2(SCH_1):PAGE50

TP_CH_D_DIMM_D1_RFU_2 @BASEBOARD_FAB2_LIB.BASEBOARD_FAB2(SCH_1):TP_CH_D_DIMM_D1_RFU_2
  J6M1  144 RFU<2> SCONN288_H44441003_PIP-SCONN,HA   I158 @BASEBOARD_FAB2_LIB.BASEBOARD_FAB2(SCH_1):PAGE50

TP_CH_E_DIMM_E0_RFU_0 @BASEBOARD_FAB2_LIB.BASEBOARD_FAB2(SCH_1):TP_CH_E_DIMM_E0_RFU_0
  J4A2  205 RFU<0> SCONN288_H44441004_PIP-SCONN,HA   I111 @BASEBOARD_FAB2_LIB.BASEBOARD_FAB2(SCH_1):PAGE51

TP_CH_E_DIMM_E0_RFU_1 @BASEBOARD_FAB2_LIB.BASEBOARD_FAB2(SCH_1):TP_CH_E_DIMM_E0_RFU_1
  J4A2  227 RFU<1> SCONN288_H44441004_PIP-SCONN,HA   I111 @BASEBOARD_FAB2_LIB.BASEBOARD_FAB2(SCH_1):PAGE51

TP_CH_E_DIMM_E0_RFU_2 @BASEBOARD_FAB2_LIB.BASEBOARD_FAB2(SCH_1):TP_CH_E_DIMM_E0_RFU_2
  J4A2  144 RFU<2> SCONN288_H44441004_PIP-SCONN,HA   I111 @BASEBOARD_FAB2_LIB.BASEBOARD_FAB2(SCH_1):PAGE51

TP_CH_E_DIMM_E1_RFU_0 @BASEBOARD_FAB2_LIB.BASEBOARD_FAB2(SCH_1):TP_CH_E_DIMM_E1_RFU_0
  J6L2  205 RFU<0> SCONN288_H44441003_PIP-SCONN,HA    I12 @BASEBOARD_FAB2_LIB.BASEBOARD_FAB2(SCH_1):PAGE52

TP_CH_E_DIMM_E1_RFU_1 @BASEBOARD_FAB2_LIB.BASEBOARD_FAB2(SCH_1):TP_CH_E_DIMM_E1_RFU_1
  J6L2  227 RFU<1> SCONN288_H44441003_PIP-SCONN,HA    I12 @BASEBOARD_FAB2_LIB.BASEBOARD_FAB2(SCH_1):PAGE52

TP_CH_E_DIMM_E1_RFU_2 @BASEBOARD_FAB2_LIB.BASEBOARD_FAB2(SCH_1):TP_CH_E_DIMM_E1_RFU_2
  J6L2  144 RFU<2> SCONN288_H44441003_PIP-SCONN,HA    I12 @BASEBOARD_FAB2_LIB.BASEBOARD_FAB2(SCH_1):PAGE52

TP_CH_F_DIMM_F0_RFU_0 @BASEBOARD_FAB2_LIB.BASEBOARD_FAB2(SCH_1):TP_CH_F_DIMM_F0_RFU_0
  J4A1  205 RFU<0> SCONN288_H44441004_PIP-SCONN,HA   I111 @BASEBOARD_FAB2_LIB.BASEBOARD_FAB2(SCH_1):PAGE53

TP_CH_F_DIMM_F0_RFU_1 @BASEBOARD_FAB2_LIB.BASEBOARD_FAB2(SCH_1):TP_CH_F_DIMM_F0_RFU_1
  J4A1  227 RFU<1> SCONN288_H44441004_PIP-SCONN,HA   I111 @BASEBOARD_FAB2_LIB.BASEBOARD_FAB2(SCH_1):PAGE53

TP_CH_F_DIMM_F0_RFU_2 @BASEBOARD_FAB2_LIB.BASEBOARD_FAB2(SCH_1):TP_CH_F_DIMM_F0_RFU_2
  J4A1  144 RFU<2> SCONN288_H44441004_PIP-SCONN,HA   I111 @BASEBOARD_FAB2_LIB.BASEBOARD_FAB2(SCH_1):PAGE53

TP_CH_F_DIMM_F1_RFU_0 @BASEBOARD_FAB2_LIB.BASEBOARD_FAB2(SCH_1):TP_CH_F_DIMM_F1_RFU_0
  J6L1  205 RFU<0> SCONN288_H44441003_PIP-SCONN,HA   I111 @BASEBOARD_FAB2_LIB.BASEBOARD_FAB2(SCH_1):PAGE54

TP_CH_F_DIMM_F1_RFU_1 @BASEBOARD_FAB2_LIB.BASEBOARD_FAB2(SCH_1):TP_CH_F_DIMM_F1_RFU_1
  J6L1  227 RFU<1> SCONN288_H44441003_PIP-SCONN,HA   I111 @BASEBOARD_FAB2_LIB.BASEBOARD_FAB2(SCH_1):PAGE54

TP_CH_F_DIMM_F1_RFU_2 @BASEBOARD_FAB2_LIB.BASEBOARD_FAB2(SCH_1):TP_CH_F_DIMM_F1_RFU_2
  J6L1  144 RFU<2> SCONN288_H44441003_PIP-SCONN,HA   I111 @BASEBOARD_FAB2_LIB.BASEBOARD_FAB2(SCH_1):PAGE54

TP_CH_G_DIMM0_RFU_0 @BASEBOARD_FAB2_LIB.BASEBOARD_FAB2(SCH_1):TP_CH_G_DIMM0_RFU_0
  J9T1  205 RFU<0> SCONN288_H44441003_PIP-SCONN,HA    I13 @BASEBOARD_FAB2_LIB.BASEBOARD_FAB2(SCH_1):PAGE78

TP_CH_G_DIMM0_RFU_1 @BASEBOARD_FAB2_LIB.BASEBOARD_FAB2(SCH_1):TP_CH_G_DIMM0_RFU_1
  J9T1  227 RFU<1> SCONN288_H44441003_PIP-SCONN,HA    I13 @BASEBOARD_FAB2_LIB.BASEBOARD_FAB2(SCH_1):PAGE78

TP_CH_G_DIMM0_RFU_2 @BASEBOARD_FAB2_LIB.BASEBOARD_FAB2(SCH_1):TP_CH_G_DIMM0_RFU_2
  J9T1  144 RFU<2> SCONN288_H44441003_PIP-SCONN,HA    I13 @BASEBOARD_FAB2_LIB.BASEBOARD_FAB2(SCH_1):PAGE78

TP_CH_G_DIMM_G0_RFU_0 @BASEBOARD_FAB2_LIB.BASEBOARD_FAB2(SCH_1):TP_CH_G_DIMM_G0_RFU_0
  J1G1  205 RFU<0> SCONN288_H44441004_PIP-SCONN,HA   I111 @BASEBOARD_FAB2_LIB.BASEBOARD_FAB2(SCH_1):PAGE77

TP_CH_G_DIMM_G0_RFU_1 @BASEBOARD_FAB2_LIB.BASEBOARD_FAB2(SCH_1):TP_CH_G_DIMM_G0_RFU_1
  J1G1  227 RFU<1> SCONN288_H44441004_PIP-SCONN,HA   I111 @BASEBOARD_FAB2_LIB.BASEBOARD_FAB2(SCH_1):PAGE77

TP_CH_G_DIMM_G0_RFU_2 @BASEBOARD_FAB2_LIB.BASEBOARD_FAB2(SCH_1):TP_CH_G_DIMM_G0_RFU_2
  J1G1  144 RFU<2> SCONN288_H44441004_PIP-SCONN,HA   I111 @BASEBOARD_FAB2_LIB.BASEBOARD_FAB2(SCH_1):PAGE77

TP_CH_H_DIMM0_RFU_0 @BASEBOARD_FAB2_LIB.BASEBOARD_FAB2(SCH_1):TP_CH_H_DIMM0_RFU_0
  J9U1  205 RFU<0> SCONN288_H44441003_PIP-SCONN,HA    I24 @BASEBOARD_FAB2_LIB.BASEBOARD_FAB2(SCH_1):PAGE80

TP_CH_H_DIMM0_RFU_1 @BASEBOARD_FAB2_LIB.BASEBOARD_FAB2(SCH_1):TP_CH_H_DIMM0_RFU_1
  J9U1  227 RFU<1> SCONN288_H44441003_PIP-SCONN,HA    I24 @BASEBOARD_FAB2_LIB.BASEBOARD_FAB2(SCH_1):PAGE80

TP_CH_H_DIMM0_RFU_2 @BASEBOARD_FAB2_LIB.BASEBOARD_FAB2(SCH_1):TP_CH_H_DIMM0_RFU_2
  J9U1  144 RFU<2> SCONN288_H44441003_PIP-SCONN,HA    I24 @BASEBOARD_FAB2_LIB.BASEBOARD_FAB2(SCH_1):PAGE80

TP_CH_H_DIMM_H0_RFU_0 @BASEBOARD_FAB2_LIB.BASEBOARD_FAB2(SCH_1):TP_CH_H_DIMM_H0_RFU_0
  J1G2  205 RFU<0> SCONN288_H44441004_PIP-SCONN,HA   I111 @BASEBOARD_FAB2_LIB.BASEBOARD_FAB2(SCH_1):PAGE79

TP_CH_H_DIMM_H0_RFU_1 @BASEBOARD_FAB2_LIB.BASEBOARD_FAB2(SCH_1):TP_CH_H_DIMM_H0_RFU_1
  J1G2  227 RFU<1> SCONN288_H44441004_PIP-SCONN,HA   I111 @BASEBOARD_FAB2_LIB.BASEBOARD_FAB2(SCH_1):PAGE79

TP_CH_H_DIMM_H0_RFU_2 @BASEBOARD_FAB2_LIB.BASEBOARD_FAB2(SCH_1):TP_CH_H_DIMM_H0_RFU_2
  J1G2  144 RFU<2> SCONN288_H44441004_PIP-SCONN,HA   I111 @BASEBOARD_FAB2_LIB.BASEBOARD_FAB2(SCH_1):PAGE79

TP_CH_J_DIMM_J0_RFU_0 @BASEBOARD_FAB2_LIB.BASEBOARD_FAB2(SCH_1):TP_CH_J_DIMM_J0_RFU_0
  J1G3  205 RFU<0> SCONN288_H44441004_PIP-SCONN,HA   I186 @BASEBOARD_FAB2_LIB.BASEBOARD_FAB2(SCH_1):PAGE81

TP_CH_J_DIMM_J0_RFU_1 @BASEBOARD_FAB2_LIB.BASEBOARD_FAB2(SCH_1):TP_CH_J_DIMM_J0_RFU_1
  J1G3  227 RFU<1> SCONN288_H44441004_PIP-SCONN,HA   I186 @BASEBOARD_FAB2_LIB.BASEBOARD_FAB2(SCH_1):PAGE81

TP_CH_J_DIMM_J0_RFU_2 @BASEBOARD_FAB2_LIB.BASEBOARD_FAB2(SCH_1):TP_CH_J_DIMM_J0_RFU_2
  J1G3  144 RFU<2> SCONN288_H44441004_PIP-SCONN,HA   I186 @BASEBOARD_FAB2_LIB.BASEBOARD_FAB2(SCH_1):PAGE81

TP_CH_J_DIMM_J1_RFU_0 @BASEBOARD_FAB2_LIB.BASEBOARD_FAB2(SCH_1):TP_CH_J_DIMM_J1_RFU_0
  J9U2  205 RFU<0> SCONN288_H44441003_PIP-SCONN,HA   I187 @BASEBOARD_FAB2_LIB.BASEBOARD_FAB2(SCH_1):PAGE82

TP_CH_J_DIMM_J1_RFU_1 @BASEBOARD_FAB2_LIB.BASEBOARD_FAB2(SCH_1):TP_CH_J_DIMM_J1_RFU_1
  J9U2  227 RFU<1> SCONN288_H44441003_PIP-SCONN,HA   I187 @BASEBOARD_FAB2_LIB.BASEBOARD_FAB2(SCH_1):PAGE82

TP_CH_J_DIMM_J1_RFU_2 @BASEBOARD_FAB2_LIB.BASEBOARD_FAB2(SCH_1):TP_CH_J_DIMM_J1_RFU_2
  J9U2  144 RFU<2> SCONN288_H44441003_PIP-SCONN,HA   I187 @BASEBOARD_FAB2_LIB.BASEBOARD_FAB2(SCH_1):PAGE82

TP_CH_K_DIMM0_RFU_0 @BASEBOARD_FAB2_LIB.BASEBOARD_FAB2(SCH_1):TP_CH_K_DIMM0_RFU_0
  J9M1  205 RFU<0> SCONN288_H44441003_PIP-SCONN,HA    I14 @BASEBOARD_FAB2_LIB.BASEBOARD_FAB2(SCH_1):PAGE84

TP_CH_K_DIMM0_RFU_1 @BASEBOARD_FAB2_LIB.BASEBOARD_FAB2(SCH_1):TP_CH_K_DIMM0_RFU_1
  J9M1  227 RFU<1> SCONN288_H44441003_PIP-SCONN,HA    I14 @BASEBOARD_FAB2_LIB.BASEBOARD_FAB2(SCH_1):PAGE84

TP_CH_K_DIMM0_RFU_2 @BASEBOARD_FAB2_LIB.BASEBOARD_FAB2(SCH_1):TP_CH_K_DIMM0_RFU_2
  J9M1  144 RFU<2> SCONN288_H44441003_PIP-SCONN,HA    I14 @BASEBOARD_FAB2_LIB.BASEBOARD_FAB2(SCH_1):PAGE84

TP_CH_K_DIMM_K0_RFU_0 @BASEBOARD_FAB2_LIB.BASEBOARD_FAB2(SCH_1):TP_CH_K_DIMM_K0_RFU_0
  J1B1  205 RFU<0> SCONN288_H44441004_PIP-SCONN,HA   I111 @BASEBOARD_FAB2_LIB.BASEBOARD_FAB2(SCH_1):PAGE83

TP_CH_K_DIMM_K0_RFU_1 @BASEBOARD_FAB2_LIB.BASEBOARD_FAB2(SCH_1):TP_CH_K_DIMM_K0_RFU_1
  J1B1  227 RFU<1> SCONN288_H44441004_PIP-SCONN,HA   I111 @BASEBOARD_FAB2_LIB.BASEBOARD_FAB2(SCH_1):PAGE83

TP_CH_K_DIMM_K0_RFU_2 @BASEBOARD_FAB2_LIB.BASEBOARD_FAB2(SCH_1):TP_CH_K_DIMM_K0_RFU_2
  J1B1  144 RFU<2> SCONN288_H44441004_PIP-SCONN,HA   I111 @BASEBOARD_FAB2_LIB.BASEBOARD_FAB2(SCH_1):PAGE83

TP_CH_L_DIMM0_RFU_0 @BASEBOARD_FAB2_LIB.BASEBOARD_FAB2(SCH_1):TP_CH_L_DIMM0_RFU_0
  J9L2  205 RFU<0> SCONN288_H44441003_PIP-SCONN,HA    I12 @BASEBOARD_FAB2_LIB.BASEBOARD_FAB2(SCH_1):PAGE86

TP_CH_L_DIMM0_RFU_1 @BASEBOARD_FAB2_LIB.BASEBOARD_FAB2(SCH_1):TP_CH_L_DIMM0_RFU_1
  J9L2  227 RFU<1> SCONN288_H44441003_PIP-SCONN,HA    I12 @BASEBOARD_FAB2_LIB.BASEBOARD_FAB2(SCH_1):PAGE86

TP_CH_L_DIMM0_RFU_2 @BASEBOARD_FAB2_LIB.BASEBOARD_FAB2(SCH_1):TP_CH_L_DIMM0_RFU_2
  J9L2  144 RFU<2> SCONN288_H44441003_PIP-SCONN,HA    I12 @BASEBOARD_FAB2_LIB.BASEBOARD_FAB2(SCH_1):PAGE86

TP_CH_L_DIMM_L0_RFU_0 @BASEBOARD_FAB2_LIB.BASEBOARD_FAB2(SCH_1):TP_CH_L_DIMM_L0_RFU_0
  J1A2  205 RFU<0> SCONN288_H44441004_PIP-SCONN,HA   I111 @BASEBOARD_FAB2_LIB.BASEBOARD_FAB2(SCH_1):PAGE85

TP_CH_L_DIMM_L0_RFU_1 @BASEBOARD_FAB2_LIB.BASEBOARD_FAB2(SCH_1):TP_CH_L_DIMM_L0_RFU_1
  J1A2  227 RFU<1> SCONN288_H44441004_PIP-SCONN,HA   I111 @BASEBOARD_FAB2_LIB.BASEBOARD_FAB2(SCH_1):PAGE85

TP_CH_L_DIMM_L0_RFU_2 @BASEBOARD_FAB2_LIB.BASEBOARD_FAB2(SCH_1):TP_CH_L_DIMM_L0_RFU_2
  J1A2  144 RFU<2> SCONN288_H44441004_PIP-SCONN,HA   I111 @BASEBOARD_FAB2_LIB.BASEBOARD_FAB2(SCH_1):PAGE85

TP_CH_M_DIMM_M0_RFU_0 @BASEBOARD_FAB2_LIB.BASEBOARD_FAB2(SCH_1):TP_CH_M_DIMM_M0_RFU_0
  J1A1  205 RFU<0> SCONN288_H44441004_PIP-SCONN,HA   I186 @BASEBOARD_FAB2_LIB.BASEBOARD_FAB2(SCH_1):PAGE87

TP_CH_M_DIMM_M0_RFU_1 @BASEBOARD_FAB2_LIB.BASEBOARD_FAB2(SCH_1):TP_CH_M_DIMM_M0_RFU_1
  J1A1  227 RFU<1> SCONN288_H44441004_PIP-SCONN,HA   I186 @BASEBOARD_FAB2_LIB.BASEBOARD_FAB2(SCH_1):PAGE87

TP_CH_M_DIMM_M0_RFU_2 @BASEBOARD_FAB2_LIB.BASEBOARD_FAB2(SCH_1):TP_CH_M_DIMM_M0_RFU_2
  J1A1  144 RFU<2> SCONN288_H44441004_PIP-SCONN,HA   I186 @BASEBOARD_FAB2_LIB.BASEBOARD_FAB2(SCH_1):PAGE87

TP_CH_M_DIMM_M1_RFU_0 @BASEBOARD_FAB2_LIB.BASEBOARD_FAB2(SCH_1):TP_CH_M_DIMM_M1_RFU_0
  J9L1  205 RFU<0> SCONN288_H44441003_PIP-SCONN,HA   I111 @BASEBOARD_FAB2_LIB.BASEBOARD_FAB2(SCH_1):PAGE88

TP_CH_M_DIMM_M1_RFU_1 @BASEBOARD_FAB2_LIB.BASEBOARD_FAB2(SCH_1):TP_CH_M_DIMM_M1_RFU_1
  J9L1  227 RFU<1> SCONN288_H44441003_PIP-SCONN,HA   I111 @BASEBOARD_FAB2_LIB.BASEBOARD_FAB2(SCH_1):PAGE88

TP_CH_M_DIMM_M1_RFU_2 @BASEBOARD_FAB2_LIB.BASEBOARD_FAB2(SCH_1):TP_CH_M_DIMM_M1_RFU_2
  J9L1  144 RFU<2> SCONN288_H44441003_PIP-SCONN,HA   I111 @BASEBOARD_FAB2_LIB.BASEBOARD_FAB2(SCH_1):PAGE88

TP_CLK5_50M_CKMNG @BASEBOARD_FAB2_LIB.BASEBOARD_FAB2(SCH_1):TP_CLK5_50M_CKMNG
 EU8F2   24 RMII<5> ICS9FGP204_MLFP-IC,E95226-001    I34 @BASEBOARD_FAB2_LIB.BASEBOARD_FAB2(SCH_1):PAGE101

TP_CLK_100M_NSSCC0_DN @BASEBOARD_FAB2_LIB.BASEBOARD_FAB2(SCH_1):TP_CLK_100M_NSSCC0_DN
  U7C1  A32 CLKOUT_NSSCCAP0N LBG_CORE_QAT_EXT_D_BGA1-IC,H91A    I40 @BASEBOARD_FAB2_LIB.BASEBOARD_FAB2(SCH_1):PAGE114

TP_CLK_100M_NSSCC0_DP @BASEBOARD_FAB2_LIB.BASEBOARD_FAB2(SCH_1):TP_CLK_100M_NSSCC0_DP
  U7C1  C32 CLKOUT_NSSCCAP0P LBG_CORE_QAT_EXT_D_BGA1-IC,H91A    I40 @BASEBOARD_FAB2_LIB.BASEBOARD_FAB2(SCH_1):PAGE114

TP_CLK_100M_NSSCC1_DN @BASEBOARD_FAB2_LIB.BASEBOARD_FAB2(SCH_1):TP_CLK_100M_NSSCC1_DN
  U7C1  B38 CLKOUT_NSSCCAP1N LBG_CORE_QAT_EXT_D_BGA1-IC,H91A    I40 @BASEBOARD_FAB2_LIB.BASEBOARD_FAB2(SCH_1):PAGE114

TP_CLK_100M_NSSCC1_DP @BASEBOARD_FAB2_LIB.BASEBOARD_FAB2(SCH_1):TP_CLK_100M_NSSCC1_DP
  U7C1  D38 CLKOUT_NSSCCAP1P LBG_CORE_QAT_EXT_D_BGA1-IC,H91A    I40 @BASEBOARD_FAB2_LIB.BASEBOARD_FAB2(SCH_1):PAGE114

TP_CLK_100M_PLAT1_DN @BASEBOARD_FAB2_LIB.BASEBOARD_FAB2(SCH_1):TP_CLK_100M_PLAT1_DN
  U7C1  B40 CLKOUT_PLAT1N LBG_CORE_QAT_EXT_D_BGA1-IC,H91A    I40 @BASEBOARD_FAB2_LIB.BASEBOARD_FAB2(SCH_1):PAGE114

TP_CLK_100M_PLAT1_DP @BASEBOARD_FAB2_LIB.BASEBOARD_FAB2(SCH_1):TP_CLK_100M_PLAT1_DP
  U7C1  D40 CLKOUT_PLAT1P LBG_CORE_QAT_EXT_D_BGA1-IC,H91A    I40 @BASEBOARD_FAB2_LIB.BASEBOARD_FAB2(SCH_1):PAGE114

TP_CLK_100M_R_DN @BASEBOARD_FAB2_LIB.BASEBOARD_FAB2(SCH_1):TP_CLK_100M_R_DN
 EU8F2    8 CPUCLKC0 ICS9FGP204_MLFP-IC,E95226-001    I34 @BASEBOARD_FAB2_LIB.BASEBOARD_FAB2(SCH_1):PAGE101

TP_CLK_100M_R_DP @BASEBOARD_FAB2_LIB.BASEBOARD_FAB2(SCH_1):TP_CLK_100M_R_DP
 EU8F2    7 CPUCLKT0 ICS9FGP204_MLFP-IC,E95226-001    I34 @BASEBOARD_FAB2_LIB.BASEBOARD_FAB2(SCH_1):PAGE101

TP_CLK_125M @BASEBOARD_FAB2_LIB.BASEBOARD_FAB2(SCH_1):TP_CLK_125M
 EU8F2   36 RGMII<1> ICS9FGP204_MLFP-IC,E95226-001    I34 @BASEBOARD_FAB2_LIB.BASEBOARD_FAB2(SCH_1):PAGE101

TP_CLK_125M_BMCA @BASEBOARD_FAB2_LIB.BASEBOARD_FAB2(SCH_1):TP_CLK_125M_BMCA
 EU8F2   37 RGMII<0> ICS9FGP204_MLFP-IC,E95226-001    I34 @BASEBOARD_FAB2_LIB.BASEBOARD_FAB2(SCH_1):PAGE101

TP_CLK_24M_PMSYNC2 @BASEBOARD_FAB2_LIB.BASEBOARD_FAB2(SCH_1):TP_CLK_24M_PMSYNC2
  U7C1 BV51 CLOCKSE_PMSYNCCLK2 LBG_CORE_QAT_EXT_D_BGA1-IC,H91A    I40 @BASEBOARD_FAB2_LIB.BASEBOARD_FAB2(SCH_1):PAGE114

TP_CLK_96M_CKMNG_N @BASEBOARD_FAB2_LIB.BASEBOARD_FAB2(SCH_1):TP_CLK_96M_CKMNG_N
 EU8F2    4 DOT96SSC ICS9FGP204_MLFP-IC,E95226-001    I34 @BASEBOARD_FAB2_LIB.BASEBOARD_FAB2(SCH_1):PAGE101

TP_CLK_96M_CKMNG_P @BASEBOARD_FAB2_LIB.BASEBOARD_FAB2(SCH_1):TP_CLK_96M_CKMNG_P
 EU8F2    3 DOT96SST ICS9FGP204_MLFP-IC,E95226-001    I34 @BASEBOARD_FAB2_LIB.BASEBOARD_FAB2(SCH_1):PAGE101

TP_CPLD1_PB16A_PCLKT2_1 @BASEBOARD_FAB2_LIB.BASEBOARD_FAB2(SCH_1):TP_CPLD1_PB16A_PCLKT2_1
  U8D7   T9 PB16A_PCLKT2_1 LCMXO2_A_256BGA-IC,H63395-001   I179 @BASEBOARD_FAB2_LIB.BASEBOARD_FAB2(SCH_1):PAGE190

TP_CPLD1_PB16B_PCLKC2_1 @BASEBOARD_FAB2_LIB.BASEBOARD_FAB2(SCH_1):TP_CPLD1_PB16B_PCLKC2_1
  U8D7   P9 PB16B_PCLKC2_1 LCMXO2_A_256BGA-IC,H63395-001   I179 @BASEBOARD_FAB2_LIB.BASEBOARD_FAB2(SCH_1):PAGE190

TP_CPLD1_PB25B_SI_SISPI @BASEBOARD_FAB2_LIB.BASEBOARD_FAB2(SCH_1):TP_CPLD1_PB25B_SI_SISPI
  U8D7  P13 PB25B_SI_SISPI LCMXO2_A_256BGA-IC,H63395-001   I179 @BASEBOARD_FAB2_LIB.BASEBOARD_FAB2(SCH_1):PAGE190

TP_CPLD1_PB5A_CSSPIN @BASEBOARD_FAB2_LIB.BASEBOARD_FAB2(SCH_1):TP_CPLD1_PB5A_CSSPIN
  U8D7   R5 PB5A_CSSPIN LCMXO2_A_256BGA-IC,H63395-001   I179 @BASEBOARD_FAB2_LIB.BASEBOARD_FAB2(SCH_1):PAGE190

TP_CPLD1_PB8A_MCLK_CCLK @BASEBOARD_FAB2_LIB.BASEBOARD_FAB2(SCH_1):TP_CPLD1_PB8A_MCLK_CCLK
  U8D7   P6 PB8A_MCLK_CCLK LCMXO2_A_256BGA-IC,H63395-001   I179 @BASEBOARD_FAB2_LIB.BASEBOARD_FAB2(SCH_1):PAGE190

TP_CPLD1_PB8B_SO_SPISO @BASEBOARD_FAB2_LIB.BASEBOARD_FAB2(SCH_1):TP_CPLD1_PB8B_SO_SPISO
  U8D7   T6 PB8B_SO_SPISO LCMXO2_A_256BGA-IC,H63395-001   I179 @BASEBOARD_FAB2_LIB.BASEBOARD_FAB2(SCH_1):PAGE190

TP_CPLD1_PL11A @BASEBOARD_FAB2_LIB.BASEBOARD_FAB2(SCH_1):TP_CPLD1_PL11A
  U8D7   L3  PL11B LCMXO2_A_256BGA-IC,H63395-001   I179 @BASEBOARD_FAB2_LIB.BASEBOARD_FAB2(SCH_1):PAGE190

TP_CPLD1_PL1A_L_GPLLT_FB @BASEBOARD_FAB2_LIB.BASEBOARD_FAB2(SCH_1):TP_CPLD1_PL1A_L_GPLLT_FB
  U8D7   D3 PL1A_L_GPLLT_FB LCMXO2_A_256BGA-IC,H63395-001   I179 @BASEBOARD_FAB2_LIB.BASEBOARD_FAB2(SCH_1):PAGE190

TP_CPLD1_PL1B_L_GPLLC_FB @BASEBOARD_FAB2_LIB.BASEBOARD_FAB2(SCH_1):TP_CPLD1_PL1B_L_GPLLC_FB
  U8D7   D1 PL1B_L_GPLLC_FB LCMXO2_A_256BGA-IC,H63395-001   I179 @BASEBOARD_FAB2_LIB.BASEBOARD_FAB2(SCH_1):PAGE190

TP_CPLD1_PL2B_L_GPLLC_IN @BASEBOARD_FAB2_LIB.BASEBOARD_FAB2(SCH_1):TP_CPLD1_PL2B_L_GPLLC_IN
  U8D7   E3 PL2B_L_GPLLC_IN LCMXO2_A_256BGA-IC,H63395-001   I179 @BASEBOARD_FAB2_LIB.BASEBOARD_FAB2(SCH_1):PAGE190

TP_CPLD1_PL7D_PCLKT4_0 @BASEBOARD_FAB2_LIB.BASEBOARD_FAB2(SCH_1):TP_CPLD1_PL7D_PCLKT4_0
  U8D7   J3 PL7D_PCLKC4_0 LCMXO2_A_256BGA-IC,H63395-001   I179 @BASEBOARD_FAB2_LIB.BASEBOARD_FAB2(SCH_1):PAGE190

TP_CPLD1_PR10C @BASEBOARD_FAB2_LIB.BASEBOARD_FAB2(SCH_1):TP_CPLD1_PR10C
  U8D7  J11  PR10C LCMXO2_A_256BGA-IC,H63395-001    I59 @BASEBOARD_FAB2_LIB.BASEBOARD_FAB2(SCH_1):PAGE191

TP_CPLD1_PR11B @BASEBOARD_FAB2_LIB.BASEBOARD_FAB2(SCH_1):TP_CPLD1_PR11B
  U8D7  L14  PR11B LCMXO2_A_256BGA-IC,H63395-001    I59 @BASEBOARD_FAB2_LIB.BASEBOARD_FAB2(SCH_1):PAGE191

TP_CPLD1_PR12D @BASEBOARD_FAB2_LIB.BASEBOARD_FAB2(SCH_1):TP_CPLD1_PR12D
  U8D7  L13  PR12D LCMXO2_A_256BGA-IC,H63395-001    I59 @BASEBOARD_FAB2_LIB.BASEBOARD_FAB2(SCH_1):PAGE191

TP_CPLD1_PR7A_PCLKT1_0 @BASEBOARD_FAB2_LIB.BASEBOARD_FAB2(SCH_1):TP_CPLD1_PR7A_PCLKT1_0
  U8D7  H14 PR7A_PCLKT1_0 LCMXO2_A_256BGA-IC,H63395-001    I59 @BASEBOARD_FAB2_LIB.BASEBOARD_FAB2(SCH_1):PAGE191

TP_CPLD1_PR7B_PCLKC1_0 @BASEBOARD_FAB2_LIB.BASEBOARD_FAB2(SCH_1):TP_CPLD1_PR7B_PCLKC1_0
  U8D7  H16 PR7B_PCLKC1_0 LCMXO2_A_256BGA-IC,H63395-001    I59 @BASEBOARD_FAB2_LIB.BASEBOARD_FAB2(SCH_1):PAGE191

TP_CPLD1_PR7C @BASEBOARD_FAB2_LIB.BASEBOARD_FAB2(SCH_1):TP_CPLD1_PR7C
  U8D7  J16   PR7C LCMXO2_A_256BGA-IC,H63395-001    I59 @BASEBOARD_FAB2_LIB.BASEBOARD_FAB2(SCH_1):PAGE191

TP_CPLD1_PR7D @BASEBOARD_FAB2_LIB.BASEBOARD_FAB2(SCH_1):TP_CPLD1_PR7D
  U8D7  J14   PR7D LCMXO2_A_256BGA-IC,H63395-001    I59 @BASEBOARD_FAB2_LIB.BASEBOARD_FAB2(SCH_1):PAGE191

TP_CPLD1_PR9A @BASEBOARD_FAB2_LIB.BASEBOARD_FAB2(SCH_1):TP_CPLD1_PR9A
  U8D7  J15   PR9A LCMXO2_A_256BGA-IC,H63395-001    I59 @BASEBOARD_FAB2_LIB.BASEBOARD_FAB2(SCH_1):PAGE191

TP_CPLD1_PR9C @BASEBOARD_FAB2_LIB.BASEBOARD_FAB2(SCH_1):TP_CPLD1_PR9C
  U8D7  H11   PR9C LCMXO2_A_256BGA-IC,H63395-001    I59 @BASEBOARD_FAB2_LIB.BASEBOARD_FAB2(SCH_1):PAGE191

TP_CPLD1_PR9D @BASEBOARD_FAB2_LIB.BASEBOARD_FAB2(SCH_1):TP_CPLD1_PR9D
  U8D7  J13   PR9D LCMXO2_A_256BGA-IC,H63395-001    I59 @BASEBOARD_FAB2_LIB.BASEBOARD_FAB2(SCH_1):PAGE191

TP_CPLD1_PT11A @BASEBOARD_FAB2_LIB.BASEBOARD_FAB2(SCH_1):TP_CPLD1_PT11A
  U8D7   A5  PT11A LCMXO2_A_256BGA-IC,H63395-001    I59 @BASEBOARD_FAB2_LIB.BASEBOARD_FAB2(SCH_1):PAGE191

TP_CPLD1_PT11B @BASEBOARD_FAB2_LIB.BASEBOARD_FAB2(SCH_1):TP_CPLD1_PT11B
  U8D7   B6  PT11B LCMXO2_A_256BGA-IC,H63395-001    I59 @BASEBOARD_FAB2_LIB.BASEBOARD_FAB2(SCH_1):PAGE191

TP_CPLD1_PT13A @BASEBOARD_FAB2_LIB.BASEBOARD_FAB2(SCH_1):TP_CPLD1_PT13A
  U8D7   B7  PT13A LCMXO2_A_256BGA-IC,H63395-001    I59 @BASEBOARD_FAB2_LIB.BASEBOARD_FAB2(SCH_1):PAGE191

TP_CPLD1_PT16B @BASEBOARD_FAB2_LIB.BASEBOARD_FAB2(SCH_1):TP_CPLD1_PT16B
  U8D7   E8  PT16B LCMXO2_A_256BGA-IC,H63395-001    I59 @BASEBOARD_FAB2_LIB.BASEBOARD_FAB2(SCH_1):PAGE191

TP_CPLD1_PT17B_PCLKC0_1 @BASEBOARD_FAB2_LIB.BASEBOARD_FAB2(SCH_1):TP_CPLD1_PT17B_PCLKC0_1
  U8D7   A8 PT17B_PCLKC0_1 LCMXO2_A_256BGA-IC,H63395-001    I59 @BASEBOARD_FAB2_LIB.BASEBOARD_FAB2(SCH_1):PAGE191

TP_CPLD1_PT17C @BASEBOARD_FAB2_LIB.BASEBOARD_FAB2(SCH_1):TP_CPLD1_PT17C
  U8D7   D8  PT17C LCMXO2_A_256BGA-IC,H63395-001    I59 @BASEBOARD_FAB2_LIB.BASEBOARD_FAB2(SCH_1):PAGE191

TP_CPLD1_PT19D @BASEBOARD_FAB2_LIB.BASEBOARD_FAB2(SCH_1):TP_CPLD1_PT19D
  U8D7  E11  PT19D LCMXO2_A_256BGA-IC,H63395-001    I59 @BASEBOARD_FAB2_LIB.BASEBOARD_FAB2(SCH_1):PAGE191

TP_CPLD1_PT20A @BASEBOARD_FAB2_LIB.BASEBOARD_FAB2(SCH_1):TP_CPLD1_PT20A
  U8D7  D10  PT20A LCMXO2_A_256BGA-IC,H63395-001    I59 @BASEBOARD_FAB2_LIB.BASEBOARD_FAB2(SCH_1):PAGE191

TP_CPLD1_PT20B @BASEBOARD_FAB2_LIB.BASEBOARD_FAB2(SCH_1):TP_CPLD1_PT20B
  U8D7  E10  PT20B LCMXO2_A_256BGA-IC,H63395-001    I59 @BASEBOARD_FAB2_LIB.BASEBOARD_FAB2(SCH_1):PAGE191

TP_CPLD1_PT22C @BASEBOARD_FAB2_LIB.BASEBOARD_FAB2(SCH_1):TP_CPLD1_PT22C
  U8D7  B13  PT22C LCMXO2_A_256BGA-IC,H63395-001    I59 @BASEBOARD_FAB2_LIB.BASEBOARD_FAB2(SCH_1):PAGE191

TP_CPLD1_PT22D @BASEBOARD_FAB2_LIB.BASEBOARD_FAB2(SCH_1):TP_CPLD1_PT22D
  U8D7  A14  PT22D LCMXO2_A_256BGA-IC,H63395-001    I59 @BASEBOARD_FAB2_LIB.BASEBOARD_FAB2(SCH_1):PAGE191

TP_CPLD1_PT24B @BASEBOARD_FAB2_LIB.BASEBOARD_FAB2(SCH_1):TP_CPLD1_PT24B
  U8D7  A15  PT24B LCMXO2_A_256BGA-IC,H63395-001    I59 @BASEBOARD_FAB2_LIB.BASEBOARD_FAB2(SCH_1):PAGE191

TP_CPLD1_PT24C_INITN @BASEBOARD_FAB2_LIB.BASEBOARD_FAB2(SCH_1):TP_CPLD1_PT24C_INITN
  U8D7  A13 PT24C_INITN LCMXO2_A_256BGA-IC,H63395-001    I59 @BASEBOARD_FAB2_LIB.BASEBOARD_FAB2(SCH_1):PAGE191

TP_CPLD1_PT24D_DONE @BASEBOARD_FAB2_LIB.BASEBOARD_FAB2(SCH_1):TP_CPLD1_PT24D_DONE
  U8D7  C13 PT24D_DONE LCMXO2_A_256BGA-IC,H63395-001    I59 @BASEBOARD_FAB2_LIB.BASEBOARD_FAB2(SCH_1):PAGE191

TP_CPU0_KTI2_AMONV @BASEBOARD_FAB2_LIB.BASEBOARD_FAB2(SCH_1):TP_CPU0_KTI2_AMONV
  U5D1 CN22 RSVD<77> SKX_EXT_B_BGA1-IC,TBD   I127 @BASEBOARD_FAB2_LIB.BASEBOARD_FAB2(SCH_1):PAGE39

TP_CPU0_KTI2_DFX_DN @BASEBOARD_FAB2_LIB.BASEBOARD_FAB2(SCH_1):TP_CPU0_KTI2_DFX_DN
  U5D1 CW22 RSVD<63> SKX_EXT_B_BGA1-IC,TBD   I127 @BASEBOARD_FAB2_LIB.BASEBOARD_FAB2(SCH_1):PAGE39

TP_CPU0_PROCDIS_G_N @BASEBOARD_FAB2_LIB.BASEBOARD_FAB2(SCH_1):TP_CPU0_PROCDIS_G_N
  U5D1 AB17 PROCDIS_N SKX_EXT_B_BGA1-IC,TBD   I259 @BASEBOARD_FAB2_LIB.BASEBOARD_FAB2(SCH_1):PAGE21

TP_CPU0_RSVD_0 @BASEBOARD_FAB2_LIB.BASEBOARD_FAB2(SCH_1):TP_CPU0_RSVD_0
  U5D1 EF83 RSVD<0> SKX_EXT_B_BGA1-IC,TBD   I127 @BASEBOARD_FAB2_LIB.BASEBOARD_FAB2(SCH_1):PAGE39

TP_CPU0_RSVD_1 @BASEBOARD_FAB2_LIB.BASEBOARD_FAB2(SCH_1):TP_CPU0_RSVD_1
  U5D1 EF81 RSVD<1> SKX_EXT_B_BGA1-IC,TBD   I127 @BASEBOARD_FAB2_LIB.BASEBOARD_FAB2(SCH_1):PAGE39

TP_CPU0_RSVD_10 @BASEBOARD_FAB2_LIB.BASEBOARD_FAB2(SCH_1):TP_CPU0_RSVD_10
  U5D1  ED5 RSVD<10> SKX_EXT_B_BGA1-IC,TBD   I127 @BASEBOARD_FAB2_LIB.BASEBOARD_FAB2(SCH_1):PAGE39

TP_CPU0_RSVD_100 @BASEBOARD_FAB2_LIB.BASEBOARD_FAB2(SCH_1):TP_CPU0_RSVD_100
  U5D1 CF81 RSVD<100> SKX_EXT_B_BGA1-IC,TBD    I15 @BASEBOARD_FAB2_LIB.BASEBOARD_FAB2(SCH_1):PAGE36

TP_CPU0_RSVD_101 @BASEBOARD_FAB2_LIB.BASEBOARD_FAB2(SCH_1):TP_CPU0_RSVD_101
  U5D1 CF79 RSVD<101> SKX_EXT_B_BGA1-IC,TBD    I15 @BASEBOARD_FAB2_LIB.BASEBOARD_FAB2(SCH_1):PAGE36

TP_CPU0_RSVD_105 @BASEBOARD_FAB2_LIB.BASEBOARD_FAB2(SCH_1):TP_CPU0_RSVD_105
  U5D1 CE80 RSVD<105> SKX_EXT_B_BGA1-IC,TBD    I15 @BASEBOARD_FAB2_LIB.BASEBOARD_FAB2(SCH_1):PAGE36

TP_CPU0_RSVD_106 @BASEBOARD_FAB2_LIB.BASEBOARD_FAB2(SCH_1):TP_CPU0_RSVD_106
  U5D1 CE78 RSVD<106> SKX_EXT_B_BGA1-IC,TBD    I15 @BASEBOARD_FAB2_LIB.BASEBOARD_FAB2(SCH_1):PAGE36

TP_CPU0_RSVD_108 @BASEBOARD_FAB2_LIB.BASEBOARD_FAB2(SCH_1):TP_CPU0_RSVD_108
  U5D1 CD25 RSVD<108> SKX_EXT_B_BGA1-IC,TBD    I15 @BASEBOARD_FAB2_LIB.BASEBOARD_FAB2(SCH_1):PAGE36

TP_CPU0_RSVD_11 @BASEBOARD_FAB2_LIB.BASEBOARD_FAB2(SCH_1):TP_CPU0_RSVD_11
  U5D1 ED45 RSVD<11> SKX_EXT_B_BGA1-IC,TBD   I127 @BASEBOARD_FAB2_LIB.BASEBOARD_FAB2(SCH_1):PAGE39

TP_CPU0_RSVD_111 @BASEBOARD_FAB2_LIB.BASEBOARD_FAB2(SCH_1):TP_CPU0_RSVD_111
  U5D1  CC6 RSVD<111> SKX_EXT_B_BGA1-IC,TBD    I15 @BASEBOARD_FAB2_LIB.BASEBOARD_FAB2(SCH_1):PAGE36

TP_CPU0_RSVD_113 @BASEBOARD_FAB2_LIB.BASEBOARD_FAB2(SCH_1):TP_CPU0_RSVD_113
  U5D1  CB5 RSVD<113> SKX_EXT_B_BGA1-IC,TBD    I15 @BASEBOARD_FAB2_LIB.BASEBOARD_FAB2(SCH_1):PAGE36

TP_CPU0_RSVD_114 @BASEBOARD_FAB2_LIB.BASEBOARD_FAB2(SCH_1):TP_CPU0_RSVD_114
  U5D1 CB25 RSVD<114> SKX_EXT_B_BGA1-IC,TBD    I15 @BASEBOARD_FAB2_LIB.BASEBOARD_FAB2(SCH_1):PAGE36

TP_CPU0_RSVD_117 @BASEBOARD_FAB2_LIB.BASEBOARD_FAB2(SCH_1):TP_CPU0_RSVD_117
  U5D1 CA24 RSVD<117> SKX_EXT_B_BGA1-IC,TBD    I15 @BASEBOARD_FAB2_LIB.BASEBOARD_FAB2(SCH_1):PAGE36

TP_CPU0_RSVD_119 @BASEBOARD_FAB2_LIB.BASEBOARD_FAB2(SCH_1):TP_CPU0_RSVD_119
  U5D1 BY25 RSVD<119> SKX_EXT_B_BGA1-IC,TBD    I15 @BASEBOARD_FAB2_LIB.BASEBOARD_FAB2(SCH_1):PAGE36

TP_CPU0_RSVD_12 @BASEBOARD_FAB2_LIB.BASEBOARD_FAB2(SCH_1):TP_CPU0_RSVD_12
  U5D1 EC84 RSVD<12> SKX_EXT_B_BGA1-IC,TBD   I127 @BASEBOARD_FAB2_LIB.BASEBOARD_FAB2(SCH_1):PAGE39

TP_CPU0_RSVD_121 @BASEBOARD_FAB2_LIB.BASEBOARD_FAB2(SCH_1):TP_CPU0_RSVD_121
  U5D1 BW22 RSVD<121> SKX_EXT_B_BGA1-IC,TBD    I15 @BASEBOARD_FAB2_LIB.BASEBOARD_FAB2(SCH_1):PAGE36

TP_CPU0_RSVD_123 @BASEBOARD_FAB2_LIB.BASEBOARD_FAB2(SCH_1):TP_CPU0_RSVD_123
  U5D1 BW10 RSVD<123> SKX_EXT_B_BGA1-IC,TBD    I15 @BASEBOARD_FAB2_LIB.BASEBOARD_FAB2(SCH_1):PAGE36

TP_CPU0_RSVD_124 @BASEBOARD_FAB2_LIB.BASEBOARD_FAB2(SCH_1):TP_CPU0_RSVD_124
  U5D1 BV23 RSVD<124> SKX_EXT_B_BGA1-IC,TBD    I15 @BASEBOARD_FAB2_LIB.BASEBOARD_FAB2(SCH_1):PAGE36

TP_CPU0_RSVD_13 @BASEBOARD_FAB2_LIB.BASEBOARD_FAB2(SCH_1):TP_CPU0_RSVD_13
  U5D1 EC44 RSVD<13> SKX_EXT_B_BGA1-IC,TBD   I127 @BASEBOARD_FAB2_LIB.BASEBOARD_FAB2(SCH_1):PAGE39

TP_CPU0_RSVD_14 @BASEBOARD_FAB2_LIB.BASEBOARD_FAB2(SCH_1):TP_CPU0_RSVD_14
  U5D1  EC4 RSVD<14> SKX_EXT_B_BGA1-IC,TBD   I127 @BASEBOARD_FAB2_LIB.BASEBOARD_FAB2(SCH_1):PAGE39

TP_CPU0_RSVD_144 @BASEBOARD_FAB2_LIB.BASEBOARD_FAB2(SCH_1):TP_CPU0_RSVD_144
  U5D1 BG20 RSVD<144> SKX_EXT_B_BGA1-IC,TBD    I15 @BASEBOARD_FAB2_LIB.BASEBOARD_FAB2(SCH_1):PAGE36

TP_CPU0_RSVD_145 @BASEBOARD_FAB2_LIB.BASEBOARD_FAB2(SCH_1):TP_CPU0_RSVD_145
  U5D1 BG18 RSVD<145> SKX_EXT_B_BGA1-IC,TBD    I15 @BASEBOARD_FAB2_LIB.BASEBOARD_FAB2(SCH_1):PAGE36

TP_CPU0_RSVD_146 @BASEBOARD_FAB2_LIB.BASEBOARD_FAB2(SCH_1):TP_CPU0_RSVD_146
  U5D1 BF21 RSVD<146> SKX_EXT_B_BGA1-IC,TBD    I15 @BASEBOARD_FAB2_LIB.BASEBOARD_FAB2(SCH_1):PAGE36

TP_CPU0_RSVD_147 @BASEBOARD_FAB2_LIB.BASEBOARD_FAB2(SCH_1):TP_CPU0_RSVD_147
  U5D1 BE22 RSVD<147> SKX_EXT_B_BGA1-IC,TBD    I15 @BASEBOARD_FAB2_LIB.BASEBOARD_FAB2(SCH_1):PAGE36

TP_CPU0_RSVD_148 @BASEBOARD_FAB2_LIB.BASEBOARD_FAB2(SCH_1):TP_CPU0_RSVD_148
  U5D1 BE20 RSVD<148> SKX_EXT_B_BGA1-IC,TBD    I15 @BASEBOARD_FAB2_LIB.BASEBOARD_FAB2(SCH_1):PAGE36

TP_CPU0_RSVD_149 @BASEBOARD_FAB2_LIB.BASEBOARD_FAB2(SCH_1):TP_CPU0_RSVD_149
  U5D1 BE18 RSVD<149> SKX_EXT_B_BGA1-IC,TBD    I15 @BASEBOARD_FAB2_LIB.BASEBOARD_FAB2(SCH_1):PAGE36

TP_CPU0_RSVD_15 @BASEBOARD_FAB2_LIB.BASEBOARD_FAB2(SCH_1):TP_CPU0_RSVD_15
  U5D1 EC16 RSVD<15> SKX_EXT_B_BGA1-IC,TBD   I127 @BASEBOARD_FAB2_LIB.BASEBOARD_FAB2(SCH_1):PAGE39

TP_CPU0_RSVD_150 @BASEBOARD_FAB2_LIB.BASEBOARD_FAB2(SCH_1):TP_CPU0_RSVD_150
  U5D1 BD69 RSVD<150> SKX_EXT_B_BGA1-IC,TBD    I15 @BASEBOARD_FAB2_LIB.BASEBOARD_FAB2(SCH_1):PAGE36

TP_CPU0_RSVD_151 @BASEBOARD_FAB2_LIB.BASEBOARD_FAB2(SCH_1):TP_CPU0_RSVD_151
  U5D1 BD67 RSVD<151> SKX_EXT_B_BGA1-IC,TBD    I15 @BASEBOARD_FAB2_LIB.BASEBOARD_FAB2(SCH_1):PAGE36

TP_CPU0_RSVD_152 @BASEBOARD_FAB2_LIB.BASEBOARD_FAB2(SCH_1):TP_CPU0_RSVD_152
  U5D1 BD65 RSVD<152> SKX_EXT_B_BGA1-IC,TBD    I15 @BASEBOARD_FAB2_LIB.BASEBOARD_FAB2(SCH_1):PAGE36

TP_CPU0_RSVD_154 @BASEBOARD_FAB2_LIB.BASEBOARD_FAB2(SCH_1):TP_CPU0_RSVD_154
  U5D1 BD19 RSVD<154> SKX_EXT_B_BGA1-IC,TBD    I15 @BASEBOARD_FAB2_LIB.BASEBOARD_FAB2(SCH_1):PAGE36

TP_CPU0_RSVD_155 @BASEBOARD_FAB2_LIB.BASEBOARD_FAB2(SCH_1):TP_CPU0_RSVD_155
  U5D1 BD17 RSVD<155> SKX_EXT_B_BGA1-IC,TBD    I15 @BASEBOARD_FAB2_LIB.BASEBOARD_FAB2(SCH_1):PAGE36

TP_CPU0_RSVD_156 @BASEBOARD_FAB2_LIB.BASEBOARD_FAB2(SCH_1):TP_CPU0_RSVD_156
  U5D1 BC68 RSVD<156> SKX_EXT_B_BGA1-IC,TBD    I15 @BASEBOARD_FAB2_LIB.BASEBOARD_FAB2(SCH_1):PAGE36

TP_CPU0_RSVD_157 @BASEBOARD_FAB2_LIB.BASEBOARD_FAB2(SCH_1):TP_CPU0_RSVD_157
  U5D1 BC66 RSVD<157> SKX_EXT_B_BGA1-IC,TBD    I15 @BASEBOARD_FAB2_LIB.BASEBOARD_FAB2(SCH_1):PAGE36

TP_CPU0_RSVD_158 @BASEBOARD_FAB2_LIB.BASEBOARD_FAB2(SCH_1):TP_CPU0_RSVD_158
  U5D1 BC64 RSVD<158> SKX_EXT_B_BGA1-IC,TBD    I15 @BASEBOARD_FAB2_LIB.BASEBOARD_FAB2(SCH_1):PAGE36

TP_CPU0_RSVD_159 @BASEBOARD_FAB2_LIB.BASEBOARD_FAB2(SCH_1):TP_CPU0_RSVD_159
  U5D1 BC22 RSVD<159> SKX_EXT_B_BGA1-IC,TBD    I15 @BASEBOARD_FAB2_LIB.BASEBOARD_FAB2(SCH_1):PAGE36

TP_CPU0_RSVD_16 @BASEBOARD_FAB2_LIB.BASEBOARD_FAB2(SCH_1):TP_CPU0_RSVD_16
  U5D1 EB85 RSVD<16> SKX_EXT_B_BGA1-IC,TBD   I127 @BASEBOARD_FAB2_LIB.BASEBOARD_FAB2(SCH_1):PAGE39

TP_CPU0_RSVD_160 @BASEBOARD_FAB2_LIB.BASEBOARD_FAB2(SCH_1):TP_CPU0_RSVD_160
  U5D1 BC20 RSVD<160> SKX_EXT_B_BGA1-IC,TBD    I15 @BASEBOARD_FAB2_LIB.BASEBOARD_FAB2(SCH_1):PAGE36

TP_CPU0_RSVD_161 @BASEBOARD_FAB2_LIB.BASEBOARD_FAB2(SCH_1):TP_CPU0_RSVD_161
  U5D1 BC18 RSVD<161> SKX_EXT_B_BGA1-IC,TBD    I15 @BASEBOARD_FAB2_LIB.BASEBOARD_FAB2(SCH_1):PAGE36

TP_CPU0_RSVD_162 @BASEBOARD_FAB2_LIB.BASEBOARD_FAB2(SCH_1):TP_CPU0_RSVD_162
  U5D1 BC14 RSVD<162> SKX_EXT_B_BGA1-IC,TBD    I15 @BASEBOARD_FAB2_LIB.BASEBOARD_FAB2(SCH_1):PAGE36

TP_CPU0_RSVD_163 @BASEBOARD_FAB2_LIB.BASEBOARD_FAB2(SCH_1):TP_CPU0_RSVD_163
  U5D1 BB67 RSVD<163> SKX_EXT_B_BGA1-IC,TBD    I15 @BASEBOARD_FAB2_LIB.BASEBOARD_FAB2(SCH_1):PAGE36

TP_CPU0_RSVD_164 @BASEBOARD_FAB2_LIB.BASEBOARD_FAB2(SCH_1):TP_CPU0_RSVD_164
  U5D1 BB65 RSVD<164> SKX_EXT_B_BGA1-IC,TBD    I15 @BASEBOARD_FAB2_LIB.BASEBOARD_FAB2(SCH_1):PAGE36

TP_CPU0_RSVD_166 @BASEBOARD_FAB2_LIB.BASEBOARD_FAB2(SCH_1):TP_CPU0_RSVD_166
  U5D1 BB21 RSVD<166> SKX_EXT_B_BGA1-IC,TBD    I15 @BASEBOARD_FAB2_LIB.BASEBOARD_FAB2(SCH_1):PAGE36

TP_CPU0_RSVD_167 @BASEBOARD_FAB2_LIB.BASEBOARD_FAB2(SCH_1):TP_CPU0_RSVD_167
  U5D1 BB17 RSVD<167> SKX_EXT_B_BGA1-IC,TBD    I15 @BASEBOARD_FAB2_LIB.BASEBOARD_FAB2(SCH_1):PAGE36

TP_CPU0_RSVD_168 @BASEBOARD_FAB2_LIB.BASEBOARD_FAB2(SCH_1):TP_CPU0_RSVD_168
  U5D1 BB15 RSVD<168> SKX_EXT_B_BGA1-IC,TBD    I15 @BASEBOARD_FAB2_LIB.BASEBOARD_FAB2(SCH_1):PAGE36

TP_CPU0_RSVD_169 @BASEBOARD_FAB2_LIB.BASEBOARD_FAB2(SCH_1):TP_CPU0_RSVD_169
  U5D1 BB13 RSVD<169> SKX_EXT_B_BGA1-IC,TBD    I15 @BASEBOARD_FAB2_LIB.BASEBOARD_FAB2(SCH_1):PAGE36

TP_CPU0_RSVD_17 @BASEBOARD_FAB2_LIB.BASEBOARD_FAB2(SCH_1):TP_CPU0_RSVD_17
  U5D1  EB5 RSVD<17> SKX_EXT_B_BGA1-IC,TBD   I127 @BASEBOARD_FAB2_LIB.BASEBOARD_FAB2(SCH_1):PAGE39

TP_CPU0_RSVD_170 @BASEBOARD_FAB2_LIB.BASEBOARD_FAB2(SCH_1):TP_CPU0_RSVD_170
  U5D1 BA82 RSVD<170> SKX_EXT_B_BGA1-IC,TBD    I15 @BASEBOARD_FAB2_LIB.BASEBOARD_FAB2(SCH_1):PAGE36

TP_CPU0_RSVD_171 @BASEBOARD_FAB2_LIB.BASEBOARD_FAB2(SCH_1):TP_CPU0_RSVD_171
  U5D1 BA78 RSVD<171> SKX_EXT_B_BGA1-IC,TBD    I15 @BASEBOARD_FAB2_LIB.BASEBOARD_FAB2(SCH_1):PAGE36

TP_CPU0_RSVD_172 @BASEBOARD_FAB2_LIB.BASEBOARD_FAB2(SCH_1):TP_CPU0_RSVD_172
  U5D1 BA76 RSVD<172> SKX_EXT_B_BGA1-IC,TBD    I61 @BASEBOARD_FAB2_LIB.BASEBOARD_FAB2(SCH_1):PAGE29

TP_CPU0_RSVD_173 @BASEBOARD_FAB2_LIB.BASEBOARD_FAB2(SCH_1):TP_CPU0_RSVD_173
  U5D1 BA66 RSVD<173> SKX_EXT_B_BGA1-IC,TBD    I61 @BASEBOARD_FAB2_LIB.BASEBOARD_FAB2(SCH_1):PAGE29

TP_CPU0_RSVD_174 @BASEBOARD_FAB2_LIB.BASEBOARD_FAB2(SCH_1):TP_CPU0_RSVD_174
  U5D1 BA64 RSVD<174> SKX_EXT_B_BGA1-IC,TBD    I61 @BASEBOARD_FAB2_LIB.BASEBOARD_FAB2(SCH_1):PAGE29

TP_CPU0_RSVD_175 @BASEBOARD_FAB2_LIB.BASEBOARD_FAB2(SCH_1):TP_CPU0_RSVD_175
  U5D1 BA22 RSVD<175> SKX_EXT_B_BGA1-IC,TBD    I61 @BASEBOARD_FAB2_LIB.BASEBOARD_FAB2(SCH_1):PAGE29

TP_CPU0_RSVD_176 @BASEBOARD_FAB2_LIB.BASEBOARD_FAB2(SCH_1):TP_CPU0_RSVD_176
  U5D1 BA18 RSVD<176> SKX_EXT_B_BGA1-IC,TBD    I61 @BASEBOARD_FAB2_LIB.BASEBOARD_FAB2(SCH_1):PAGE29

TP_CPU0_RSVD_177 @BASEBOARD_FAB2_LIB.BASEBOARD_FAB2(SCH_1):TP_CPU0_RSVD_177
  U5D1 BA16 RSVD<177> SKX_EXT_B_BGA1-IC,TBD    I61 @BASEBOARD_FAB2_LIB.BASEBOARD_FAB2(SCH_1):PAGE29

TP_CPU0_RSVD_178 @BASEBOARD_FAB2_LIB.BASEBOARD_FAB2(SCH_1):TP_CPU0_RSVD_178
  U5D1 BA14 RSVD<178> SKX_EXT_B_BGA1-IC,TBD    I61 @BASEBOARD_FAB2_LIB.BASEBOARD_FAB2(SCH_1):PAGE29

TP_CPU0_RSVD_179 @BASEBOARD_FAB2_LIB.BASEBOARD_FAB2(SCH_1):TP_CPU0_RSVD_179
  U5D1 AY77 RSVD<179> SKX_EXT_B_BGA1-IC,TBD    I61 @BASEBOARD_FAB2_LIB.BASEBOARD_FAB2(SCH_1):PAGE29

TP_CPU0_RSVD_18 @BASEBOARD_FAB2_LIB.BASEBOARD_FAB2(SCH_1):TP_CPU0_RSVD_18
  U5D1  EB3 RSVD<18> SKX_EXT_B_BGA1-IC,TBD   I127 @BASEBOARD_FAB2_LIB.BASEBOARD_FAB2(SCH_1):PAGE39

TP_CPU0_RSVD_180 @BASEBOARD_FAB2_LIB.BASEBOARD_FAB2(SCH_1):TP_CPU0_RSVD_180
  U5D1 AY75 RSVD<180> SKX_EXT_B_BGA1-IC,TBD    I61 @BASEBOARD_FAB2_LIB.BASEBOARD_FAB2(SCH_1):PAGE29

TP_CPU0_RSVD_181 @BASEBOARD_FAB2_LIB.BASEBOARD_FAB2(SCH_1):TP_CPU0_RSVD_181
  U5D1 AY67 RSVD<181> SKX_EXT_B_BGA1-IC,TBD    I61 @BASEBOARD_FAB2_LIB.BASEBOARD_FAB2(SCH_1):PAGE29

TP_CPU0_RSVD_182 @BASEBOARD_FAB2_LIB.BASEBOARD_FAB2(SCH_1):TP_CPU0_RSVD_182
  U5D1 AY65 RSVD<182> SKX_EXT_B_BGA1-IC,TBD    I61 @BASEBOARD_FAB2_LIB.BASEBOARD_FAB2(SCH_1):PAGE29

TP_CPU0_RSVD_183 @BASEBOARD_FAB2_LIB.BASEBOARD_FAB2(SCH_1):TP_CPU0_RSVD_183
  U5D1 AW76 RSVD<183> SKX_EXT_B_BGA1-IC,TBD    I61 @BASEBOARD_FAB2_LIB.BASEBOARD_FAB2(SCH_1):PAGE29

TP_CPU0_RSVD_184 @BASEBOARD_FAB2_LIB.BASEBOARD_FAB2(SCH_1):TP_CPU0_RSVD_184
  U5D1 AW64 RSVD<184> SKX_EXT_B_BGA1-IC,TBD    I61 @BASEBOARD_FAB2_LIB.BASEBOARD_FAB2(SCH_1):PAGE29

TP_CPU0_RSVD_186 @BASEBOARD_FAB2_LIB.BASEBOARD_FAB2(SCH_1):TP_CPU0_RSVD_186
  U5D1 AV77 RSVD<186> SKX_EXT_B_BGA1-IC,TBD    I61 @BASEBOARD_FAB2_LIB.BASEBOARD_FAB2(SCH_1):PAGE29

TP_CPU0_RSVD_189 @BASEBOARD_FAB2_LIB.BASEBOARD_FAB2(SCH_1):TP_CPU0_RSVD_189
  U5D1 AT13 RSVD<189> SKX_EXT_B_BGA1-IC,TBD    I61 @BASEBOARD_FAB2_LIB.BASEBOARD_FAB2(SCH_1):PAGE29

TP_CPU0_RSVD_19 @BASEBOARD_FAB2_LIB.BASEBOARD_FAB2(SCH_1):TP_CPU0_RSVD_19
  U5D1 EA44 RSVD<19> SKX_EXT_B_BGA1-IC,TBD   I127 @BASEBOARD_FAB2_LIB.BASEBOARD_FAB2(SCH_1):PAGE39

TP_CPU0_RSVD_190 @BASEBOARD_FAB2_LIB.BASEBOARD_FAB2(SCH_1):TP_CPU0_RSVD_190
  U5D1 AR62 RSVD<190> SKX_EXT_B_BGA1-IC,TBD    I61 @BASEBOARD_FAB2_LIB.BASEBOARD_FAB2(SCH_1):PAGE29

TP_CPU0_RSVD_194 @BASEBOARD_FAB2_LIB.BASEBOARD_FAB2(SCH_1):TP_CPU0_RSVD_194
  U5D1 AP61 RSVD<194> SKX_EXT_B_BGA1-IC,TBD   I204 @BASEBOARD_FAB2_LIB.BASEBOARD_FAB2(SCH_1):PAGE22

TP_CPU0_RSVD_198 @BASEBOARD_FAB2_LIB.BASEBOARD_FAB2(SCH_1):TP_CPU0_RSVD_198
  U5D1 AN62 RSVD<198> SKX_EXT_B_BGA1-IC,TBD   I204 @BASEBOARD_FAB2_LIB.BASEBOARD_FAB2(SCH_1):PAGE22

TP_CPU0_RSVD_199 @BASEBOARD_FAB2_LIB.BASEBOARD_FAB2(SCH_1):TP_CPU0_RSVD_199
  U5D1 AN60 RSVD<199> SKX_EXT_B_BGA1-IC,TBD   I204 @BASEBOARD_FAB2_LIB.BASEBOARD_FAB2(SCH_1):PAGE22

TP_CPU0_RSVD_2 @BASEBOARD_FAB2_LIB.BASEBOARD_FAB2(SCH_1):TP_CPU0_RSVD_2
  U5D1 EF77 RSVD<2> SKX_EXT_B_BGA1-IC,TBD   I127 @BASEBOARD_FAB2_LIB.BASEBOARD_FAB2(SCH_1):PAGE39

TP_CPU0_RSVD_20 @BASEBOARD_FAB2_LIB.BASEBOARD_FAB2(SCH_1):TP_CPU0_RSVD_20
  U5D1  EA4 RSVD<20> SKX_EXT_B_BGA1-IC,TBD   I127 @BASEBOARD_FAB2_LIB.BASEBOARD_FAB2(SCH_1):PAGE39

TP_CPU0_RSVD_204 @BASEBOARD_FAB2_LIB.BASEBOARD_FAB2(SCH_1):TP_CPU0_RSVD_204
  U5D1 AM61 RSVD<204> SKX_EXT_B_BGA1-IC,TBD   I204 @BASEBOARD_FAB2_LIB.BASEBOARD_FAB2(SCH_1):PAGE22

TP_CPU0_RSVD_205 @BASEBOARD_FAB2_LIB.BASEBOARD_FAB2(SCH_1):TP_CPU0_RSVD_205
  U5D1 AM59 RSVD<205> SKX_EXT_B_BGA1-IC,TBD   I204 @BASEBOARD_FAB2_LIB.BASEBOARD_FAB2(SCH_1):PAGE22

TP_CPU0_RSVD_208 @BASEBOARD_FAB2_LIB.BASEBOARD_FAB2(SCH_1):TP_CPU0_RSVD_208
  U5D1 AM23 RSVD<208> SKX_EXT_B_BGA1-IC,TBD   I204 @BASEBOARD_FAB2_LIB.BASEBOARD_FAB2(SCH_1):PAGE22

TP_CPU0_RSVD_21 @BASEBOARD_FAB2_LIB.BASEBOARD_FAB2(SCH_1):TP_CPU0_RSVD_21
  U5D1  DY3 RSVD<21> SKX_EXT_B_BGA1-IC,TBD   I127 @BASEBOARD_FAB2_LIB.BASEBOARD_FAB2(SCH_1):PAGE39

TP_CPU0_RSVD_210 @BASEBOARD_FAB2_LIB.BASEBOARD_FAB2(SCH_1):TP_CPU0_RSVD_210
  U5D1 AL62 RSVD<210> SKX_EXT_B_BGA1-IC,TBD   I204 @BASEBOARD_FAB2_LIB.BASEBOARD_FAB2(SCH_1):PAGE22

TP_CPU0_RSVD_211 @BASEBOARD_FAB2_LIB.BASEBOARD_FAB2(SCH_1):TP_CPU0_RSVD_211
  U5D1 AL60 RSVD<211> SKX_EXT_B_BGA1-IC,TBD   I204 @BASEBOARD_FAB2_LIB.BASEBOARD_FAB2(SCH_1):PAGE22

TP_CPU0_RSVD_212 @BASEBOARD_FAB2_LIB.BASEBOARD_FAB2(SCH_1):TP_CPU0_RSVD_212
  U5D1 AL58 RSVD<212> SKX_EXT_B_BGA1-IC,TBD   I204 @BASEBOARD_FAB2_LIB.BASEBOARD_FAB2(SCH_1):PAGE22

TP_CPU0_RSVD_214 @BASEBOARD_FAB2_LIB.BASEBOARD_FAB2(SCH_1):TP_CPU0_RSVD_214
  U5D1 AL22 RSVD<214> SKX_EXT_B_BGA1-IC,TBD   I204 @BASEBOARD_FAB2_LIB.BASEBOARD_FAB2(SCH_1):PAGE22

TP_CPU0_RSVD_216 @BASEBOARD_FAB2_LIB.BASEBOARD_FAB2(SCH_1):TP_CPU0_RSVD_216
  U5D1 AK69 RSVD<216> SKX_EXT_B_BGA1-IC,TBD   I204 @BASEBOARD_FAB2_LIB.BASEBOARD_FAB2(SCH_1):PAGE22

TP_CPU0_RSVD_217 @BASEBOARD_FAB2_LIB.BASEBOARD_FAB2(SCH_1):TP_CPU0_RSVD_217
  U5D1 AK61 RSVD<217> SKX_EXT_B_BGA1-IC,TBD   I204 @BASEBOARD_FAB2_LIB.BASEBOARD_FAB2(SCH_1):PAGE22

TP_CPU0_RSVD_218 @BASEBOARD_FAB2_LIB.BASEBOARD_FAB2(SCH_1):TP_CPU0_RSVD_218
  U5D1 AK59 RSVD<218> SKX_EXT_B_BGA1-IC,TBD   I204 @BASEBOARD_FAB2_LIB.BASEBOARD_FAB2(SCH_1):PAGE22

TP_CPU0_RSVD_219 @BASEBOARD_FAB2_LIB.BASEBOARD_FAB2(SCH_1):TP_CPU0_RSVD_219
  U5D1 AK57 RSVD<219> SKX_EXT_B_BGA1-IC,TBD   I204 @BASEBOARD_FAB2_LIB.BASEBOARD_FAB2(SCH_1):PAGE22

TP_CPU0_RSVD_22 @BASEBOARD_FAB2_LIB.BASEBOARD_FAB2(SCH_1):TP_CPU0_RSVD_22
  U5D1 DW46 RSVD<22> SKX_EXT_B_BGA1-IC,TBD   I127 @BASEBOARD_FAB2_LIB.BASEBOARD_FAB2(SCH_1):PAGE39

TP_CPU0_RSVD_222 @BASEBOARD_FAB2_LIB.BASEBOARD_FAB2(SCH_1):TP_CPU0_RSVD_222
  U5D1 AJ70 RSVD<222> SKX_EXT_B_BGA1-IC,TBD   I204 @BASEBOARD_FAB2_LIB.BASEBOARD_FAB2(SCH_1):PAGE22

TP_CPU0_RSVD_223 @BASEBOARD_FAB2_LIB.BASEBOARD_FAB2(SCH_1):TP_CPU0_RSVD_223
  U5D1 AJ62 RSVD<223> SKX_EXT_B_BGA1-IC,TBD   I204 @BASEBOARD_FAB2_LIB.BASEBOARD_FAB2(SCH_1):PAGE22

TP_CPU0_RSVD_224 @BASEBOARD_FAB2_LIB.BASEBOARD_FAB2(SCH_1):TP_CPU0_RSVD_224
  U5D1 AJ60 RSVD<224> SKX_EXT_B_BGA1-IC,TBD   I204 @BASEBOARD_FAB2_LIB.BASEBOARD_FAB2(SCH_1):PAGE22

TP_CPU0_RSVD_225 @BASEBOARD_FAB2_LIB.BASEBOARD_FAB2(SCH_1):TP_CPU0_RSVD_225
  U5D1 AJ58 RSVD<225> SKX_EXT_B_BGA1-IC,TBD   I204 @BASEBOARD_FAB2_LIB.BASEBOARD_FAB2(SCH_1):PAGE22

TP_CPU0_RSVD_226 @BASEBOARD_FAB2_LIB.BASEBOARD_FAB2(SCH_1):TP_CPU0_RSVD_226
  U5D1 AJ56 RSVD<226> SKX_EXT_B_BGA1-IC,TBD   I204 @BASEBOARD_FAB2_LIB.BASEBOARD_FAB2(SCH_1):PAGE22

TP_CPU0_RSVD_227 @BASEBOARD_FAB2_LIB.BASEBOARD_FAB2(SCH_1):TP_CPU0_RSVD_227
  U5D1 AJ20 RSVD<227> SKX_EXT_B_BGA1-IC,TBD   I204 @BASEBOARD_FAB2_LIB.BASEBOARD_FAB2(SCH_1):PAGE22

TP_CPU0_RSVD_228 @BASEBOARD_FAB2_LIB.BASEBOARD_FAB2(SCH_1):TP_CPU0_RSVD_228
  U5D1 AH73 RSVD<228> SKX_EXT_B_BGA1-IC,TBD   I204 @BASEBOARD_FAB2_LIB.BASEBOARD_FAB2(SCH_1):PAGE22

TP_CPU0_RSVD_229 @BASEBOARD_FAB2_LIB.BASEBOARD_FAB2(SCH_1):TP_CPU0_RSVD_229
  U5D1 AH71 RSVD<229> SKX_EXT_B_BGA1-IC,TBD   I204 @BASEBOARD_FAB2_LIB.BASEBOARD_FAB2(SCH_1):PAGE22

TP_CPU0_RSVD_23 @BASEBOARD_FAB2_LIB.BASEBOARD_FAB2(SCH_1):TP_CPU0_RSVD_23
  U5D1 DW44 RSVD<23> SKX_EXT_B_BGA1-IC,TBD   I127 @BASEBOARD_FAB2_LIB.BASEBOARD_FAB2(SCH_1):PAGE39

TP_CPU0_RSVD_230 @BASEBOARD_FAB2_LIB.BASEBOARD_FAB2(SCH_1):TP_CPU0_RSVD_230
  U5D1 AH57 RSVD<230> SKX_EXT_B_BGA1-IC,TBD   I204 @BASEBOARD_FAB2_LIB.BASEBOARD_FAB2(SCH_1):PAGE22

TP_CPU0_RSVD_231 @BASEBOARD_FAB2_LIB.BASEBOARD_FAB2(SCH_1):TP_CPU0_RSVD_231
  U5D1 AH55 RSVD<231> SKX_EXT_B_BGA1-IC,TBD   I204 @BASEBOARD_FAB2_LIB.BASEBOARD_FAB2(SCH_1):PAGE22

TP_CPU0_RSVD_232 @BASEBOARD_FAB2_LIB.BASEBOARD_FAB2(SCH_1):TP_CPU0_RSVD_232
  U5D1 AH19 RSVD<232> SKX_EXT_B_BGA1-IC,TBD   I204 @BASEBOARD_FAB2_LIB.BASEBOARD_FAB2(SCH_1):PAGE22

TP_CPU0_RSVD_233 @BASEBOARD_FAB2_LIB.BASEBOARD_FAB2(SCH_1):TP_CPU0_RSVD_233
  U5D1 AH15 RSVD<233> SKX_EXT_B_BGA1-IC,TBD   I204 @BASEBOARD_FAB2_LIB.BASEBOARD_FAB2(SCH_1):PAGE22

TP_CPU0_RSVD_234 @BASEBOARD_FAB2_LIB.BASEBOARD_FAB2(SCH_1):TP_CPU0_RSVD_234
  U5D1 AG72 RSVD<234> SKX_EXT_B_BGA1-IC,TBD   I204 @BASEBOARD_FAB2_LIB.BASEBOARD_FAB2(SCH_1):PAGE22

TP_CPU0_RSVD_235 @BASEBOARD_FAB2_LIB.BASEBOARD_FAB2(SCH_1):TP_CPU0_RSVD_235
  U5D1 AG56 RSVD<235> SKX_EXT_B_BGA1-IC,TBD   I204 @BASEBOARD_FAB2_LIB.BASEBOARD_FAB2(SCH_1):PAGE22

TP_CPU0_RSVD_236 @BASEBOARD_FAB2_LIB.BASEBOARD_FAB2(SCH_1):TP_CPU0_RSVD_236
  U5D1 AG54 RSVD<236> SKX_EXT_B_BGA1-IC,TBD   I204 @BASEBOARD_FAB2_LIB.BASEBOARD_FAB2(SCH_1):PAGE22

TP_CPU0_RSVD_237 @BASEBOARD_FAB2_LIB.BASEBOARD_FAB2(SCH_1):TP_CPU0_RSVD_237
  U5D1 AG52 RSVD<237> SKX_EXT_B_BGA1-IC,TBD   I204 @BASEBOARD_FAB2_LIB.BASEBOARD_FAB2(SCH_1):PAGE22

TP_CPU0_RSVD_238 @BASEBOARD_FAB2_LIB.BASEBOARD_FAB2(SCH_1):TP_CPU0_RSVD_238
  U5D1 AG50 RSVD<238> SKX_EXT_B_BGA1-IC,TBD   I204 @BASEBOARD_FAB2_LIB.BASEBOARD_FAB2(SCH_1):PAGE22

TP_CPU0_RSVD_239 @BASEBOARD_FAB2_LIB.BASEBOARD_FAB2(SCH_1):TP_CPU0_RSVD_239
  U5D1 AG48 RSVD<239> SKX_EXT_B_BGA1-IC,TBD   I204 @BASEBOARD_FAB2_LIB.BASEBOARD_FAB2(SCH_1):PAGE22

TP_CPU0_RSVD_24 @BASEBOARD_FAB2_LIB.BASEBOARD_FAB2(SCH_1):TP_CPU0_RSVD_24
  U5D1 DV71 RSVD<24> SKX_EXT_B_BGA1-IC,TBD   I127 @BASEBOARD_FAB2_LIB.BASEBOARD_FAB2(SCH_1):PAGE39

TP_CPU0_RSVD_240 @BASEBOARD_FAB2_LIB.BASEBOARD_FAB2(SCH_1):TP_CPU0_RSVD_240
  U5D1 AG20 RSVD<240> SKX_EXT_B_BGA1-IC,TBD   I204 @BASEBOARD_FAB2_LIB.BASEBOARD_FAB2(SCH_1):PAGE22

TP_CPU0_RSVD_241 @BASEBOARD_FAB2_LIB.BASEBOARD_FAB2(SCH_1):TP_CPU0_RSVD_241
  U5D1 AF71 RSVD<241> SKX_EXT_B_BGA1-IC,TBD   I204 @BASEBOARD_FAB2_LIB.BASEBOARD_FAB2(SCH_1):PAGE22

TP_CPU0_RSVD_242 @BASEBOARD_FAB2_LIB.BASEBOARD_FAB2(SCH_1):TP_CPU0_RSVD_242
  U5D1 AF53 RSVD<242> SKX_EXT_B_BGA1-IC,TBD   I204 @BASEBOARD_FAB2_LIB.BASEBOARD_FAB2(SCH_1):PAGE22

TP_CPU0_RSVD_243 @BASEBOARD_FAB2_LIB.BASEBOARD_FAB2(SCH_1):TP_CPU0_RSVD_243
  U5D1 AF51 RSVD<243> SKX_EXT_B_BGA1-IC,TBD   I204 @BASEBOARD_FAB2_LIB.BASEBOARD_FAB2(SCH_1):PAGE22

TP_CPU0_RSVD_244 @BASEBOARD_FAB2_LIB.BASEBOARD_FAB2(SCH_1):TP_CPU0_RSVD_244
  U5D1 AF49 RSVD<244> SKX_EXT_B_BGA1-IC,TBD   I204 @BASEBOARD_FAB2_LIB.BASEBOARD_FAB2(SCH_1):PAGE22

TP_CPU0_RSVD_245 @BASEBOARD_FAB2_LIB.BASEBOARD_FAB2(SCH_1):TP_CPU0_RSVD_245
  U5D1 AF47 RSVD<245> SKX_EXT_B_BGA1-IC,TBD   I204 @BASEBOARD_FAB2_LIB.BASEBOARD_FAB2(SCH_1):PAGE22

TP_CPU0_RSVD_246 @BASEBOARD_FAB2_LIB.BASEBOARD_FAB2(SCH_1):TP_CPU0_RSVD_246
  U5D1 AF19 RSVD<246> SKX_EXT_B_BGA1-IC,TBD   I204 @BASEBOARD_FAB2_LIB.BASEBOARD_FAB2(SCH_1):PAGE22

TP_CPU0_RSVD_247 @BASEBOARD_FAB2_LIB.BASEBOARD_FAB2(SCH_1):TP_CPU0_RSVD_247
  U5D1 AE72 RSVD<247> SKX_EXT_B_BGA1-IC,TBD   I204 @BASEBOARD_FAB2_LIB.BASEBOARD_FAB2(SCH_1):PAGE22

TP_CPU0_RSVD_248 @BASEBOARD_FAB2_LIB.BASEBOARD_FAB2(SCH_1):TP_CPU0_RSVD_248
  U5D1 AE52 RSVD<248> SKX_EXT_B_BGA1-IC,TBD   I204 @BASEBOARD_FAB2_LIB.BASEBOARD_FAB2(SCH_1):PAGE22

TP_CPU0_RSVD_249 @BASEBOARD_FAB2_LIB.BASEBOARD_FAB2(SCH_1):TP_CPU0_RSVD_249
  U5D1 AE50 RSVD<249> SKX_EXT_B_BGA1-IC,TBD   I204 @BASEBOARD_FAB2_LIB.BASEBOARD_FAB2(SCH_1):PAGE22

TP_CPU0_RSVD_25 @BASEBOARD_FAB2_LIB.BASEBOARD_FAB2(SCH_1):TP_CPU0_RSVD_25
  U5D1 DV61 RSVD<25> SKX_EXT_B_BGA1-IC,TBD   I127 @BASEBOARD_FAB2_LIB.BASEBOARD_FAB2(SCH_1):PAGE39

TP_CPU0_RSVD_250 @BASEBOARD_FAB2_LIB.BASEBOARD_FAB2(SCH_1):TP_CPU0_RSVD_250
  U5D1 AE48 RSVD<250> SKX_EXT_B_BGA1-IC,TBD   I204 @BASEBOARD_FAB2_LIB.BASEBOARD_FAB2(SCH_1):PAGE22

TP_CPU0_RSVD_251 @BASEBOARD_FAB2_LIB.BASEBOARD_FAB2(SCH_1):TP_CPU0_RSVD_251
  U5D1 AE46 RSVD<251> SKX_EXT_B_BGA1-IC,TBD   I204 @BASEBOARD_FAB2_LIB.BASEBOARD_FAB2(SCH_1):PAGE22

TP_CPU0_RSVD_252 @BASEBOARD_FAB2_LIB.BASEBOARD_FAB2(SCH_1):TP_CPU0_RSVD_252
  U5D1 AD51 RSVD<252> SKX_EXT_B_BGA1-IC,TBD   I204 @BASEBOARD_FAB2_LIB.BASEBOARD_FAB2(SCH_1):PAGE22

TP_CPU0_RSVD_253 @BASEBOARD_FAB2_LIB.BASEBOARD_FAB2(SCH_1):TP_CPU0_RSVD_253
  U5D1 AD49 RSVD<253> SKX_EXT_B_BGA1-IC,TBD   I204 @BASEBOARD_FAB2_LIB.BASEBOARD_FAB2(SCH_1):PAGE22

TP_CPU0_RSVD_254 @BASEBOARD_FAB2_LIB.BASEBOARD_FAB2(SCH_1):TP_CPU0_RSVD_254
  U5D1 AD47 RSVD<254> SKX_EXT_B_BGA1-IC,TBD   I204 @BASEBOARD_FAB2_LIB.BASEBOARD_FAB2(SCH_1):PAGE22

TP_CPU0_RSVD_255 @BASEBOARD_FAB2_LIB.BASEBOARD_FAB2(SCH_1):TP_CPU0_RSVD_255
  U5D1 AY83 RSVD<255> SKX_EXT_B_BGA1-IC,TBD    I15 @BASEBOARD_FAB2_LIB.BASEBOARD_FAB2(SCH_1):PAGE36

TP_CPU0_RSVD_256 @BASEBOARD_FAB2_LIB.BASEBOARD_FAB2(SCH_1):TP_CPU0_RSVD_256
  U5D1  Y65 RSVD<256> SKX_EXT_B_BGA1-IC,TBD   I204 @BASEBOARD_FAB2_LIB.BASEBOARD_FAB2(SCH_1):PAGE22

TP_CPU0_RSVD_258 @BASEBOARD_FAB2_LIB.BASEBOARD_FAB2(SCH_1):TP_CPU0_RSVD_258
  U5D1  W66 RSVD<258> SKX_EXT_B_BGA1-IC,TBD   I204 @BASEBOARD_FAB2_LIB.BASEBOARD_FAB2(SCH_1):PAGE22

TP_CPU0_RSVD_259 @BASEBOARD_FAB2_LIB.BASEBOARD_FAB2(SCH_1):TP_CPU0_RSVD_259
  U5D1  V67 RSVD<259> SKX_EXT_B_BGA1-IC,TBD   I204 @BASEBOARD_FAB2_LIB.BASEBOARD_FAB2(SCH_1):PAGE22

TP_CPU0_RSVD_26 @BASEBOARD_FAB2_LIB.BASEBOARD_FAB2(SCH_1):TP_CPU0_RSVD_26
  U5D1 DU44 RSVD<26> SKX_EXT_B_BGA1-IC,TBD   I127 @BASEBOARD_FAB2_LIB.BASEBOARD_FAB2(SCH_1):PAGE39

TP_CPU0_RSVD_260 @BASEBOARD_FAB2_LIB.BASEBOARD_FAB2(SCH_1):TP_CPU0_RSVD_260
  U5D1  V65 RSVD<260> SKX_EXT_B_BGA1-IC,TBD   I204 @BASEBOARD_FAB2_LIB.BASEBOARD_FAB2(SCH_1):PAGE22

TP_CPU0_RSVD_261 @BASEBOARD_FAB2_LIB.BASEBOARD_FAB2(SCH_1):TP_CPU0_RSVD_261
  U5D1  U66 RSVD<261> SKX_EXT_B_BGA1-IC,TBD   I204 @BASEBOARD_FAB2_LIB.BASEBOARD_FAB2(SCH_1):PAGE22

TP_CPU0_RSVD_262 @BASEBOARD_FAB2_LIB.BASEBOARD_FAB2(SCH_1):TP_CPU0_RSVD_262
  U5D1  T67 RSVD<262> SKX_EXT_B_BGA1-IC,TBD   I204 @BASEBOARD_FAB2_LIB.BASEBOARD_FAB2(SCH_1):PAGE22

TP_CPU0_RSVD_263 @BASEBOARD_FAB2_LIB.BASEBOARD_FAB2(SCH_1):TP_CPU0_RSVD_263
  U5D1  R66 RSVD<263> SKX_EXT_B_BGA1-IC,TBD   I204 @BASEBOARD_FAB2_LIB.BASEBOARD_FAB2(SCH_1):PAGE22

TP_CPU0_RSVD_264 @BASEBOARD_FAB2_LIB.BASEBOARD_FAB2(SCH_1):TP_CPU0_RSVD_264
  U5D1  R62 RSVD<264> SKX_EXT_B_BGA1-IC,TBD   I204 @BASEBOARD_FAB2_LIB.BASEBOARD_FAB2(SCH_1):PAGE22

TP_CPU0_RSVD_265 @BASEBOARD_FAB2_LIB.BASEBOARD_FAB2(SCH_1):TP_CPU0_RSVD_265
  U5D1  P65 RSVD<265> SKX_EXT_B_BGA1-IC,TBD   I204 @BASEBOARD_FAB2_LIB.BASEBOARD_FAB2(SCH_1):PAGE22

TP_CPU0_RSVD_266 @BASEBOARD_FAB2_LIB.BASEBOARD_FAB2(SCH_1):TP_CPU0_RSVD_266
  U5D1  M63 RSVD<266> SKX_EXT_B_BGA1-IC,TBD   I204 @BASEBOARD_FAB2_LIB.BASEBOARD_FAB2(SCH_1):PAGE22

TP_CPU0_RSVD_267 @BASEBOARD_FAB2_LIB.BASEBOARD_FAB2(SCH_1):TP_CPU0_RSVD_267
  U5D1  K61 RSVD<267> SKX_EXT_B_BGA1-IC,TBD   I204 @BASEBOARD_FAB2_LIB.BASEBOARD_FAB2(SCH_1):PAGE22

TP_CPU0_RSVD_268 @BASEBOARD_FAB2_LIB.BASEBOARD_FAB2(SCH_1):TP_CPU0_RSVD_268
  U5D1  J62 RSVD<268> SKX_EXT_B_BGA1-IC,TBD   I204 @BASEBOARD_FAB2_LIB.BASEBOARD_FAB2(SCH_1):PAGE22

TP_CPU0_RSVD_269 @BASEBOARD_FAB2_LIB.BASEBOARD_FAB2(SCH_1):TP_CPU0_RSVD_269
  U5D1  J46 RSVD<269> SKX_EXT_B_BGA1-IC,TBD   I204 @BASEBOARD_FAB2_LIB.BASEBOARD_FAB2(SCH_1):PAGE22

TP_CPU0_RSVD_27 @BASEBOARD_FAB2_LIB.BASEBOARD_FAB2(SCH_1):TP_CPU0_RSVD_27
  U5D1 DT71 RSVD<27> SKX_EXT_B_BGA1-IC,TBD   I127 @BASEBOARD_FAB2_LIB.BASEBOARD_FAB2(SCH_1):PAGE39

TP_CPU0_RSVD_270 @BASEBOARD_FAB2_LIB.BASEBOARD_FAB2(SCH_1):TP_CPU0_RSVD_270
  U5D1  H85 RSVD<270> SKX_EXT_B_BGA1-IC,TBD   I204 @BASEBOARD_FAB2_LIB.BASEBOARD_FAB2(SCH_1):PAGE22

TP_CPU0_RSVD_271 @BASEBOARD_FAB2_LIB.BASEBOARD_FAB2(SCH_1):TP_CPU0_RSVD_271
  U5D1  H83 RSVD<271> SKX_EXT_B_BGA1-IC,TBD   I204 @BASEBOARD_FAB2_LIB.BASEBOARD_FAB2(SCH_1):PAGE22

TP_CPU0_RSVD_272 @BASEBOARD_FAB2_LIB.BASEBOARD_FAB2(SCH_1):TP_CPU0_RSVD_272
  U5D1   H1 RSVD<272> SKX_EXT_B_BGA1-IC,TBD   I204 @BASEBOARD_FAB2_LIB.BASEBOARD_FAB2(SCH_1):PAGE22

TP_CPU0_RSVD_273 @BASEBOARD_FAB2_LIB.BASEBOARD_FAB2(SCH_1):TP_CPU0_RSVD_273
  U5D1  G84 RSVD<273> SKX_EXT_B_BGA1-IC,TBD   I204 @BASEBOARD_FAB2_LIB.BASEBOARD_FAB2(SCH_1):PAGE22

TP_CPU0_RSVD_274 @BASEBOARD_FAB2_LIB.BASEBOARD_FAB2(SCH_1):TP_CPU0_RSVD_274
  U5D1  G64 RSVD<274> SKX_EXT_B_BGA1-IC,TBD   I204 @BASEBOARD_FAB2_LIB.BASEBOARD_FAB2(SCH_1):PAGE22

TP_CPU0_RSVD_275 @BASEBOARD_FAB2_LIB.BASEBOARD_FAB2(SCH_1):TP_CPU0_RSVD_275
  U5D1   G2 RSVD<275> SKX_EXT_B_BGA1-IC,TBD   I204 @BASEBOARD_FAB2_LIB.BASEBOARD_FAB2(SCH_1):PAGE22

TP_CPU0_RSVD_276 @BASEBOARD_FAB2_LIB.BASEBOARD_FAB2(SCH_1):TP_CPU0_RSVD_276
  U5D1  F83 RSVD<276> SKX_EXT_B_BGA1-IC,TBD   I204 @BASEBOARD_FAB2_LIB.BASEBOARD_FAB2(SCH_1):PAGE22

TP_CPU0_RSVD_277 @BASEBOARD_FAB2_LIB.BASEBOARD_FAB2(SCH_1):TP_CPU0_RSVD_277
  U5D1  F65 RSVD<277> SKX_EXT_B_BGA1-IC,TBD   I204 @BASEBOARD_FAB2_LIB.BASEBOARD_FAB2(SCH_1):PAGE22

TP_CPU0_RSVD_278 @BASEBOARD_FAB2_LIB.BASEBOARD_FAB2(SCH_1):TP_CPU0_RSVD_278
  U5D1  F23 RSVD<278> SKX_EXT_B_BGA1-IC,TBD   I204 @BASEBOARD_FAB2_LIB.BASEBOARD_FAB2(SCH_1):PAGE22

TP_CPU0_RSVD_279 @BASEBOARD_FAB2_LIB.BASEBOARD_FAB2(SCH_1):TP_CPU0_RSVD_279
  U5D1   F3 RSVD<279> SKX_EXT_B_BGA1-IC,TBD   I204 @BASEBOARD_FAB2_LIB.BASEBOARD_FAB2(SCH_1):PAGE22

TP_CPU0_RSVD_28 @BASEBOARD_FAB2_LIB.BASEBOARD_FAB2(SCH_1):TP_CPU0_RSVD_28
  U5D1 DR44 RSVD<28> SKX_EXT_B_BGA1-IC,TBD   I127 @BASEBOARD_FAB2_LIB.BASEBOARD_FAB2(SCH_1):PAGE39

TP_CPU0_RSVD_280 @BASEBOARD_FAB2_LIB.BASEBOARD_FAB2(SCH_1):TP_CPU0_RSVD_280
  U5D1  E84 RSVD<280> SKX_EXT_B_BGA1-IC,TBD   I204 @BASEBOARD_FAB2_LIB.BASEBOARD_FAB2(SCH_1):PAGE22

TP_CPU0_RSVD_281 @BASEBOARD_FAB2_LIB.BASEBOARD_FAB2(SCH_1):TP_CPU0_RSVD_281
  U5D1  E24 RSVD<281> SKX_EXT_B_BGA1-IC,TBD   I204 @BASEBOARD_FAB2_LIB.BASEBOARD_FAB2(SCH_1):PAGE22

TP_CPU0_RSVD_282 @BASEBOARD_FAB2_LIB.BASEBOARD_FAB2(SCH_1):TP_CPU0_RSVD_282
  U5D1   E4 RSVD<282> SKX_EXT_B_BGA1-IC,TBD   I204 @BASEBOARD_FAB2_LIB.BASEBOARD_FAB2(SCH_1):PAGE22

TP_CPU0_RSVD_283 @BASEBOARD_FAB2_LIB.BASEBOARD_FAB2(SCH_1):TP_CPU0_RSVD_283
  U5D1   E2 RSVD<283> SKX_EXT_B_BGA1-IC,TBD   I204 @BASEBOARD_FAB2_LIB.BASEBOARD_FAB2(SCH_1):PAGE22

TP_CPU0_RSVD_284 @BASEBOARD_FAB2_LIB.BASEBOARD_FAB2(SCH_1):TP_CPU0_RSVD_284
  U5D1  D83 RSVD<284> SKX_EXT_B_BGA1-IC,TBD   I204 @BASEBOARD_FAB2_LIB.BASEBOARD_FAB2(SCH_1):PAGE22

TP_CPU0_RSVD_285 @BASEBOARD_FAB2_LIB.BASEBOARD_FAB2(SCH_1):TP_CPU0_RSVD_285
  U5D1  D65 RSVD<285> SKX_EXT_B_BGA1-IC,TBD   I204 @BASEBOARD_FAB2_LIB.BASEBOARD_FAB2(SCH_1):PAGE22

TP_CPU0_RSVD_286 @BASEBOARD_FAB2_LIB.BASEBOARD_FAB2(SCH_1):TP_CPU0_RSVD_286
  U5D1  D17 RSVD<286> SKX_EXT_B_BGA1-IC,TBD   I204 @BASEBOARD_FAB2_LIB.BASEBOARD_FAB2(SCH_1):PAGE22

TP_CPU0_RSVD_287 @BASEBOARD_FAB2_LIB.BASEBOARD_FAB2(SCH_1):TP_CPU0_RSVD_287
  U5D1   D5 RSVD<287> SKX_EXT_B_BGA1-IC,TBD   I204 @BASEBOARD_FAB2_LIB.BASEBOARD_FAB2(SCH_1):PAGE22

TP_CPU0_RSVD_288 @BASEBOARD_FAB2_LIB.BASEBOARD_FAB2(SCH_1):TP_CPU0_RSVD_288
  U5D1  C82 RSVD<288> SKX_EXT_B_BGA1-IC,TBD   I204 @BASEBOARD_FAB2_LIB.BASEBOARD_FAB2(SCH_1):PAGE22

TP_CPU0_RSVD_289 @BASEBOARD_FAB2_LIB.BASEBOARD_FAB2(SCH_1):TP_CPU0_RSVD_289
  U5D1  C24 RSVD<289> SKX_EXT_B_BGA1-IC,TBD   I204 @BASEBOARD_FAB2_LIB.BASEBOARD_FAB2(SCH_1):PAGE22

TP_CPU0_RSVD_29 @BASEBOARD_FAB2_LIB.BASEBOARD_FAB2(SCH_1):TP_CPU0_RSVD_29
  U5D1 DP65 RSVD<29> SKX_EXT_B_BGA1-IC,TBD   I127 @BASEBOARD_FAB2_LIB.BASEBOARD_FAB2(SCH_1):PAGE39

TP_CPU0_RSVD_290 @BASEBOARD_FAB2_LIB.BASEBOARD_FAB2(SCH_1):TP_CPU0_RSVD_290
  U5D1  C18 RSVD<290> SKX_EXT_B_BGA1-IC,TBD   I204 @BASEBOARD_FAB2_LIB.BASEBOARD_FAB2(SCH_1):PAGE22

TP_CPU0_RSVD_291 @BASEBOARD_FAB2_LIB.BASEBOARD_FAB2(SCH_1):TP_CPU0_RSVD_291
  U5D1   C6 RSVD<291> SKX_EXT_B_BGA1-IC,TBD   I204 @BASEBOARD_FAB2_LIB.BASEBOARD_FAB2(SCH_1):PAGE22

TP_CPU0_RSVD_292 @BASEBOARD_FAB2_LIB.BASEBOARD_FAB2(SCH_1):TP_CPU0_RSVD_292
  U5D1  B81 RSVD<292> SKX_EXT_B_BGA1-IC,TBD   I204 @BASEBOARD_FAB2_LIB.BASEBOARD_FAB2(SCH_1):PAGE22

TP_CPU0_RSVD_293 @BASEBOARD_FAB2_LIB.BASEBOARD_FAB2(SCH_1):TP_CPU0_RSVD_293
  U5D1  B77 RSVD<293> SKX_EXT_B_BGA1-IC,TBD   I204 @BASEBOARD_FAB2_LIB.BASEBOARD_FAB2(SCH_1):PAGE22

TP_CPU0_RSVD_298 @BASEBOARD_FAB2_LIB.BASEBOARD_FAB2(SCH_1):TP_CPU0_RSVD_298
  U5D1   B7 RSVD<298> SKX_EXT_B_BGA1-IC,TBD   I204 @BASEBOARD_FAB2_LIB.BASEBOARD_FAB2(SCH_1):PAGE22

TP_CPU0_RSVD_299 @BASEBOARD_FAB2_LIB.BASEBOARD_FAB2(SCH_1):TP_CPU0_RSVD_299
  U5D1   B3 RSVD<299> SKX_EXT_B_BGA1-IC,TBD   I204 @BASEBOARD_FAB2_LIB.BASEBOARD_FAB2(SCH_1):PAGE22

TP_CPU0_RSVD_3 @BASEBOARD_FAB2_LIB.BASEBOARD_FAB2(SCH_1):TP_CPU0_RSVD_3
  U5D1 EF47 RSVD<3> SKX_EXT_B_BGA1-IC,TBD   I127 @BASEBOARD_FAB2_LIB.BASEBOARD_FAB2(SCH_1):PAGE39

TP_CPU0_RSVD_30 @BASEBOARD_FAB2_LIB.BASEBOARD_FAB2(SCH_1):TP_CPU0_RSVD_30
  U5D1 DP17 RSVD<30> SKX_EXT_B_BGA1-IC,TBD   I127 @BASEBOARD_FAB2_LIB.BASEBOARD_FAB2(SCH_1):PAGE39

TP_CPU0_RSVD_300 @BASEBOARD_FAB2_LIB.BASEBOARD_FAB2(SCH_1):TP_CPU0_RSVD_300
  U5D1  A24 RSVD<300> SKX_EXT_B_BGA1-IC,TBD   I204 @BASEBOARD_FAB2_LIB.BASEBOARD_FAB2(SCH_1):PAGE22

TP_CPU0_RSVD_303 @BASEBOARD_FAB2_LIB.BASEBOARD_FAB2(SCH_1):TP_CPU0_RSVD_303
  U5D1   A6 RSVD<303> SKX_EXT_B_BGA1-IC,TBD   I204 @BASEBOARD_FAB2_LIB.BASEBOARD_FAB2(SCH_1):PAGE22

TP_CPU0_RSVD_304 @BASEBOARD_FAB2_LIB.BASEBOARD_FAB2(SCH_1):TP_CPU0_RSVD_304
  U5D1   A4 RSVD<304> SKX_EXT_B_BGA1-IC,TBD   I204 @BASEBOARD_FAB2_LIB.BASEBOARD_FAB2(SCH_1):PAGE22

TP_CPU0_RSVD_31 @BASEBOARD_FAB2_LIB.BASEBOARD_FAB2(SCH_1):TP_CPU0_RSVD_31
  U5D1 DN66 RSVD<31> SKX_EXT_B_BGA1-IC,TBD   I127 @BASEBOARD_FAB2_LIB.BASEBOARD_FAB2(SCH_1):PAGE39

TP_CPU0_RSVD_32 @BASEBOARD_FAB2_LIB.BASEBOARD_FAB2(SCH_1):TP_CPU0_RSVD_32
  U5D1 DN62 RSVD<32> SKX_EXT_B_BGA1-IC,TBD   I127 @BASEBOARD_FAB2_LIB.BASEBOARD_FAB2(SCH_1):PAGE39

TP_CPU0_RSVD_33 @BASEBOARD_FAB2_LIB.BASEBOARD_FAB2(SCH_1):TP_CPU0_RSVD_33
  U5D1 DM67 RSVD<33> SKX_EXT_B_BGA1-IC,TBD   I127 @BASEBOARD_FAB2_LIB.BASEBOARD_FAB2(SCH_1):PAGE39

TP_CPU0_RSVD_34 @BASEBOARD_FAB2_LIB.BASEBOARD_FAB2(SCH_1):TP_CPU0_RSVD_34
  U5D1 DL66 RSVD<34> SKX_EXT_B_BGA1-IC,TBD   I127 @BASEBOARD_FAB2_LIB.BASEBOARD_FAB2(SCH_1):PAGE39

TP_CPU0_RSVD_35 @BASEBOARD_FAB2_LIB.BASEBOARD_FAB2(SCH_1):TP_CPU0_RSVD_35
  U5D1 DL38 RSVD<35> SKX_EXT_B_BGA1-IC,TBD   I127 @BASEBOARD_FAB2_LIB.BASEBOARD_FAB2(SCH_1):PAGE39

TP_CPU0_RSVD_36 @BASEBOARD_FAB2_LIB.BASEBOARD_FAB2(SCH_1):TP_CPU0_RSVD_36
  U5D1 DK67 RSVD<36> SKX_EXT_B_BGA1-IC,TBD   I127 @BASEBOARD_FAB2_LIB.BASEBOARD_FAB2(SCH_1):PAGE39

TP_CPU0_RSVD_37 @BASEBOARD_FAB2_LIB.BASEBOARD_FAB2(SCH_1):TP_CPU0_RSVD_37
  U5D1 DK65 RSVD<37> SKX_EXT_B_BGA1-IC,TBD   I127 @BASEBOARD_FAB2_LIB.BASEBOARD_FAB2(SCH_1):PAGE39

TP_CPU0_RSVD_38 @BASEBOARD_FAB2_LIB.BASEBOARD_FAB2(SCH_1):TP_CPU0_RSVD_38
  U5D1 DK37 RSVD<38> SKX_EXT_B_BGA1-IC,TBD   I127 @BASEBOARD_FAB2_LIB.BASEBOARD_FAB2(SCH_1):PAGE39

TP_CPU0_RSVD_39 @BASEBOARD_FAB2_LIB.BASEBOARD_FAB2(SCH_1):TP_CPU0_RSVD_39
  U5D1 DK15 RSVD<39> SKX_EXT_B_BGA1-IC,TBD   I127 @BASEBOARD_FAB2_LIB.BASEBOARD_FAB2(SCH_1):PAGE39

TP_CPU0_RSVD_4 @BASEBOARD_FAB2_LIB.BASEBOARD_FAB2(SCH_1):TP_CPU0_RSVD_4
  U5D1 EE84 RSVD<4> SKX_EXT_B_BGA1-IC,TBD   I127 @BASEBOARD_FAB2_LIB.BASEBOARD_FAB2(SCH_1):PAGE39

TP_CPU0_RSVD_40 @BASEBOARD_FAB2_LIB.BASEBOARD_FAB2(SCH_1):TP_CPU0_RSVD_40
  U5D1 DJ66 RSVD<40> SKX_EXT_B_BGA1-IC,TBD   I127 @BASEBOARD_FAB2_LIB.BASEBOARD_FAB2(SCH_1):PAGE39

TP_CPU0_RSVD_41 @BASEBOARD_FAB2_LIB.BASEBOARD_FAB2(SCH_1):TP_CPU0_RSVD_41
  U5D1 DJ36 RSVD<41> SKX_EXT_B_BGA1-IC,TBD   I127 @BASEBOARD_FAB2_LIB.BASEBOARD_FAB2(SCH_1):PAGE39

TP_CPU0_RSVD_42 @BASEBOARD_FAB2_LIB.BASEBOARD_FAB2(SCH_1):TP_CPU0_RSVD_42
  U5D1 DH65 RSVD<42> SKX_EXT_B_BGA1-IC,TBD   I127 @BASEBOARD_FAB2_LIB.BASEBOARD_FAB2(SCH_1):PAGE39

TP_CPU0_RSVD_43 @BASEBOARD_FAB2_LIB.BASEBOARD_FAB2(SCH_1):TP_CPU0_RSVD_43
  U5D1 DG64 RSVD<43> SKX_EXT_B_BGA1-IC,TBD   I127 @BASEBOARD_FAB2_LIB.BASEBOARD_FAB2(SCH_1):PAGE39

TP_CPU0_RSVD_44 @BASEBOARD_FAB2_LIB.BASEBOARD_FAB2(SCH_1):TP_CPU0_RSVD_44
  U5D1 DG36 RSVD<44> SKX_EXT_B_BGA1-IC,TBD   I127 @BASEBOARD_FAB2_LIB.BASEBOARD_FAB2(SCH_1):PAGE39

TP_CPU0_RSVD_45 @BASEBOARD_FAB2_LIB.BASEBOARD_FAB2(SCH_1):TP_CPU0_RSVD_45
  U5D1 DD51 RSVD<45> SKX_EXT_B_BGA1-IC,TBD   I127 @BASEBOARD_FAB2_LIB.BASEBOARD_FAB2(SCH_1):PAGE39

TP_CPU0_RSVD_46 @BASEBOARD_FAB2_LIB.BASEBOARD_FAB2(SCH_1):TP_CPU0_RSVD_46
  U5D1 DC52 RSVD<46> SKX_EXT_B_BGA1-IC,TBD   I127 @BASEBOARD_FAB2_LIB.BASEBOARD_FAB2(SCH_1):PAGE39

TP_CPU0_RSVD_47 @BASEBOARD_FAB2_LIB.BASEBOARD_FAB2(SCH_1):TP_CPU0_RSVD_47
  U5D1 DC46 RSVD<47> SKX_EXT_B_BGA1-IC,TBD   I127 @BASEBOARD_FAB2_LIB.BASEBOARD_FAB2(SCH_1):PAGE39

TP_CPU0_RSVD_48 @BASEBOARD_FAB2_LIB.BASEBOARD_FAB2(SCH_1):TP_CPU0_RSVD_48
  U5D1 DA56 RSVD<48> SKX_EXT_B_BGA1-IC,TBD   I127 @BASEBOARD_FAB2_LIB.BASEBOARD_FAB2(SCH_1):PAGE39

TP_CPU0_RSVD_49 @BASEBOARD_FAB2_LIB.BASEBOARD_FAB2(SCH_1):TP_CPU0_RSVD_49
  U5D1 DA54 RSVD<49> SKX_EXT_B_BGA1-IC,TBD   I127 @BASEBOARD_FAB2_LIB.BASEBOARD_FAB2(SCH_1):PAGE39

TP_CPU0_RSVD_5 @BASEBOARD_FAB2_LIB.BASEBOARD_FAB2(SCH_1):TP_CPU0_RSVD_5
  U5D1 EE82 RSVD<5> SKX_EXT_B_BGA1-IC,TBD   I127 @BASEBOARD_FAB2_LIB.BASEBOARD_FAB2(SCH_1):PAGE39

TP_CPU0_RSVD_50 @BASEBOARD_FAB2_LIB.BASEBOARD_FAB2(SCH_1):TP_CPU0_RSVD_50
  U5D1 DA52 RSVD<50> SKX_EXT_B_BGA1-IC,TBD   I127 @BASEBOARD_FAB2_LIB.BASEBOARD_FAB2(SCH_1):PAGE39

TP_CPU0_RSVD_51 @BASEBOARD_FAB2_LIB.BASEBOARD_FAB2(SCH_1):TP_CPU0_RSVD_51
  U5D1 DA40 RSVD<51> SKX_EXT_B_BGA1-IC,TBD   I127 @BASEBOARD_FAB2_LIB.BASEBOARD_FAB2(SCH_1):PAGE39

TP_CPU0_RSVD_53 @BASEBOARD_FAB2_LIB.BASEBOARD_FAB2(SCH_1):TP_CPU0_RSVD_53
  U5D1 CY73 RSVD<53> SKX_EXT_B_BGA1-IC,TBD   I127 @BASEBOARD_FAB2_LIB.BASEBOARD_FAB2(SCH_1):PAGE39

TP_CPU0_RSVD_54 @BASEBOARD_FAB2_LIB.BASEBOARD_FAB2(SCH_1):TP_CPU0_RSVD_54
  U5D1 CY63 RSVD<54> SKX_EXT_B_BGA1-IC,TBD   I127 @BASEBOARD_FAB2_LIB.BASEBOARD_FAB2(SCH_1):PAGE39

TP_CPU0_RSVD_55 @BASEBOARD_FAB2_LIB.BASEBOARD_FAB2(SCH_1):TP_CPU0_RSVD_55
  U5D1 CY57 RSVD<55> SKX_EXT_B_BGA1-IC,TBD   I127 @BASEBOARD_FAB2_LIB.BASEBOARD_FAB2(SCH_1):PAGE39

TP_CPU0_RSVD_56 @BASEBOARD_FAB2_LIB.BASEBOARD_FAB2(SCH_1):TP_CPU0_RSVD_56
  U5D1 CY53 RSVD<56> SKX_EXT_B_BGA1-IC,TBD   I127 @BASEBOARD_FAB2_LIB.BASEBOARD_FAB2(SCH_1):PAGE39

TP_CPU0_RSVD_57 @BASEBOARD_FAB2_LIB.BASEBOARD_FAB2(SCH_1):TP_CPU0_RSVD_57
  U5D1 CY39 RSVD<57> SKX_EXT_B_BGA1-IC,TBD   I127 @BASEBOARD_FAB2_LIB.BASEBOARD_FAB2(SCH_1):PAGE39

TP_CPU0_RSVD_59 @BASEBOARD_FAB2_LIB.BASEBOARD_FAB2(SCH_1):TP_CPU0_RSVD_59
  U5D1 CY23 RSVD<59> SKX_EXT_B_BGA1-IC,TBD   I127 @BASEBOARD_FAB2_LIB.BASEBOARD_FAB2(SCH_1):PAGE39

TP_CPU0_RSVD_6 @BASEBOARD_FAB2_LIB.BASEBOARD_FAB2(SCH_1):TP_CPU0_RSVD_6
  U5D1  EE6 RSVD<6> SKX_EXT_B_BGA1-IC,TBD   I127 @BASEBOARD_FAB2_LIB.BASEBOARD_FAB2(SCH_1):PAGE39

TP_CPU0_RSVD_60 @BASEBOARD_FAB2_LIB.BASEBOARD_FAB2(SCH_1):TP_CPU0_RSVD_60
  U5D1 CW62 RSVD<60> SKX_EXT_B_BGA1-IC,TBD   I127 @BASEBOARD_FAB2_LIB.BASEBOARD_FAB2(SCH_1):PAGE39

TP_CPU0_RSVD_61 @BASEBOARD_FAB2_LIB.BASEBOARD_FAB2(SCH_1):TP_CPU0_RSVD_61
  U5D1 CW60 RSVD<61> SKX_EXT_B_BGA1-IC,TBD   I127 @BASEBOARD_FAB2_LIB.BASEBOARD_FAB2(SCH_1):PAGE39

TP_CPU0_RSVD_64 @BASEBOARD_FAB2_LIB.BASEBOARD_FAB2(SCH_1):TP_CPU0_RSVD_64
  U5D1 CV69 RSVD<64> SKX_EXT_B_BGA1-IC,TBD   I127 @BASEBOARD_FAB2_LIB.BASEBOARD_FAB2(SCH_1):PAGE39

TP_CPU0_RSVD_66 @BASEBOARD_FAB2_LIB.BASEBOARD_FAB2(SCH_1):TP_CPU0_RSVD_66
  U5D1 CU60 RSVD<66> SKX_EXT_B_BGA1-IC,TBD   I127 @BASEBOARD_FAB2_LIB.BASEBOARD_FAB2(SCH_1):PAGE39

TP_CPU0_RSVD_67 @BASEBOARD_FAB2_LIB.BASEBOARD_FAB2(SCH_1):TP_CPU0_RSVD_67
  U5D1  CU6 RSVD<67> SKX_EXT_B_BGA1-IC,TBD   I127 @BASEBOARD_FAB2_LIB.BASEBOARD_FAB2(SCH_1):PAGE39

TP_CPU0_RSVD_69 @BASEBOARD_FAB2_LIB.BASEBOARD_FAB2(SCH_1):TP_CPU0_RSVD_69
  U5D1 CT69 RSVD<69> SKX_EXT_B_BGA1-IC,TBD   I127 @BASEBOARD_FAB2_LIB.BASEBOARD_FAB2(SCH_1):PAGE39

TP_CPU0_RSVD_7 @BASEBOARD_FAB2_LIB.BASEBOARD_FAB2(SCH_1):TP_CPU0_RSVD_7
  U5D1 EE46 RSVD<7> SKX_EXT_B_BGA1-IC,TBD   I127 @BASEBOARD_FAB2_LIB.BASEBOARD_FAB2(SCH_1):PAGE39

TP_CPU0_RSVD_70 @BASEBOARD_FAB2_LIB.BASEBOARD_FAB2(SCH_1):TP_CPU0_RSVD_70
  U5D1  CT5 RSVD<70> SKX_EXT_B_BGA1-IC,TBD   I127 @BASEBOARD_FAB2_LIB.BASEBOARD_FAB2(SCH_1):PAGE39

TP_CPU0_RSVD_72 @BASEBOARD_FAB2_LIB.BASEBOARD_FAB2(SCH_1):TP_CPU0_RSVD_72
  U5D1 CR60 RSVD<72> SKX_EXT_B_BGA1-IC,TBD   I127 @BASEBOARD_FAB2_LIB.BASEBOARD_FAB2(SCH_1):PAGE39

TP_CPU0_RSVD_73 @BASEBOARD_FAB2_LIB.BASEBOARD_FAB2(SCH_1):TP_CPU0_RSVD_73
  U5D1 CP31 RSVD<73> SKX_EXT_B_BGA1-IC,TBD   I127 @BASEBOARD_FAB2_LIB.BASEBOARD_FAB2(SCH_1):PAGE39

TP_CPU0_RSVD_8 @BASEBOARD_FAB2_LIB.BASEBOARD_FAB2(SCH_1):TP_CPU0_RSVD_8
  U5D1 EE16 RSVD<8> SKX_EXT_B_BGA1-IC,TBD   I127 @BASEBOARD_FAB2_LIB.BASEBOARD_FAB2(SCH_1):PAGE39

TP_CPU0_RSVD_82 @BASEBOARD_FAB2_LIB.BASEBOARD_FAB2(SCH_1):TP_CPU0_RSVD_82
  U5D1 CK77 RSVD<82> SKX_EXT_B_BGA1-IC,TBD    I16 @BASEBOARD_FAB2_LIB.BASEBOARD_FAB2(SCH_1):PAGE36

TP_CPU0_RSVD_85 @BASEBOARD_FAB2_LIB.BASEBOARD_FAB2(SCH_1):TP_CPU0_RSVD_85
  U5D1 CK19 RSVD<85> SKX_EXT_B_BGA1-IC,TBD    I16 @BASEBOARD_FAB2_LIB.BASEBOARD_FAB2(SCH_1):PAGE36

TP_CPU0_RSVD_9 @BASEBOARD_FAB2_LIB.BASEBOARD_FAB2(SCH_1):TP_CPU0_RSVD_9
  U5D1 ED83 RSVD<9> SKX_EXT_B_BGA1-IC,TBD   I127 @BASEBOARD_FAB2_LIB.BASEBOARD_FAB2(SCH_1):PAGE39

TP_CPU0_RSVD_90 @BASEBOARD_FAB2_LIB.BASEBOARD_FAB2(SCH_1):TP_CPU0_RSVD_90
  U5D1 CH77 RSVD<90> SKX_EXT_B_BGA1-IC,TBD    I16 @BASEBOARD_FAB2_LIB.BASEBOARD_FAB2(SCH_1):PAGE36

TP_CPU0_RSVD_91 @BASEBOARD_FAB2_LIB.BASEBOARD_FAB2(SCH_1):TP_CPU0_RSVD_91
  U5D1 CH25 RSVD<91> SKX_EXT_B_BGA1-IC,TBD    I16 @BASEBOARD_FAB2_LIB.BASEBOARD_FAB2(SCH_1):PAGE36

TP_CPU0_RSVD_94 @BASEBOARD_FAB2_LIB.BASEBOARD_FAB2(SCH_1):TP_CPU0_RSVD_94
  U5D1 CG82 RSVD<94> SKX_EXT_B_BGA1-IC,TBD    I15 @BASEBOARD_FAB2_LIB.BASEBOARD_FAB2(SCH_1):PAGE36

TP_CPU0_RSVD_95 @BASEBOARD_FAB2_LIB.BASEBOARD_FAB2(SCH_1):TP_CPU0_RSVD_95
  U5D1 CG78 RSVD<95> SKX_EXT_B_BGA1-IC,TBD    I15 @BASEBOARD_FAB2_LIB.BASEBOARD_FAB2(SCH_1):PAGE36

TP_CPU0_RSVD_97 @BASEBOARD_FAB2_LIB.BASEBOARD_FAB2(SCH_1):TP_CPU0_RSVD_97
  U5D1 CG24 RSVD<97> SKX_EXT_B_BGA1-IC,TBD    I15 @BASEBOARD_FAB2_LIB.BASEBOARD_FAB2(SCH_1):PAGE36

TP_CPU0_RSVD_99 @BASEBOARD_FAB2_LIB.BASEBOARD_FAB2(SCH_1):TP_CPU0_RSVD_99
  U5D1 CG10 RSVD<99> SKX_EXT_B_BGA1-IC,TBD    I15 @BASEBOARD_FAB2_LIB.BASEBOARD_FAB2(SCH_1):PAGE36

TP_CPU0_RSVD_TEST_11 @BASEBOARD_FAB2_LIB.BASEBOARD_FAB2(SCH_1):TP_CPU0_RSVD_TEST_11
  U5D1 AY13 TEST_11 SKX_EXT_B_BGA1-IC,TBD   I204 @BASEBOARD_FAB2_LIB.BASEBOARD_FAB2(SCH_1):PAGE22

TP_CPU0_RSVD_TEST_3 @BASEBOARD_FAB2_LIB.BASEBOARD_FAB2(SCH_1):TP_CPU0_RSVD_TEST_3
  U5D1 AM13 TEST_3 SKX_EXT_B_BGA1-IC,TBD   I204 @BASEBOARD_FAB2_LIB.BASEBOARD_FAB2(SCH_1):PAGE22

TP_CPU0_RSVD_TEST_4 @BASEBOARD_FAB2_LIB.BASEBOARD_FAB2(SCH_1):TP_CPU0_RSVD_TEST_4
  U5D1 AN12 TEST_4 SKX_EXT_B_BGA1-IC,TBD   I204 @BASEBOARD_FAB2_LIB.BASEBOARD_FAB2(SCH_1):PAGE22

TP_CPU0_RSVD_TEST_5 @BASEBOARD_FAB2_LIB.BASEBOARD_FAB2(SCH_1):TP_CPU0_RSVD_TEST_5
  U5D1 AN14 TEST_5 SKX_EXT_B_BGA1-IC,TBD   I204 @BASEBOARD_FAB2_LIB.BASEBOARD_FAB2(SCH_1):PAGE22

TP_CPU0_SOCKET_ID_2 @BASEBOARD_FAB2_LIB.BASEBOARD_FAB2(SCH_1):TP_CPU0_SOCKET_ID_2
  U5D1 AU20 SOCKET_ID<2> SKX_EXT_B_BGA1-IC,TBD   I259 @BASEBOARD_FAB2_LIB.BASEBOARD_FAB2(SCH_1):PAGE21

TP_CPU0_TEST_10 @BASEBOARD_FAB2_LIB.BASEBOARD_FAB2(SCH_1):TP_CPU0_TEST_10
  U5D1 AW22 TEST_10 SKX_EXT_B_BGA1-IC,TBD    I16 @BASEBOARD_FAB2_LIB.BASEBOARD_FAB2(SCH_1):PAGE36

TP_CPU0_TEST_6 @BASEBOARD_FAB2_LIB.BASEBOARD_FAB2(SCH_1):TP_CPU0_TEST_6
  U5D1 AR16 TEST_6 SKX_EXT_B_BGA1-IC,TBD    I16 @BASEBOARD_FAB2_LIB.BASEBOARD_FAB2(SCH_1):PAGE36

TP_CPU0_TEST_7 @BASEBOARD_FAB2_LIB.BASEBOARD_FAB2(SCH_1):TP_CPU0_TEST_7
  U5D1 AU18 TEST_7 SKX_EXT_B_BGA1-IC,TBD    I16 @BASEBOARD_FAB2_LIB.BASEBOARD_FAB2(SCH_1):PAGE36

TP_CPU0_TEST_8 @BASEBOARD_FAB2_LIB.BASEBOARD_FAB2(SCH_1):TP_CPU0_TEST_8
  U5D1 AW16 TEST_8 SKX_EXT_B_BGA1-IC,TBD    I16 @BASEBOARD_FAB2_LIB.BASEBOARD_FAB2(SCH_1):PAGE36

TP_CPU0_TEST_9 @BASEBOARD_FAB2_LIB.BASEBOARD_FAB2(SCH_1):TP_CPU0_TEST_9
  U5D1 AW20 TEST_9 SKX_EXT_B_BGA1-IC,TBD    I16 @BASEBOARD_FAB2_LIB.BASEBOARD_FAB2(SCH_1):PAGE36

TP_CPU0_UPI2_RSVD_CA12 @BASEBOARD_FAB2_LIB.BASEBOARD_FAB2(SCH_1):TP_CPU0_UPI2_RSVD_CA12
  U5D1 DP21 UPI2_TX_DP<0> SKX_EXT_B_BGA1-IC,TBD     I3 @BASEBOARD_FAB2_LIB.BASEBOARD_FAB2(SCH_1):PAGE35

TP_CPU0_UPI2_RSVD_CB11 @BASEBOARD_FAB2_LIB.BASEBOARD_FAB2(SCH_1):TP_CPU0_UPI2_RSVD_CB11
  U5D1 DN20 UPI2_TX_DP<1> SKX_EXT_B_BGA1-IC,TBD     I3 @BASEBOARD_FAB2_LIB.BASEBOARD_FAB2(SCH_1):PAGE35

TP_CPU0_UPI2_RSVD_CC10 @BASEBOARD_FAB2_LIB.BASEBOARD_FAB2(SCH_1):TP_CPU0_UPI2_RSVD_CC10
  U5D1 DM21 UPI2_TX_DN<1> SKX_EXT_B_BGA1-IC,TBD     I3 @BASEBOARD_FAB2_LIB.BASEBOARD_FAB2(SCH_1):PAGE35

TP_CPU0_UPI2_RSVD_CC12 @BASEBOARD_FAB2_LIB.BASEBOARD_FAB2(SCH_1):TP_CPU0_UPI2_RSVD_CC12
  U5D1 DT21 UPI2_TX_DN<0> SKX_EXT_B_BGA1-IC,TBD     I3 @BASEBOARD_FAB2_LIB.BASEBOARD_FAB2(SCH_1):PAGE35

TP_CPU0_UPI2_RSVD_CD11 @BASEBOARD_FAB2_LIB.BASEBOARD_FAB2(SCH_1):TP_CPU0_UPI2_RSVD_CD11
  U5D1 DK19 UPI2_TX_DP<2> SKX_EXT_B_BGA1-IC,TBD     I3 @BASEBOARD_FAB2_LIB.BASEBOARD_FAB2(SCH_1):PAGE35

TP_CPU0_UPI2_RSVD_CE12 @BASEBOARD_FAB2_LIB.BASEBOARD_FAB2(SCH_1):TP_CPU0_UPI2_RSVD_CE12
  U5D1 DL20 UPI2_TX_DN<2> SKX_EXT_B_BGA1-IC,TBD     I3 @BASEBOARD_FAB2_LIB.BASEBOARD_FAB2(SCH_1):PAGE35

TP_CPU0_UPI2_RSVD_CF11 @BASEBOARD_FAB2_LIB.BASEBOARD_FAB2(SCH_1):TP_CPU0_UPI2_RSVD_CF11
  U5D1 DJ20 UPI2_TX_DP<3> SKX_EXT_B_BGA1-IC,TBD     I3 @BASEBOARD_FAB2_LIB.BASEBOARD_FAB2(SCH_1):PAGE35

TP_CPU0_UPI2_RSVD_CF13 @BASEBOARD_FAB2_LIB.BASEBOARD_FAB2(SCH_1):TP_CPU0_UPI2_RSVD_CF13
  U5D1 DH19 UPI2_TX_DN<4> SKX_EXT_B_BGA1-IC,TBD     I3 @BASEBOARD_FAB2_LIB.BASEBOARD_FAB2(SCH_1):PAGE35

TP_CPU0_UPI2_RSVD_CG12 @BASEBOARD_FAB2_LIB.BASEBOARD_FAB2(SCH_1):TP_CPU0_UPI2_RSVD_CG12
  U5D1 DJ18 UPI2_TX_DP<4> SKX_EXT_B_BGA1-IC,TBD     I3 @BASEBOARD_FAB2_LIB.BASEBOARD_FAB2(SCH_1):PAGE35

TP_CPU0_UPI2_RSVD_CH11 @BASEBOARD_FAB2_LIB.BASEBOARD_FAB2(SCH_1):TP_CPU0_UPI2_RSVD_CH11
  U5D1 DG20 UPI2_TX_DN<3> SKX_EXT_B_BGA1-IC,TBD     I3 @BASEBOARD_FAB2_LIB.BASEBOARD_FAB2(SCH_1):PAGE35

TP_CPU0_UPI2_RSVD_CH13 @BASEBOARD_FAB2_LIB.BASEBOARD_FAB2(SCH_1):TP_CPU0_UPI2_RSVD_CH13
  U5D1 DH17 UPI2_TX_DP<5> SKX_EXT_B_BGA1-IC,TBD     I3 @BASEBOARD_FAB2_LIB.BASEBOARD_FAB2(SCH_1):PAGE35

TP_CPU0_UPI2_RSVD_CJ14 @BASEBOARD_FAB2_LIB.BASEBOARD_FAB2(SCH_1):TP_CPU0_UPI2_RSVD_CJ14
  U5D1 DK17 UPI2_TX_DN<5> SKX_EXT_B_BGA1-IC,TBD     I3 @BASEBOARD_FAB2_LIB.BASEBOARD_FAB2(SCH_1):PAGE35

TP_CPU0_UPI2_RSVD_CK13 @BASEBOARD_FAB2_LIB.BASEBOARD_FAB2(SCH_1):TP_CPU0_UPI2_RSVD_CK13
  U5D1 DF17 UPI2_TX_DP<6> SKX_EXT_B_BGA1-IC,TBD     I3 @BASEBOARD_FAB2_LIB.BASEBOARD_FAB2(SCH_1):PAGE35

TP_CPU0_UPI2_RSVD_CM13 @BASEBOARD_FAB2_LIB.BASEBOARD_FAB2(SCH_1):TP_CPU0_UPI2_RSVD_CM13
  U5D1 DG18 UPI2_TX_DN<6> SKX_EXT_B_BGA1-IC,TBD     I3 @BASEBOARD_FAB2_LIB.BASEBOARD_FAB2(SCH_1):PAGE35

TP_CPU0_UPI2_RSVD_CR14 @BASEBOARD_FAB2_LIB.BASEBOARD_FAB2(SCH_1):TP_CPU0_UPI2_RSVD_CR14
  U5D1 DE16 UPI2_TX_DP<7> SKX_EXT_B_BGA1-IC,TBD     I3 @BASEBOARD_FAB2_LIB.BASEBOARD_FAB2(SCH_1):PAGE35

TP_CPU0_UPI2_RSVD_CU14 @BASEBOARD_FAB2_LIB.BASEBOARD_FAB2(SCH_1):TP_CPU0_UPI2_RSVD_CU14
  U5D1 DD17 UPI2_TX_DN<7> SKX_EXT_B_BGA1-IC,TBD     I3 @BASEBOARD_FAB2_LIB.BASEBOARD_FAB2(SCH_1):PAGE35

TP_CPU0_UPI2_RSVD_CV13 @BASEBOARD_FAB2_LIB.BASEBOARD_FAB2(SCH_1):TP_CPU0_UPI2_RSVD_CV13
  U5D1 DD15 UPI2_TX_DP<8> SKX_EXT_B_BGA1-IC,TBD     I3 @BASEBOARD_FAB2_LIB.BASEBOARD_FAB2(SCH_1):PAGE35

TP_CPU0_UPI2_RSVD_CW14 @BASEBOARD_FAB2_LIB.BASEBOARD_FAB2(SCH_1):TP_CPU0_UPI2_RSVD_CW14
  U5D1 DF15 UPI2_TX_DN<8> SKX_EXT_B_BGA1-IC,TBD     I3 @BASEBOARD_FAB2_LIB.BASEBOARD_FAB2(SCH_1):PAGE35

TP_CPU0_UPI2_RSVD_CW16 @BASEBOARD_FAB2_LIB.BASEBOARD_FAB2(SCH_1):TP_CPU0_UPI2_RSVD_CW16
  U5D1 DB15 UPI2_TX_DP<9> SKX_EXT_B_BGA1-IC,TBD     I3 @BASEBOARD_FAB2_LIB.BASEBOARD_FAB2(SCH_1):PAGE35

TP_CPU0_UPI2_RSVD_DA16 @BASEBOARD_FAB2_LIB.BASEBOARD_FAB2(SCH_1):TP_CPU0_UPI2_RSVD_DA16
  U5D1 DC16 UPI2_TX_DN<9> SKX_EXT_B_BGA1-IC,TBD     I3 @BASEBOARD_FAB2_LIB.BASEBOARD_FAB2(SCH_1):PAGE35

TP_CPU0_UPI2_RSVD_DB15 @BASEBOARD_FAB2_LIB.BASEBOARD_FAB2(SCH_1):TP_CPU0_UPI2_RSVD_DB15
  U5D1 CW16 UPI2_TX_DP<10> SKX_EXT_B_BGA1-IC,TBD     I3 @BASEBOARD_FAB2_LIB.BASEBOARD_FAB2(SCH_1):PAGE35

TP_CPU0_UPI2_RSVD_DC16 @BASEBOARD_FAB2_LIB.BASEBOARD_FAB2(SCH_1):TP_CPU0_UPI2_RSVD_DC16
  U5D1 DA16 UPI2_TX_DN<10> SKX_EXT_B_BGA1-IC,TBD     I3 @BASEBOARD_FAB2_LIB.BASEBOARD_FAB2(SCH_1):PAGE35

TP_CPU0_UPI2_RSVD_DD15 @BASEBOARD_FAB2_LIB.BASEBOARD_FAB2(SCH_1):TP_CPU0_UPI2_RSVD_DD15
  U5D1 CV13 UPI2_TX_DP<11> SKX_EXT_B_BGA1-IC,TBD     I3 @BASEBOARD_FAB2_LIB.BASEBOARD_FAB2(SCH_1):PAGE35

TP_CPU0_UPI2_RSVD_DD17 @BASEBOARD_FAB2_LIB.BASEBOARD_FAB2(SCH_1):TP_CPU0_UPI2_RSVD_DD17
  U5D1 CU14 UPI2_TX_DN<12> SKX_EXT_B_BGA1-IC,TBD     I3 @BASEBOARD_FAB2_LIB.BASEBOARD_FAB2(SCH_1):PAGE35

TP_CPU0_UPI2_RSVD_DE16 @BASEBOARD_FAB2_LIB.BASEBOARD_FAB2(SCH_1):TP_CPU0_UPI2_RSVD_DE16
  U5D1 CR14 UPI2_TX_DP<12> SKX_EXT_B_BGA1-IC,TBD     I3 @BASEBOARD_FAB2_LIB.BASEBOARD_FAB2(SCH_1):PAGE35

TP_CPU0_UPI2_RSVD_DF15 @BASEBOARD_FAB2_LIB.BASEBOARD_FAB2(SCH_1):TP_CPU0_UPI2_RSVD_DF15
  U5D1 CW14 UPI2_TX_DN<11> SKX_EXT_B_BGA1-IC,TBD     I3 @BASEBOARD_FAB2_LIB.BASEBOARD_FAB2(SCH_1):PAGE35

TP_CPU0_UPI2_RSVD_DF17 @BASEBOARD_FAB2_LIB.BASEBOARD_FAB2(SCH_1):TP_CPU0_UPI2_RSVD_DF17
  U5D1 CK13 UPI2_TX_DP<13> SKX_EXT_B_BGA1-IC,TBD     I3 @BASEBOARD_FAB2_LIB.BASEBOARD_FAB2(SCH_1):PAGE35

TP_CPU0_UPI2_RSVD_DG18 @BASEBOARD_FAB2_LIB.BASEBOARD_FAB2(SCH_1):TP_CPU0_UPI2_RSVD_DG18
  U5D1 CM13 UPI2_TX_DN<13> SKX_EXT_B_BGA1-IC,TBD     I3 @BASEBOARD_FAB2_LIB.BASEBOARD_FAB2(SCH_1):PAGE35

TP_CPU0_UPI2_RSVD_DG20 @BASEBOARD_FAB2_LIB.BASEBOARD_FAB2(SCH_1):TP_CPU0_UPI2_RSVD_DG20
  U5D1 CH11 UPI2_TX_DN<16> SKX_EXT_B_BGA1-IC,TBD     I3 @BASEBOARD_FAB2_LIB.BASEBOARD_FAB2(SCH_1):PAGE35

TP_CPU0_UPI2_RSVD_DH17 @BASEBOARD_FAB2_LIB.BASEBOARD_FAB2(SCH_1):TP_CPU0_UPI2_RSVD_DH17
  U5D1 CH13 UPI2_TX_DP<14> SKX_EXT_B_BGA1-IC,TBD     I3 @BASEBOARD_FAB2_LIB.BASEBOARD_FAB2(SCH_1):PAGE35

TP_CPU0_UPI2_RSVD_DH19 @BASEBOARD_FAB2_LIB.BASEBOARD_FAB2(SCH_1):TP_CPU0_UPI2_RSVD_DH19
  U5D1 CF13 UPI2_TX_DN<15> SKX_EXT_B_BGA1-IC,TBD     I3 @BASEBOARD_FAB2_LIB.BASEBOARD_FAB2(SCH_1):PAGE35

TP_CPU0_UPI2_RSVD_DJ18 @BASEBOARD_FAB2_LIB.BASEBOARD_FAB2(SCH_1):TP_CPU0_UPI2_RSVD_DJ18
  U5D1 CG12 UPI2_TX_DP<15> SKX_EXT_B_BGA1-IC,TBD     I3 @BASEBOARD_FAB2_LIB.BASEBOARD_FAB2(SCH_1):PAGE35

TP_CPU0_UPI2_RSVD_DJ20 @BASEBOARD_FAB2_LIB.BASEBOARD_FAB2(SCH_1):TP_CPU0_UPI2_RSVD_DJ20
  U5D1 CF11 UPI2_TX_DP<16> SKX_EXT_B_BGA1-IC,TBD     I3 @BASEBOARD_FAB2_LIB.BASEBOARD_FAB2(SCH_1):PAGE35

TP_CPU0_UPI2_RSVD_DK17 @BASEBOARD_FAB2_LIB.BASEBOARD_FAB2(SCH_1):TP_CPU0_UPI2_RSVD_DK17
  U5D1 CJ14 UPI2_TX_DN<14> SKX_EXT_B_BGA1-IC,TBD     I3 @BASEBOARD_FAB2_LIB.BASEBOARD_FAB2(SCH_1):PAGE35

TP_CPU0_UPI2_RSVD_DK19 @BASEBOARD_FAB2_LIB.BASEBOARD_FAB2(SCH_1):TP_CPU0_UPI2_RSVD_DK19
  U5D1 CD11 UPI2_TX_DP<17> SKX_EXT_B_BGA1-IC,TBD     I3 @BASEBOARD_FAB2_LIB.BASEBOARD_FAB2(SCH_1):PAGE35

TP_CPU0_UPI2_RSVD_DL20 @BASEBOARD_FAB2_LIB.BASEBOARD_FAB2(SCH_1):TP_CPU0_UPI2_RSVD_DL20
  U5D1 CE12 UPI2_TX_DN<17> SKX_EXT_B_BGA1-IC,TBD     I3 @BASEBOARD_FAB2_LIB.BASEBOARD_FAB2(SCH_1):PAGE35

TP_CPU0_UPI2_RSVD_DM21 @BASEBOARD_FAB2_LIB.BASEBOARD_FAB2(SCH_1):TP_CPU0_UPI2_RSVD_DM21
  U5D1 CC10 UPI2_TX_DN<18> SKX_EXT_B_BGA1-IC,TBD     I3 @BASEBOARD_FAB2_LIB.BASEBOARD_FAB2(SCH_1):PAGE35

TP_CPU0_UPI2_RSVD_DN20 @BASEBOARD_FAB2_LIB.BASEBOARD_FAB2(SCH_1):TP_CPU0_UPI2_RSVD_DN20
  U5D1 CB11 UPI2_TX_DP<18> SKX_EXT_B_BGA1-IC,TBD     I3 @BASEBOARD_FAB2_LIB.BASEBOARD_FAB2(SCH_1):PAGE35

TP_CPU0_UPI2_RSVD_DP21 @BASEBOARD_FAB2_LIB.BASEBOARD_FAB2(SCH_1):TP_CPU0_UPI2_RSVD_DP21
  U5D1 CA12 UPI2_TX_DP<19> SKX_EXT_B_BGA1-IC,TBD     I3 @BASEBOARD_FAB2_LIB.BASEBOARD_FAB2(SCH_1):PAGE35

TP_CPU0_UPI2_RSVD_DT21 @BASEBOARD_FAB2_LIB.BASEBOARD_FAB2(SCH_1):TP_CPU0_UPI2_RSVD_DT21
  U5D1 CC12 UPI2_TX_DN<19> SKX_EXT_B_BGA1-IC,TBD     I3 @BASEBOARD_FAB2_LIB.BASEBOARD_FAB2(SCH_1):PAGE35

TP_CPU1_DMI_RX_DN0 @BASEBOARD_FAB2_LIB.BASEBOARD_FAB2(SCH_1):TP_CPU1_DMI_RX_DN0
  U2D1  CK9 DMI_RX_DN<0> SKX_EXT_B_BGA1-IC,TBD    I23 @BASEBOARD_FAB2_LIB.BASEBOARD_FAB2(SCH_1):PAGE63

TP_CPU1_DMI_RX_DN1 @BASEBOARD_FAB2_LIB.BASEBOARD_FAB2(SCH_1):TP_CPU1_DMI_RX_DN1
  U2D1 CM11 DMI_RX_DN<1> SKX_EXT_B_BGA1-IC,TBD    I23 @BASEBOARD_FAB2_LIB.BASEBOARD_FAB2(SCH_1):PAGE63

TP_CPU1_DMI_RX_DN2 @BASEBOARD_FAB2_LIB.BASEBOARD_FAB2(SCH_1):TP_CPU1_DMI_RX_DN2
  U2D1 CR12 DMI_RX_DN<2> SKX_EXT_B_BGA1-IC,TBD    I23 @BASEBOARD_FAB2_LIB.BASEBOARD_FAB2(SCH_1):PAGE63

TP_CPU1_DMI_RX_DN3 @BASEBOARD_FAB2_LIB.BASEBOARD_FAB2(SCH_1):TP_CPU1_DMI_RX_DN3
  U2D1 CT11 DMI_RX_DN<3> SKX_EXT_B_BGA1-IC,TBD    I23 @BASEBOARD_FAB2_LIB.BASEBOARD_FAB2(SCH_1):PAGE63

TP_CPU1_DMI_RX_DP0 @BASEBOARD_FAB2_LIB.BASEBOARD_FAB2(SCH_1):TP_CPU1_DMI_RX_DP0
  U2D1 CL10 DMI_RX_DP<0> SKX_EXT_B_BGA1-IC,TBD    I23 @BASEBOARD_FAB2_LIB.BASEBOARD_FAB2(SCH_1):PAGE63

TP_CPU1_DMI_RX_DP1 @BASEBOARD_FAB2_LIB.BASEBOARD_FAB2(SCH_1):TP_CPU1_DMI_RX_DP1
  U2D1 CN10 DMI_RX_DP<1> SKX_EXT_B_BGA1-IC,TBD    I23 @BASEBOARD_FAB2_LIB.BASEBOARD_FAB2(SCH_1):PAGE63

TP_CPU1_DMI_RX_DP2 @BASEBOARD_FAB2_LIB.BASEBOARD_FAB2(SCH_1):TP_CPU1_DMI_RX_DP2
  U2D1 CP11 DMI_RX_DP<2> SKX_EXT_B_BGA1-IC,TBD    I23 @BASEBOARD_FAB2_LIB.BASEBOARD_FAB2(SCH_1):PAGE63

TP_CPU1_DMI_RX_DP3 @BASEBOARD_FAB2_LIB.BASEBOARD_FAB2(SCH_1):TP_CPU1_DMI_RX_DP3
  U2D1 CV11 DMI_RX_DP<3> SKX_EXT_B_BGA1-IC,TBD    I23 @BASEBOARD_FAB2_LIB.BASEBOARD_FAB2(SCH_1):PAGE63

TP_CPU1_DMI_TX_DN0 @BASEBOARD_FAB2_LIB.BASEBOARD_FAB2(SCH_1):TP_CPU1_DMI_TX_DN0
  U2D1  CG4 DMI_TX_DN<0> SKX_EXT_B_BGA1-IC,TBD    I23 @BASEBOARD_FAB2_LIB.BASEBOARD_FAB2(SCH_1):PAGE63

TP_CPU1_DMI_TX_DN1 @BASEBOARD_FAB2_LIB.BASEBOARD_FAB2(SCH_1):TP_CPU1_DMI_TX_DN1
  U2D1  CJ4 DMI_TX_DN<1> SKX_EXT_B_BGA1-IC,TBD    I23 @BASEBOARD_FAB2_LIB.BASEBOARD_FAB2(SCH_1):PAGE63

TP_CPU1_DMI_TX_DN2 @BASEBOARD_FAB2_LIB.BASEBOARD_FAB2(SCH_1):TP_CPU1_DMI_TX_DN2
  U2D1  CN4 DMI_TX_DN<2> SKX_EXT_B_BGA1-IC,TBD    I23 @BASEBOARD_FAB2_LIB.BASEBOARD_FAB2(SCH_1):PAGE63

TP_CPU1_DMI_TX_DN3 @BASEBOARD_FAB2_LIB.BASEBOARD_FAB2(SCH_1):TP_CPU1_DMI_TX_DN3
  U2D1  CP5 DMI_TX_DN<3> SKX_EXT_B_BGA1-IC,TBD    I23 @BASEBOARD_FAB2_LIB.BASEBOARD_FAB2(SCH_1):PAGE63

TP_CPU1_DMI_TX_DP0 @BASEBOARD_FAB2_LIB.BASEBOARD_FAB2(SCH_1):TP_CPU1_DMI_TX_DP0
  U2D1  CH5 DMI_TX_DP<0> SKX_EXT_B_BGA1-IC,TBD    I23 @BASEBOARD_FAB2_LIB.BASEBOARD_FAB2(SCH_1):PAGE63

TP_CPU1_DMI_TX_DP1 @BASEBOARD_FAB2_LIB.BASEBOARD_FAB2(SCH_1):TP_CPU1_DMI_TX_DP1
  U2D1  CL4 DMI_TX_DP<1> SKX_EXT_B_BGA1-IC,TBD    I23 @BASEBOARD_FAB2_LIB.BASEBOARD_FAB2(SCH_1):PAGE63

TP_CPU1_DMI_TX_DP2 @BASEBOARD_FAB2_LIB.BASEBOARD_FAB2(SCH_1):TP_CPU1_DMI_TX_DP2
  U2D1  CM3 DMI_TX_DP<2> SKX_EXT_B_BGA1-IC,TBD    I23 @BASEBOARD_FAB2_LIB.BASEBOARD_FAB2(SCH_1):PAGE63

TP_CPU1_DMI_TX_DP3 @BASEBOARD_FAB2_LIB.BASEBOARD_FAB2(SCH_1):TP_CPU1_DMI_TX_DP3
  U2D1  CR4 DMI_TX_DP<3> SKX_EXT_B_BGA1-IC,TBD    I23 @BASEBOARD_FAB2_LIB.BASEBOARD_FAB2(SCH_1):PAGE63

TP_CPU1_KTI2_AMONV @BASEBOARD_FAB2_LIB.BASEBOARD_FAB2(SCH_1):TP_CPU1_KTI2_AMONV
  U2D1 CN22 RSVD<77> SKX_EXT_B_BGA1-IC,TBD   I107 @BASEBOARD_FAB2_LIB.BASEBOARD_FAB2(SCH_1):PAGE73

TP_CPU1_KTI2_DFX_DN @BASEBOARD_FAB2_LIB.BASEBOARD_FAB2(SCH_1):TP_CPU1_KTI2_DFX_DN
  U2D1 CW22 RSVD<63> SKX_EXT_B_BGA1-IC,TBD   I107 @BASEBOARD_FAB2_LIB.BASEBOARD_FAB2(SCH_1):PAGE73

TP_CPU1_NMI @BASEBOARD_FAB2_LIB.BASEBOARD_FAB2(SCH_1):TP_CPU1_NMI
  U2D1 AP11    NMI SKX_EXT_B_BGA1-IC,TBD   I172 @BASEBOARD_FAB2_LIB.BASEBOARD_FAB2(SCH_1):PAGE55

TP_CPU1_PROC_DIS_G_N @BASEBOARD_FAB2_LIB.BASEBOARD_FAB2(SCH_1):TP_CPU1_PROC_DIS_G_N
  U2D1 AB17 PROCDIS_N SKX_EXT_B_BGA1-IC,TBD   I172 @BASEBOARD_FAB2_LIB.BASEBOARD_FAB2(SCH_1):PAGE55

TP_CPU1_RSVD_0 @BASEBOARD_FAB2_LIB.BASEBOARD_FAB2(SCH_1):TP_CPU1_RSVD_0
  U2D1 EF83 RSVD<0> SKX_EXT_B_BGA1-IC,TBD   I107 @BASEBOARD_FAB2_LIB.BASEBOARD_FAB2(SCH_1):PAGE73

TP_CPU1_RSVD_1 @BASEBOARD_FAB2_LIB.BASEBOARD_FAB2(SCH_1):TP_CPU1_RSVD_1
  U2D1 EF81 RSVD<1> SKX_EXT_B_BGA1-IC,TBD   I107 @BASEBOARD_FAB2_LIB.BASEBOARD_FAB2(SCH_1):PAGE73

TP_CPU1_RSVD_10 @BASEBOARD_FAB2_LIB.BASEBOARD_FAB2(SCH_1):TP_CPU1_RSVD_10
  U2D1  ED5 RSVD<10> SKX_EXT_B_BGA1-IC,TBD   I107 @BASEBOARD_FAB2_LIB.BASEBOARD_FAB2(SCH_1):PAGE73

TP_CPU1_RSVD_100 @BASEBOARD_FAB2_LIB.BASEBOARD_FAB2(SCH_1):TP_CPU1_RSVD_100
  U2D1 CF81 RSVD<100> SKX_EXT_B_BGA1-IC,TBD     I9 @BASEBOARD_FAB2_LIB.BASEBOARD_FAB2(SCH_1):PAGE70

TP_CPU1_RSVD_101 @BASEBOARD_FAB2_LIB.BASEBOARD_FAB2(SCH_1):TP_CPU1_RSVD_101
  U2D1 CF79 RSVD<101> SKX_EXT_B_BGA1-IC,TBD     I9 @BASEBOARD_FAB2_LIB.BASEBOARD_FAB2(SCH_1):PAGE70

TP_CPU1_RSVD_105 @BASEBOARD_FAB2_LIB.BASEBOARD_FAB2(SCH_1):TP_CPU1_RSVD_105
  U2D1 CE80 RSVD<105> SKX_EXT_B_BGA1-IC,TBD     I9 @BASEBOARD_FAB2_LIB.BASEBOARD_FAB2(SCH_1):PAGE70

TP_CPU1_RSVD_106 @BASEBOARD_FAB2_LIB.BASEBOARD_FAB2(SCH_1):TP_CPU1_RSVD_106
  U2D1 CE78 RSVD<106> SKX_EXT_B_BGA1-IC,TBD     I9 @BASEBOARD_FAB2_LIB.BASEBOARD_FAB2(SCH_1):PAGE70

TP_CPU1_RSVD_108 @BASEBOARD_FAB2_LIB.BASEBOARD_FAB2(SCH_1):TP_CPU1_RSVD_108
  U2D1 CD25 RSVD<108> SKX_EXT_B_BGA1-IC,TBD     I9 @BASEBOARD_FAB2_LIB.BASEBOARD_FAB2(SCH_1):PAGE70

TP_CPU1_RSVD_11 @BASEBOARD_FAB2_LIB.BASEBOARD_FAB2(SCH_1):TP_CPU1_RSVD_11
  U2D1 ED45 RSVD<11> SKX_EXT_B_BGA1-IC,TBD   I107 @BASEBOARD_FAB2_LIB.BASEBOARD_FAB2(SCH_1):PAGE73

TP_CPU1_RSVD_111 @BASEBOARD_FAB2_LIB.BASEBOARD_FAB2(SCH_1):TP_CPU1_RSVD_111
  U2D1  CC6 RSVD<111> SKX_EXT_B_BGA1-IC,TBD     I9 @BASEBOARD_FAB2_LIB.BASEBOARD_FAB2(SCH_1):PAGE70

TP_CPU1_RSVD_113 @BASEBOARD_FAB2_LIB.BASEBOARD_FAB2(SCH_1):TP_CPU1_RSVD_113
  U2D1  CB5 RSVD<113> SKX_EXT_B_BGA1-IC,TBD     I9 @BASEBOARD_FAB2_LIB.BASEBOARD_FAB2(SCH_1):PAGE70

TP_CPU1_RSVD_114 @BASEBOARD_FAB2_LIB.BASEBOARD_FAB2(SCH_1):TP_CPU1_RSVD_114
  U2D1 CB25 RSVD<114> SKX_EXT_B_BGA1-IC,TBD     I9 @BASEBOARD_FAB2_LIB.BASEBOARD_FAB2(SCH_1):PAGE70

TP_CPU1_RSVD_117 @BASEBOARD_FAB2_LIB.BASEBOARD_FAB2(SCH_1):TP_CPU1_RSVD_117
  U2D1 CA24 RSVD<117> SKX_EXT_B_BGA1-IC,TBD     I9 @BASEBOARD_FAB2_LIB.BASEBOARD_FAB2(SCH_1):PAGE70

TP_CPU1_RSVD_119 @BASEBOARD_FAB2_LIB.BASEBOARD_FAB2(SCH_1):TP_CPU1_RSVD_119
  U2D1 BY25 RSVD<119> SKX_EXT_B_BGA1-IC,TBD     I9 @BASEBOARD_FAB2_LIB.BASEBOARD_FAB2(SCH_1):PAGE70

TP_CPU1_RSVD_12 @BASEBOARD_FAB2_LIB.BASEBOARD_FAB2(SCH_1):TP_CPU1_RSVD_12
  U2D1 EC84 RSVD<12> SKX_EXT_B_BGA1-IC,TBD   I107 @BASEBOARD_FAB2_LIB.BASEBOARD_FAB2(SCH_1):PAGE73

TP_CPU1_RSVD_121 @BASEBOARD_FAB2_LIB.BASEBOARD_FAB2(SCH_1):TP_CPU1_RSVD_121
  U2D1 BW22 RSVD<121> SKX_EXT_B_BGA1-IC,TBD     I9 @BASEBOARD_FAB2_LIB.BASEBOARD_FAB2(SCH_1):PAGE70

TP_CPU1_RSVD_123 @BASEBOARD_FAB2_LIB.BASEBOARD_FAB2(SCH_1):TP_CPU1_RSVD_123
  U2D1 BW10 RSVD<123> SKX_EXT_B_BGA1-IC,TBD     I9 @BASEBOARD_FAB2_LIB.BASEBOARD_FAB2(SCH_1):PAGE70

TP_CPU1_RSVD_124 @BASEBOARD_FAB2_LIB.BASEBOARD_FAB2(SCH_1):TP_CPU1_RSVD_124
  U2D1 BV23 RSVD<124> SKX_EXT_B_BGA1-IC,TBD     I9 @BASEBOARD_FAB2_LIB.BASEBOARD_FAB2(SCH_1):PAGE70

TP_CPU1_RSVD_13 @BASEBOARD_FAB2_LIB.BASEBOARD_FAB2(SCH_1):TP_CPU1_RSVD_13
  U2D1 EC44 RSVD<13> SKX_EXT_B_BGA1-IC,TBD   I107 @BASEBOARD_FAB2_LIB.BASEBOARD_FAB2(SCH_1):PAGE73

TP_CPU1_RSVD_14 @BASEBOARD_FAB2_LIB.BASEBOARD_FAB2(SCH_1):TP_CPU1_RSVD_14
  U2D1  EC4 RSVD<14> SKX_EXT_B_BGA1-IC,TBD   I107 @BASEBOARD_FAB2_LIB.BASEBOARD_FAB2(SCH_1):PAGE73

TP_CPU1_RSVD_144 @BASEBOARD_FAB2_LIB.BASEBOARD_FAB2(SCH_1):TP_CPU1_RSVD_144
  U2D1 BG20 RSVD<144> SKX_EXT_B_BGA1-IC,TBD     I9 @BASEBOARD_FAB2_LIB.BASEBOARD_FAB2(SCH_1):PAGE70

TP_CPU1_RSVD_145 @BASEBOARD_FAB2_LIB.BASEBOARD_FAB2(SCH_1):TP_CPU1_RSVD_145
  U2D1 BG18 RSVD<145> SKX_EXT_B_BGA1-IC,TBD     I9 @BASEBOARD_FAB2_LIB.BASEBOARD_FAB2(SCH_1):PAGE70

TP_CPU1_RSVD_146 @BASEBOARD_FAB2_LIB.BASEBOARD_FAB2(SCH_1):TP_CPU1_RSVD_146
  U2D1 BF21 RSVD<146> SKX_EXT_B_BGA1-IC,TBD     I9 @BASEBOARD_FAB2_LIB.BASEBOARD_FAB2(SCH_1):PAGE70

TP_CPU1_RSVD_147 @BASEBOARD_FAB2_LIB.BASEBOARD_FAB2(SCH_1):TP_CPU1_RSVD_147
  U2D1 BE22 RSVD<147> SKX_EXT_B_BGA1-IC,TBD     I9 @BASEBOARD_FAB2_LIB.BASEBOARD_FAB2(SCH_1):PAGE70

TP_CPU1_RSVD_148 @BASEBOARD_FAB2_LIB.BASEBOARD_FAB2(SCH_1):TP_CPU1_RSVD_148
  U2D1 BE20 RSVD<148> SKX_EXT_B_BGA1-IC,TBD     I9 @BASEBOARD_FAB2_LIB.BASEBOARD_FAB2(SCH_1):PAGE70

TP_CPU1_RSVD_149 @BASEBOARD_FAB2_LIB.BASEBOARD_FAB2(SCH_1):TP_CPU1_RSVD_149
  U2D1 BE18 RSVD<149> SKX_EXT_B_BGA1-IC,TBD     I9 @BASEBOARD_FAB2_LIB.BASEBOARD_FAB2(SCH_1):PAGE70

TP_CPU1_RSVD_15 @BASEBOARD_FAB2_LIB.BASEBOARD_FAB2(SCH_1):TP_CPU1_RSVD_15
  U2D1 EC16 RSVD<15> SKX_EXT_B_BGA1-IC,TBD   I107 @BASEBOARD_FAB2_LIB.BASEBOARD_FAB2(SCH_1):PAGE73

TP_CPU1_RSVD_150 @BASEBOARD_FAB2_LIB.BASEBOARD_FAB2(SCH_1):TP_CPU1_RSVD_150
  U2D1 BD69 RSVD<150> SKX_EXT_B_BGA1-IC,TBD     I9 @BASEBOARD_FAB2_LIB.BASEBOARD_FAB2(SCH_1):PAGE70

TP_CPU1_RSVD_151 @BASEBOARD_FAB2_LIB.BASEBOARD_FAB2(SCH_1):TP_CPU1_RSVD_151
  U2D1 BD67 RSVD<151> SKX_EXT_B_BGA1-IC,TBD     I9 @BASEBOARD_FAB2_LIB.BASEBOARD_FAB2(SCH_1):PAGE70

TP_CPU1_RSVD_152 @BASEBOARD_FAB2_LIB.BASEBOARD_FAB2(SCH_1):TP_CPU1_RSVD_152
  U2D1 BD65 RSVD<152> SKX_EXT_B_BGA1-IC,TBD     I9 @BASEBOARD_FAB2_LIB.BASEBOARD_FAB2(SCH_1):PAGE70

TP_CPU1_RSVD_154 @BASEBOARD_FAB2_LIB.BASEBOARD_FAB2(SCH_1):TP_CPU1_RSVD_154
  U2D1 BD19 RSVD<154> SKX_EXT_B_BGA1-IC,TBD     I9 @BASEBOARD_FAB2_LIB.BASEBOARD_FAB2(SCH_1):PAGE70

TP_CPU1_RSVD_155 @BASEBOARD_FAB2_LIB.BASEBOARD_FAB2(SCH_1):TP_CPU1_RSVD_155
  U2D1 BD17 RSVD<155> SKX_EXT_B_BGA1-IC,TBD     I9 @BASEBOARD_FAB2_LIB.BASEBOARD_FAB2(SCH_1):PAGE70

TP_CPU1_RSVD_156 @BASEBOARD_FAB2_LIB.BASEBOARD_FAB2(SCH_1):TP_CPU1_RSVD_156
  U2D1 BC68 RSVD<156> SKX_EXT_B_BGA1-IC,TBD     I9 @BASEBOARD_FAB2_LIB.BASEBOARD_FAB2(SCH_1):PAGE70

TP_CPU1_RSVD_157 @BASEBOARD_FAB2_LIB.BASEBOARD_FAB2(SCH_1):TP_CPU1_RSVD_157
  U2D1 BC66 RSVD<157> SKX_EXT_B_BGA1-IC,TBD     I9 @BASEBOARD_FAB2_LIB.BASEBOARD_FAB2(SCH_1):PAGE70

TP_CPU1_RSVD_158 @BASEBOARD_FAB2_LIB.BASEBOARD_FAB2(SCH_1):TP_CPU1_RSVD_158
  U2D1 BC64 RSVD<158> SKX_EXT_B_BGA1-IC,TBD     I9 @BASEBOARD_FAB2_LIB.BASEBOARD_FAB2(SCH_1):PAGE70

TP_CPU1_RSVD_159 @BASEBOARD_FAB2_LIB.BASEBOARD_FAB2(SCH_1):TP_CPU1_RSVD_159
  U2D1 BC22 RSVD<159> SKX_EXT_B_BGA1-IC,TBD     I9 @BASEBOARD_FAB2_LIB.BASEBOARD_FAB2(SCH_1):PAGE70

TP_CPU1_RSVD_16 @BASEBOARD_FAB2_LIB.BASEBOARD_FAB2(SCH_1):TP_CPU1_RSVD_16
  U2D1 EB85 RSVD<16> SKX_EXT_B_BGA1-IC,TBD   I107 @BASEBOARD_FAB2_LIB.BASEBOARD_FAB2(SCH_1):PAGE73

TP_CPU1_RSVD_160 @BASEBOARD_FAB2_LIB.BASEBOARD_FAB2(SCH_1):TP_CPU1_RSVD_160
  U2D1 BC20 RSVD<160> SKX_EXT_B_BGA1-IC,TBD     I9 @BASEBOARD_FAB2_LIB.BASEBOARD_FAB2(SCH_1):PAGE70

TP_CPU1_RSVD_161 @BASEBOARD_FAB2_LIB.BASEBOARD_FAB2(SCH_1):TP_CPU1_RSVD_161
  U2D1 BC18 RSVD<161> SKX_EXT_B_BGA1-IC,TBD     I9 @BASEBOARD_FAB2_LIB.BASEBOARD_FAB2(SCH_1):PAGE70

TP_CPU1_RSVD_162 @BASEBOARD_FAB2_LIB.BASEBOARD_FAB2(SCH_1):TP_CPU1_RSVD_162
  U2D1 BC14 RSVD<162> SKX_EXT_B_BGA1-IC,TBD     I9 @BASEBOARD_FAB2_LIB.BASEBOARD_FAB2(SCH_1):PAGE70

TP_CPU1_RSVD_163 @BASEBOARD_FAB2_LIB.BASEBOARD_FAB2(SCH_1):TP_CPU1_RSVD_163
  U2D1 BB67 RSVD<163> SKX_EXT_B_BGA1-IC,TBD     I9 @BASEBOARD_FAB2_LIB.BASEBOARD_FAB2(SCH_1):PAGE70

TP_CPU1_RSVD_164 @BASEBOARD_FAB2_LIB.BASEBOARD_FAB2(SCH_1):TP_CPU1_RSVD_164
  U2D1 BB65 RSVD<164> SKX_EXT_B_BGA1-IC,TBD     I9 @BASEBOARD_FAB2_LIB.BASEBOARD_FAB2(SCH_1):PAGE70

TP_CPU1_RSVD_166 @BASEBOARD_FAB2_LIB.BASEBOARD_FAB2(SCH_1):TP_CPU1_RSVD_166
  U2D1 BB21 RSVD<166> SKX_EXT_B_BGA1-IC,TBD     I9 @BASEBOARD_FAB2_LIB.BASEBOARD_FAB2(SCH_1):PAGE70

TP_CPU1_RSVD_167 @BASEBOARD_FAB2_LIB.BASEBOARD_FAB2(SCH_1):TP_CPU1_RSVD_167
  U2D1 BB17 RSVD<167> SKX_EXT_B_BGA1-IC,TBD     I9 @BASEBOARD_FAB2_LIB.BASEBOARD_FAB2(SCH_1):PAGE70

TP_CPU1_RSVD_168 @BASEBOARD_FAB2_LIB.BASEBOARD_FAB2(SCH_1):TP_CPU1_RSVD_168
  U2D1 BB15 RSVD<168> SKX_EXT_B_BGA1-IC,TBD     I9 @BASEBOARD_FAB2_LIB.BASEBOARD_FAB2(SCH_1):PAGE70

TP_CPU1_RSVD_169 @BASEBOARD_FAB2_LIB.BASEBOARD_FAB2(SCH_1):TP_CPU1_RSVD_169
  U2D1 BB13 RSVD<169> SKX_EXT_B_BGA1-IC,TBD     I9 @BASEBOARD_FAB2_LIB.BASEBOARD_FAB2(SCH_1):PAGE70

TP_CPU1_RSVD_17 @BASEBOARD_FAB2_LIB.BASEBOARD_FAB2(SCH_1):TP_CPU1_RSVD_17
  U2D1  EB5 RSVD<17> SKX_EXT_B_BGA1-IC,TBD   I107 @BASEBOARD_FAB2_LIB.BASEBOARD_FAB2(SCH_1):PAGE73

TP_CPU1_RSVD_170 @BASEBOARD_FAB2_LIB.BASEBOARD_FAB2(SCH_1):TP_CPU1_RSVD_170
  U2D1 BA82 RSVD<170> SKX_EXT_B_BGA1-IC,TBD     I9 @BASEBOARD_FAB2_LIB.BASEBOARD_FAB2(SCH_1):PAGE70

TP_CPU1_RSVD_171 @BASEBOARD_FAB2_LIB.BASEBOARD_FAB2(SCH_1):TP_CPU1_RSVD_171
  U2D1 BA78 RSVD<171> SKX_EXT_B_BGA1-IC,TBD     I9 @BASEBOARD_FAB2_LIB.BASEBOARD_FAB2(SCH_1):PAGE70

TP_CPU1_RSVD_172 @BASEBOARD_FAB2_LIB.BASEBOARD_FAB2(SCH_1):TP_CPU1_RSVD_172
  U2D1 BA76 RSVD<172> SKX_EXT_B_BGA1-IC,TBD    I23 @BASEBOARD_FAB2_LIB.BASEBOARD_FAB2(SCH_1):PAGE63

TP_CPU1_RSVD_173 @BASEBOARD_FAB2_LIB.BASEBOARD_FAB2(SCH_1):TP_CPU1_RSVD_173
  U2D1 BA66 RSVD<173> SKX_EXT_B_BGA1-IC,TBD    I23 @BASEBOARD_FAB2_LIB.BASEBOARD_FAB2(SCH_1):PAGE63

TP_CPU1_RSVD_174 @BASEBOARD_FAB2_LIB.BASEBOARD_FAB2(SCH_1):TP_CPU1_RSVD_174
  U2D1 BA64 RSVD<174> SKX_EXT_B_BGA1-IC,TBD    I23 @BASEBOARD_FAB2_LIB.BASEBOARD_FAB2(SCH_1):PAGE63

TP_CPU1_RSVD_175 @BASEBOARD_FAB2_LIB.BASEBOARD_FAB2(SCH_1):TP_CPU1_RSVD_175
  U2D1 BA22 RSVD<175> SKX_EXT_B_BGA1-IC,TBD    I23 @BASEBOARD_FAB2_LIB.BASEBOARD_FAB2(SCH_1):PAGE63

TP_CPU1_RSVD_176 @BASEBOARD_FAB2_LIB.BASEBOARD_FAB2(SCH_1):TP_CPU1_RSVD_176
  U2D1 BA18 RSVD<176> SKX_EXT_B_BGA1-IC,TBD    I23 @BASEBOARD_FAB2_LIB.BASEBOARD_FAB2(SCH_1):PAGE63

TP_CPU1_RSVD_177 @BASEBOARD_FAB2_LIB.BASEBOARD_FAB2(SCH_1):TP_CPU1_RSVD_177
  U2D1 BA16 RSVD<177> SKX_EXT_B_BGA1-IC,TBD    I23 @BASEBOARD_FAB2_LIB.BASEBOARD_FAB2(SCH_1):PAGE63

TP_CPU1_RSVD_178 @BASEBOARD_FAB2_LIB.BASEBOARD_FAB2(SCH_1):TP_CPU1_RSVD_178
  U2D1 BA14 RSVD<178> SKX_EXT_B_BGA1-IC,TBD    I23 @BASEBOARD_FAB2_LIB.BASEBOARD_FAB2(SCH_1):PAGE63

TP_CPU1_RSVD_179 @BASEBOARD_FAB2_LIB.BASEBOARD_FAB2(SCH_1):TP_CPU1_RSVD_179
  U2D1 AY77 RSVD<179> SKX_EXT_B_BGA1-IC,TBD    I23 @BASEBOARD_FAB2_LIB.BASEBOARD_FAB2(SCH_1):PAGE63

TP_CPU1_RSVD_18 @BASEBOARD_FAB2_LIB.BASEBOARD_FAB2(SCH_1):TP_CPU1_RSVD_18
  U2D1  EB3 RSVD<18> SKX_EXT_B_BGA1-IC,TBD   I107 @BASEBOARD_FAB2_LIB.BASEBOARD_FAB2(SCH_1):PAGE73

TP_CPU1_RSVD_180 @BASEBOARD_FAB2_LIB.BASEBOARD_FAB2(SCH_1):TP_CPU1_RSVD_180
  U2D1 AY75 RSVD<180> SKX_EXT_B_BGA1-IC,TBD    I23 @BASEBOARD_FAB2_LIB.BASEBOARD_FAB2(SCH_1):PAGE63

TP_CPU1_RSVD_181 @BASEBOARD_FAB2_LIB.BASEBOARD_FAB2(SCH_1):TP_CPU1_RSVD_181
  U2D1 AY67 RSVD<181> SKX_EXT_B_BGA1-IC,TBD    I23 @BASEBOARD_FAB2_LIB.BASEBOARD_FAB2(SCH_1):PAGE63

TP_CPU1_RSVD_182 @BASEBOARD_FAB2_LIB.BASEBOARD_FAB2(SCH_1):TP_CPU1_RSVD_182
  U2D1 AY65 RSVD<182> SKX_EXT_B_BGA1-IC,TBD    I23 @BASEBOARD_FAB2_LIB.BASEBOARD_FAB2(SCH_1):PAGE63

TP_CPU1_RSVD_183 @BASEBOARD_FAB2_LIB.BASEBOARD_FAB2(SCH_1):TP_CPU1_RSVD_183
  U2D1 AW76 RSVD<183> SKX_EXT_B_BGA1-IC,TBD    I23 @BASEBOARD_FAB2_LIB.BASEBOARD_FAB2(SCH_1):PAGE63

TP_CPU1_RSVD_184 @BASEBOARD_FAB2_LIB.BASEBOARD_FAB2(SCH_1):TP_CPU1_RSVD_184
  U2D1 AW64 RSVD<184> SKX_EXT_B_BGA1-IC,TBD    I23 @BASEBOARD_FAB2_LIB.BASEBOARD_FAB2(SCH_1):PAGE63

TP_CPU1_RSVD_186 @BASEBOARD_FAB2_LIB.BASEBOARD_FAB2(SCH_1):TP_CPU1_RSVD_186
  U2D1 AV77 RSVD<186> SKX_EXT_B_BGA1-IC,TBD    I23 @BASEBOARD_FAB2_LIB.BASEBOARD_FAB2(SCH_1):PAGE63

TP_CPU1_RSVD_189 @BASEBOARD_FAB2_LIB.BASEBOARD_FAB2(SCH_1):TP_CPU1_RSVD_189
  U2D1 AT13 RSVD<189> SKX_EXT_B_BGA1-IC,TBD    I23 @BASEBOARD_FAB2_LIB.BASEBOARD_FAB2(SCH_1):PAGE63

TP_CPU1_RSVD_19 @BASEBOARD_FAB2_LIB.BASEBOARD_FAB2(SCH_1):TP_CPU1_RSVD_19
  U2D1 EA44 RSVD<19> SKX_EXT_B_BGA1-IC,TBD   I107 @BASEBOARD_FAB2_LIB.BASEBOARD_FAB2(SCH_1):PAGE73

TP_CPU1_RSVD_190 @BASEBOARD_FAB2_LIB.BASEBOARD_FAB2(SCH_1):TP_CPU1_RSVD_190
  U2D1 AR62 RSVD<190> SKX_EXT_B_BGA1-IC,TBD    I23 @BASEBOARD_FAB2_LIB.BASEBOARD_FAB2(SCH_1):PAGE63

TP_CPU1_RSVD_194 @BASEBOARD_FAB2_LIB.BASEBOARD_FAB2(SCH_1):TP_CPU1_RSVD_194
  U2D1 AP61 RSVD<194> SKX_EXT_B_BGA1-IC,TBD   I169 @BASEBOARD_FAB2_LIB.BASEBOARD_FAB2(SCH_1):PAGE56

TP_CPU1_RSVD_198 @BASEBOARD_FAB2_LIB.BASEBOARD_FAB2(SCH_1):TP_CPU1_RSVD_198
  U2D1 AN62 RSVD<198> SKX_EXT_B_BGA1-IC,TBD   I169 @BASEBOARD_FAB2_LIB.BASEBOARD_FAB2(SCH_1):PAGE56

TP_CPU1_RSVD_199 @BASEBOARD_FAB2_LIB.BASEBOARD_FAB2(SCH_1):TP_CPU1_RSVD_199
  U2D1 AN60 RSVD<199> SKX_EXT_B_BGA1-IC,TBD   I169 @BASEBOARD_FAB2_LIB.BASEBOARD_FAB2(SCH_1):PAGE56

TP_CPU1_RSVD_2 @BASEBOARD_FAB2_LIB.BASEBOARD_FAB2(SCH_1):TP_CPU1_RSVD_2
  U2D1 EF77 RSVD<2> SKX_EXT_B_BGA1-IC,TBD   I107 @BASEBOARD_FAB2_LIB.BASEBOARD_FAB2(SCH_1):PAGE73

TP_CPU1_RSVD_20 @BASEBOARD_FAB2_LIB.BASEBOARD_FAB2(SCH_1):TP_CPU1_RSVD_20
  U2D1  EA4 RSVD<20> SKX_EXT_B_BGA1-IC,TBD   I107 @BASEBOARD_FAB2_LIB.BASEBOARD_FAB2(SCH_1):PAGE73

TP_CPU1_RSVD_204 @BASEBOARD_FAB2_LIB.BASEBOARD_FAB2(SCH_1):TP_CPU1_RSVD_204
  U2D1 AM61 RSVD<204> SKX_EXT_B_BGA1-IC,TBD   I169 @BASEBOARD_FAB2_LIB.BASEBOARD_FAB2(SCH_1):PAGE56

TP_CPU1_RSVD_205 @BASEBOARD_FAB2_LIB.BASEBOARD_FAB2(SCH_1):TP_CPU1_RSVD_205
  U2D1 AM59 RSVD<205> SKX_EXT_B_BGA1-IC,TBD   I169 @BASEBOARD_FAB2_LIB.BASEBOARD_FAB2(SCH_1):PAGE56

TP_CPU1_RSVD_208 @BASEBOARD_FAB2_LIB.BASEBOARD_FAB2(SCH_1):TP_CPU1_RSVD_208
  U2D1 AM23 RSVD<208> SKX_EXT_B_BGA1-IC,TBD   I169 @BASEBOARD_FAB2_LIB.BASEBOARD_FAB2(SCH_1):PAGE56

TP_CPU1_RSVD_21 @BASEBOARD_FAB2_LIB.BASEBOARD_FAB2(SCH_1):TP_CPU1_RSVD_21
  U2D1  DY3 RSVD<21> SKX_EXT_B_BGA1-IC,TBD   I107 @BASEBOARD_FAB2_LIB.BASEBOARD_FAB2(SCH_1):PAGE73

TP_CPU1_RSVD_210 @BASEBOARD_FAB2_LIB.BASEBOARD_FAB2(SCH_1):TP_CPU1_RSVD_210
  U2D1 AL62 RSVD<210> SKX_EXT_B_BGA1-IC,TBD   I169 @BASEBOARD_FAB2_LIB.BASEBOARD_FAB2(SCH_1):PAGE56

TP_CPU1_RSVD_211 @BASEBOARD_FAB2_LIB.BASEBOARD_FAB2(SCH_1):TP_CPU1_RSVD_211
  U2D1 AL60 RSVD<211> SKX_EXT_B_BGA1-IC,TBD   I169 @BASEBOARD_FAB2_LIB.BASEBOARD_FAB2(SCH_1):PAGE56

TP_CPU1_RSVD_212 @BASEBOARD_FAB2_LIB.BASEBOARD_FAB2(SCH_1):TP_CPU1_RSVD_212
  U2D1 AL58 RSVD<212> SKX_EXT_B_BGA1-IC,TBD   I169 @BASEBOARD_FAB2_LIB.BASEBOARD_FAB2(SCH_1):PAGE56

TP_CPU1_RSVD_214 @BASEBOARD_FAB2_LIB.BASEBOARD_FAB2(SCH_1):TP_CPU1_RSVD_214
  U2D1 AL22 RSVD<214> SKX_EXT_B_BGA1-IC,TBD   I169 @BASEBOARD_FAB2_LIB.BASEBOARD_FAB2(SCH_1):PAGE56

TP_CPU1_RSVD_216 @BASEBOARD_FAB2_LIB.BASEBOARD_FAB2(SCH_1):TP_CPU1_RSVD_216
  U2D1 AK69 RSVD<216> SKX_EXT_B_BGA1-IC,TBD   I169 @BASEBOARD_FAB2_LIB.BASEBOARD_FAB2(SCH_1):PAGE56

TP_CPU1_RSVD_217 @BASEBOARD_FAB2_LIB.BASEBOARD_FAB2(SCH_1):TP_CPU1_RSVD_217
  U2D1 AK61 RSVD<217> SKX_EXT_B_BGA1-IC,TBD   I169 @BASEBOARD_FAB2_LIB.BASEBOARD_FAB2(SCH_1):PAGE56

TP_CPU1_RSVD_218 @BASEBOARD_FAB2_LIB.BASEBOARD_FAB2(SCH_1):TP_CPU1_RSVD_218
  U2D1 AK59 RSVD<218> SKX_EXT_B_BGA1-IC,TBD   I169 @BASEBOARD_FAB2_LIB.BASEBOARD_FAB2(SCH_1):PAGE56

TP_CPU1_RSVD_219 @BASEBOARD_FAB2_LIB.BASEBOARD_FAB2(SCH_1):TP_CPU1_RSVD_219
  U2D1 AK57 RSVD<219> SKX_EXT_B_BGA1-IC,TBD   I169 @BASEBOARD_FAB2_LIB.BASEBOARD_FAB2(SCH_1):PAGE56

TP_CPU1_RSVD_22 @BASEBOARD_FAB2_LIB.BASEBOARD_FAB2(SCH_1):TP_CPU1_RSVD_22
  U2D1 DW46 RSVD<22> SKX_EXT_B_BGA1-IC,TBD   I107 @BASEBOARD_FAB2_LIB.BASEBOARD_FAB2(SCH_1):PAGE73

TP_CPU1_RSVD_222 @BASEBOARD_FAB2_LIB.BASEBOARD_FAB2(SCH_1):TP_CPU1_RSVD_222
  U2D1 AJ70 RSVD<222> SKX_EXT_B_BGA1-IC,TBD   I169 @BASEBOARD_FAB2_LIB.BASEBOARD_FAB2(SCH_1):PAGE56

TP_CPU1_RSVD_223 @BASEBOARD_FAB2_LIB.BASEBOARD_FAB2(SCH_1):TP_CPU1_RSVD_223
  U2D1 AJ62 RSVD<223> SKX_EXT_B_BGA1-IC,TBD   I169 @BASEBOARD_FAB2_LIB.BASEBOARD_FAB2(SCH_1):PAGE56

TP_CPU1_RSVD_224 @BASEBOARD_FAB2_LIB.BASEBOARD_FAB2(SCH_1):TP_CPU1_RSVD_224
  U2D1 AJ60 RSVD<224> SKX_EXT_B_BGA1-IC,TBD   I169 @BASEBOARD_FAB2_LIB.BASEBOARD_FAB2(SCH_1):PAGE56

TP_CPU1_RSVD_225 @BASEBOARD_FAB2_LIB.BASEBOARD_FAB2(SCH_1):TP_CPU1_RSVD_225
  U2D1 AJ58 RSVD<225> SKX_EXT_B_BGA1-IC,TBD   I169 @BASEBOARD_FAB2_LIB.BASEBOARD_FAB2(SCH_1):PAGE56

TP_CPU1_RSVD_226 @BASEBOARD_FAB2_LIB.BASEBOARD_FAB2(SCH_1):TP_CPU1_RSVD_226
  U2D1 AJ56 RSVD<226> SKX_EXT_B_BGA1-IC,TBD   I169 @BASEBOARD_FAB2_LIB.BASEBOARD_FAB2(SCH_1):PAGE56

TP_CPU1_RSVD_227 @BASEBOARD_FAB2_LIB.BASEBOARD_FAB2(SCH_1):TP_CPU1_RSVD_227
  U2D1 AJ20 RSVD<227> SKX_EXT_B_BGA1-IC,TBD   I169 @BASEBOARD_FAB2_LIB.BASEBOARD_FAB2(SCH_1):PAGE56

TP_CPU1_RSVD_228 @BASEBOARD_FAB2_LIB.BASEBOARD_FAB2(SCH_1):TP_CPU1_RSVD_228
  U2D1 AH73 RSVD<228> SKX_EXT_B_BGA1-IC,TBD   I169 @BASEBOARD_FAB2_LIB.BASEBOARD_FAB2(SCH_1):PAGE56

TP_CPU1_RSVD_229 @BASEBOARD_FAB2_LIB.BASEBOARD_FAB2(SCH_1):TP_CPU1_RSVD_229
  U2D1 AH71 RSVD<229> SKX_EXT_B_BGA1-IC,TBD   I169 @BASEBOARD_FAB2_LIB.BASEBOARD_FAB2(SCH_1):PAGE56

TP_CPU1_RSVD_23 @BASEBOARD_FAB2_LIB.BASEBOARD_FAB2(SCH_1):TP_CPU1_RSVD_23
  U2D1 DW44 RSVD<23> SKX_EXT_B_BGA1-IC,TBD   I107 @BASEBOARD_FAB2_LIB.BASEBOARD_FAB2(SCH_1):PAGE73

TP_CPU1_RSVD_230 @BASEBOARD_FAB2_LIB.BASEBOARD_FAB2(SCH_1):TP_CPU1_RSVD_230
  U2D1 AH57 RSVD<230> SKX_EXT_B_BGA1-IC,TBD   I169 @BASEBOARD_FAB2_LIB.BASEBOARD_FAB2(SCH_1):PAGE56

TP_CPU1_RSVD_231 @BASEBOARD_FAB2_LIB.BASEBOARD_FAB2(SCH_1):TP_CPU1_RSVD_231
  U2D1 AH55 RSVD<231> SKX_EXT_B_BGA1-IC,TBD   I169 @BASEBOARD_FAB2_LIB.BASEBOARD_FAB2(SCH_1):PAGE56

TP_CPU1_RSVD_232 @BASEBOARD_FAB2_LIB.BASEBOARD_FAB2(SCH_1):TP_CPU1_RSVD_232
  U2D1 AH19 RSVD<232> SKX_EXT_B_BGA1-IC,TBD   I169 @BASEBOARD_FAB2_LIB.BASEBOARD_FAB2(SCH_1):PAGE56

TP_CPU1_RSVD_233 @BASEBOARD_FAB2_LIB.BASEBOARD_FAB2(SCH_1):TP_CPU1_RSVD_233
  U2D1 AH15 RSVD<233> SKX_EXT_B_BGA1-IC,TBD   I169 @BASEBOARD_FAB2_LIB.BASEBOARD_FAB2(SCH_1):PAGE56

TP_CPU1_RSVD_234 @BASEBOARD_FAB2_LIB.BASEBOARD_FAB2(SCH_1):TP_CPU1_RSVD_234
  U2D1 AG72 RSVD<234> SKX_EXT_B_BGA1-IC,TBD   I169 @BASEBOARD_FAB2_LIB.BASEBOARD_FAB2(SCH_1):PAGE56

TP_CPU1_RSVD_235 @BASEBOARD_FAB2_LIB.BASEBOARD_FAB2(SCH_1):TP_CPU1_RSVD_235
  U2D1 AG56 RSVD<235> SKX_EXT_B_BGA1-IC,TBD   I169 @BASEBOARD_FAB2_LIB.BASEBOARD_FAB2(SCH_1):PAGE56

TP_CPU1_RSVD_236 @BASEBOARD_FAB2_LIB.BASEBOARD_FAB2(SCH_1):TP_CPU1_RSVD_236
  U2D1 AG54 RSVD<236> SKX_EXT_B_BGA1-IC,TBD   I169 @BASEBOARD_FAB2_LIB.BASEBOARD_FAB2(SCH_1):PAGE56

TP_CPU1_RSVD_237 @BASEBOARD_FAB2_LIB.BASEBOARD_FAB2(SCH_1):TP_CPU1_RSVD_237
  U2D1 AG52 RSVD<237> SKX_EXT_B_BGA1-IC,TBD   I169 @BASEBOARD_FAB2_LIB.BASEBOARD_FAB2(SCH_1):PAGE56

TP_CPU1_RSVD_238 @BASEBOARD_FAB2_LIB.BASEBOARD_FAB2(SCH_1):TP_CPU1_RSVD_238
  U2D1 AG50 RSVD<238> SKX_EXT_B_BGA1-IC,TBD   I169 @BASEBOARD_FAB2_LIB.BASEBOARD_FAB2(SCH_1):PAGE56

TP_CPU1_RSVD_239 @BASEBOARD_FAB2_LIB.BASEBOARD_FAB2(SCH_1):TP_CPU1_RSVD_239
  U2D1 AG48 RSVD<239> SKX_EXT_B_BGA1-IC,TBD   I169 @BASEBOARD_FAB2_LIB.BASEBOARD_FAB2(SCH_1):PAGE56

TP_CPU1_RSVD_24 @BASEBOARD_FAB2_LIB.BASEBOARD_FAB2(SCH_1):TP_CPU1_RSVD_24
  U2D1 DV71 RSVD<24> SKX_EXT_B_BGA1-IC,TBD   I107 @BASEBOARD_FAB2_LIB.BASEBOARD_FAB2(SCH_1):PAGE73

TP_CPU1_RSVD_240 @BASEBOARD_FAB2_LIB.BASEBOARD_FAB2(SCH_1):TP_CPU1_RSVD_240
  U2D1 AG20 RSVD<240> SKX_EXT_B_BGA1-IC,TBD   I169 @BASEBOARD_FAB2_LIB.BASEBOARD_FAB2(SCH_1):PAGE56

TP_CPU1_RSVD_241 @BASEBOARD_FAB2_LIB.BASEBOARD_FAB2(SCH_1):TP_CPU1_RSVD_241
  U2D1 AF71 RSVD<241> SKX_EXT_B_BGA1-IC,TBD   I169 @BASEBOARD_FAB2_LIB.BASEBOARD_FAB2(SCH_1):PAGE56

TP_CPU1_RSVD_242 @BASEBOARD_FAB2_LIB.BASEBOARD_FAB2(SCH_1):TP_CPU1_RSVD_242
  U2D1 AF53 RSVD<242> SKX_EXT_B_BGA1-IC,TBD   I169 @BASEBOARD_FAB2_LIB.BASEBOARD_FAB2(SCH_1):PAGE56

TP_CPU1_RSVD_243 @BASEBOARD_FAB2_LIB.BASEBOARD_FAB2(SCH_1):TP_CPU1_RSVD_243
  U2D1 AF51 RSVD<243> SKX_EXT_B_BGA1-IC,TBD   I169 @BASEBOARD_FAB2_LIB.BASEBOARD_FAB2(SCH_1):PAGE56

TP_CPU1_RSVD_244 @BASEBOARD_FAB2_LIB.BASEBOARD_FAB2(SCH_1):TP_CPU1_RSVD_244
  U2D1 AF49 RSVD<244> SKX_EXT_B_BGA1-IC,TBD   I169 @BASEBOARD_FAB2_LIB.BASEBOARD_FAB2(SCH_1):PAGE56

TP_CPU1_RSVD_245 @BASEBOARD_FAB2_LIB.BASEBOARD_FAB2(SCH_1):TP_CPU1_RSVD_245
  U2D1 AF47 RSVD<245> SKX_EXT_B_BGA1-IC,TBD   I169 @BASEBOARD_FAB2_LIB.BASEBOARD_FAB2(SCH_1):PAGE56

TP_CPU1_RSVD_246 @BASEBOARD_FAB2_LIB.BASEBOARD_FAB2(SCH_1):TP_CPU1_RSVD_246
  U2D1 AF19 RSVD<246> SKX_EXT_B_BGA1-IC,TBD   I169 @BASEBOARD_FAB2_LIB.BASEBOARD_FAB2(SCH_1):PAGE56

TP_CPU1_RSVD_247 @BASEBOARD_FAB2_LIB.BASEBOARD_FAB2(SCH_1):TP_CPU1_RSVD_247
  U2D1 AE72 RSVD<247> SKX_EXT_B_BGA1-IC,TBD   I169 @BASEBOARD_FAB2_LIB.BASEBOARD_FAB2(SCH_1):PAGE56

TP_CPU1_RSVD_248 @BASEBOARD_FAB2_LIB.BASEBOARD_FAB2(SCH_1):TP_CPU1_RSVD_248
  U2D1 AE52 RSVD<248> SKX_EXT_B_BGA1-IC,TBD   I169 @BASEBOARD_FAB2_LIB.BASEBOARD_FAB2(SCH_1):PAGE56

TP_CPU1_RSVD_249 @BASEBOARD_FAB2_LIB.BASEBOARD_FAB2(SCH_1):TP_CPU1_RSVD_249
  U2D1 AE50 RSVD<249> SKX_EXT_B_BGA1-IC,TBD   I169 @BASEBOARD_FAB2_LIB.BASEBOARD_FAB2(SCH_1):PAGE56

TP_CPU1_RSVD_25 @BASEBOARD_FAB2_LIB.BASEBOARD_FAB2(SCH_1):TP_CPU1_RSVD_25
  U2D1 DV61 RSVD<25> SKX_EXT_B_BGA1-IC,TBD   I107 @BASEBOARD_FAB2_LIB.BASEBOARD_FAB2(SCH_1):PAGE73

TP_CPU1_RSVD_250 @BASEBOARD_FAB2_LIB.BASEBOARD_FAB2(SCH_1):TP_CPU1_RSVD_250
  U2D1 AE48 RSVD<250> SKX_EXT_B_BGA1-IC,TBD   I169 @BASEBOARD_FAB2_LIB.BASEBOARD_FAB2(SCH_1):PAGE56

TP_CPU1_RSVD_251 @BASEBOARD_FAB2_LIB.BASEBOARD_FAB2(SCH_1):TP_CPU1_RSVD_251
  U2D1 AE46 RSVD<251> SKX_EXT_B_BGA1-IC,TBD   I169 @BASEBOARD_FAB2_LIB.BASEBOARD_FAB2(SCH_1):PAGE56

TP_CPU1_RSVD_252 @BASEBOARD_FAB2_LIB.BASEBOARD_FAB2(SCH_1):TP_CPU1_RSVD_252
  U2D1 AD51 RSVD<252> SKX_EXT_B_BGA1-IC,TBD   I169 @BASEBOARD_FAB2_LIB.BASEBOARD_FAB2(SCH_1):PAGE56

TP_CPU1_RSVD_253 @BASEBOARD_FAB2_LIB.BASEBOARD_FAB2(SCH_1):TP_CPU1_RSVD_253
  U2D1 AD49 RSVD<253> SKX_EXT_B_BGA1-IC,TBD   I169 @BASEBOARD_FAB2_LIB.BASEBOARD_FAB2(SCH_1):PAGE56

TP_CPU1_RSVD_254 @BASEBOARD_FAB2_LIB.BASEBOARD_FAB2(SCH_1):TP_CPU1_RSVD_254
  U2D1 AD47 RSVD<254> SKX_EXT_B_BGA1-IC,TBD   I169 @BASEBOARD_FAB2_LIB.BASEBOARD_FAB2(SCH_1):PAGE56

TP_CPU1_RSVD_255 @BASEBOARD_FAB2_LIB.BASEBOARD_FAB2(SCH_1):TP_CPU1_RSVD_255
  U2D1 AY83 RSVD<255> SKX_EXT_B_BGA1-IC,TBD     I9 @BASEBOARD_FAB2_LIB.BASEBOARD_FAB2(SCH_1):PAGE70

TP_CPU1_RSVD_256 @BASEBOARD_FAB2_LIB.BASEBOARD_FAB2(SCH_1):TP_CPU1_RSVD_256
  U2D1  Y65 RSVD<256> SKX_EXT_B_BGA1-IC,TBD   I169 @BASEBOARD_FAB2_LIB.BASEBOARD_FAB2(SCH_1):PAGE56

TP_CPU1_RSVD_258 @BASEBOARD_FAB2_LIB.BASEBOARD_FAB2(SCH_1):TP_CPU1_RSVD_258
  U2D1  W66 RSVD<258> SKX_EXT_B_BGA1-IC,TBD   I169 @BASEBOARD_FAB2_LIB.BASEBOARD_FAB2(SCH_1):PAGE56

TP_CPU1_RSVD_259 @BASEBOARD_FAB2_LIB.BASEBOARD_FAB2(SCH_1):TP_CPU1_RSVD_259
  U2D1  V67 RSVD<259> SKX_EXT_B_BGA1-IC,TBD   I169 @BASEBOARD_FAB2_LIB.BASEBOARD_FAB2(SCH_1):PAGE56

TP_CPU1_RSVD_26 @BASEBOARD_FAB2_LIB.BASEBOARD_FAB2(SCH_1):TP_CPU1_RSVD_26
  U2D1 DU44 RSVD<26> SKX_EXT_B_BGA1-IC,TBD   I107 @BASEBOARD_FAB2_LIB.BASEBOARD_FAB2(SCH_1):PAGE73

TP_CPU1_RSVD_260 @BASEBOARD_FAB2_LIB.BASEBOARD_FAB2(SCH_1):TP_CPU1_RSVD_260
  U2D1  V65 RSVD<260> SKX_EXT_B_BGA1-IC,TBD   I169 @BASEBOARD_FAB2_LIB.BASEBOARD_FAB2(SCH_1):PAGE56

TP_CPU1_RSVD_261 @BASEBOARD_FAB2_LIB.BASEBOARD_FAB2(SCH_1):TP_CPU1_RSVD_261
  U2D1  U66 RSVD<261> SKX_EXT_B_BGA1-IC,TBD   I169 @BASEBOARD_FAB2_LIB.BASEBOARD_FAB2(SCH_1):PAGE56

TP_CPU1_RSVD_262 @BASEBOARD_FAB2_LIB.BASEBOARD_FAB2(SCH_1):TP_CPU1_RSVD_262
  U2D1  T67 RSVD<262> SKX_EXT_B_BGA1-IC,TBD   I169 @BASEBOARD_FAB2_LIB.BASEBOARD_FAB2(SCH_1):PAGE56

TP_CPU1_RSVD_263 @BASEBOARD_FAB2_LIB.BASEBOARD_FAB2(SCH_1):TP_CPU1_RSVD_263
  U2D1  R66 RSVD<263> SKX_EXT_B_BGA1-IC,TBD   I169 @BASEBOARD_FAB2_LIB.BASEBOARD_FAB2(SCH_1):PAGE56

TP_CPU1_RSVD_264 @BASEBOARD_FAB2_LIB.BASEBOARD_FAB2(SCH_1):TP_CPU1_RSVD_264
  U2D1  R62 RSVD<264> SKX_EXT_B_BGA1-IC,TBD   I169 @BASEBOARD_FAB2_LIB.BASEBOARD_FAB2(SCH_1):PAGE56

TP_CPU1_RSVD_265 @BASEBOARD_FAB2_LIB.BASEBOARD_FAB2(SCH_1):TP_CPU1_RSVD_265
  U2D1  P65 RSVD<265> SKX_EXT_B_BGA1-IC,TBD   I169 @BASEBOARD_FAB2_LIB.BASEBOARD_FAB2(SCH_1):PAGE56

TP_CPU1_RSVD_266 @BASEBOARD_FAB2_LIB.BASEBOARD_FAB2(SCH_1):TP_CPU1_RSVD_266
  U2D1  M63 RSVD<266> SKX_EXT_B_BGA1-IC,TBD   I169 @BASEBOARD_FAB2_LIB.BASEBOARD_FAB2(SCH_1):PAGE56

TP_CPU1_RSVD_267 @BASEBOARD_FAB2_LIB.BASEBOARD_FAB2(SCH_1):TP_CPU1_RSVD_267
  U2D1  K61 RSVD<267> SKX_EXT_B_BGA1-IC,TBD   I169 @BASEBOARD_FAB2_LIB.BASEBOARD_FAB2(SCH_1):PAGE56

TP_CPU1_RSVD_268 @BASEBOARD_FAB2_LIB.BASEBOARD_FAB2(SCH_1):TP_CPU1_RSVD_268
  U2D1  J62 RSVD<268> SKX_EXT_B_BGA1-IC,TBD   I169 @BASEBOARD_FAB2_LIB.BASEBOARD_FAB2(SCH_1):PAGE56

TP_CPU1_RSVD_269 @BASEBOARD_FAB2_LIB.BASEBOARD_FAB2(SCH_1):TP_CPU1_RSVD_269
  U2D1  J46 RSVD<269> SKX_EXT_B_BGA1-IC,TBD   I169 @BASEBOARD_FAB2_LIB.BASEBOARD_FAB2(SCH_1):PAGE56

TP_CPU1_RSVD_27 @BASEBOARD_FAB2_LIB.BASEBOARD_FAB2(SCH_1):TP_CPU1_RSVD_27
  U2D1 DT71 RSVD<27> SKX_EXT_B_BGA1-IC,TBD   I107 @BASEBOARD_FAB2_LIB.BASEBOARD_FAB2(SCH_1):PAGE73

TP_CPU1_RSVD_270 @BASEBOARD_FAB2_LIB.BASEBOARD_FAB2(SCH_1):TP_CPU1_RSVD_270
  U2D1  H85 RSVD<270> SKX_EXT_B_BGA1-IC,TBD   I169 @BASEBOARD_FAB2_LIB.BASEBOARD_FAB2(SCH_1):PAGE56

TP_CPU1_RSVD_271 @BASEBOARD_FAB2_LIB.BASEBOARD_FAB2(SCH_1):TP_CPU1_RSVD_271
  U2D1  H83 RSVD<271> SKX_EXT_B_BGA1-IC,TBD   I169 @BASEBOARD_FAB2_LIB.BASEBOARD_FAB2(SCH_1):PAGE56

TP_CPU1_RSVD_272 @BASEBOARD_FAB2_LIB.BASEBOARD_FAB2(SCH_1):TP_CPU1_RSVD_272
  U2D1   H1 RSVD<272> SKX_EXT_B_BGA1-IC,TBD   I169 @BASEBOARD_FAB2_LIB.BASEBOARD_FAB2(SCH_1):PAGE56

TP_CPU1_RSVD_273 @BASEBOARD_FAB2_LIB.BASEBOARD_FAB2(SCH_1):TP_CPU1_RSVD_273
  U2D1  G84 RSVD<273> SKX_EXT_B_BGA1-IC,TBD   I169 @BASEBOARD_FAB2_LIB.BASEBOARD_FAB2(SCH_1):PAGE56

TP_CPU1_RSVD_274 @BASEBOARD_FAB2_LIB.BASEBOARD_FAB2(SCH_1):TP_CPU1_RSVD_274
  U2D1  G64 RSVD<274> SKX_EXT_B_BGA1-IC,TBD   I169 @BASEBOARD_FAB2_LIB.BASEBOARD_FAB2(SCH_1):PAGE56

TP_CPU1_RSVD_275 @BASEBOARD_FAB2_LIB.BASEBOARD_FAB2(SCH_1):TP_CPU1_RSVD_275
  U2D1   G2 RSVD<275> SKX_EXT_B_BGA1-IC,TBD   I169 @BASEBOARD_FAB2_LIB.BASEBOARD_FAB2(SCH_1):PAGE56

TP_CPU1_RSVD_276 @BASEBOARD_FAB2_LIB.BASEBOARD_FAB2(SCH_1):TP_CPU1_RSVD_276
  U2D1  F83 RSVD<276> SKX_EXT_B_BGA1-IC,TBD   I169 @BASEBOARD_FAB2_LIB.BASEBOARD_FAB2(SCH_1):PAGE56

TP_CPU1_RSVD_277 @BASEBOARD_FAB2_LIB.BASEBOARD_FAB2(SCH_1):TP_CPU1_RSVD_277
  U2D1  F65 RSVD<277> SKX_EXT_B_BGA1-IC,TBD   I169 @BASEBOARD_FAB2_LIB.BASEBOARD_FAB2(SCH_1):PAGE56

TP_CPU1_RSVD_278 @BASEBOARD_FAB2_LIB.BASEBOARD_FAB2(SCH_1):TP_CPU1_RSVD_278
  U2D1  F23 RSVD<278> SKX_EXT_B_BGA1-IC,TBD   I169 @BASEBOARD_FAB2_LIB.BASEBOARD_FAB2(SCH_1):PAGE56

TP_CPU1_RSVD_279 @BASEBOARD_FAB2_LIB.BASEBOARD_FAB2(SCH_1):TP_CPU1_RSVD_279
  U2D1   F3 RSVD<279> SKX_EXT_B_BGA1-IC,TBD   I169 @BASEBOARD_FAB2_LIB.BASEBOARD_FAB2(SCH_1):PAGE56

TP_CPU1_RSVD_28 @BASEBOARD_FAB2_LIB.BASEBOARD_FAB2(SCH_1):TP_CPU1_RSVD_28
  U2D1 DR44 RSVD<28> SKX_EXT_B_BGA1-IC,TBD   I107 @BASEBOARD_FAB2_LIB.BASEBOARD_FAB2(SCH_1):PAGE73

TP_CPU1_RSVD_280 @BASEBOARD_FAB2_LIB.BASEBOARD_FAB2(SCH_1):TP_CPU1_RSVD_280
  U2D1  E84 RSVD<280> SKX_EXT_B_BGA1-IC,TBD   I169 @BASEBOARD_FAB2_LIB.BASEBOARD_FAB2(SCH_1):PAGE56

TP_CPU1_RSVD_281 @BASEBOARD_FAB2_LIB.BASEBOARD_FAB2(SCH_1):TP_CPU1_RSVD_281
  U2D1  E24 RSVD<281> SKX_EXT_B_BGA1-IC,TBD   I169 @BASEBOARD_FAB2_LIB.BASEBOARD_FAB2(SCH_1):PAGE56

TP_CPU1_RSVD_282 @BASEBOARD_FAB2_LIB.BASEBOARD_FAB2(SCH_1):TP_CPU1_RSVD_282
  U2D1   E4 RSVD<282> SKX_EXT_B_BGA1-IC,TBD   I169 @BASEBOARD_FAB2_LIB.BASEBOARD_FAB2(SCH_1):PAGE56

TP_CPU1_RSVD_283 @BASEBOARD_FAB2_LIB.BASEBOARD_FAB2(SCH_1):TP_CPU1_RSVD_283
  U2D1   E2 RSVD<283> SKX_EXT_B_BGA1-IC,TBD   I169 @BASEBOARD_FAB2_LIB.BASEBOARD_FAB2(SCH_1):PAGE56

TP_CPU1_RSVD_284 @BASEBOARD_FAB2_LIB.BASEBOARD_FAB2(SCH_1):TP_CPU1_RSVD_284
  U2D1  D83 RSVD<284> SKX_EXT_B_BGA1-IC,TBD   I169 @BASEBOARD_FAB2_LIB.BASEBOARD_FAB2(SCH_1):PAGE56

TP_CPU1_RSVD_285 @BASEBOARD_FAB2_LIB.BASEBOARD_FAB2(SCH_1):TP_CPU1_RSVD_285
  U2D1  D65 RSVD<285> SKX_EXT_B_BGA1-IC,TBD   I169 @BASEBOARD_FAB2_LIB.BASEBOARD_FAB2(SCH_1):PAGE56

TP_CPU1_RSVD_286 @BASEBOARD_FAB2_LIB.BASEBOARD_FAB2(SCH_1):TP_CPU1_RSVD_286
  U2D1  D17 RSVD<286> SKX_EXT_B_BGA1-IC,TBD   I169 @BASEBOARD_FAB2_LIB.BASEBOARD_FAB2(SCH_1):PAGE56

TP_CPU1_RSVD_287 @BASEBOARD_FAB2_LIB.BASEBOARD_FAB2(SCH_1):TP_CPU1_RSVD_287
  U2D1   D5 RSVD<287> SKX_EXT_B_BGA1-IC,TBD   I169 @BASEBOARD_FAB2_LIB.BASEBOARD_FAB2(SCH_1):PAGE56

TP_CPU1_RSVD_288 @BASEBOARD_FAB2_LIB.BASEBOARD_FAB2(SCH_1):TP_CPU1_RSVD_288
  U2D1  C82 RSVD<288> SKX_EXT_B_BGA1-IC,TBD   I169 @BASEBOARD_FAB2_LIB.BASEBOARD_FAB2(SCH_1):PAGE56

TP_CPU1_RSVD_289 @BASEBOARD_FAB2_LIB.BASEBOARD_FAB2(SCH_1):TP_CPU1_RSVD_289
  U2D1  C24 RSVD<289> SKX_EXT_B_BGA1-IC,TBD   I169 @BASEBOARD_FAB2_LIB.BASEBOARD_FAB2(SCH_1):PAGE56

TP_CPU1_RSVD_29 @BASEBOARD_FAB2_LIB.BASEBOARD_FAB2(SCH_1):TP_CPU1_RSVD_29
  U2D1 DP65 RSVD<29> SKX_EXT_B_BGA1-IC,TBD   I107 @BASEBOARD_FAB2_LIB.BASEBOARD_FAB2(SCH_1):PAGE73

TP_CPU1_RSVD_290 @BASEBOARD_FAB2_LIB.BASEBOARD_FAB2(SCH_1):TP_CPU1_RSVD_290
  U2D1  C18 RSVD<290> SKX_EXT_B_BGA1-IC,TBD   I169 @BASEBOARD_FAB2_LIB.BASEBOARD_FAB2(SCH_1):PAGE56

TP_CPU1_RSVD_291 @BASEBOARD_FAB2_LIB.BASEBOARD_FAB2(SCH_1):TP_CPU1_RSVD_291
  U2D1   C6 RSVD<291> SKX_EXT_B_BGA1-IC,TBD   I169 @BASEBOARD_FAB2_LIB.BASEBOARD_FAB2(SCH_1):PAGE56

TP_CPU1_RSVD_292 @BASEBOARD_FAB2_LIB.BASEBOARD_FAB2(SCH_1):TP_CPU1_RSVD_292
  U2D1  B81 RSVD<292> SKX_EXT_B_BGA1-IC,TBD   I169 @BASEBOARD_FAB2_LIB.BASEBOARD_FAB2(SCH_1):PAGE56

TP_CPU1_RSVD_293 @BASEBOARD_FAB2_LIB.BASEBOARD_FAB2(SCH_1):TP_CPU1_RSVD_293
  U2D1  B77 RSVD<293> SKX_EXT_B_BGA1-IC,TBD   I169 @BASEBOARD_FAB2_LIB.BASEBOARD_FAB2(SCH_1):PAGE56

TP_CPU1_RSVD_298 @BASEBOARD_FAB2_LIB.BASEBOARD_FAB2(SCH_1):TP_CPU1_RSVD_298
  U2D1   B7 RSVD<298> SKX_EXT_B_BGA1-IC,TBD   I169 @BASEBOARD_FAB2_LIB.BASEBOARD_FAB2(SCH_1):PAGE56

TP_CPU1_RSVD_299 @BASEBOARD_FAB2_LIB.BASEBOARD_FAB2(SCH_1):TP_CPU1_RSVD_299
  U2D1   B3 RSVD<299> SKX_EXT_B_BGA1-IC,TBD   I169 @BASEBOARD_FAB2_LIB.BASEBOARD_FAB2(SCH_1):PAGE56

TP_CPU1_RSVD_3 @BASEBOARD_FAB2_LIB.BASEBOARD_FAB2(SCH_1):TP_CPU1_RSVD_3
  U2D1 EF47 RSVD<3> SKX_EXT_B_BGA1-IC,TBD   I107 @BASEBOARD_FAB2_LIB.BASEBOARD_FAB2(SCH_1):PAGE73

TP_CPU1_RSVD_30 @BASEBOARD_FAB2_LIB.BASEBOARD_FAB2(SCH_1):TP_CPU1_RSVD_30
  U2D1 DP17 RSVD<30> SKX_EXT_B_BGA1-IC,TBD   I107 @BASEBOARD_FAB2_LIB.BASEBOARD_FAB2(SCH_1):PAGE73

TP_CPU1_RSVD_300 @BASEBOARD_FAB2_LIB.BASEBOARD_FAB2(SCH_1):TP_CPU1_RSVD_300
  U2D1  A24 RSVD<300> SKX_EXT_B_BGA1-IC,TBD   I169 @BASEBOARD_FAB2_LIB.BASEBOARD_FAB2(SCH_1):PAGE56

TP_CPU1_RSVD_303 @BASEBOARD_FAB2_LIB.BASEBOARD_FAB2(SCH_1):TP_CPU1_RSVD_303
  U2D1   A6 RSVD<303> SKX_EXT_B_BGA1-IC,TBD   I169 @BASEBOARD_FAB2_LIB.BASEBOARD_FAB2(SCH_1):PAGE56

TP_CPU1_RSVD_304 @BASEBOARD_FAB2_LIB.BASEBOARD_FAB2(SCH_1):TP_CPU1_RSVD_304
  U2D1   A4 RSVD<304> SKX_EXT_B_BGA1-IC,TBD   I169 @BASEBOARD_FAB2_LIB.BASEBOARD_FAB2(SCH_1):PAGE56

TP_CPU1_RSVD_31 @BASEBOARD_FAB2_LIB.BASEBOARD_FAB2(SCH_1):TP_CPU1_RSVD_31
  U2D1 DN66 RSVD<31> SKX_EXT_B_BGA1-IC,TBD   I107 @BASEBOARD_FAB2_LIB.BASEBOARD_FAB2(SCH_1):PAGE73

TP_CPU1_RSVD_32 @BASEBOARD_FAB2_LIB.BASEBOARD_FAB2(SCH_1):TP_CPU1_RSVD_32
  U2D1 DN62 RSVD<32> SKX_EXT_B_BGA1-IC,TBD   I107 @BASEBOARD_FAB2_LIB.BASEBOARD_FAB2(SCH_1):PAGE73

TP_CPU1_RSVD_33 @BASEBOARD_FAB2_LIB.BASEBOARD_FAB2(SCH_1):TP_CPU1_RSVD_33
  U2D1 DM67 RSVD<33> SKX_EXT_B_BGA1-IC,TBD   I107 @BASEBOARD_FAB2_LIB.BASEBOARD_FAB2(SCH_1):PAGE73

TP_CPU1_RSVD_34 @BASEBOARD_FAB2_LIB.BASEBOARD_FAB2(SCH_1):TP_CPU1_RSVD_34
  U2D1 DL66 RSVD<34> SKX_EXT_B_BGA1-IC,TBD   I107 @BASEBOARD_FAB2_LIB.BASEBOARD_FAB2(SCH_1):PAGE73

TP_CPU1_RSVD_35 @BASEBOARD_FAB2_LIB.BASEBOARD_FAB2(SCH_1):TP_CPU1_RSVD_35
  U2D1 DL38 RSVD<35> SKX_EXT_B_BGA1-IC,TBD   I107 @BASEBOARD_FAB2_LIB.BASEBOARD_FAB2(SCH_1):PAGE73

TP_CPU1_RSVD_36 @BASEBOARD_FAB2_LIB.BASEBOARD_FAB2(SCH_1):TP_CPU1_RSVD_36
  U2D1 DK67 RSVD<36> SKX_EXT_B_BGA1-IC,TBD   I107 @BASEBOARD_FAB2_LIB.BASEBOARD_FAB2(SCH_1):PAGE73

TP_CPU1_RSVD_37 @BASEBOARD_FAB2_LIB.BASEBOARD_FAB2(SCH_1):TP_CPU1_RSVD_37
  U2D1 DK65 RSVD<37> SKX_EXT_B_BGA1-IC,TBD   I107 @BASEBOARD_FAB2_LIB.BASEBOARD_FAB2(SCH_1):PAGE73

TP_CPU1_RSVD_38 @BASEBOARD_FAB2_LIB.BASEBOARD_FAB2(SCH_1):TP_CPU1_RSVD_38
  U2D1 DK37 RSVD<38> SKX_EXT_B_BGA1-IC,TBD   I107 @BASEBOARD_FAB2_LIB.BASEBOARD_FAB2(SCH_1):PAGE73

TP_CPU1_RSVD_39 @BASEBOARD_FAB2_LIB.BASEBOARD_FAB2(SCH_1):TP_CPU1_RSVD_39
  U2D1 DK15 RSVD<39> SKX_EXT_B_BGA1-IC,TBD   I107 @BASEBOARD_FAB2_LIB.BASEBOARD_FAB2(SCH_1):PAGE73

TP_CPU1_RSVD_4 @BASEBOARD_FAB2_LIB.BASEBOARD_FAB2(SCH_1):TP_CPU1_RSVD_4
  U2D1 EE84 RSVD<4> SKX_EXT_B_BGA1-IC,TBD   I107 @BASEBOARD_FAB2_LIB.BASEBOARD_FAB2(SCH_1):PAGE73

TP_CPU1_RSVD_40 @BASEBOARD_FAB2_LIB.BASEBOARD_FAB2(SCH_1):TP_CPU1_RSVD_40
  U2D1 DJ66 RSVD<40> SKX_EXT_B_BGA1-IC,TBD   I107 @BASEBOARD_FAB2_LIB.BASEBOARD_FAB2(SCH_1):PAGE73

TP_CPU1_RSVD_41 @BASEBOARD_FAB2_LIB.BASEBOARD_FAB2(SCH_1):TP_CPU1_RSVD_41
  U2D1 DJ36 RSVD<41> SKX_EXT_B_BGA1-IC,TBD   I107 @BASEBOARD_FAB2_LIB.BASEBOARD_FAB2(SCH_1):PAGE73

TP_CPU1_RSVD_42 @BASEBOARD_FAB2_LIB.BASEBOARD_FAB2(SCH_1):TP_CPU1_RSVD_42
  U2D1 DH65 RSVD<42> SKX_EXT_B_BGA1-IC,TBD   I107 @BASEBOARD_FAB2_LIB.BASEBOARD_FAB2(SCH_1):PAGE73

TP_CPU1_RSVD_43 @BASEBOARD_FAB2_LIB.BASEBOARD_FAB2(SCH_1):TP_CPU1_RSVD_43
  U2D1 DG64 RSVD<43> SKX_EXT_B_BGA1-IC,TBD   I107 @BASEBOARD_FAB2_LIB.BASEBOARD_FAB2(SCH_1):PAGE73

TP_CPU1_RSVD_44 @BASEBOARD_FAB2_LIB.BASEBOARD_FAB2(SCH_1):TP_CPU1_RSVD_44
  U2D1 DG36 RSVD<44> SKX_EXT_B_BGA1-IC,TBD   I107 @BASEBOARD_FAB2_LIB.BASEBOARD_FAB2(SCH_1):PAGE73

TP_CPU1_RSVD_45 @BASEBOARD_FAB2_LIB.BASEBOARD_FAB2(SCH_1):TP_CPU1_RSVD_45
  U2D1 DD51 RSVD<45> SKX_EXT_B_BGA1-IC,TBD   I107 @BASEBOARD_FAB2_LIB.BASEBOARD_FAB2(SCH_1):PAGE73

TP_CPU1_RSVD_46 @BASEBOARD_FAB2_LIB.BASEBOARD_FAB2(SCH_1):TP_CPU1_RSVD_46
  U2D1 DC52 RSVD<46> SKX_EXT_B_BGA1-IC,TBD   I107 @BASEBOARD_FAB2_LIB.BASEBOARD_FAB2(SCH_1):PAGE73

TP_CPU1_RSVD_47 @BASEBOARD_FAB2_LIB.BASEBOARD_FAB2(SCH_1):TP_CPU1_RSVD_47
  U2D1 DC46 RSVD<47> SKX_EXT_B_BGA1-IC,TBD   I107 @BASEBOARD_FAB2_LIB.BASEBOARD_FAB2(SCH_1):PAGE73

TP_CPU1_RSVD_48 @BASEBOARD_FAB2_LIB.BASEBOARD_FAB2(SCH_1):TP_CPU1_RSVD_48
  U2D1 DA56 RSVD<48> SKX_EXT_B_BGA1-IC,TBD   I107 @BASEBOARD_FAB2_LIB.BASEBOARD_FAB2(SCH_1):PAGE73

TP_CPU1_RSVD_49 @BASEBOARD_FAB2_LIB.BASEBOARD_FAB2(SCH_1):TP_CPU1_RSVD_49
  U2D1 DA54 RSVD<49> SKX_EXT_B_BGA1-IC,TBD   I107 @BASEBOARD_FAB2_LIB.BASEBOARD_FAB2(SCH_1):PAGE73

TP_CPU1_RSVD_5 @BASEBOARD_FAB2_LIB.BASEBOARD_FAB2(SCH_1):TP_CPU1_RSVD_5
  U2D1 EE82 RSVD<5> SKX_EXT_B_BGA1-IC,TBD   I107 @BASEBOARD_FAB2_LIB.BASEBOARD_FAB2(SCH_1):PAGE73

TP_CPU1_RSVD_50 @BASEBOARD_FAB2_LIB.BASEBOARD_FAB2(SCH_1):TP_CPU1_RSVD_50
  U2D1 DA52 RSVD<50> SKX_EXT_B_BGA1-IC,TBD   I107 @BASEBOARD_FAB2_LIB.BASEBOARD_FAB2(SCH_1):PAGE73

TP_CPU1_RSVD_51 @BASEBOARD_FAB2_LIB.BASEBOARD_FAB2(SCH_1):TP_CPU1_RSVD_51
  U2D1 DA40 RSVD<51> SKX_EXT_B_BGA1-IC,TBD   I107 @BASEBOARD_FAB2_LIB.BASEBOARD_FAB2(SCH_1):PAGE73

TP_CPU1_RSVD_53 @BASEBOARD_FAB2_LIB.BASEBOARD_FAB2(SCH_1):TP_CPU1_RSVD_53
  U2D1 CY73 RSVD<53> SKX_EXT_B_BGA1-IC,TBD   I107 @BASEBOARD_FAB2_LIB.BASEBOARD_FAB2(SCH_1):PAGE73

TP_CPU1_RSVD_54 @BASEBOARD_FAB2_LIB.BASEBOARD_FAB2(SCH_1):TP_CPU1_RSVD_54
  U2D1 CY63 RSVD<54> SKX_EXT_B_BGA1-IC,TBD   I107 @BASEBOARD_FAB2_LIB.BASEBOARD_FAB2(SCH_1):PAGE73

TP_CPU1_RSVD_55 @BASEBOARD_FAB2_LIB.BASEBOARD_FAB2(SCH_1):TP_CPU1_RSVD_55
  U2D1 CY57 RSVD<55> SKX_EXT_B_BGA1-IC,TBD   I107 @BASEBOARD_FAB2_LIB.BASEBOARD_FAB2(SCH_1):PAGE73

TP_CPU1_RSVD_56 @BASEBOARD_FAB2_LIB.BASEBOARD_FAB2(SCH_1):TP_CPU1_RSVD_56
  U2D1 CY53 RSVD<56> SKX_EXT_B_BGA1-IC,TBD   I107 @BASEBOARD_FAB2_LIB.BASEBOARD_FAB2(SCH_1):PAGE73

TP_CPU1_RSVD_57 @BASEBOARD_FAB2_LIB.BASEBOARD_FAB2(SCH_1):TP_CPU1_RSVD_57
  U2D1 CY39 RSVD<57> SKX_EXT_B_BGA1-IC,TBD   I107 @BASEBOARD_FAB2_LIB.BASEBOARD_FAB2(SCH_1):PAGE73

TP_CPU1_RSVD_59 @BASEBOARD_FAB2_LIB.BASEBOARD_FAB2(SCH_1):TP_CPU1_RSVD_59
  U2D1 CY23 RSVD<59> SKX_EXT_B_BGA1-IC,TBD   I107 @BASEBOARD_FAB2_LIB.BASEBOARD_FAB2(SCH_1):PAGE73

TP_CPU1_RSVD_6 @BASEBOARD_FAB2_LIB.BASEBOARD_FAB2(SCH_1):TP_CPU1_RSVD_6
  U2D1  EE6 RSVD<6> SKX_EXT_B_BGA1-IC,TBD   I107 @BASEBOARD_FAB2_LIB.BASEBOARD_FAB2(SCH_1):PAGE73

TP_CPU1_RSVD_60 @BASEBOARD_FAB2_LIB.BASEBOARD_FAB2(SCH_1):TP_CPU1_RSVD_60
  U2D1 CW62 RSVD<60> SKX_EXT_B_BGA1-IC,TBD   I107 @BASEBOARD_FAB2_LIB.BASEBOARD_FAB2(SCH_1):PAGE73

TP_CPU1_RSVD_61 @BASEBOARD_FAB2_LIB.BASEBOARD_FAB2(SCH_1):TP_CPU1_RSVD_61
  U2D1 CW60 RSVD<61> SKX_EXT_B_BGA1-IC,TBD   I107 @BASEBOARD_FAB2_LIB.BASEBOARD_FAB2(SCH_1):PAGE73

TP_CPU1_RSVD_64 @BASEBOARD_FAB2_LIB.BASEBOARD_FAB2(SCH_1):TP_CPU1_RSVD_64
  U2D1 CV69 RSVD<64> SKX_EXT_B_BGA1-IC,TBD   I107 @BASEBOARD_FAB2_LIB.BASEBOARD_FAB2(SCH_1):PAGE73

TP_CPU1_RSVD_66 @BASEBOARD_FAB2_LIB.BASEBOARD_FAB2(SCH_1):TP_CPU1_RSVD_66
  U2D1 CU60 RSVD<66> SKX_EXT_B_BGA1-IC,TBD   I107 @BASEBOARD_FAB2_LIB.BASEBOARD_FAB2(SCH_1):PAGE73

TP_CPU1_RSVD_67 @BASEBOARD_FAB2_LIB.BASEBOARD_FAB2(SCH_1):TP_CPU1_RSVD_67
  U2D1  CU6 RSVD<67> SKX_EXT_B_BGA1-IC,TBD   I107 @BASEBOARD_FAB2_LIB.BASEBOARD_FAB2(SCH_1):PAGE73

TP_CPU1_RSVD_69 @BASEBOARD_FAB2_LIB.BASEBOARD_FAB2(SCH_1):TP_CPU1_RSVD_69
  U2D1 CT69 RSVD<69> SKX_EXT_B_BGA1-IC,TBD   I107 @BASEBOARD_FAB2_LIB.BASEBOARD_FAB2(SCH_1):PAGE73

TP_CPU1_RSVD_7 @BASEBOARD_FAB2_LIB.BASEBOARD_FAB2(SCH_1):TP_CPU1_RSVD_7
  U2D1 EE46 RSVD<7> SKX_EXT_B_BGA1-IC,TBD   I107 @BASEBOARD_FAB2_LIB.BASEBOARD_FAB2(SCH_1):PAGE73

TP_CPU1_RSVD_70 @BASEBOARD_FAB2_LIB.BASEBOARD_FAB2(SCH_1):TP_CPU1_RSVD_70
  U2D1  CT5 RSVD<70> SKX_EXT_B_BGA1-IC,TBD   I107 @BASEBOARD_FAB2_LIB.BASEBOARD_FAB2(SCH_1):PAGE73

TP_CPU1_RSVD_72 @BASEBOARD_FAB2_LIB.BASEBOARD_FAB2(SCH_1):TP_CPU1_RSVD_72
  U2D1 CR60 RSVD<72> SKX_EXT_B_BGA1-IC,TBD   I107 @BASEBOARD_FAB2_LIB.BASEBOARD_FAB2(SCH_1):PAGE73

TP_CPU1_RSVD_73 @BASEBOARD_FAB2_LIB.BASEBOARD_FAB2(SCH_1):TP_CPU1_RSVD_73
  U2D1 CP31 RSVD<73> SKX_EXT_B_BGA1-IC,TBD   I107 @BASEBOARD_FAB2_LIB.BASEBOARD_FAB2(SCH_1):PAGE73

TP_CPU1_RSVD_8 @BASEBOARD_FAB2_LIB.BASEBOARD_FAB2(SCH_1):TP_CPU1_RSVD_8
  U2D1 EE16 RSVD<8> SKX_EXT_B_BGA1-IC,TBD   I107 @BASEBOARD_FAB2_LIB.BASEBOARD_FAB2(SCH_1):PAGE73

TP_CPU1_RSVD_82 @BASEBOARD_FAB2_LIB.BASEBOARD_FAB2(SCH_1):TP_CPU1_RSVD_82
  U2D1 CK77 RSVD<82> SKX_EXT_B_BGA1-IC,TBD    I10 @BASEBOARD_FAB2_LIB.BASEBOARD_FAB2(SCH_1):PAGE70

TP_CPU1_RSVD_85 @BASEBOARD_FAB2_LIB.BASEBOARD_FAB2(SCH_1):TP_CPU1_RSVD_85
  U2D1 CK19 RSVD<85> SKX_EXT_B_BGA1-IC,TBD    I10 @BASEBOARD_FAB2_LIB.BASEBOARD_FAB2(SCH_1):PAGE70

TP_CPU1_RSVD_9 @BASEBOARD_FAB2_LIB.BASEBOARD_FAB2(SCH_1):TP_CPU1_RSVD_9
  U2D1 ED83 RSVD<9> SKX_EXT_B_BGA1-IC,TBD   I107 @BASEBOARD_FAB2_LIB.BASEBOARD_FAB2(SCH_1):PAGE73

TP_CPU1_RSVD_90 @BASEBOARD_FAB2_LIB.BASEBOARD_FAB2(SCH_1):TP_CPU1_RSVD_90
  U2D1 CH77 RSVD<90> SKX_EXT_B_BGA1-IC,TBD    I10 @BASEBOARD_FAB2_LIB.BASEBOARD_FAB2(SCH_1):PAGE70

TP_CPU1_RSVD_91 @BASEBOARD_FAB2_LIB.BASEBOARD_FAB2(SCH_1):TP_CPU1_RSVD_91
  U2D1 CH25 RSVD<91> SKX_EXT_B_BGA1-IC,TBD    I10 @BASEBOARD_FAB2_LIB.BASEBOARD_FAB2(SCH_1):PAGE70

TP_CPU1_RSVD_94 @BASEBOARD_FAB2_LIB.BASEBOARD_FAB2(SCH_1):TP_CPU1_RSVD_94
  U2D1 CG82 RSVD<94> SKX_EXT_B_BGA1-IC,TBD     I9 @BASEBOARD_FAB2_LIB.BASEBOARD_FAB2(SCH_1):PAGE70

TP_CPU1_RSVD_95 @BASEBOARD_FAB2_LIB.BASEBOARD_FAB2(SCH_1):TP_CPU1_RSVD_95
  U2D1 CG78 RSVD<95> SKX_EXT_B_BGA1-IC,TBD     I9 @BASEBOARD_FAB2_LIB.BASEBOARD_FAB2(SCH_1):PAGE70

TP_CPU1_RSVD_97 @BASEBOARD_FAB2_LIB.BASEBOARD_FAB2(SCH_1):TP_CPU1_RSVD_97
  U2D1 CG24 RSVD<97> SKX_EXT_B_BGA1-IC,TBD     I9 @BASEBOARD_FAB2_LIB.BASEBOARD_FAB2(SCH_1):PAGE70

TP_CPU1_RSVD_99 @BASEBOARD_FAB2_LIB.BASEBOARD_FAB2(SCH_1):TP_CPU1_RSVD_99
  U2D1 CG10 RSVD<99> SKX_EXT_B_BGA1-IC,TBD     I9 @BASEBOARD_FAB2_LIB.BASEBOARD_FAB2(SCH_1):PAGE70

TP_CPU1_RSVD_TEST_11 @BASEBOARD_FAB2_LIB.BASEBOARD_FAB2(SCH_1):TP_CPU1_RSVD_TEST_11
  U2D1 AY13 TEST_11 SKX_EXT_B_BGA1-IC,TBD   I169 @BASEBOARD_FAB2_LIB.BASEBOARD_FAB2(SCH_1):PAGE56

TP_CPU1_RSVD_TEST_3 @BASEBOARD_FAB2_LIB.BASEBOARD_FAB2(SCH_1):TP_CPU1_RSVD_TEST_3
  U2D1 AM13 TEST_3 SKX_EXT_B_BGA1-IC,TBD   I169 @BASEBOARD_FAB2_LIB.BASEBOARD_FAB2(SCH_1):PAGE56

TP_CPU1_RSVD_TEST_4 @BASEBOARD_FAB2_LIB.BASEBOARD_FAB2(SCH_1):TP_CPU1_RSVD_TEST_4
  U2D1 AN12 TEST_4 SKX_EXT_B_BGA1-IC,TBD   I169 @BASEBOARD_FAB2_LIB.BASEBOARD_FAB2(SCH_1):PAGE56

TP_CPU1_RSVD_TEST_5 @BASEBOARD_FAB2_LIB.BASEBOARD_FAB2(SCH_1):TP_CPU1_RSVD_TEST_5
  U2D1 AN14 TEST_5 SKX_EXT_B_BGA1-IC,TBD   I169 @BASEBOARD_FAB2_LIB.BASEBOARD_FAB2(SCH_1):PAGE56

TP_CPU1_SOCKET_ID_2 @BASEBOARD_FAB2_LIB.BASEBOARD_FAB2(SCH_1):TP_CPU1_SOCKET_ID_2
  U2D1 AU20 SOCKET_ID<2> SKX_EXT_B_BGA1-IC,TBD   I172 @BASEBOARD_FAB2_LIB.BASEBOARD_FAB2(SCH_1):PAGE55

TP_CPU1_TEST_10 @BASEBOARD_FAB2_LIB.BASEBOARD_FAB2(SCH_1):TP_CPU1_TEST_10
  U2D1 AW22 TEST_10 SKX_EXT_B_BGA1-IC,TBD    I10 @BASEBOARD_FAB2_LIB.BASEBOARD_FAB2(SCH_1):PAGE70

TP_CPU1_TEST_6 @BASEBOARD_FAB2_LIB.BASEBOARD_FAB2(SCH_1):TP_CPU1_TEST_6
  U2D1 AR16 TEST_6 SKX_EXT_B_BGA1-IC,TBD    I10 @BASEBOARD_FAB2_LIB.BASEBOARD_FAB2(SCH_1):PAGE70

TP_CPU1_TEST_7 @BASEBOARD_FAB2_LIB.BASEBOARD_FAB2(SCH_1):TP_CPU1_TEST_7
  U2D1 AU18 TEST_7 SKX_EXT_B_BGA1-IC,TBD    I10 @BASEBOARD_FAB2_LIB.BASEBOARD_FAB2(SCH_1):PAGE70

TP_CPU1_TEST_8 @BASEBOARD_FAB2_LIB.BASEBOARD_FAB2(SCH_1):TP_CPU1_TEST_8
  U2D1 AW16 TEST_8 SKX_EXT_B_BGA1-IC,TBD    I10 @BASEBOARD_FAB2_LIB.BASEBOARD_FAB2(SCH_1):PAGE70

TP_CPU1_TEST_9 @BASEBOARD_FAB2_LIB.BASEBOARD_FAB2(SCH_1):TP_CPU1_TEST_9
  U2D1 AW20 TEST_9 SKX_EXT_B_BGA1-IC,TBD    I10 @BASEBOARD_FAB2_LIB.BASEBOARD_FAB2(SCH_1):PAGE70

TP_CPU1_UPI2_RSVD_CA12 @BASEBOARD_FAB2_LIB.BASEBOARD_FAB2(SCH_1):TP_CPU1_UPI2_RSVD_CA12
  U2D1 DP21 UPI2_TX_DP<0> SKX_EXT_B_BGA1-IC,TBD     I1 @BASEBOARD_FAB2_LIB.BASEBOARD_FAB2(SCH_1):PAGE69

TP_CPU1_UPI2_RSVD_CB11 @BASEBOARD_FAB2_LIB.BASEBOARD_FAB2(SCH_1):TP_CPU1_UPI2_RSVD_CB11
  U2D1 DN20 UPI2_TX_DP<1> SKX_EXT_B_BGA1-IC,TBD     I1 @BASEBOARD_FAB2_LIB.BASEBOARD_FAB2(SCH_1):PAGE69

TP_CPU1_UPI2_RSVD_CC10 @BASEBOARD_FAB2_LIB.BASEBOARD_FAB2(SCH_1):TP_CPU1_UPI2_RSVD_CC10
  U2D1 DM21 UPI2_TX_DN<1> SKX_EXT_B_BGA1-IC,TBD     I1 @BASEBOARD_FAB2_LIB.BASEBOARD_FAB2(SCH_1):PAGE69

TP_CPU1_UPI2_RSVD_CC12 @BASEBOARD_FAB2_LIB.BASEBOARD_FAB2(SCH_1):TP_CPU1_UPI2_RSVD_CC12
  U2D1 DT21 UPI2_TX_DN<0> SKX_EXT_B_BGA1-IC,TBD     I1 @BASEBOARD_FAB2_LIB.BASEBOARD_FAB2(SCH_1):PAGE69

TP_CPU1_UPI2_RSVD_CD11 @BASEBOARD_FAB2_LIB.BASEBOARD_FAB2(SCH_1):TP_CPU1_UPI2_RSVD_CD11
  U2D1 DK19 UPI2_TX_DP<2> SKX_EXT_B_BGA1-IC,TBD     I1 @BASEBOARD_FAB2_LIB.BASEBOARD_FAB2(SCH_1):PAGE69

TP_CPU1_UPI2_RSVD_CE12 @BASEBOARD_FAB2_LIB.BASEBOARD_FAB2(SCH_1):TP_CPU1_UPI2_RSVD_CE12
  U2D1 DL20 UPI2_TX_DN<2> SKX_EXT_B_BGA1-IC,TBD     I1 @BASEBOARD_FAB2_LIB.BASEBOARD_FAB2(SCH_1):PAGE69

TP_CPU1_UPI2_RSVD_CF11 @BASEBOARD_FAB2_LIB.BASEBOARD_FAB2(SCH_1):TP_CPU1_UPI2_RSVD_CF11
  U2D1 DJ20 UPI2_TX_DP<3> SKX_EXT_B_BGA1-IC,TBD     I1 @BASEBOARD_FAB2_LIB.BASEBOARD_FAB2(SCH_1):PAGE69

TP_CPU1_UPI2_RSVD_CF13 @BASEBOARD_FAB2_LIB.BASEBOARD_FAB2(SCH_1):TP_CPU1_UPI2_RSVD_CF13
  U2D1 DH19 UPI2_TX_DN<4> SKX_EXT_B_BGA1-IC,TBD     I1 @BASEBOARD_FAB2_LIB.BASEBOARD_FAB2(SCH_1):PAGE69

TP_CPU1_UPI2_RSVD_CG12 @BASEBOARD_FAB2_LIB.BASEBOARD_FAB2(SCH_1):TP_CPU1_UPI2_RSVD_CG12
  U2D1 DJ18 UPI2_TX_DP<4> SKX_EXT_B_BGA1-IC,TBD     I1 @BASEBOARD_FAB2_LIB.BASEBOARD_FAB2(SCH_1):PAGE69

TP_CPU1_UPI2_RSVD_CH11 @BASEBOARD_FAB2_LIB.BASEBOARD_FAB2(SCH_1):TP_CPU1_UPI2_RSVD_CH11
  U2D1 DG20 UPI2_TX_DN<3> SKX_EXT_B_BGA1-IC,TBD     I1 @BASEBOARD_FAB2_LIB.BASEBOARD_FAB2(SCH_1):PAGE69

TP_CPU1_UPI2_RSVD_CH13 @BASEBOARD_FAB2_LIB.BASEBOARD_FAB2(SCH_1):TP_CPU1_UPI2_RSVD_CH13
  U2D1 DH17 UPI2_TX_DP<5> SKX_EXT_B_BGA1-IC,TBD     I1 @BASEBOARD_FAB2_LIB.BASEBOARD_FAB2(SCH_1):PAGE69

TP_CPU1_UPI2_RSVD_CJ14 @BASEBOARD_FAB2_LIB.BASEBOARD_FAB2(SCH_1):TP_CPU1_UPI2_RSVD_CJ14
  U2D1 DK17 UPI2_TX_DN<5> SKX_EXT_B_BGA1-IC,TBD     I1 @BASEBOARD_FAB2_LIB.BASEBOARD_FAB2(SCH_1):PAGE69

TP_CPU1_UPI2_RSVD_CK13 @BASEBOARD_FAB2_LIB.BASEBOARD_FAB2(SCH_1):TP_CPU1_UPI2_RSVD_CK13
  U2D1 DF17 UPI2_TX_DP<6> SKX_EXT_B_BGA1-IC,TBD     I1 @BASEBOARD_FAB2_LIB.BASEBOARD_FAB2(SCH_1):PAGE69

TP_CPU1_UPI2_RSVD_CM13 @BASEBOARD_FAB2_LIB.BASEBOARD_FAB2(SCH_1):TP_CPU1_UPI2_RSVD_CM13
  U2D1 DG18 UPI2_TX_DN<6> SKX_EXT_B_BGA1-IC,TBD     I1 @BASEBOARD_FAB2_LIB.BASEBOARD_FAB2(SCH_1):PAGE69

TP_CPU1_UPI2_RSVD_CR14 @BASEBOARD_FAB2_LIB.BASEBOARD_FAB2(SCH_1):TP_CPU1_UPI2_RSVD_CR14
  U2D1 DE16 UPI2_TX_DP<7> SKX_EXT_B_BGA1-IC,TBD     I1 @BASEBOARD_FAB2_LIB.BASEBOARD_FAB2(SCH_1):PAGE69

TP_CPU1_UPI2_RSVD_CU14 @BASEBOARD_FAB2_LIB.BASEBOARD_FAB2(SCH_1):TP_CPU1_UPI2_RSVD_CU14
  U2D1 DD17 UPI2_TX_DN<7> SKX_EXT_B_BGA1-IC,TBD     I1 @BASEBOARD_FAB2_LIB.BASEBOARD_FAB2(SCH_1):PAGE69

TP_CPU1_UPI2_RSVD_CV13 @BASEBOARD_FAB2_LIB.BASEBOARD_FAB2(SCH_1):TP_CPU1_UPI2_RSVD_CV13
  U2D1 DD15 UPI2_TX_DP<8> SKX_EXT_B_BGA1-IC,TBD     I1 @BASEBOARD_FAB2_LIB.BASEBOARD_FAB2(SCH_1):PAGE69

TP_CPU1_UPI2_RSVD_CW14 @BASEBOARD_FAB2_LIB.BASEBOARD_FAB2(SCH_1):TP_CPU1_UPI2_RSVD_CW14
  U2D1 DF15 UPI2_TX_DN<8> SKX_EXT_B_BGA1-IC,TBD     I1 @BASEBOARD_FAB2_LIB.BASEBOARD_FAB2(SCH_1):PAGE69

TP_CPU1_UPI2_RSVD_CW16 @BASEBOARD_FAB2_LIB.BASEBOARD_FAB2(SCH_1):TP_CPU1_UPI2_RSVD_CW16
  U2D1 DB15 UPI2_TX_DP<9> SKX_EXT_B_BGA1-IC,TBD     I1 @BASEBOARD_FAB2_LIB.BASEBOARD_FAB2(SCH_1):PAGE69

TP_CPU1_UPI2_RSVD_DA16 @BASEBOARD_FAB2_LIB.BASEBOARD_FAB2(SCH_1):TP_CPU1_UPI2_RSVD_DA16
  U2D1 DC16 UPI2_TX_DN<9> SKX_EXT_B_BGA1-IC,TBD     I1 @BASEBOARD_FAB2_LIB.BASEBOARD_FAB2(SCH_1):PAGE69

TP_CPU1_UPI2_RSVD_DB15 @BASEBOARD_FAB2_LIB.BASEBOARD_FAB2(SCH_1):TP_CPU1_UPI2_RSVD_DB15
  U2D1 CW16 UPI2_TX_DP<10> SKX_EXT_B_BGA1-IC,TBD     I1 @BASEBOARD_FAB2_LIB.BASEBOARD_FAB2(SCH_1):PAGE69

TP_CPU1_UPI2_RSVD_DC16 @BASEBOARD_FAB2_LIB.BASEBOARD_FAB2(SCH_1):TP_CPU1_UPI2_RSVD_DC16
  U2D1 DA16 UPI2_TX_DN<10> SKX_EXT_B_BGA1-IC,TBD     I1 @BASEBOARD_FAB2_LIB.BASEBOARD_FAB2(SCH_1):PAGE69

TP_CPU1_UPI2_RSVD_DD15 @BASEBOARD_FAB2_LIB.BASEBOARD_FAB2(SCH_1):TP_CPU1_UPI2_RSVD_DD15
  U2D1 CV13 UPI2_TX_DP<11> SKX_EXT_B_BGA1-IC,TBD     I1 @BASEBOARD_FAB2_LIB.BASEBOARD_FAB2(SCH_1):PAGE69

TP_CPU1_UPI2_RSVD_DD17 @BASEBOARD_FAB2_LIB.BASEBOARD_FAB2(SCH_1):TP_CPU1_UPI2_RSVD_DD17
  U2D1 CU14 UPI2_TX_DN<12> SKX_EXT_B_BGA1-IC,TBD     I1 @BASEBOARD_FAB2_LIB.BASEBOARD_FAB2(SCH_1):PAGE69

TP_CPU1_UPI2_RSVD_DE16 @BASEBOARD_FAB2_LIB.BASEBOARD_FAB2(SCH_1):TP_CPU1_UPI2_RSVD_DE16
  U2D1 CR14 UPI2_TX_DP<12> SKX_EXT_B_BGA1-IC,TBD     I1 @BASEBOARD_FAB2_LIB.BASEBOARD_FAB2(SCH_1):PAGE69

TP_CPU1_UPI2_RSVD_DF15 @BASEBOARD_FAB2_LIB.BASEBOARD_FAB2(SCH_1):TP_CPU1_UPI2_RSVD_DF15
  U2D1 CW14 UPI2_TX_DN<11> SKX_EXT_B_BGA1-IC,TBD     I1 @BASEBOARD_FAB2_LIB.BASEBOARD_FAB2(SCH_1):PAGE69

TP_CPU1_UPI2_RSVD_DF17 @BASEBOARD_FAB2_LIB.BASEBOARD_FAB2(SCH_1):TP_CPU1_UPI2_RSVD_DF17
  U2D1 CK13 UPI2_TX_DP<13> SKX_EXT_B_BGA1-IC,TBD     I1 @BASEBOARD_FAB2_LIB.BASEBOARD_FAB2(SCH_1):PAGE69

TP_CPU1_UPI2_RSVD_DG18 @BASEBOARD_FAB2_LIB.BASEBOARD_FAB2(SCH_1):TP_CPU1_UPI2_RSVD_DG18
  U2D1 CM13 UPI2_TX_DN<13> SKX_EXT_B_BGA1-IC,TBD     I1 @BASEBOARD_FAB2_LIB.BASEBOARD_FAB2(SCH_1):PAGE69

TP_CPU1_UPI2_RSVD_DG20 @BASEBOARD_FAB2_LIB.BASEBOARD_FAB2(SCH_1):TP_CPU1_UPI2_RSVD_DG20
  U2D1 CH11 UPI2_TX_DN<16> SKX_EXT_B_BGA1-IC,TBD     I1 @BASEBOARD_FAB2_LIB.BASEBOARD_FAB2(SCH_1):PAGE69

TP_CPU1_UPI2_RSVD_DH17 @BASEBOARD_FAB2_LIB.BASEBOARD_FAB2(SCH_1):TP_CPU1_UPI2_RSVD_DH17
  U2D1 CH13 UPI2_TX_DP<14> SKX_EXT_B_BGA1-IC,TBD     I1 @BASEBOARD_FAB2_LIB.BASEBOARD_FAB2(SCH_1):PAGE69

TP_CPU1_UPI2_RSVD_DH19 @BASEBOARD_FAB2_LIB.BASEBOARD_FAB2(SCH_1):TP_CPU1_UPI2_RSVD_DH19
  U2D1 CF13 UPI2_TX_DN<15> SKX_EXT_B_BGA1-IC,TBD     I1 @BASEBOARD_FAB2_LIB.BASEBOARD_FAB2(SCH_1):PAGE69

TP_CPU1_UPI2_RSVD_DJ18 @BASEBOARD_FAB2_LIB.BASEBOARD_FAB2(SCH_1):TP_CPU1_UPI2_RSVD_DJ18
  U2D1 CG12 UPI2_TX_DP<15> SKX_EXT_B_BGA1-IC,TBD     I1 @BASEBOARD_FAB2_LIB.BASEBOARD_FAB2(SCH_1):PAGE69

TP_CPU1_UPI2_RSVD_DJ20 @BASEBOARD_FAB2_LIB.BASEBOARD_FAB2(SCH_1):TP_CPU1_UPI2_RSVD_DJ20
  U2D1 CF11 UPI2_TX_DP<16> SKX_EXT_B_BGA1-IC,TBD     I1 @BASEBOARD_FAB2_LIB.BASEBOARD_FAB2(SCH_1):PAGE69

TP_CPU1_UPI2_RSVD_DK17 @BASEBOARD_FAB2_LIB.BASEBOARD_FAB2(SCH_1):TP_CPU1_UPI2_RSVD_DK17
  U2D1 CJ14 UPI2_TX_DN<14> SKX_EXT_B_BGA1-IC,TBD     I1 @BASEBOARD_FAB2_LIB.BASEBOARD_FAB2(SCH_1):PAGE69

TP_CPU1_UPI2_RSVD_DK19 @BASEBOARD_FAB2_LIB.BASEBOARD_FAB2(SCH_1):TP_CPU1_UPI2_RSVD_DK19
  U2D1 CD11 UPI2_TX_DP<17> SKX_EXT_B_BGA1-IC,TBD     I1 @BASEBOARD_FAB2_LIB.BASEBOARD_FAB2(SCH_1):PAGE69

TP_CPU1_UPI2_RSVD_DL20 @BASEBOARD_FAB2_LIB.BASEBOARD_FAB2(SCH_1):TP_CPU1_UPI2_RSVD_DL20
  U2D1 CE12 UPI2_TX_DN<17> SKX_EXT_B_BGA1-IC,TBD     I1 @BASEBOARD_FAB2_LIB.BASEBOARD_FAB2(SCH_1):PAGE69

TP_CPU1_UPI2_RSVD_DM21 @BASEBOARD_FAB2_LIB.BASEBOARD_FAB2(SCH_1):TP_CPU1_UPI2_RSVD_DM21
  U2D1 CC10 UPI2_TX_DN<18> SKX_EXT_B_BGA1-IC,TBD     I1 @BASEBOARD_FAB2_LIB.BASEBOARD_FAB2(SCH_1):PAGE69

TP_CPU1_UPI2_RSVD_DN20 @BASEBOARD_FAB2_LIB.BASEBOARD_FAB2(SCH_1):TP_CPU1_UPI2_RSVD_DN20
  U2D1 CB11 UPI2_TX_DP<18> SKX_EXT_B_BGA1-IC,TBD     I1 @BASEBOARD_FAB2_LIB.BASEBOARD_FAB2(SCH_1):PAGE69

TP_CPU1_UPI2_RSVD_DP21 @BASEBOARD_FAB2_LIB.BASEBOARD_FAB2(SCH_1):TP_CPU1_UPI2_RSVD_DP21
  U2D1 CA12 UPI2_TX_DP<19> SKX_EXT_B_BGA1-IC,TBD     I1 @BASEBOARD_FAB2_LIB.BASEBOARD_FAB2(SCH_1):PAGE69

TP_CPU1_UPI2_RSVD_DT21 @BASEBOARD_FAB2_LIB.BASEBOARD_FAB2(SCH_1):TP_CPU1_UPI2_RSVD_DT21
  U2D1 CC12 UPI2_TX_DN<19> SKX_EXT_B_BGA1-IC,TBD     I1 @BASEBOARD_FAB2_LIB.BASEBOARD_FAB2(SCH_1):PAGE69

TP_CPU_PCH_TRIGGER_IN @BASEBOARD_FAB2_LIB.BASEBOARD_FAB2(SCH_1):TP_CPU_PCH_TRIGGER_IN
  U7C1   M7 TRIGGER_IN LBG_CORE_QAT_EXT_D_BGA1-IC,H91A    I73 @BASEBOARD_FAB2_LIB.BASEBOARD_FAB2(SCH_1):PAGE118

TP_CPU_PCH_TRIGGER_OUT @BASEBOARD_FAB2_LIB.BASEBOARD_FAB2(SCH_1):TP_CPU_PCH_TRIGGER_OUT
  U7C1  R13 TRIGGER_OUT LBG_CORE_QAT_EXT_D_BGA1-IC,H91A    I73 @BASEBOARD_FAB2_LIB.BASEBOARD_FAB2(SCH_1):PAGE118

TP_FET_Q56_3 @BASEBOARD_FAB2_LIB.BASEBOARD_FAB2(SCH_1):TP_FET_Q56_3
  Q1L4    3 DRAIN<0> FET_N_DUAL_SMLF-2N7002DW,FET,DA    I18 @BASEBOARD_FAB2_LIB.BASEBOARD_FAB2(SCH_1):PAGE168

TP_FET_Q56_4 @BASEBOARD_FAB2_LIB.BASEBOARD_FAB2(SCH_1):TP_FET_Q56_4
  Q1L4    5 GATE<0> FET_N_DUAL_SMLF-2N7002DW,FET,DA    I18 @BASEBOARD_FAB2_LIB.BASEBOARD_FAB2(SCH_1):PAGE168
  Q1L4    4 SOURCE<0> FET_N_DUAL_SMLF-2N7002DW,FET,DA    I18 @BASEBOARD_FAB2_LIB.BASEBOARD_FAB2(SCH_1):PAGE168

TP_FM_CPU1_CD_HFI0_MODPRST_N @BASEBOARD_FAB2_LIB.BASEBOARD_FAB2(SCH_1):TP_FM_CPU1_CD_HFI0_MODPRST_N
  U2D1 BR20 CD_HFI0_MODPRST_N SKX_EXT_B_BGA1-IC,TBD    I23 @BASEBOARD_FAB2_LIB.BASEBOARD_FAB2(SCH_1):PAGE63

TP_FM_QAT_CBL_PRSNT0_R_N @BASEBOARD_FAB2_LIB.BASEBOARD_FAB2(SCH_1):TP_FM_QAT_CBL_PRSNT0_R_N
  J8A1  1A1 SIDEBANDA_7 CONN72_G97614002_A_CP-CONN,G97A   I163 @BASEBOARD_FAB2_LIB.BASEBOARD_FAB2(SCH_1):PAGE173

TP_FM_QAT_CBL_PRSNT1_N_R @BASEBOARD_FAB2_LIB.BASEBOARD_FAB2(SCH_1):TP_FM_QAT_CBL_PRSNT1_N_R
  J8A1  2A1 SIDEBANDB_7 CONN72_G97614002_A_CP-CONN,G97A   I163 @BASEBOARD_FAB2_LIB.BASEBOARD_FAB2(SCH_1):PAGE173

TP_FM_WAKE_N @BASEBOARD_FAB2_LIB.BASEBOARD_FAB2(SCH_1):TP_FM_WAKE_N
  J1C1   B4 FAN_TACH2 DM-FCI-CONN76-8R-GP-U-01_CONN-A    I79 @BASEBOARD_FAB2_LIB.BASEBOARD_FAB2(SCH_1):PAGE182

TP_GTL2014_6_A0 @BASEBOARD_FAB2_LIB.BASEBOARD_FAB2(SCH_1):TP_GTL2014_6_A0
U25W11   13     A0 GTL2014_SM-IC,D66151-001    I33 @BASEBOARD_FAB2_LIB.BASEBOARD_FAB2(SCH_1):PAGE268

TP_GTL2014_6_A2 @BASEBOARD_FAB2_LIB.BASEBOARD_FAB2(SCH_1):TP_GTL2014_6_A2
U25W11   10     A2 GTL2014_SM-IC,D66151-001    I33 @BASEBOARD_FAB2_LIB.BASEBOARD_FAB2(SCH_1):PAGE268

TP_HFI_IO_CONN0_RSVD_17 @BASEBOARD_FAB2_LIB.BASEBOARD_FAB2(SCH_1):TP_HFI_IO_CONN0_RSVD_17
  J8B1   17   IO17 SCONN24_H46321001_SM-SCONN,H46A     I1 @BASEBOARD_FAB2_LIB.BASEBOARD_FAB2(SCH_1):PAGE91

TP_HSC_ALERT2_N @BASEBOARD_FAB2_LIB.BASEBOARD_FAB2(SCH_1):TP_HSC_ALERT2_N
 EU1D2   14 GPO2_ALERT2_N ADM1278_SM-IC,G99251-001    I10 @BASEBOARD_FAB2_LIB.BASEBOARD_FAB2(SCH_1):PAGE199

TP_HSC_MCLK @BASEBOARD_FAB2_LIB.BASEBOARD_FAB2(SCH_1):TP_HSC_MCLK
 EU1D2   10   MCLK ADM1278_SM-IC,G99251-001    I10 @BASEBOARD_FAB2_LIB.BASEBOARD_FAB2(SCH_1):PAGE199

TP_HSC_MDAT @BASEBOARD_FAB2_LIB.BASEBOARD_FAB2(SCH_1):TP_HSC_MDAT
 EU1D2   11   MDAT ADM1278_SM-IC,G99251-001    I10 @BASEBOARD_FAB2_LIB.BASEBOARD_FAB2(SCH_1):PAGE199

TP_HSC_SPISSN @BASEBOARD_FAB2_LIB.BASEBOARD_FAB2(SCH_1):TP_HSC_SPISSN
 EU1D2    9 SPISS_N ADM1278_SM-IC,G99251-001    I10 @BASEBOARD_FAB2_LIB.BASEBOARD_FAB2(SCH_1):PAGE199

TP_IE_DEBUG_MODE @BASEBOARD_FAB2_LIB.BASEBOARD_FAB2(SCH_1):TP_IE_DEBUG_MODE
  J9G1    7    IO7 CONN12_C73564003_PIP-CONN,C735A   I128 @BASEBOARD_FAB2_LIB.BASEBOARD_FAB2(SCH_1):PAGE137

TP_IOA5 @BASEBOARD_FAB2_LIB.BASEBOARD_FAB2(SCH_1):TP_IOA5
  J1C1   A5 MNG_TX_DP DM-FCI-CONN76-8R-GP-U-01_CONN-A    I79 @BASEBOARD_FAB2_LIB.BASEBOARD_FAB2(SCH_1):PAGE182

TP_IOE4 @BASEBOARD_FAB2_LIB.BASEBOARD_FAB2(SCH_1):TP_IOE4
  J1C1   E4 MATED_IN# DM-FCI-CONN76-8R-GP-U-01_CONN-A    I79 @BASEBOARD_FAB2_LIB.BASEBOARD_FAB2(SCH_1):PAGE182

TP_IOF4 @BASEBOARD_FAB2_LIB.BASEBOARD_FAB2(SCH_1):TP_IOF4
  J1C1   F4 FAN_PWM0 DM-FCI-CONN76-8R-GP-U-01_CONN-A    I79 @BASEBOARD_FAB2_LIB.BASEBOARD_FAB2(SCH_1):PAGE182

TP_IOG3 @BASEBOARD_FAB2_LIB.BASEBOARD_FAB2(SCH_1):TP_IOG3
  J1C1   G3 COM_TX DM-FCI-CONN76-8R-GP-U-01_CONN-A    I79 @BASEBOARD_FAB2_LIB.BASEBOARD_FAB2(SCH_1):PAGE182

TP_IOH3 @BASEBOARD_FAB2_LIB.BASEBOARD_FAB2(SCH_1):TP_IOH3
  J1C1   H3 COM_RX DM-FCI-CONN76-8R-GP-U-01_CONN-A    I79 @BASEBOARD_FAB2_LIB.BASEBOARD_FAB2(SCH_1):PAGE182

TP_IOH4 @BASEBOARD_FAB2_LIB.BASEBOARD_FAB2(SCH_1):TP_IOH4
  J1C1   H4 PCIE_CLK_100M_DP DM-FCI-CONN76-8R-GP-U-01_CONN-A    I79 @BASEBOARD_FAB2_LIB.BASEBOARD_FAB2(SCH_1):PAGE182

TP_IOI4 @BASEBOARD_FAB2_LIB.BASEBOARD_FAB2(SCH_1):TP_IOI4
  J1C1   I4 PCIE_CLK_100M_DN DM-FCI-CONN76-8R-GP-U-01_CONN-A    I79 @BASEBOARD_FAB2_LIB.BASEBOARD_FAB2(SCH_1):PAGE182

TP_IRQ_CPU1_CD_HFI0_N @BASEBOARD_FAB2_LIB.BASEBOARD_FAB2(SCH_1):TP_IRQ_CPU1_CD_HFI0_N
  U2D1 BP19 CD_HFI0_INT_N SKX_EXT_B_BGA1-IC,TBD    I23 @BASEBOARD_FAB2_LIB.BASEBOARD_FAB2(SCH_1):PAGE63

TP_JTAG_MCP_IO8_RSVD @BASEBOARD_FAB2_LIB.BASEBOARD_FAB2(SCH_1):TP_JTAG_MCP_IO8_RSVD
  J9B4    8    IO8 SCONN10_C12536004_SMLF-CONN,C1A   I175 @BASEBOARD_FAB2_LIB.BASEBOARD_FAB2(SCH_1):PAGE113

TP_JUMPER_BLOCK_1_1 @BASEBOARD_FAB2_LIB.BASEBOARD_FAB2(SCH_1):TP_JUMPER_BLOCK_1_1
  J8G2    1    IO1 CONN12_C73564003_PIP-CONN,C735A   I124 @BASEBOARD_FAB2_LIB.BASEBOARD_FAB2(SCH_1):PAGE135

TP_JUMPER_BLOCK_1_2 @BASEBOARD_FAB2_LIB.BASEBOARD_FAB2(SCH_1):TP_JUMPER_BLOCK_1_2
  J8G2    2    IO2 CONN12_C73564003_PIP-CONN,C735A   I124 @BASEBOARD_FAB2_LIB.BASEBOARD_FAB2(SCH_1):PAGE135

TP_JUMPER_BLOCK_1_7 @BASEBOARD_FAB2_LIB.BASEBOARD_FAB2(SCH_1):TP_JUMPER_BLOCK_ 1_7
  J8G2    7    IO7 CONN12_C73564003_PIP-CONN,C735A   I124 @BASEBOARD_FAB2_LIB.BASEBOARD_FAB2(SCH_1):PAGE135

TP_JUMPER_BLOCK_1_8 @BASEBOARD_FAB2_LIB.BASEBOARD_FAB2(SCH_1):TP_JUMPER_BLOCK_1_8
  J8G2    8    IO8 CONN12_C73564003_PIP-CONN,C735A   I124 @BASEBOARD_FAB2_LIB.BASEBOARD_FAB2(SCH_1):PAGE135

TP_LED_CPU1_CD_HFI0_N @BASEBOARD_FAB2_LIB.BASEBOARD_FAB2(SCH_1):TP_LED_CPU1_CD_HFI0_N
  U2D1 BK21 CD_HFI0_LED_N SKX_EXT_B_BGA1-IC,TBD    I23 @BASEBOARD_FAB2_LIB.BASEBOARD_FAB2(SCH_1):PAGE63

TP_LED_M2_ACT_N @BASEBOARD_FAB2_LIB.BASEBOARD_FAB2(SCH_1):TP_LED_M2_ACT_N
  J8F1   10     10 SKT-MINI67P-41-GP_SOCKET-G4-SKA   I143 @BASEBOARD_FAB2_LIB.BASEBOARD_FAB2(SCH_1):PAGE185

TP_M2_32M_SUSCLK @BASEBOARD_FAB2_LIB.BASEBOARD_FAB2(SCH_1):TP_M2_32M_SUSCLK
  J8F1   68     68 SKT-MINI67P-41-GP_SOCKET-G4-SKA   I143 @BASEBOARD_FAB2_LIB.BASEBOARD_FAB2(SCH_1):PAGE185

TP_M2_DEVSLP @BASEBOARD_FAB2_LIB.BASEBOARD_FAB2(SCH_1):TP_M2_DEVSLP
  J8F1   38     38 SKT-MINI67P-41-GP_SOCKET-G4-SKA   I143 @BASEBOARD_FAB2_LIB.BASEBOARD_FAB2(SCH_1):PAGE185

TP_ME_RCVR_BOOT @BASEBOARD_FAB2_LIB.BASEBOARD_FAB2(SCH_1):TP_ME_RCVR_BOOT
  J7G3    1    IO1 CONN12_C73564003_PIP-CONN,C735A   I174 @BASEBOARD_FAB2_LIB.BASEBOARD_FAB2(SCH_1):PAGE136

TP_NMI_CPU0 @BASEBOARD_FAB2_LIB.BASEBOARD_FAB2(SCH_1):TP_NMI_CPU0
  U5D1 AP11    NMI SKX_EXT_B_BGA1-IC,TBD   I259 @BASEBOARD_FAB2_LIB.BASEBOARD_FAB2(SCH_1):PAGE21

TP_P1V05_PCH_GL_0 @BASEBOARD_FAB2_LIB.BASEBOARD_FAB2(SCH_1):TP_P1V05_PCH_GL_0
 EU7A2    6  GL<0> IR354XX_SM-IR35412,IC,H73684-0A   I117 @BASEBOARD_FAB2_LIB.BASEBOARD_FAB2(SCH_1):PAGE236

TP_P1V05_PCH_GL_1 @BASEBOARD_FAB2_LIB.BASEBOARD_FAB2(SCH_1):TP_P1V05_PCH_GL_1
 EU7A2   41  GL<1> IR354XX_SM-IR35412,IC,H73684-0A   I117 @BASEBOARD_FAB2_LIB.BASEBOARD_FAB2(SCH_1):PAGE236

TP_P3E_CPU1_PE1_MP_RXN<0> @BASEBOARD_FAB2_LIB.BASEBOARD_FAB2(SCH_1):TP_P3E_CPU1_PE1_MP_RXN(0)
  U2D1  CW8 PE1_RX_DN<0> SKX_EXT_B_BGA1-IC,TBD    I68 @BASEBOARD_FAB2_LIB.BASEBOARD_FAB2(SCH_1):PAGE64

TP_P3E_CPU1_PE1_MP_RXN<1> @BASEBOARD_FAB2_LIB.BASEBOARD_FAB2(SCH_1):TP_P3E_CPU1_PE1_MP_RXN(1)
  U2D1  DA8 PE1_RX_DN<1> SKX_EXT_B_BGA1-IC,TBD    I68 @BASEBOARD_FAB2_LIB.BASEBOARD_FAB2(SCH_1):PAGE64

TP_P3E_CPU1_PE1_MP_RXN<2> @BASEBOARD_FAB2_LIB.BASEBOARD_FAB2(SCH_1):TP_P3E_CPU1_PE1_MP_RXN(2)
  U2D1  DC8 PE1_RX_DN<2> SKX_EXT_B_BGA1-IC,TBD    I68 @BASEBOARD_FAB2_LIB.BASEBOARD_FAB2(SCH_1):PAGE64

TP_P3E_CPU1_PE1_MP_RXN<3> @BASEBOARD_FAB2_LIB.BASEBOARD_FAB2(SCH_1):TP_P3E_CPU1_PE1_MP_RXN(3)
  U2D1 DC10 PE1_RX_DN<3> SKX_EXT_B_BGA1-IC,TBD    I68 @BASEBOARD_FAB2_LIB.BASEBOARD_FAB2(SCH_1):PAGE64

TP_P3E_CPU1_PE1_MP_RXN<4> @BASEBOARD_FAB2_LIB.BASEBOARD_FAB2(SCH_1):TP_P3E_CPU1_PE1_MP_RXN(4)
  U2D1 DE10 PE1_RX_DN<4> SKX_EXT_B_BGA1-IC,TBD    I68 @BASEBOARD_FAB2_LIB.BASEBOARD_FAB2(SCH_1):PAGE64

TP_P3E_CPU1_PE1_MP_RXN<5> @BASEBOARD_FAB2_LIB.BASEBOARD_FAB2(SCH_1):TP_P3E_CPU1_PE1_MP_RXN(5)
  U2D1  DH9 PE1_RX_DN<5> SKX_EXT_B_BGA1-IC,TBD    I68 @BASEBOARD_FAB2_LIB.BASEBOARD_FAB2(SCH_1):PAGE64

TP_P3E_CPU1_PE1_MP_RXN<6> @BASEBOARD_FAB2_LIB.BASEBOARD_FAB2(SCH_1):TP_P3E_CPU1_PE1_MP_RXN(6)
  U2D1  DK9 PE1_RX_DN<6> SKX_EXT_B_BGA1-IC,TBD    I68 @BASEBOARD_FAB2_LIB.BASEBOARD_FAB2(SCH_1):PAGE64

TP_P3E_CPU1_PE1_MP_RXN<7> @BASEBOARD_FAB2_LIB.BASEBOARD_FAB2(SCH_1):TP_P3E_CPU1_PE1_MP_RXN(7)
  U2D1  DM9 PE1_RX_DN<7> SKX_EXT_B_BGA1-IC,TBD    I68 @BASEBOARD_FAB2_LIB.BASEBOARD_FAB2(SCH_1):PAGE64

TP_P3E_CPU1_PE1_MP_RXP<0> @BASEBOARD_FAB2_LIB.BASEBOARD_FAB2(SCH_1):TP_P3E_CPU1_PE1_MP_RXP(0)
  U2D1  CU8 PE1_RX_DP<0> SKX_EXT_B_BGA1-IC,TBD    I68 @BASEBOARD_FAB2_LIB.BASEBOARD_FAB2(SCH_1):PAGE64

TP_P3E_CPU1_PE1_MP_RXP<1> @BASEBOARD_FAB2_LIB.BASEBOARD_FAB2(SCH_1):TP_P3E_CPU1_PE1_MP_RXP(1)
  U2D1  CY7 PE1_RX_DP<1> SKX_EXT_B_BGA1-IC,TBD    I68 @BASEBOARD_FAB2_LIB.BASEBOARD_FAB2(SCH_1):PAGE64

TP_P3E_CPU1_PE1_MP_RXP<2> @BASEBOARD_FAB2_LIB.BASEBOARD_FAB2(SCH_1):TP_P3E_CPU1_PE1_MP_RXP(2)
  U2D1  DB9 PE1_RX_DP<2> SKX_EXT_B_BGA1-IC,TBD    I68 @BASEBOARD_FAB2_LIB.BASEBOARD_FAB2(SCH_1):PAGE64

TP_P3E_CPU1_PE1_MP_RXP<3> @BASEBOARD_FAB2_LIB.BASEBOARD_FAB2(SCH_1):TP_P3E_CPU1_PE1_MP_RXP(3)
  U2D1 DA10 PE1_RX_DP<3> SKX_EXT_B_BGA1-IC,TBD    I68 @BASEBOARD_FAB2_LIB.BASEBOARD_FAB2(SCH_1):PAGE64

TP_P3E_CPU1_PE1_MP_RXP<4> @BASEBOARD_FAB2_LIB.BASEBOARD_FAB2(SCH_1):TP_P3E_CPU1_PE1_MP_RXP(4)
  U2D1  DD9 PE1_RX_DP<4> SKX_EXT_B_BGA1-IC,TBD    I68 @BASEBOARD_FAB2_LIB.BASEBOARD_FAB2(SCH_1):PAGE64

TP_P3E_CPU1_PE1_MP_RXP<5> @BASEBOARD_FAB2_LIB.BASEBOARD_FAB2(SCH_1):TP_P3E_CPU1_PE1_MP_RXP(5)
  U2D1  DF9 PE1_RX_DP<5> SKX_EXT_B_BGA1-IC,TBD    I68 @BASEBOARD_FAB2_LIB.BASEBOARD_FAB2(SCH_1):PAGE64

TP_P3E_CPU1_PE1_MP_RXP<6> @BASEBOARD_FAB2_LIB.BASEBOARD_FAB2(SCH_1):TP_P3E_CPU1_PE1_MP_RXP(6)
  U2D1  DJ8 PE1_RX_DP<6> SKX_EXT_B_BGA1-IC,TBD    I68 @BASEBOARD_FAB2_LIB.BASEBOARD_FAB2(SCH_1):PAGE64

TP_P3E_CPU1_PE1_MP_RXP<7> @BASEBOARD_FAB2_LIB.BASEBOARD_FAB2(SCH_1):TP_P3E_CPU1_PE1_MP_RXP(7)
  U2D1 DL10 PE1_RX_DP<7> SKX_EXT_B_BGA1-IC,TBD    I68 @BASEBOARD_FAB2_LIB.BASEBOARD_FAB2(SCH_1):PAGE64

TP_P3E_CPU1_PE1_MP_TXN<0> @BASEBOARD_FAB2_LIB.BASEBOARD_FAB2(SCH_1):TP_P3E_CPU1_PE1_MP_TXN(0)
  U2D1  DA2 PE1_TX_DN<0> SKX_EXT_B_BGA1-IC,TBD    I68 @BASEBOARD_FAB2_LIB.BASEBOARD_FAB2(SCH_1):PAGE64

TP_P3E_CPU1_PE1_MP_TXN<1> @BASEBOARD_FAB2_LIB.BASEBOARD_FAB2(SCH_1):TP_P3E_CPU1_PE1_MP_TXN(1)
  U2D1  DC2 PE1_TX_DN<1> SKX_EXT_B_BGA1-IC,TBD    I68 @BASEBOARD_FAB2_LIB.BASEBOARD_FAB2(SCH_1):PAGE64

TP_P3E_CPU1_PE1_MP_TXN<2> @BASEBOARD_FAB2_LIB.BASEBOARD_FAB2(SCH_1):TP_P3E_CPU1_PE1_MP_TXN(2)
  U2D1  DE2 PE1_TX_DN<2> SKX_EXT_B_BGA1-IC,TBD    I68 @BASEBOARD_FAB2_LIB.BASEBOARD_FAB2(SCH_1):PAGE64

TP_P3E_CPU1_PE1_MP_TXN<3> @BASEBOARD_FAB2_LIB.BASEBOARD_FAB2(SCH_1):TP_P3E_CPU1_PE1_MP_TXN(3)
  U2D1  DE4 PE1_TX_DN<3> SKX_EXT_B_BGA1-IC,TBD    I68 @BASEBOARD_FAB2_LIB.BASEBOARD_FAB2(SCH_1):PAGE64

TP_P3E_CPU1_PE1_MP_TXN<4> @BASEBOARD_FAB2_LIB.BASEBOARD_FAB2(SCH_1):TP_P3E_CPU1_PE1_MP_TXN(4)
  U2D1  DG4 PE1_TX_DN<4> SKX_EXT_B_BGA1-IC,TBD    I68 @BASEBOARD_FAB2_LIB.BASEBOARD_FAB2(SCH_1):PAGE64

TP_P3E_CPU1_PE1_MP_TXN<5> @BASEBOARD_FAB2_LIB.BASEBOARD_FAB2(SCH_1):TP_P3E_CPU1_PE1_MP_TXN(5)
  U2D1  DK3 PE1_TX_DN<5> SKX_EXT_B_BGA1-IC,TBD    I68 @BASEBOARD_FAB2_LIB.BASEBOARD_FAB2(SCH_1):PAGE64

TP_P3E_CPU1_PE1_MP_TXN<6> @BASEBOARD_FAB2_LIB.BASEBOARD_FAB2(SCH_1):TP_P3E_CPU1_PE1_MP_TXN(6)
  U2D1  DM3 PE1_TX_DN<6> SKX_EXT_B_BGA1-IC,TBD    I68 @BASEBOARD_FAB2_LIB.BASEBOARD_FAB2(SCH_1):PAGE64

TP_P3E_CPU1_PE1_MP_TXN<7> @BASEBOARD_FAB2_LIB.BASEBOARD_FAB2(SCH_1):TP_P3E_CPU1_PE1_MP_TXN(7)
  U2D1  DN4 PE1_TX_DN<7> SKX_EXT_B_BGA1-IC,TBD    I68 @BASEBOARD_FAB2_LIB.BASEBOARD_FAB2(SCH_1):PAGE64

TP_P3E_CPU1_PE1_MP_TXP<0> @BASEBOARD_FAB2_LIB.BASEBOARD_FAB2(SCH_1):TP_P3E_CPU1_PE1_MP_TXP(0)
  U2D1  CW2 PE1_TX_DP<0> SKX_EXT_B_BGA1-IC,TBD    I68 @BASEBOARD_FAB2_LIB.BASEBOARD_FAB2(SCH_1):PAGE64

TP_P3E_CPU1_PE1_MP_TXP<1> @BASEBOARD_FAB2_LIB.BASEBOARD_FAB2(SCH_1):TP_P3E_CPU1_PE1_MP_TXP(1)
  U2D1  DB1 PE1_TX_DP<1> SKX_EXT_B_BGA1-IC,TBD    I68 @BASEBOARD_FAB2_LIB.BASEBOARD_FAB2(SCH_1):PAGE64

TP_P3E_CPU1_PE1_MP_TXP<2> @BASEBOARD_FAB2_LIB.BASEBOARD_FAB2(SCH_1):TP_P3E_CPU1_PE1_MP_TXP(2)
  U2D1  DD3 PE1_TX_DP<2> SKX_EXT_B_BGA1-IC,TBD    I68 @BASEBOARD_FAB2_LIB.BASEBOARD_FAB2(SCH_1):PAGE64

TP_P3E_CPU1_PE1_MP_TXP<3> @BASEBOARD_FAB2_LIB.BASEBOARD_FAB2(SCH_1):TP_P3E_CPU1_PE1_MP_TXP(3)
  U2D1  DC4 PE1_TX_DP<3> SKX_EXT_B_BGA1-IC,TBD    I68 @BASEBOARD_FAB2_LIB.BASEBOARD_FAB2(SCH_1):PAGE64

TP_P3E_CPU1_PE1_MP_TXP<4> @BASEBOARD_FAB2_LIB.BASEBOARD_FAB2(SCH_1):TP_P3E_CPU1_PE1_MP_TXP(4)
  U2D1  DF3 PE1_TX_DP<4> SKX_EXT_B_BGA1-IC,TBD    I68 @BASEBOARD_FAB2_LIB.BASEBOARD_FAB2(SCH_1):PAGE64

TP_P3E_CPU1_PE1_MP_TXP<5> @BASEBOARD_FAB2_LIB.BASEBOARD_FAB2(SCH_1):TP_P3E_CPU1_PE1_MP_TXP(5)
  U2D1  DH3 PE1_TX_DP<5> SKX_EXT_B_BGA1-IC,TBD    I68 @BASEBOARD_FAB2_LIB.BASEBOARD_FAB2(SCH_1):PAGE64

TP_P3E_CPU1_PE1_MP_TXP<6> @BASEBOARD_FAB2_LIB.BASEBOARD_FAB2(SCH_1):TP_P3E_CPU1_PE1_MP_TXP(6)
  U2D1  DL2 PE1_TX_DP<6> SKX_EXT_B_BGA1-IC,TBD    I68 @BASEBOARD_FAB2_LIB.BASEBOARD_FAB2(SCH_1):PAGE64

TP_P3E_CPU1_PE1_MP_TXP<7> @BASEBOARD_FAB2_LIB.BASEBOARD_FAB2(SCH_1):TP_P3E_CPU1_PE1_MP_TXP(7)
  U2D1  DP3 PE1_TX_DP<7> SKX_EXT_B_BGA1-IC,TBD    I68 @BASEBOARD_FAB2_LIB.BASEBOARD_FAB2(SCH_1):PAGE64

TP_P3E_CPU1_PE1_RSR3_RXN<10> @BASEBOARD_FAB2_LIB.BASEBOARD_FAB2(SCH_1):TP_P3E_CPU1_PE1_RSR3_RXN(10)
  U2D1 DT11 PE1_RX_DN<10> SKX_EXT_B_BGA1-IC,TBD    I68 @BASEBOARD_FAB2_LIB.BASEBOARD_FAB2(SCH_1):PAGE64

TP_P3E_CPU1_PE1_RSR3_RXN<11> @BASEBOARD_FAB2_LIB.BASEBOARD_FAB2(SCH_1):TP_P3E_CPU1_PE1_RSR3_RXN(11)
  U2D1 DT13 PE1_RX_DN<11> SKX_EXT_B_BGA1-IC,TBD    I68 @BASEBOARD_FAB2_LIB.BASEBOARD_FAB2(SCH_1):PAGE64

TP_P3E_CPU1_PE1_RSR3_RXN<12> @BASEBOARD_FAB2_LIB.BASEBOARD_FAB2(SCH_1):TP_P3E_CPU1_PE1_RSR3_RXN(12)
  U2D1 DV13 PE1_RX_DN<12> SKX_EXT_B_BGA1-IC,TBD    I68 @BASEBOARD_FAB2_LIB.BASEBOARD_FAB2(SCH_1):PAGE64

TP_P3E_CPU1_PE1_RSR3_RXN<13> @BASEBOARD_FAB2_LIB.BASEBOARD_FAB2(SCH_1):TP_P3E_CPU1_PE1_RSR3_RXN(13)
  U2D1 DW14 PE1_RX_DN<13> SKX_EXT_B_BGA1-IC,TBD    I68 @BASEBOARD_FAB2_LIB.BASEBOARD_FAB2(SCH_1):PAGE64

TP_P3E_CPU1_PE1_RSR3_RXN<14> @BASEBOARD_FAB2_LIB.BASEBOARD_FAB2(SCH_1):TP_P3E_CPU1_PE1_RSR3_RXN(14)
  U2D1 DY15 PE1_RX_DN<14> SKX_EXT_B_BGA1-IC,TBD    I68 @BASEBOARD_FAB2_LIB.BASEBOARD_FAB2(SCH_1):PAGE64

TP_P3E_CPU1_PE1_RSR3_RXN<15> @BASEBOARD_FAB2_LIB.BASEBOARD_FAB2(SCH_1):TP_P3E_CPU1_PE1_RSR3_RXN(15)
  U2D1 DU16 PE1_RX_DN<15> SKX_EXT_B_BGA1-IC,TBD    I68 @BASEBOARD_FAB2_LIB.BASEBOARD_FAB2(SCH_1):PAGE64

TP_P3E_CPU1_PE1_RSR3_RXN<8> @BASEBOARD_FAB2_LIB.BASEBOARD_FAB2(SCH_1):TP_P3E_CPU1_PE1_RSR3_RXN(8)
  U2D1 DM11 PE1_RX_DN<8> SKX_EXT_B_BGA1-IC,TBD    I68 @BASEBOARD_FAB2_LIB.BASEBOARD_FAB2(SCH_1):PAGE64

TP_P3E_CPU1_PE1_RSR3_RXN<9> @BASEBOARD_FAB2_LIB.BASEBOARD_FAB2(SCH_1):TP_P3E_CPU1_PE1_RSR3_RXN(9)
  U2D1 DP11 PE1_RX_DN<9> SKX_EXT_B_BGA1-IC,TBD    I68 @BASEBOARD_FAB2_LIB.BASEBOARD_FAB2(SCH_1):PAGE64

TP_P3E_CPU1_PE1_RSR3_RXP<10> @BASEBOARD_FAB2_LIB.BASEBOARD_FAB2(SCH_1):TP_P3E_CPU1_PE1_RSR3_RXP(10)
  U2D1 DR12 PE1_RX_DP<10> SKX_EXT_B_BGA1-IC,TBD    I68 @BASEBOARD_FAB2_LIB.BASEBOARD_FAB2(SCH_1):PAGE64

TP_P3E_CPU1_PE1_RSR3_RXP<11> @BASEBOARD_FAB2_LIB.BASEBOARD_FAB2(SCH_1):TP_P3E_CPU1_PE1_RSR3_RXP(11)
  U2D1 DP13 PE1_RX_DP<11> SKX_EXT_B_BGA1-IC,TBD    I68 @BASEBOARD_FAB2_LIB.BASEBOARD_FAB2(SCH_1):PAGE64

TP_P3E_CPU1_PE1_RSR3_RXP<12> @BASEBOARD_FAB2_LIB.BASEBOARD_FAB2(SCH_1):TP_P3E_CPU1_PE1_RSR3_RXP(12)
  U2D1 DU12 PE1_RX_DP<12> SKX_EXT_B_BGA1-IC,TBD    I68 @BASEBOARD_FAB2_LIB.BASEBOARD_FAB2(SCH_1):PAGE64

TP_P3E_CPU1_PE1_RSR3_RXP<13> @BASEBOARD_FAB2_LIB.BASEBOARD_FAB2(SCH_1):TP_P3E_CPU1_PE1_RSR3_RXP(13)
  U2D1 DY13 PE1_RX_DP<13> SKX_EXT_B_BGA1-IC,TBD    I68 @BASEBOARD_FAB2_LIB.BASEBOARD_FAB2(SCH_1):PAGE64

TP_P3E_CPU1_PE1_RSR3_RXP<14> @BASEBOARD_FAB2_LIB.BASEBOARD_FAB2(SCH_1):TP_P3E_CPU1_PE1_RSR3_RXP(14)
  U2D1 DV15 PE1_RX_DP<14> SKX_EXT_B_BGA1-IC,TBD    I68 @BASEBOARD_FAB2_LIB.BASEBOARD_FAB2(SCH_1):PAGE64

TP_P3E_CPU1_PE1_RSR3_RXP<15> @BASEBOARD_FAB2_LIB.BASEBOARD_FAB2(SCH_1):TP_P3E_CPU1_PE1_RSR3_RXP(15)
  U2D1 DT15 PE1_RX_DP<15> SKX_EXT_B_BGA1-IC,TBD    I68 @BASEBOARD_FAB2_LIB.BASEBOARD_FAB2(SCH_1):PAGE64

TP_P3E_CPU1_PE1_RSR3_RXP<8> @BASEBOARD_FAB2_LIB.BASEBOARD_FAB2(SCH_1):TP_P3E_CPU1_PE1_RSR3_RXP(8)
  U2D1 DK11 PE1_RX_DP<8> SKX_EXT_B_BGA1-IC,TBD    I68 @BASEBOARD_FAB2_LIB.BASEBOARD_FAB2(SCH_1):PAGE64

TP_P3E_CPU1_PE1_RSR3_RXP<9> @BASEBOARD_FAB2_LIB.BASEBOARD_FAB2(SCH_1):TP_P3E_CPU1_PE1_RSR3_RXP(9)
  U2D1 DN10 PE1_RX_DP<9> SKX_EXT_B_BGA1-IC,TBD    I68 @BASEBOARD_FAB2_LIB.BASEBOARD_FAB2(SCH_1):PAGE64

TP_P3E_CPU1_PE1_RSR3_TXN<10> @BASEBOARD_FAB2_LIB.BASEBOARD_FAB2(SCH_1):TP_P3E_CPU1_PE1_RSR3_TXN(10)
  U2D1  DW4 PE1_TX_DN<10> SKX_EXT_B_BGA1-IC,TBD    I68 @BASEBOARD_FAB2_LIB.BASEBOARD_FAB2(SCH_1):PAGE64

TP_P3E_CPU1_PE1_RSR3_TXN<11> @BASEBOARD_FAB2_LIB.BASEBOARD_FAB2(SCH_1):TP_P3E_CPU1_PE1_RSR3_TXN(11)
  U2D1  DU6 PE1_TX_DN<11> SKX_EXT_B_BGA1-IC,TBD    I68 @BASEBOARD_FAB2_LIB.BASEBOARD_FAB2(SCH_1):PAGE64

TP_P3E_CPU1_PE1_RSR3_TXN<12> @BASEBOARD_FAB2_LIB.BASEBOARD_FAB2(SCH_1):TP_P3E_CPU1_PE1_RSR3_TXN(12)
  U2D1  DV7 PE1_TX_DN<12> SKX_EXT_B_BGA1-IC,TBD    I68 @BASEBOARD_FAB2_LIB.BASEBOARD_FAB2(SCH_1):PAGE64

TP_P3E_CPU1_PE1_RSR3_TXN<13> @BASEBOARD_FAB2_LIB.BASEBOARD_FAB2(SCH_1):TP_P3E_CPU1_PE1_RSR3_TXN(13)
  U2D1  DY7 PE1_TX_DN<13> SKX_EXT_B_BGA1-IC,TBD    I68 @BASEBOARD_FAB2_LIB.BASEBOARD_FAB2(SCH_1):PAGE64

TP_P3E_CPU1_PE1_RSR3_TXN<14> @BASEBOARD_FAB2_LIB.BASEBOARD_FAB2(SCH_1):TP_P3E_CPU1_PE1_RSR3_TXN(14)
  U2D1  EA8 PE1_TX_DN<14> SKX_EXT_B_BGA1-IC,TBD    I68 @BASEBOARD_FAB2_LIB.BASEBOARD_FAB2(SCH_1):PAGE64

TP_P3E_CPU1_PE1_RSR3_TXN<15> @BASEBOARD_FAB2_LIB.BASEBOARD_FAB2(SCH_1):TP_P3E_CPU1_PE1_RSR3_TXN(15)
  U2D1  ED9 PE1_TX_DN<15> SKX_EXT_B_BGA1-IC,TBD    I68 @BASEBOARD_FAB2_LIB.BASEBOARD_FAB2(SCH_1):PAGE64

TP_P3E_CPU1_PE1_RSR3_TXN<8> @BASEBOARD_FAB2_LIB.BASEBOARD_FAB2(SCH_1):TP_P3E_CPU1_PE1_RSR3_TXN(8)
  U2D1  DT5 PE1_TX_DN<8> SKX_EXT_B_BGA1-IC,TBD    I68 @BASEBOARD_FAB2_LIB.BASEBOARD_FAB2(SCH_1):PAGE64

TP_P3E_CPU1_PE1_RSR3_TXN<9> @BASEBOARD_FAB2_LIB.BASEBOARD_FAB2(SCH_1):TP_P3E_CPU1_PE1_RSR3_TXN(9)
  U2D1  DV3 PE1_TX_DN<9> SKX_EXT_B_BGA1-IC,TBD    I68 @BASEBOARD_FAB2_LIB.BASEBOARD_FAB2(SCH_1):PAGE64

TP_P3E_CPU1_PE1_RSR3_TXP<10> @BASEBOARD_FAB2_LIB.BASEBOARD_FAB2(SCH_1):TP_P3E_CPU1_PE1_RSR3_TXP(10)
  U2D1  DU4 PE1_TX_DP<10> SKX_EXT_B_BGA1-IC,TBD    I68 @BASEBOARD_FAB2_LIB.BASEBOARD_FAB2(SCH_1):PAGE64

TP_P3E_CPU1_PE1_RSR3_TXP<11> @BASEBOARD_FAB2_LIB.BASEBOARD_FAB2(SCH_1):TP_P3E_CPU1_PE1_RSR3_TXP(11)
  U2D1  DV5 PE1_TX_DP<11> SKX_EXT_B_BGA1-IC,TBD    I68 @BASEBOARD_FAB2_LIB.BASEBOARD_FAB2(SCH_1):PAGE64

TP_P3E_CPU1_PE1_RSR3_TXP<12> @BASEBOARD_FAB2_LIB.BASEBOARD_FAB2(SCH_1):TP_P3E_CPU1_PE1_RSR3_TXP(12)
  U2D1  DT7 PE1_TX_DP<12> SKX_EXT_B_BGA1-IC,TBD    I68 @BASEBOARD_FAB2_LIB.BASEBOARD_FAB2(SCH_1):PAGE64

TP_P3E_CPU1_PE1_RSR3_TXP<13> @BASEBOARD_FAB2_LIB.BASEBOARD_FAB2(SCH_1):TP_P3E_CPU1_PE1_RSR3_TXP(13)
  U2D1  DW6 PE1_TX_DP<13> SKX_EXT_B_BGA1-IC,TBD    I68 @BASEBOARD_FAB2_LIB.BASEBOARD_FAB2(SCH_1):PAGE64

TP_P3E_CPU1_PE1_RSR3_TXP<14> @BASEBOARD_FAB2_LIB.BASEBOARD_FAB2(SCH_1):TP_P3E_CPU1_PE1_RSR3_TXP(14)
  U2D1  EB7 PE1_TX_DP<14> SKX_EXT_B_BGA1-IC,TBD    I68 @BASEBOARD_FAB2_LIB.BASEBOARD_FAB2(SCH_1):PAGE64

TP_P3E_CPU1_PE1_RSR3_TXP<15> @BASEBOARD_FAB2_LIB.BASEBOARD_FAB2(SCH_1):TP_P3E_CPU1_PE1_RSR3_TXP(15)
  U2D1  EC8 PE1_TX_DP<15> SKX_EXT_B_BGA1-IC,TBD    I68 @BASEBOARD_FAB2_LIB.BASEBOARD_FAB2(SCH_1):PAGE64

TP_P3E_CPU1_PE1_RSR3_TXP<8> @BASEBOARD_FAB2_LIB.BASEBOARD_FAB2(SCH_1):TP_P3E_CPU1_PE1_RSR3_TXP(8)
  U2D1  DR4 PE1_TX_DP<8> SKX_EXT_B_BGA1-IC,TBD    I68 @BASEBOARD_FAB2_LIB.BASEBOARD_FAB2(SCH_1):PAGE64

TP_P3E_CPU1_PE1_RSR3_TXP<9> @BASEBOARD_FAB2_LIB.BASEBOARD_FAB2(SCH_1):TP_P3E_CPU1_PE1_RSR3_TXP(9)
  U2D1  DU2 PE1_TX_DP<9> SKX_EXT_B_BGA1-IC,TBD    I68 @BASEBOARD_FAB2_LIB.BASEBOARD_FAB2(SCH_1):PAGE64

TP_P3E_CPU1_PE2_RSR_RXN<0> @BASEBOARD_FAB2_LIB.BASEBOARD_FAB2(SCH_1):TP_P3E_CPU1_PE2_RSR_RXN(0)
  U2D1  CT9 PE2_RX_DN<0> SKX_EXT_B_BGA1-IC,TBD    I68 @BASEBOARD_FAB2_LIB.BASEBOARD_FAB2(SCH_1):PAGE65

TP_P3E_CPU1_PE2_RSR_RXN<10> @BASEBOARD_FAB2_LIB.BASEBOARD_FAB2(SCH_1):TP_P3E_CPU1_PE2_RSR_RXN(10)
  U2D1  BV7 PE2_RX_DN<10> SKX_EXT_B_BGA1-IC,TBD    I68 @BASEBOARD_FAB2_LIB.BASEBOARD_FAB2(SCH_1):PAGE65

TP_P3E_CPU1_PE2_RSR_RXN<11> @BASEBOARD_FAB2_LIB.BASEBOARD_FAB2(SCH_1):TP_P3E_CPU1_PE2_RSR_RXN(11)
  U2D1  BT7 PE2_RX_DN<11> SKX_EXT_B_BGA1-IC,TBD    I68 @BASEBOARD_FAB2_LIB.BASEBOARD_FAB2(SCH_1):PAGE65

TP_P3E_CPU1_PE2_RSR_RXN<12> @BASEBOARD_FAB2_LIB.BASEBOARD_FAB2(SCH_1):TP_P3E_CPU1_PE2_RSR_RXN(12)
  U2D1  BR8 PE2_RX_DN<12> SKX_EXT_B_BGA1-IC,TBD    I68 @BASEBOARD_FAB2_LIB.BASEBOARD_FAB2(SCH_1):PAGE65

TP_P3E_CPU1_PE2_RSR_RXN<13> @BASEBOARD_FAB2_LIB.BASEBOARD_FAB2(SCH_1):TP_P3E_CPU1_PE2_RSR_RXN(13)
  U2D1  BN8 PE2_RX_DN<13> SKX_EXT_B_BGA1-IC,TBD    I68 @BASEBOARD_FAB2_LIB.BASEBOARD_FAB2(SCH_1):PAGE65

TP_P3E_CPU1_PE2_RSR_RXN<14> @BASEBOARD_FAB2_LIB.BASEBOARD_FAB2(SCH_1):TP_P3E_CPU1_PE2_RSR_RXN(14)
  U2D1  BL8 PE2_RX_DN<14> SKX_EXT_B_BGA1-IC,TBD    I68 @BASEBOARD_FAB2_LIB.BASEBOARD_FAB2(SCH_1):PAGE65

TP_P3E_CPU1_PE2_RSR_RXN<15> @BASEBOARD_FAB2_LIB.BASEBOARD_FAB2(SCH_1):TP_P3E_CPU1_PE2_RSR_RXN(15)
  U2D1  BK9 PE2_RX_DN<15> SKX_EXT_B_BGA1-IC,TBD    I68 @BASEBOARD_FAB2_LIB.BASEBOARD_FAB2(SCH_1):PAGE65

TP_P3E_CPU1_PE2_RSR_RXN<1> @BASEBOARD_FAB2_LIB.BASEBOARD_FAB2(SCH_1):TP_P3E_CPU1_PE2_RSR_RXN(1)
  U2D1  CP9 PE2_RX_DN<1> SKX_EXT_B_BGA1-IC,TBD    I68 @BASEBOARD_FAB2_LIB.BASEBOARD_FAB2(SCH_1):PAGE65

TP_P3E_CPU1_PE2_RSR_RXN<2> @BASEBOARD_FAB2_LIB.BASEBOARD_FAB2(SCH_1):TP_P3E_CPU1_PE2_RSR_RXN(2)
  U2D1  CP7 PE2_RX_DN<2> SKX_EXT_B_BGA1-IC,TBD    I68 @BASEBOARD_FAB2_LIB.BASEBOARD_FAB2(SCH_1):PAGE65

TP_P3E_CPU1_PE2_RSR_RXN<3> @BASEBOARD_FAB2_LIB.BASEBOARD_FAB2(SCH_1):TP_P3E_CPU1_PE2_RSR_RXN(3)
  U2D1  CM7 PE2_RX_DN<3> SKX_EXT_B_BGA1-IC,TBD    I68 @BASEBOARD_FAB2_LIB.BASEBOARD_FAB2(SCH_1):PAGE65

TP_P3E_CPU1_PE2_RSR_RXN<4> @BASEBOARD_FAB2_LIB.BASEBOARD_FAB2(SCH_1):TP_P3E_CPU1_PE2_RSR_RXN(4)
  U2D1  CK7 PE2_RX_DN<4> SKX_EXT_B_BGA1-IC,TBD    I68 @BASEBOARD_FAB2_LIB.BASEBOARD_FAB2(SCH_1):PAGE65

TP_P3E_CPU1_PE2_RSR_RXN<5> @BASEBOARD_FAB2_LIB.BASEBOARD_FAB2(SCH_1):TP_P3E_CPU1_PE2_RSR_RXN(5)
  U2D1  CG8 PE2_RX_DN<5> SKX_EXT_B_BGA1-IC,TBD    I68 @BASEBOARD_FAB2_LIB.BASEBOARD_FAB2(SCH_1):PAGE65

TP_P3E_CPU1_PE2_RSR_RXN<6> @BASEBOARD_FAB2_LIB.BASEBOARD_FAB2(SCH_1):TP_P3E_CPU1_PE2_RSR_RXN(6)
  U2D1  CE6 PE2_RX_DN<6> SKX_EXT_B_BGA1-IC,TBD    I68 @BASEBOARD_FAB2_LIB.BASEBOARD_FAB2(SCH_1):PAGE65

TP_P3E_CPU1_PE2_RSR_RXN<7> @BASEBOARD_FAB2_LIB.BASEBOARD_FAB2(SCH_1):TP_P3E_CPU1_PE2_RSR_RXN(7)
  U2D1  CE8 PE2_RX_DN<7> SKX_EXT_B_BGA1-IC,TBD    I68 @BASEBOARD_FAB2_LIB.BASEBOARD_FAB2(SCH_1):PAGE65

TP_P3E_CPU1_PE2_RSR_RXN<8> @BASEBOARD_FAB2_LIB.BASEBOARD_FAB2(SCH_1):TP_P3E_CPU1_PE2_RSR_RXN(8)
  U2D1  BY9 PE2_RX_DN<8> SKX_EXT_B_BGA1-IC,TBD    I68 @BASEBOARD_FAB2_LIB.BASEBOARD_FAB2(SCH_1):PAGE65

TP_P3E_CPU1_PE2_RSR_RXN<9> @BASEBOARD_FAB2_LIB.BASEBOARD_FAB2(SCH_1):TP_P3E_CPU1_PE2_RSR_RXN(9)
  U2D1  BY7 PE2_RX_DN<9> SKX_EXT_B_BGA1-IC,TBD    I68 @BASEBOARD_FAB2_LIB.BASEBOARD_FAB2(SCH_1):PAGE65

TP_P3E_CPU1_PE2_RSR_RXP<0> @BASEBOARD_FAB2_LIB.BASEBOARD_FAB2(SCH_1):TP_P3E_CPU1_PE2_RSR_RXP(0)
  U2D1  CR8 PE2_RX_DP<0> SKX_EXT_B_BGA1-IC,TBD    I68 @BASEBOARD_FAB2_LIB.BASEBOARD_FAB2(SCH_1):PAGE65

TP_P3E_CPU1_PE2_RSR_RXP<10> @BASEBOARD_FAB2_LIB.BASEBOARD_FAB2(SCH_1):TP_P3E_CPU1_PE2_RSR_RXP(10)
  U2D1  BU6 PE2_RX_DP<10> SKX_EXT_B_BGA1-IC,TBD    I68 @BASEBOARD_FAB2_LIB.BASEBOARD_FAB2(SCH_1):PAGE65

TP_P3E_CPU1_PE2_RSR_RXP<11> @BASEBOARD_FAB2_LIB.BASEBOARD_FAB2(SCH_1):TP_P3E_CPU1_PE2_RSR_RXP(11)
  U2D1  BP7 PE2_RX_DP<11> SKX_EXT_B_BGA1-IC,TBD    I68 @BASEBOARD_FAB2_LIB.BASEBOARD_FAB2(SCH_1):PAGE65

TP_P3E_CPU1_PE2_RSR_RXP<12> @BASEBOARD_FAB2_LIB.BASEBOARD_FAB2(SCH_1):TP_P3E_CPU1_PE2_RSR_RXP(12)
  U2D1  BP9 PE2_RX_DP<12> SKX_EXT_B_BGA1-IC,TBD    I68 @BASEBOARD_FAB2_LIB.BASEBOARD_FAB2(SCH_1):PAGE65

TP_P3E_CPU1_PE2_RSR_RXP<13> @BASEBOARD_FAB2_LIB.BASEBOARD_FAB2(SCH_1):TP_P3E_CPU1_PE2_RSR_RXP(13)
  U2D1  BM7 PE2_RX_DP<13> SKX_EXT_B_BGA1-IC,TBD    I68 @BASEBOARD_FAB2_LIB.BASEBOARD_FAB2(SCH_1):PAGE65

TP_P3E_CPU1_PE2_RSR_RXP<14> @BASEBOARD_FAB2_LIB.BASEBOARD_FAB2(SCH_1):TP_P3E_CPU1_PE2_RSR_RXP(14)
  U2D1  BJ8 PE2_RX_DP<14> SKX_EXT_B_BGA1-IC,TBD    I68 @BASEBOARD_FAB2_LIB.BASEBOARD_FAB2(SCH_1):PAGE65

TP_P3E_CPU1_PE2_RSR_RXP<15> @BASEBOARD_FAB2_LIB.BASEBOARD_FAB2(SCH_1):TP_P3E_CPU1_PE2_RSR_RXP(15)
  U2D1 BJ10 PE2_RX_DP<15> SKX_EXT_B_BGA1-IC,TBD    I68 @BASEBOARD_FAB2_LIB.BASEBOARD_FAB2(SCH_1):PAGE65

TP_P3E_CPU1_PE2_RSR_RXP<1> @BASEBOARD_FAB2_LIB.BASEBOARD_FAB2(SCH_1):TP_P3E_CPU1_PE2_RSR_RXP(1)
  U2D1  CM9 PE2_RX_DP<1> SKX_EXT_B_BGA1-IC,TBD    I68 @BASEBOARD_FAB2_LIB.BASEBOARD_FAB2(SCH_1):PAGE65

TP_P3E_CPU1_PE2_RSR_RXP<2> @BASEBOARD_FAB2_LIB.BASEBOARD_FAB2(SCH_1):TP_P3E_CPU1_PE2_RSR_RXP(2)
  U2D1  CN8 PE2_RX_DP<2> SKX_EXT_B_BGA1-IC,TBD    I68 @BASEBOARD_FAB2_LIB.BASEBOARD_FAB2(SCH_1):PAGE65

TP_P3E_CPU1_PE2_RSR_RXP<3> @BASEBOARD_FAB2_LIB.BASEBOARD_FAB2(SCH_1):TP_P3E_CPU1_PE2_RSR_RXP(3)
  U2D1  CL6 PE2_RX_DP<3> SKX_EXT_B_BGA1-IC,TBD    I68 @BASEBOARD_FAB2_LIB.BASEBOARD_FAB2(SCH_1):PAGE65

TP_P3E_CPU1_PE2_RSR_RXP<4> @BASEBOARD_FAB2_LIB.BASEBOARD_FAB2(SCH_1):TP_P3E_CPU1_PE2_RSR_RXP(4)
  U2D1  CH7 PE2_RX_DP<4> SKX_EXT_B_BGA1-IC,TBD    I68 @BASEBOARD_FAB2_LIB.BASEBOARD_FAB2(SCH_1):PAGE65

TP_P3E_CPU1_PE2_RSR_RXP<5> @BASEBOARD_FAB2_LIB.BASEBOARD_FAB2(SCH_1):TP_P3E_CPU1_PE2_RSR_RXP(5)
  U2D1  CF7 PE2_RX_DP<5> SKX_EXT_B_BGA1-IC,TBD    I68 @BASEBOARD_FAB2_LIB.BASEBOARD_FAB2(SCH_1):PAGE65

TP_P3E_CPU1_PE2_RSR_RXP<6> @BASEBOARD_FAB2_LIB.BASEBOARD_FAB2(SCH_1):TP_P3E_CPU1_PE2_RSR_RXP(6)
  U2D1  CD7 PE2_RX_DP<6> SKX_EXT_B_BGA1-IC,TBD    I68 @BASEBOARD_FAB2_LIB.BASEBOARD_FAB2(SCH_1):PAGE65

TP_P3E_CPU1_PE2_RSR_RXP<7> @BASEBOARD_FAB2_LIB.BASEBOARD_FAB2(SCH_1):TP_P3E_CPU1_PE2_RSR_RXP(7)
  U2D1  CC8 PE2_RX_DP<7> SKX_EXT_B_BGA1-IC,TBD    I68 @BASEBOARD_FAB2_LIB.BASEBOARD_FAB2(SCH_1):PAGE65

TP_P3E_CPU1_PE2_RSR_RXP<8> @BASEBOARD_FAB2_LIB.BASEBOARD_FAB2(SCH_1):TP_P3E_CPU1_PE2_RSR_RXP(8)
  U2D1  BV9 PE2_RX_DP<8> SKX_EXT_B_BGA1-IC,TBD    I68 @BASEBOARD_FAB2_LIB.BASEBOARD_FAB2(SCH_1):PAGE65

TP_P3E_CPU1_PE2_RSR_RXP<9> @BASEBOARD_FAB2_LIB.BASEBOARD_FAB2(SCH_1):TP_P3E_CPU1_PE2_RSR_RXP(9)
  U2D1  BW8 PE2_RX_DP<9> SKX_EXT_B_BGA1-IC,TBD    I68 @BASEBOARD_FAB2_LIB.BASEBOARD_FAB2(SCH_1):PAGE65

TP_P3E_CPU1_PE2_RSR_TXN<0> @BASEBOARD_FAB2_LIB.BASEBOARD_FAB2(SCH_1):TP_P3E_CPU1_PE2_RSR_TXN(0)
  U2D1  CY3 PE2_TX_DN<0> SKX_EXT_B_BGA1-IC,TBD    I68 @BASEBOARD_FAB2_LIB.BASEBOARD_FAB2(SCH_1):PAGE65

TP_P3E_CPU1_PE2_RSR_TXN<10> @BASEBOARD_FAB2_LIB.BASEBOARD_FAB2(SCH_1):TP_P3E_CPU1_PE2_RSR_TXN(10)
  U2D1  CA4 PE2_TX_DN<10> SKX_EXT_B_BGA1-IC,TBD    I68 @BASEBOARD_FAB2_LIB.BASEBOARD_FAB2(SCH_1):PAGE65

TP_P3E_CPU1_PE2_RSR_TXN<11> @BASEBOARD_FAB2_LIB.BASEBOARD_FAB2(SCH_1):TP_P3E_CPU1_PE2_RSR_TXN(11)
  U2D1  BW4 PE2_TX_DN<11> SKX_EXT_B_BGA1-IC,TBD    I68 @BASEBOARD_FAB2_LIB.BASEBOARD_FAB2(SCH_1):PAGE65

TP_P3E_CPU1_PE2_RSR_TXN<12> @BASEBOARD_FAB2_LIB.BASEBOARD_FAB2(SCH_1):TP_P3E_CPU1_PE2_RSR_TXN(12)
  U2D1  BU4 PE2_TX_DN<12> SKX_EXT_B_BGA1-IC,TBD    I68 @BASEBOARD_FAB2_LIB.BASEBOARD_FAB2(SCH_1):PAGE65

TP_P3E_CPU1_PE2_RSR_TXN<13> @BASEBOARD_FAB2_LIB.BASEBOARD_FAB2(SCH_1):TP_P3E_CPU1_PE2_RSR_TXN(13)
  U2D1  BP5 PE2_TX_DN<13> SKX_EXT_B_BGA1-IC,TBD    I68 @BASEBOARD_FAB2_LIB.BASEBOARD_FAB2(SCH_1):PAGE65

TP_P3E_CPU1_PE2_RSR_TXN<14> @BASEBOARD_FAB2_LIB.BASEBOARD_FAB2(SCH_1):TP_P3E_CPU1_PE2_RSR_TXN(14)
  U2D1  BL4 PE2_TX_DN<14> SKX_EXT_B_BGA1-IC,TBD    I68 @BASEBOARD_FAB2_LIB.BASEBOARD_FAB2(SCH_1):PAGE65

TP_P3E_CPU1_PE2_RSR_TXN<15> @BASEBOARD_FAB2_LIB.BASEBOARD_FAB2(SCH_1):TP_P3E_CPU1_PE2_RSR_TXN(15)
  U2D1  BM5 PE2_TX_DN<15> SKX_EXT_B_BGA1-IC,TBD    I68 @BASEBOARD_FAB2_LIB.BASEBOARD_FAB2(SCH_1):PAGE65

TP_P3E_CPU1_PE2_RSR_TXN<1> @BASEBOARD_FAB2_LIB.BASEBOARD_FAB2(SCH_1):TP_P3E_CPU1_PE2_RSR_TXN(1)
  U2D1  CV3 PE2_TX_DN<1> SKX_EXT_B_BGA1-IC,TBD    I68 @BASEBOARD_FAB2_LIB.BASEBOARD_FAB2(SCH_1):PAGE65

TP_P3E_CPU1_PE2_RSR_TXN<2> @BASEBOARD_FAB2_LIB.BASEBOARD_FAB2(SCH_1):TP_P3E_CPU1_PE2_RSR_TXN(2)
  U2D1  CT1 PE2_TX_DN<2> SKX_EXT_B_BGA1-IC,TBD    I68 @BASEBOARD_FAB2_LIB.BASEBOARD_FAB2(SCH_1):PAGE65

TP_P3E_CPU1_PE2_RSR_TXN<3> @BASEBOARD_FAB2_LIB.BASEBOARD_FAB2(SCH_1):TP_P3E_CPU1_PE2_RSR_TXN(3)
  U2D1  CT3 PE2_TX_DN<3> SKX_EXT_B_BGA1-IC,TBD    I68 @BASEBOARD_FAB2_LIB.BASEBOARD_FAB2(SCH_1):PAGE65

TP_P3E_CPU1_PE2_RSR_TXN<4> @BASEBOARD_FAB2_LIB.BASEBOARD_FAB2(SCH_1):TP_P3E_CPU1_PE2_RSR_TXN(4)
  U2D1  CM1 PE2_TX_DN<4> SKX_EXT_B_BGA1-IC,TBD    I68 @BASEBOARD_FAB2_LIB.BASEBOARD_FAB2(SCH_1):PAGE65

TP_P3E_CPU1_PE2_RSR_TXN<5> @BASEBOARD_FAB2_LIB.BASEBOARD_FAB2(SCH_1):TP_P3E_CPU1_PE2_RSR_TXN(5)
  U2D1  CL2 PE2_TX_DN<5> SKX_EXT_B_BGA1-IC,TBD    I68 @BASEBOARD_FAB2_LIB.BASEBOARD_FAB2(SCH_1):PAGE65

TP_P3E_CPU1_PE2_RSR_TXN<6> @BASEBOARD_FAB2_LIB.BASEBOARD_FAB2(SCH_1):TP_P3E_CPU1_PE2_RSR_TXN(6)
  U2D1  CG2 PE2_TX_DN<6> SKX_EXT_B_BGA1-IC,TBD    I68 @BASEBOARD_FAB2_LIB.BASEBOARD_FAB2(SCH_1):PAGE65

TP_P3E_CPU1_PE2_RSR_TXN<7> @BASEBOARD_FAB2_LIB.BASEBOARD_FAB2(SCH_1):TP_P3E_CPU1_PE2_RSR_TXN(7)
  U2D1  CF3 PE2_TX_DN<7> SKX_EXT_B_BGA1-IC,TBD    I68 @BASEBOARD_FAB2_LIB.BASEBOARD_FAB2(SCH_1):PAGE65

TP_P3E_CPU1_PE2_RSR_TXN<8> @BASEBOARD_FAB2_LIB.BASEBOARD_FAB2(SCH_1):TP_P3E_CPU1_PE2_RSR_TXN(8)
  U2D1  CC2 PE2_TX_DN<8> SKX_EXT_B_BGA1-IC,TBD    I68 @BASEBOARD_FAB2_LIB.BASEBOARD_FAB2(SCH_1):PAGE65

TP_P3E_CPU1_PE2_RSR_TXN<9> @BASEBOARD_FAB2_LIB.BASEBOARD_FAB2(SCH_1):TP_P3E_CPU1_PE2_RSR_TXN(9)
  U2D1  CB3 PE2_TX_DN<9> SKX_EXT_B_BGA1-IC,TBD    I68 @BASEBOARD_FAB2_LIB.BASEBOARD_FAB2(SCH_1):PAGE65

TP_P3E_CPU1_PE2_RSR_TXP<0> @BASEBOARD_FAB2_LIB.BASEBOARD_FAB2(SCH_1):TP_P3E_CPU1_PE2_RSR_TXP(0)
  U2D1  CW4 PE2_TX_DP<0> SKX_EXT_B_BGA1-IC,TBD    I68 @BASEBOARD_FAB2_LIB.BASEBOARD_FAB2(SCH_1):PAGE65

TP_P3E_CPU1_PE2_RSR_TXP<10> @BASEBOARD_FAB2_LIB.BASEBOARD_FAB2(SCH_1):TP_P3E_CPU1_PE2_RSR_TXP(10)
  U2D1  BY5 PE2_TX_DP<10> SKX_EXT_B_BGA1-IC,TBD    I68 @BASEBOARD_FAB2_LIB.BASEBOARD_FAB2(SCH_1):PAGE65

TP_P3E_CPU1_PE2_RSR_TXP<11> @BASEBOARD_FAB2_LIB.BASEBOARD_FAB2(SCH_1):TP_P3E_CPU1_PE2_RSR_TXP(11)
  U2D1  BV3 PE2_TX_DP<11> SKX_EXT_B_BGA1-IC,TBD    I68 @BASEBOARD_FAB2_LIB.BASEBOARD_FAB2(SCH_1):PAGE65

TP_P3E_CPU1_PE2_RSR_TXP<12> @BASEBOARD_FAB2_LIB.BASEBOARD_FAB2(SCH_1):TP_P3E_CPU1_PE2_RSR_TXP(12)
  U2D1  BR4 PE2_TX_DP<12> SKX_EXT_B_BGA1-IC,TBD    I68 @BASEBOARD_FAB2_LIB.BASEBOARD_FAB2(SCH_1):PAGE65

TP_P3E_CPU1_PE2_RSR_TXP<13> @BASEBOARD_FAB2_LIB.BASEBOARD_FAB2(SCH_1):TP_P3E_CPU1_PE2_RSR_TXP(13)
  U2D1  BN4 PE2_TX_DP<13> SKX_EXT_B_BGA1-IC,TBD    I68 @BASEBOARD_FAB2_LIB.BASEBOARD_FAB2(SCH_1):PAGE65

TP_P3E_CPU1_PE2_RSR_TXP<14> @BASEBOARD_FAB2_LIB.BASEBOARD_FAB2(SCH_1):TP_P3E_CPU1_PE2_RSR_TXP(14)
  U2D1  BM3 PE2_TX_DP<14> SKX_EXT_B_BGA1-IC,TBD    I68 @BASEBOARD_FAB2_LIB.BASEBOARD_FAB2(SCH_1):PAGE65

TP_P3E_CPU1_PE2_RSR_TXP<15> @BASEBOARD_FAB2_LIB.BASEBOARD_FAB2(SCH_1):TP_P3E_CPU1_PE2_RSR_TXP(15)
  U2D1  BK5 PE2_TX_DP<15> SKX_EXT_B_BGA1-IC,TBD    I68 @BASEBOARD_FAB2_LIB.BASEBOARD_FAB2(SCH_1):PAGE65

TP_P3E_CPU1_PE2_RSR_TXP<1> @BASEBOARD_FAB2_LIB.BASEBOARD_FAB2(SCH_1):TP_P3E_CPU1_PE2_RSR_TXP(1)
  U2D1  CU2 PE2_TX_DP<1> SKX_EXT_B_BGA1-IC,TBD    I68 @BASEBOARD_FAB2_LIB.BASEBOARD_FAB2(SCH_1):PAGE65

TP_P3E_CPU1_PE2_RSR_TXP<2> @BASEBOARD_FAB2_LIB.BASEBOARD_FAB2(SCH_1):TP_P3E_CPU1_PE2_RSR_TXP(2)
  U2D1  CR2 PE2_TX_DP<2> SKX_EXT_B_BGA1-IC,TBD    I68 @BASEBOARD_FAB2_LIB.BASEBOARD_FAB2(SCH_1):PAGE65

TP_P3E_CPU1_PE2_RSR_TXP<3> @BASEBOARD_FAB2_LIB.BASEBOARD_FAB2(SCH_1):TP_P3E_CPU1_PE2_RSR_TXP(3)
  U2D1  CP3 PE2_TX_DP<3> SKX_EXT_B_BGA1-IC,TBD    I68 @BASEBOARD_FAB2_LIB.BASEBOARD_FAB2(SCH_1):PAGE65

TP_P3E_CPU1_PE2_RSR_TXP<4> @BASEBOARD_FAB2_LIB.BASEBOARD_FAB2(SCH_1):TP_P3E_CPU1_PE2_RSR_TXP(4)
  U2D1  CK1 PE2_TX_DP<4> SKX_EXT_B_BGA1-IC,TBD    I68 @BASEBOARD_FAB2_LIB.BASEBOARD_FAB2(SCH_1):PAGE65

TP_P3E_CPU1_PE2_RSR_TXP<5> @BASEBOARD_FAB2_LIB.BASEBOARD_FAB2(SCH_1):TP_P3E_CPU1_PE2_RSR_TXP(5)
  U2D1  CK3 PE2_TX_DP<5> SKX_EXT_B_BGA1-IC,TBD    I68 @BASEBOARD_FAB2_LIB.BASEBOARD_FAB2(SCH_1):PAGE65

TP_P3E_CPU1_PE2_RSR_TXP<6> @BASEBOARD_FAB2_LIB.BASEBOARD_FAB2(SCH_1):TP_P3E_CPU1_PE2_RSR_TXP(6)
  U2D1  CE2 PE2_TX_DP<6> SKX_EXT_B_BGA1-IC,TBD    I68 @BASEBOARD_FAB2_LIB.BASEBOARD_FAB2(SCH_1):PAGE65

TP_P3E_CPU1_PE2_RSR_TXP<7> @BASEBOARD_FAB2_LIB.BASEBOARD_FAB2(SCH_1):TP_P3E_CPU1_PE2_RSR_TXP(7)
  U2D1  CE4 PE2_TX_DP<7> SKX_EXT_B_BGA1-IC,TBD    I68 @BASEBOARD_FAB2_LIB.BASEBOARD_FAB2(SCH_1):PAGE65

TP_P3E_CPU1_PE2_RSR_TXP<8> @BASEBOARD_FAB2_LIB.BASEBOARD_FAB2(SCH_1):TP_P3E_CPU1_PE2_RSR_TXP(8)
  U2D1  CD3 PE2_TX_DP<8> SKX_EXT_B_BGA1-IC,TBD    I68 @BASEBOARD_FAB2_LIB.BASEBOARD_FAB2(SCH_1):PAGE65

TP_P3E_CPU1_PE2_RSR_TXP<9> @BASEBOARD_FAB2_LIB.BASEBOARD_FAB2(SCH_1):TP_P3E_CPU1_PE2_RSR_TXP(9)
  U2D1  BY3 PE2_TX_DP<9> SKX_EXT_B_BGA1-IC,TBD    I68 @BASEBOARD_FAB2_LIB.BASEBOARD_FAB2(SCH_1):PAGE65

TP_PASSWORD_CLEAR @BASEBOARD_FAB2_LIB.BASEBOARD_FAB2(SCH_1):TP_PASSWORD_CLEAR
  J7G3    7    IO7 CONN12_C73564003_PIP-CONN,C735A   I174 @BASEBOARD_FAB2_LIB.BASEBOARD_FAB2(SCH_1):PAGE136

TP_PCH_DISPA_BCLK @BASEBOARD_FAB2_LIB.BASEBOARD_FAB2(SCH_1):TP_PCH_DISPA_BCLK
  U7C1  U20 RSVD<66> LBG_CORE_QAT_EXT_D_BGA1-IC,H91A    I34 @BASEBOARD_FAB2_LIB.BASEBOARD_FAB2(SCH_1):PAGE121

TP_PCH_DISPA_SDI @BASEBOARD_FAB2_LIB.BASEBOARD_FAB2(SCH_1):TP_PCH_DISPA_SDI
  U7C1  R20 RSVD<67> LBG_CORE_QAT_EXT_D_BGA1-IC,H91A    I34 @BASEBOARD_FAB2_LIB.BASEBOARD_FAB2(SCH_1):PAGE121

TP_PCH_DISPA_SDO @BASEBOARD_FAB2_LIB.BASEBOARD_FAB2(SCH_1):TP_PCH_DISPA_SDO
  U7C1  V22 RSVD<68> LBG_CORE_QAT_EXT_D_BGA1-IC,H91A    I34 @BASEBOARD_FAB2_LIB.BASEBOARD_FAB2(SCH_1):PAGE121

TP_PCH_GDP8_SUSCLK @BASEBOARD_FAB2_LIB.BASEBOARD_FAB2(SCH_1):TP_PCH_GDP8_SUSCLK
  U7C1  C13 GPD8_SUSCLK LBG_CORE_QAT_EXT_D_BGA1-IC,H91A    I73 @BASEBOARD_FAB2_LIB.BASEBOARD_FAB2(SCH_1):PAGE118

TP_PCH_GPP_J17 @BASEBOARD_FAB2_LIB.BASEBOARD_FAB2(SCH_1):TP_PCH_GPP_J17
  U7C1 CA11 GPP_J17_LAN_SDP_P0_1 LBG_CORE_QAT_EXT_D_BGA1-IC,H91A   I147 @BASEBOARD_FAB2_LIB.BASEBOARD_FAB2(SCH_1):PAGE120

TP_PCH_GPP_J19 @BASEBOARD_FAB2_LIB.BASEBOARD_FAB2(SCH_1):TP_PCH_GPP_J19
  U7C1 BY14 GPP_J19_LAN_SDP_P1_1 LBG_CORE_QAT_EXT_D_BGA1-IC,H91A   I147 @BASEBOARD_FAB2_LIB.BASEBOARD_FAB2(SCH_1):PAGE120

TP_PCH_GPP_J21 @BASEBOARD_FAB2_LIB.BASEBOARD_FAB2(SCH_1):TP_PCH_GPP_J21
  U7C1 BV12 GPP_J21_LAN_SDP_P2_1 LBG_CORE_QAT_EXT_D_BGA1-IC,H91A   I147 @BASEBOARD_FAB2_LIB.BASEBOARD_FAB2(SCH_1):PAGE120

TP_PCH_GPP_J23 @BASEBOARD_FAB2_LIB.BASEBOARD_FAB2(SCH_1):TP_PCH_GPP_J23
  U7C1 BV14 GPP_J23_LAN_SDP_P3_1 LBG_CORE_QAT_EXT_D_BGA1-IC,H91A   I147 @BASEBOARD_FAB2_LIB.BASEBOARD_FAB2(SCH_1):PAGE120

TP_PCH_GPP_L10 @BASEBOARD_FAB2_LIB.BASEBOARD_FAB2(SCH_1):TP_PCH_GPP_L10
  U7C1 AF20 GPP_L10_TESTCH0_CLK LBG_CORE_QAT_EXT_D_BGA1-IC,H91A    I34 @BASEBOARD_FAB2_LIB.BASEBOARD_FAB2(SCH_1):PAGE121

TP_PCH_GPP_L11 @BASEBOARD_FAB2_LIB.BASEBOARD_FAB2(SCH_1):TP_PCH_GPP_L11
  U7C1 AD20 GPP_L11_TESTCH1_D0 LBG_CORE_QAT_EXT_D_BGA1-IC,H91A    I34 @BASEBOARD_FAB2_LIB.BASEBOARD_FAB2(SCH_1):PAGE121

TP_PCH_HDA_BCLK @BASEBOARD_FAB2_LIB.BASEBOARD_FAB2(SCH_1):TP_PCH_HDA_BCLK
  U7C1  P18 HDA_BCLK LBG_CORE_QAT_EXT_D_BGA1-IC,H91A    I34 @BASEBOARD_FAB2_LIB.BASEBOARD_FAB2(SCH_1):PAGE121

TP_PCH_HDA_SDI_0 @BASEBOARD_FAB2_LIB.BASEBOARD_FAB2(SCH_1):TP_PCH_HDA_SDI_0
  U7C1  K20 HDA_SDI_0 LBG_CORE_QAT_EXT_D_BGA1-IC,H91A    I34 @BASEBOARD_FAB2_LIB.BASEBOARD_FAB2(SCH_1):PAGE121

TP_PCH_HDA_SDI_1 @BASEBOARD_FAB2_LIB.BASEBOARD_FAB2(SCH_1):TP_PCH_HDA_SDI_1
  U7C1  V18 HDA_SDI_1 LBG_CORE_QAT_EXT_D_BGA1-IC,H91A    I34 @BASEBOARD_FAB2_LIB.BASEBOARD_FAB2(SCH_1):PAGE121

TP_PCH_HDA_SYNC @BASEBOARD_FAB2_LIB.BASEBOARD_FAB2(SCH_1):TP_PCH_HDA_SYNC
  U7C1  H20 HDA_SYNC LBG_CORE_QAT_EXT_D_BGA1-IC,H91A    I34 @BASEBOARD_FAB2_LIB.BASEBOARD_FAB2(SCH_1):PAGE121

TP_PCH_HSA_RST_N @BASEBOARD_FAB2_LIB.BASEBOARD_FAB2(SCH_1):TP_PCH_HSA_RST_N
  U7C1  M18 HDA_RST_N LBG_CORE_QAT_EXT_D_BGA1-IC,H91A    I34 @BASEBOARD_FAB2_LIB.BASEBOARD_FAB2(SCH_1):PAGE121

TP_PCH_RSVD0 @BASEBOARD_FAB2_LIB.BASEBOARD_FAB2(SCH_1):TP_PCH_RSVD0
  U7C1 AF61 RSVD<0> LBG_CORE_QAT_EXT_D_BGA1-IC,H91A    I34 @BASEBOARD_FAB2_LIB.BASEBOARD_FAB2(SCH_1):PAGE121

TP_PCH_RSVD1 @BASEBOARD_FAB2_LIB.BASEBOARD_FAB2(SCH_1):TP_PCH_RSVD1
  U7C1 AC56 RSVD<1> LBG_CORE_QAT_EXT_D_BGA1-IC,H91A    I34 @BASEBOARD_FAB2_LIB.BASEBOARD_FAB2(SCH_1):PAGE121

TP_PCH_RSVD12 @BASEBOARD_FAB2_LIB.BASEBOARD_FAB2(SCH_1):TP_PCH_RSVD12
  U7C1  C68 RSVD<12> LBG_CORE_QAT_EXT_D_BGA1-IC,H91A    I34 @BASEBOARD_FAB2_LIB.BASEBOARD_FAB2(SCH_1):PAGE121

TP_PCH_RSVD13 @BASEBOARD_FAB2_LIB.BASEBOARD_FAB2(SCH_1):TP_PCH_RSVD13
  U7C1  C67 RSVD<13> LBG_CORE_QAT_EXT_D_BGA1-IC,H91A    I34 @BASEBOARD_FAB2_LIB.BASEBOARD_FAB2(SCH_1):PAGE121

TP_PCH_RSVD14 @BASEBOARD_FAB2_LIB.BASEBOARD_FAB2(SCH_1):TP_PCH_RSVD14
  U7C1  E18 RSVD<14> LBG_CORE_QAT_EXT_D_BGA1-IC,H91A    I34 @BASEBOARD_FAB2_LIB.BASEBOARD_FAB2(SCH_1):PAGE121

TP_PCH_RSVD15 @BASEBOARD_FAB2_LIB.BASEBOARD_FAB2(SCH_1):TP_PCH_RSVD15
  U7C1   C6 RSVD<15> LBG_CORE_QAT_EXT_D_BGA1-IC,H91A    I34 @BASEBOARD_FAB2_LIB.BASEBOARD_FAB2(SCH_1):PAGE121

TP_PCH_RSVD16 @BASEBOARD_FAB2_LIB.BASEBOARD_FAB2(SCH_1):TP_PCH_RSVD16
  U7C1   C5 RSVD<16> LBG_CORE_QAT_EXT_D_BGA1-IC,H91A    I34 @BASEBOARD_FAB2_LIB.BASEBOARD_FAB2(SCH_1):PAGE121

TP_PCH_RSVD17 @BASEBOARD_FAB2_LIB.BASEBOARD_FAB2(SCH_1):TP_PCH_RSVD17
  U7C1  B10 RSVD<17> LBG_CORE_QAT_EXT_D_BGA1-IC,H91A    I34 @BASEBOARD_FAB2_LIB.BASEBOARD_FAB2(SCH_1):PAGE121

TP_PCH_RSVD18 @BASEBOARD_FAB2_LIB.BASEBOARD_FAB2(SCH_1):TP_PCH_RSVD18
  U7C1  C11 RSVD<18> LBG_CORE_QAT_EXT_D_BGA1-IC,H91A    I34 @BASEBOARD_FAB2_LIB.BASEBOARD_FAB2(SCH_1):PAGE121

TP_PCH_RSVD19 @BASEBOARD_FAB2_LIB.BASEBOARD_FAB2(SCH_1):TP_PCH_RSVD19
  U7C1   C9 RSVD<19> LBG_CORE_QAT_EXT_D_BGA1-IC,H91A    I34 @BASEBOARD_FAB2_LIB.BASEBOARD_FAB2(SCH_1):PAGE121

TP_PCH_RSVD2 @BASEBOARD_FAB2_LIB.BASEBOARD_FAB2(SCH_1):TP_PCH_RSVD2
  U7C1 AA58 RSVD<2> LBG_CORE_QAT_EXT_D_BGA1-IC,H91A    I34 @BASEBOARD_FAB2_LIB.BASEBOARD_FAB2(SCH_1):PAGE121

TP_PCH_RSVD20 @BASEBOARD_FAB2_LIB.BASEBOARD_FAB2(SCH_1):TP_PCH_RSVD20
  U7C1  D10 RSVD<20> LBG_CORE_QAT_EXT_D_BGA1-IC,H91A    I34 @BASEBOARD_FAB2_LIB.BASEBOARD_FAB2(SCH_1):PAGE121

TP_PCH_RSVD21 @BASEBOARD_FAB2_LIB.BASEBOARD_FAB2(SCH_1):TP_PCH_RSVD21
  U7C1  A11 RSVD<21> LBG_CORE_QAT_EXT_D_BGA1-IC,H91A    I34 @BASEBOARD_FAB2_LIB.BASEBOARD_FAB2(SCH_1):PAGE121

TP_PCH_RSVD22 @BASEBOARD_FAB2_LIB.BASEBOARD_FAB2(SCH_1):TP_PCH_RSVD22
  U7C1 AT71 RSVD<22> LBG_CORE_QAT_EXT_D_BGA1-IC,H91A    I34 @BASEBOARD_FAB2_LIB.BASEBOARD_FAB2(SCH_1):PAGE121

TP_PCH_RSVD23 @BASEBOARD_FAB2_LIB.BASEBOARD_FAB2(SCH_1):TP_PCH_RSVD23
  U7C1  P40 RSVD<23> LBG_CORE_QAT_EXT_D_BGA1-IC,H91A    I34 @BASEBOARD_FAB2_LIB.BASEBOARD_FAB2(SCH_1):PAGE121

TP_PCH_RSVD24 @BASEBOARD_FAB2_LIB.BASEBOARD_FAB2(SCH_1):TP_PCH_RSVD24
  U7C1  P44 RSVD<24> LBG_CORE_QAT_EXT_D_BGA1-IC,H91A    I34 @BASEBOARD_FAB2_LIB.BASEBOARD_FAB2(SCH_1):PAGE121

TP_PCH_RSVD25 @BASEBOARD_FAB2_LIB.BASEBOARD_FAB2(SCH_1):TP_PCH_RSVD25
  U7C1  P48 RSVD<25> LBG_CORE_QAT_EXT_D_BGA1-IC,H91A    I34 @BASEBOARD_FAB2_LIB.BASEBOARD_FAB2(SCH_1):PAGE121

TP_PCH_RSVD26 @BASEBOARD_FAB2_LIB.BASEBOARD_FAB2(SCH_1):TP_PCH_RSVD26
  U7C1 BH24 RSVD<26> LBG_CORE_QAT_EXT_D_BGA1-IC,H91A    I34 @BASEBOARD_FAB2_LIB.BASEBOARD_FAB2(SCH_1):PAGE121

TP_PCH_RSVD27 @BASEBOARD_FAB2_LIB.BASEBOARD_FAB2(SCH_1):TP_PCH_RSVD27
  U7C1 BG26 RSVD<27> LBG_CORE_QAT_EXT_D_BGA1-IC,H91A    I34 @BASEBOARD_FAB2_LIB.BASEBOARD_FAB2(SCH_1):PAGE121

TP_PCH_RSVD28 @BASEBOARD_FAB2_LIB.BASEBOARD_FAB2(SCH_1):TP_PCH_RSVD28
  U7C1  R35 RSVD<28> LBG_CORE_QAT_EXT_D_BGA1-IC,H91A    I63 @BASEBOARD_FAB2_LIB.BASEBOARD_FAB2(SCH_1):PAGE122

TP_PCH_RSVD29 @BASEBOARD_FAB2_LIB.BASEBOARD_FAB2(SCH_1):TP_PCH_RSVD29
  U7C1  P33 RSVD<29> LBG_CORE_QAT_EXT_D_BGA1-IC,H91A    I63 @BASEBOARD_FAB2_LIB.BASEBOARD_FAB2(SCH_1):PAGE122

TP_PCH_RSVD3 @BASEBOARD_FAB2_LIB.BASEBOARD_FAB2(SCH_1):TP_PCH_RSVD3
  U7C1  V11 RSVD<3> LBG_CORE_QAT_EXT_D_BGA1-IC,H91A    I34 @BASEBOARD_FAB2_LIB.BASEBOARD_FAB2(SCH_1):PAGE121

TP_PCH_RSVD30 @BASEBOARD_FAB2_LIB.BASEBOARD_FAB2(SCH_1):TP_PCH_RSVD30
  U7C1  R31 RSVD<30> LBG_CORE_QAT_EXT_D_BGA1-IC,H91A    I63 @BASEBOARD_FAB2_LIB.BASEBOARD_FAB2(SCH_1):PAGE122

TP_PCH_RSVD31 @BASEBOARD_FAB2_LIB.BASEBOARD_FAB2(SCH_1):TP_PCH_RSVD31
  U7C1  P29 RSVD<31> LBG_CORE_QAT_EXT_D_BGA1-IC,H91A    I63 @BASEBOARD_FAB2_LIB.BASEBOARD_FAB2(SCH_1):PAGE122

TP_PCH_RSVD32 @BASEBOARD_FAB2_LIB.BASEBOARD_FAB2(SCH_1):TP_PCH_RSVD32
  U7C1 AA54 RSVD<32> LBG_CORE_QAT_EXT_D_BGA1-IC,H91A    I73 @BASEBOARD_FAB2_LIB.BASEBOARD_FAB2(SCH_1):PAGE118

TP_PCH_RSVD33 @BASEBOARD_FAB2_LIB.BASEBOARD_FAB2(SCH_1):TP_PCH_RSVD33
  U7C1  V56 RSVD<33> LBG_CORE_QAT_EXT_D_BGA1-IC,H91A    I73 @BASEBOARD_FAB2_LIB.BASEBOARD_FAB2(SCH_1):PAGE118

TP_PCH_RSVD34 @BASEBOARD_FAB2_LIB.BASEBOARD_FAB2(SCH_1):TP_PCH_RSVD34
  U7C1  Y56 RSVD<34> LBG_CORE_QAT_EXT_D_BGA1-IC,H91A    I73 @BASEBOARD_FAB2_LIB.BASEBOARD_FAB2(SCH_1):PAGE118

TP_PCH_RSVD35 @BASEBOARD_FAB2_LIB.BASEBOARD_FAB2(SCH_1):TP_PCH_RSVD35
  U7C1  W54 RSVD<35> LBG_CORE_QAT_EXT_D_BGA1-IC,H91A    I73 @BASEBOARD_FAB2_LIB.BASEBOARD_FAB2(SCH_1):PAGE118

TP_PCH_RSVD36 @BASEBOARD_FAB2_LIB.BASEBOARD_FAB2(SCH_1):TP_PCH_RSVD36
  U7C1 AK54 RSVD<36> LBG_CORE_QAT_EXT_D_BGA1-IC,H91A    I73 @BASEBOARD_FAB2_LIB.BASEBOARD_FAB2(SCH_1):PAGE118

TP_PCH_RSVD37 @BASEBOARD_FAB2_LIB.BASEBOARD_FAB2(SCH_1):TP_PCH_RSVD37
  U7C1 BN29 RSVD<37> LBG_CORE_QAT_EXT_D_BGA1-IC,H91A    I73 @BASEBOARD_FAB2_LIB.BASEBOARD_FAB2(SCH_1):PAGE118

TP_PCH_RSVD38 @BASEBOARD_FAB2_LIB.BASEBOARD_FAB2(SCH_1):TP_PCH_RSVD38
  U7C1 BL29 RSVD<38> LBG_CORE_QAT_EXT_D_BGA1-IC,H91A    I73 @BASEBOARD_FAB2_LIB.BASEBOARD_FAB2(SCH_1):PAGE118

TP_PCH_RSVD4 @BASEBOARD_FAB2_LIB.BASEBOARD_FAB2(SCH_1):TP_PCH_RSVD4
  U7C1  P37 RSVD<4> LBG_CORE_QAT_EXT_D_BGA1-IC,H91A    I34 @BASEBOARD_FAB2_LIB.BASEBOARD_FAB2(SCH_1):PAGE121

TP_PCH_RSVD41 @BASEBOARD_FAB2_LIB.BASEBOARD_FAB2(SCH_1):TP_PCH_RSVD41
  U7C1 BJ40 RSVD<41> LBG_CORE_QAT_EXT_D_BGA1-IC,H91A    I73 @BASEBOARD_FAB2_LIB.BASEBOARD_FAB2(SCH_1):PAGE118

TP_PCH_RSVD42 @BASEBOARD_FAB2_LIB.BASEBOARD_FAB2(SCH_1):TP_PCH_RSVD42
  U7C1 BG40 RSVD<42> LBG_CORE_QAT_EXT_D_BGA1-IC,H91A    I73 @BASEBOARD_FAB2_LIB.BASEBOARD_FAB2(SCH_1):PAGE118

TP_PCH_RSVD45 @BASEBOARD_FAB2_LIB.BASEBOARD_FAB2(SCH_1):TP_PCH_RSVD45
  U7C1  P22 RSVD<45> LBG_CORE_QAT_EXT_D_BGA1-IC,H91A    I73 @BASEBOARD_FAB2_LIB.BASEBOARD_FAB2(SCH_1):PAGE118

TP_PCH_RSVD46 @BASEBOARD_FAB2_LIB.BASEBOARD_FAB2(SCH_1):TP_PCH_RSVD46
  U7C1  BW3 RSVD<46> LBG_CORE_QAT_EXT_D_BGA1-IC,H91A    I34 @BASEBOARD_FAB2_LIB.BASEBOARD_FAB2(SCH_1):PAGE121

TP_PCH_RSVD47 @BASEBOARD_FAB2_LIB.BASEBOARD_FAB2(SCH_1):TP_PCH_RSVD47
  U7C1 AP69 RSVD<47> LBG_CORE_QAT_EXT_D_BGA1-IC,H91A   I220 @BASEBOARD_FAB2_LIB.BASEBOARD_FAB2(SCH_1):PAGE116

TP_PCH_RSVD48 @BASEBOARD_FAB2_LIB.BASEBOARD_FAB2(SCH_1):TP_PCH_RSVD48
  U7C1 AP71 RSVD<48> LBG_CORE_QAT_EXT_D_BGA1-IC,H91A   I220 @BASEBOARD_FAB2_LIB.BASEBOARD_FAB2(SCH_1):PAGE116

TP_PCH_RSVD49 @BASEBOARD_FAB2_LIB.BASEBOARD_FAB2(SCH_1):TP_PCH_RSVD49
  U7C1  G67 RSVD<49> LBG_CORE_QAT_EXT_D_BGA1-IC,H91A   I220 @BASEBOARD_FAB2_LIB.BASEBOARD_FAB2(SCH_1):PAGE116

TP_PCH_RSVD5 @BASEBOARD_FAB2_LIB.BASEBOARD_FAB2(SCH_1):TP_PCH_RSVD5
  U7C1 AG15 RSVD<5> LBG_CORE_QAT_EXT_D_BGA1-IC,H91A    I34 @BASEBOARD_FAB2_LIB.BASEBOARD_FAB2(SCH_1):PAGE121

TP_PCH_RSVD50 @BASEBOARD_FAB2_LIB.BASEBOARD_FAB2(SCH_1):TP_PCH_RSVD50
  U7C1  H69 RSVD<50> LBG_CORE_QAT_EXT_D_BGA1-IC,H91A   I220 @BASEBOARD_FAB2_LIB.BASEBOARD_FAB2(SCH_1):PAGE116

TP_PCH_RSVD51 @BASEBOARD_FAB2_LIB.BASEBOARD_FAB2(SCH_1):TP_PCH_RSVD51
  U7C1 AA69 RSVD<51> LBG_CORE_QAT_EXT_D_BGA1-IC,H91A   I220 @BASEBOARD_FAB2_LIB.BASEBOARD_FAB2(SCH_1):PAGE116

TP_PCH_RSVD52 @BASEBOARD_FAB2_LIB.BASEBOARD_FAB2(SCH_1):TP_PCH_RSVD52
  U7C1 AA71 RSVD<52> LBG_CORE_QAT_EXT_D_BGA1-IC,H91A   I220 @BASEBOARD_FAB2_LIB.BASEBOARD_FAB2(SCH_1):PAGE116

TP_PCH_RSVD53 @BASEBOARD_FAB2_LIB.BASEBOARD_FAB2(SCH_1):TP_PCH_RSVD53
  U7C1  P26 RSVD<53> LBG_CORE_QAT_EXT_D_BGA1-IC,H91A    I73 @BASEBOARD_FAB2_LIB.BASEBOARD_FAB2(SCH_1):PAGE118

TP_PCH_RSVD54 @BASEBOARD_FAB2_LIB.BASEBOARD_FAB2(SCH_1):TP_PCH_RSVD54
  U7C1  R24 RSVD<54> LBG_CORE_QAT_EXT_D_BGA1-IC,H91A    I73 @BASEBOARD_FAB2_LIB.BASEBOARD_FAB2(SCH_1):PAGE118

TP_PCH_RSVD55 @BASEBOARD_FAB2_LIB.BASEBOARD_FAB2(SCH_1):TP_PCH_RSVD55
  U7C1 BN68 RSVD<55> LBG_CORE_QAT_EXT_D_BGA1-IC,H91A    I74 @BASEBOARD_FAB2_LIB.BASEBOARD_FAB2(SCH_1):PAGE115

TP_PCH_RSVD58 @BASEBOARD_FAB2_LIB.BASEBOARD_FAB2(SCH_1):TP_PCH_RSVD58
  U7C1 AP27 RSVD<58> LBG_CORE_QAT_EXT_D_BGA1-IC,H91A    I63 @BASEBOARD_FAB2_LIB.BASEBOARD_FAB2(SCH_1):PAGE122

TP_PCH_RSVD59 @BASEBOARD_FAB2_LIB.BASEBOARD_FAB2(SCH_1):TP_PCH_RSVD59
  U7C1 AT27 RSVD<59> LBG_CORE_QAT_EXT_D_BGA1-IC,H91A    I63 @BASEBOARD_FAB2_LIB.BASEBOARD_FAB2(SCH_1):PAGE122

TP_PCH_RSVD6 @BASEBOARD_FAB2_LIB.BASEBOARD_FAB2(SCH_1):TP_PCH_RSVD6
  U7C1 AT69 RSVD<6> LBG_CORE_QAT_EXT_D_BGA1-IC,H91A    I34 @BASEBOARD_FAB2_LIB.BASEBOARD_FAB2(SCH_1):PAGE121

TP_PCH_RSVD64 @BASEBOARD_FAB2_LIB.BASEBOARD_FAB2(SCH_1):TP_PCH_RSVD64
  U7C1  C26 RSVD<64> LBG_CORE_QAT_EXT_D_BGA1-IC,H91A    I40 @BASEBOARD_FAB2_LIB.BASEBOARD_FAB2(SCH_1):PAGE114

TP_PCH_RSVD65 @BASEBOARD_FAB2_LIB.BASEBOARD_FAB2(SCH_1):TP_PCH_RSVD65
  U7C1  A26 RSVD<65> LBG_CORE_QAT_EXT_D_BGA1-IC,H91A    I40 @BASEBOARD_FAB2_LIB.BASEBOARD_FAB2(SCH_1):PAGE114

TP_PCH_RSVD7 @BASEBOARD_FAB2_LIB.BASEBOARD_FAB2(SCH_1):TP_PCH_RSVD7
  U7C1   F8 RSVD<7> LBG_CORE_QAT_EXT_D_BGA1-IC,H91A    I34 @BASEBOARD_FAB2_LIB.BASEBOARD_FAB2(SCH_1):PAGE121

TP_PCH_RSVD8 @BASEBOARD_FAB2_LIB.BASEBOARD_FAB2(SCH_1):TP_PCH_RSVD8
  U7C1  F69 RSVD<8> LBG_CORE_QAT_EXT_D_BGA1-IC,H91A    I34 @BASEBOARD_FAB2_LIB.BASEBOARD_FAB2(SCH_1):PAGE121

TP_PCH_RSVD9 @BASEBOARD_FAB2_LIB.BASEBOARD_FAB2(SCH_1):TP_PCH_RSVD9
  U7C1  F66 RSVD<9> LBG_CORE_QAT_EXT_D_BGA1-IC,H91A    I34 @BASEBOARD_FAB2_LIB.BASEBOARD_FAB2(SCH_1):PAGE121

TP_PLTRST_CPU_N @BASEBOARD_FAB2_LIB.BASEBOARD_FAB2(SCH_1):TP_PLTRST_CPU_N
  U7C1  U17 PLTRST_CPU_N LBG_CORE_QAT_EXT_D_BGA1-IC,H91A    I73 @BASEBOARD_FAB2_LIB.BASEBOARD_FAB2(SCH_1):PAGE118

TP_PM_SYNC_GTL @BASEBOARD_FAB2_LIB.BASEBOARD_FAB2(SCH_1):TP_PM_SYNC_GTL
  U7C1   V7 PM_SYNC2 LBG_CORE_QAT_EXT_D_BGA1-IC,H91A    I73 @BASEBOARD_FAB2_LIB.BASEBOARD_FAB2(SCH_1):PAGE118

TP_PUMP @BASEBOARD_FAB2_LIB.BASEBOARD_FAB2(SCH_1):TP_PUMP
  J1B2    6    IO6 CONN6_C74770005_PIP-HDR,C74770A    I25 @BASEBOARD_FAB2_LIB.BASEBOARD_FAB2(SCH_1):PAGE251

TP_PVCCINC_CPU1_PH1_GL_0 @BASEBOARD_FAB2_LIB.BASEBOARD_FAB2(SCH_1):TP_PVCCINC_CPU1_PH1_GL_0
 EU1E2    6  GL<0> IR354XX_SM-IR35411,IC,H73688-0A    I20 @BASEBOARD_FAB2_LIB.BASEBOARD_FAB2(SCH_1):PAGE207

TP_PVCCINC_CPU1_PH1_GL_1 @BASEBOARD_FAB2_LIB.BASEBOARD_FAB2(SCH_1):TP_PVCCINC_CPU1_PH1_GL_1
 EU1E2   41  GL<1> IR354XX_SM-IR35411,IC,H73688-0A    I20 @BASEBOARD_FAB2_LIB.BASEBOARD_FAB2(SCH_1):PAGE207

TP_PVCCINC_CPU1_PH2_GL_0 @BASEBOARD_FAB2_LIB.BASEBOARD_FAB2(SCH_1):TP_PVCCINC_CPU1_PH2_GL_0
 EU1D4    6  GL<0> IR354XX_SM-IR35411,IC,H73688-0A   I113 @BASEBOARD_FAB2_LIB.BASEBOARD_FAB2(SCH_1):PAGE207

TP_PVCCINC_CPU1_PH2_GL_1 @BASEBOARD_FAB2_LIB.BASEBOARD_FAB2(SCH_1):TP_PVCCINC_CPU1_PH2_GL_1
 EU1D4   41  GL<1> IR354XX_SM-IR35411,IC,H73688-0A   I113 @BASEBOARD_FAB2_LIB.BASEBOARD_FAB2(SCH_1):PAGE207

TP_PVCCIN_CPU0_PH1_GL_0 @BASEBOARD_FAB2_LIB.BASEBOARD_FAB2(SCH_1):TP_PVCCIN_CPU0_PH1_GL_0
 EU4E1    6  GL<0> IR354XX_SM-IR35411,IC,H73688-0A    I63 @BASEBOARD_FAB2_LIB.BASEBOARD_FAB2(SCH_1):PAGE202

TP_PVCCIN_CPU0_PH1_GL_1 @BASEBOARD_FAB2_LIB.BASEBOARD_FAB2(SCH_1):TP_PVCCIN_CPU0_PH1_GL_1
 EU4E1   41  GL<1> IR354XX_SM-IR35411,IC,H73688-0A    I63 @BASEBOARD_FAB2_LIB.BASEBOARD_FAB2(SCH_1):PAGE202

TP_PVCCIN_CPU0_PH2_GL_0 @BASEBOARD_FAB2_LIB.BASEBOARD_FAB2(SCH_1):TP_PVCCIN_CPU0_PH2_GL_0
 EU4D6    6  GL<0> IR354XX_SM-IR35411,IC,H73688-0A    I64 @BASEBOARD_FAB2_LIB.BASEBOARD_FAB2(SCH_1):PAGE202

TP_PVCCIN_CPU0_PH2_GL_1 @BASEBOARD_FAB2_LIB.BASEBOARD_FAB2(SCH_1):TP_PVCCIN_CPU0_PH2_GL_1
 EU4D6   41  GL<1> IR354XX_SM-IR35411,IC,H73688-0A    I64 @BASEBOARD_FAB2_LIB.BASEBOARD_FAB2(SCH_1):PAGE202

TP_PVCCIN_CPU0_PH3_GL_0 @BASEBOARD_FAB2_LIB.BASEBOARD_FAB2(SCH_1):TP_PVCCIN_CPU0_PH3_GL_0
 EU4D3    6  GL<0> IR354XX_SM-IR35411,IC,H73688-0A    I70 @BASEBOARD_FAB2_LIB.BASEBOARD_FAB2(SCH_1):PAGE203

TP_PVCCIN_CPU0_PH3_GL_1 @BASEBOARD_FAB2_LIB.BASEBOARD_FAB2(SCH_1):TP_PVCCIN_CPU0_PH3_GL_1
 EU4D3   41  GL<1> IR354XX_SM-IR35411,IC,H73688-0A    I70 @BASEBOARD_FAB2_LIB.BASEBOARD_FAB2(SCH_1):PAGE203

TP_PVCCIN_CPU0_PH4_GL_0 @BASEBOARD_FAB2_LIB.BASEBOARD_FAB2(SCH_1):TP_PVCCIN_CPU0_PH4_GL_0
 EU4D1    6  GL<0> IR354XX_SM-IR35411,IC,H73688-0A    I71 @BASEBOARD_FAB2_LIB.BASEBOARD_FAB2(SCH_1):PAGE203

TP_PVCCIN_CPU0_PH4_GL_1 @BASEBOARD_FAB2_LIB.BASEBOARD_FAB2(SCH_1):TP_PVCCIN_CPU0_PH4_GL_1
 EU4D1   41  GL<1> IR354XX_SM-IR35411,IC,H73688-0A    I71 @BASEBOARD_FAB2_LIB.BASEBOARD_FAB2(SCH_1):PAGE203

TP_PVCCIN_CPU0_PH5_GL_0 @BASEBOARD_FAB2_LIB.BASEBOARD_FAB2(SCH_1):TP_PVCCIN_CPU0_PH5_GL_0
 EU4C2    6  GL<0> IR354XX_SM-IR35411,IC,H73688-0A    I71 @BASEBOARD_FAB2_LIB.BASEBOARD_FAB2(SCH_1):PAGE204

TP_PVCCIN_CPU0_PH5_GL_1 @BASEBOARD_FAB2_LIB.BASEBOARD_FAB2(SCH_1):TP_PVCCIN_CPU0_PH5_GL_1
 EU4C2   41  GL<1> IR354XX_SM-IR35411,IC,H73688-0A    I71 @BASEBOARD_FAB2_LIB.BASEBOARD_FAB2(SCH_1):PAGE204

TP_PVCCIN_CPU1_PH3_GL_0 @BASEBOARD_FAB2_LIB.BASEBOARD_FAB2(SCH_1):TP_PVCCIN_CPU1_PH3_GL_0
 EU1D3    6  GL<0> IR354XX_SM-IR35411,IC,H73688-0A    I27 @BASEBOARD_FAB2_LIB.BASEBOARD_FAB2(SCH_1):PAGE208

TP_PVCCIN_CPU1_PH3_GL_1 @BASEBOARD_FAB2_LIB.BASEBOARD_FAB2(SCH_1):TP_PVCCIN_CPU1_PH3_GL_1
 EU1D3   41  GL<1> IR354XX_SM-IR35411,IC,H73688-0A    I27 @BASEBOARD_FAB2_LIB.BASEBOARD_FAB2(SCH_1):PAGE208

TP_PVCCIN_CPU1_PH4_GL_0 @BASEBOARD_FAB2_LIB.BASEBOARD_FAB2(SCH_1):TP_PVCCIN_CPU1_PH4_GL_0
 EU1D1    6  GL<0> IR354XX_SM-IR35411,IC,H73688-0A    I71 @BASEBOARD_FAB2_LIB.BASEBOARD_FAB2(SCH_1):PAGE208

TP_PVCCIN_CPU1_PH4_GL_1 @BASEBOARD_FAB2_LIB.BASEBOARD_FAB2(SCH_1):TP_PVCCIN_CPU1_PH4_GL_1
 EU1D1   41  GL<1> IR354XX_SM-IR35411,IC,H73688-0A    I71 @BASEBOARD_FAB2_LIB.BASEBOARD_FAB2(SCH_1):PAGE208

TP_PVCCIN_CPU1_PH5_GL_0 @BASEBOARD_FAB2_LIB.BASEBOARD_FAB2(SCH_1):TP_PVCCIN_CPU1_PH5_GL_0
 EU1C3    6  GL<0> IR354XX_SM-IR35411,IC,H73688-0A    I56 @BASEBOARD_FAB2_LIB.BASEBOARD_FAB2(SCH_1):PAGE209

TP_PVCCIN_CPU1_PH5_GL_1 @BASEBOARD_FAB2_LIB.BASEBOARD_FAB2(SCH_1):TP_PVCCIN_CPU1_PH5_GL_1
 EU1C3   41  GL<1> IR354XX_SM-IR35411,IC,H73688-0A    I56 @BASEBOARD_FAB2_LIB.BASEBOARD_FAB2(SCH_1):PAGE209

TP_PVCCIO_CPU0_GL_0 @BASEBOARD_FAB2_LIB.BASEBOARD_FAB2(SCH_1):TP_PVCCIO_CPU0_GL_0
 EU7C1    6  GL<0> IR354XX_SM-IR35412,IC,H73684-0A   I101 @BASEBOARD_FAB2_LIB.BASEBOARD_FAB2(SCH_1):PAGE212

TP_PVCCIO_CPU0_GL_1 @BASEBOARD_FAB2_LIB.BASEBOARD_FAB2(SCH_1):TP_PVCCIO_CPU0_GL_1
 EU7C1   41  GL<1> IR354XX_SM-IR35412,IC,H73684-0A   I101 @BASEBOARD_FAB2_LIB.BASEBOARD_FAB2(SCH_1):PAGE212

TP_PVCCIO_CPU1_GL_0 @BASEBOARD_FAB2_LIB.BASEBOARD_FAB2(SCH_1):TP_PVCCIO_CPU1_GL_0
 EU4E2    6  GL<0> IR354XX_SM-IR35412,IC,H73684-0A   I126 @BASEBOARD_FAB2_LIB.BASEBOARD_FAB2(SCH_1):PAGE214

TP_PVCCIO_CPU1_GL_1 @BASEBOARD_FAB2_LIB.BASEBOARD_FAB2(SCH_1):TP_PVCCIO_CPU1_GL_1
 EU4E2   41  GL<1> IR354XX_SM-IR35412,IC,H73684-0A   I126 @BASEBOARD_FAB2_LIB.BASEBOARD_FAB2(SCH_1):PAGE214

TP_PVDDQ_ABC_MP1 @BASEBOARD_FAB2_LIB.BASEBOARD_FAB2(SCH_1):TP_PVDDQ_ABC_MP1
R12W26    1      A RES_0402-0.0,5%,1/16W,EMPTY,G2A    I45 @BASEBOARD_FAB2_LIB.BASEBOARD_FAB2(SCH_1):PAGE215
 EU7G1   14    MP1 PXM1310B_QFN-IC,H89186-001    I69 @BASEBOARD_FAB2_LIB.BASEBOARD_FAB2(SCH_1):PAGE215

TP_PVDDQ_ABC_MP2 @BASEBOARD_FAB2_LIB.BASEBOARD_FAB2(SCH_1):TP_PVDDQ_ABC_MP2
R12W27    1      A RES_0402-0.0,5%,1/16W,EMPTY,G2A    I54 @BASEBOARD_FAB2_LIB.BASEBOARD_FAB2(SCH_1):PAGE215
 EU7G1   18    MP2 PXM1310B_QFN-IC,H89186-001    I69 @BASEBOARD_FAB2_LIB.BASEBOARD_FAB2(SCH_1):PAGE215

TP_PVDDQ_ABC_PH1_GL_0 @BASEBOARD_FAB2_LIB.BASEBOARD_FAB2(SCH_1):TP_PVDDQ_ABC_PH1_GL_0
 EU7G2    6  GL<0> IR354XX_SM-IR35411,IC,H73688-0A   I102 @BASEBOARD_FAB2_LIB.BASEBOARD_FAB2(SCH_1):PAGE216

TP_PVDDQ_ABC_PH1_GL_1 @BASEBOARD_FAB2_LIB.BASEBOARD_FAB2(SCH_1):TP_PVDDQ_ABC_PH1_GL_1
 EU7G2   41  GL<1> IR354XX_SM-IR35411,IC,H73688-0A   I102 @BASEBOARD_FAB2_LIB.BASEBOARD_FAB2(SCH_1):PAGE216

TP_PVDDQ_ABC_PH2_GL_0 @BASEBOARD_FAB2_LIB.BASEBOARD_FAB2(SCH_1):TP_PVDDQ_ABC_PH2_GL_0
 EU7G3    6  GL<0> IR354XX_SM-IR35411,IC,H73688-0A   I103 @BASEBOARD_FAB2_LIB.BASEBOARD_FAB2(SCH_1):PAGE216

TP_PVDDQ_ABC_PH2_GL_1 @BASEBOARD_FAB2_LIB.BASEBOARD_FAB2(SCH_1):TP_PVDDQ_ABC_PH2_GL_1
 EU7G3   41  GL<1> IR354XX_SM-IR35411,IC,H73688-0A   I103 @BASEBOARD_FAB2_LIB.BASEBOARD_FAB2(SCH_1):PAGE216

TP_PVDDQ_DEF_MP1 @BASEBOARD_FAB2_LIB.BASEBOARD_FAB2(SCH_1):TP_PVDDQ_DEF_MP1
R12W29    1      A RES_0402-0.0,5%,1/16W,EMPTY,G2A    I46 @BASEBOARD_FAB2_LIB.BASEBOARD_FAB2(SCH_1):PAGE218
 EU7A5   14    MP1 PXM1310B_QFN-IC,H89186-001    I69 @BASEBOARD_FAB2_LIB.BASEBOARD_FAB2(SCH_1):PAGE218

TP_PVDDQ_DEF_MP2 @BASEBOARD_FAB2_LIB.BASEBOARD_FAB2(SCH_1):TP_PVDDQ_DEF_MP2
R12W30    1      A RES_0402-0.0,5%,1/16W,EMPTY,G2A    I55 @BASEBOARD_FAB2_LIB.BASEBOARD_FAB2(SCH_1):PAGE218
 EU7A5   18    MP2 PXM1310B_QFN-IC,H89186-001    I69 @BASEBOARD_FAB2_LIB.BASEBOARD_FAB2(SCH_1):PAGE218

TP_PVDDQ_DEF_PH1_GL_0 @BASEBOARD_FAB2_LIB.BASEBOARD_FAB2(SCH_1):TP_PVDDQ_DEF_PH1_GL_0
 EU7A1    6  GL<0> IR354XX_SM-IR35411,IC,H73688-0A   I106 @BASEBOARD_FAB2_LIB.BASEBOARD_FAB2(SCH_1):PAGE219

TP_PVDDQ_DEF_PH1_GL_1 @BASEBOARD_FAB2_LIB.BASEBOARD_FAB2(SCH_1):TP_PVDDQ_DEF_PH1_GL_1
 EU7A1   41  GL<1> IR354XX_SM-IR35411,IC,H73688-0A   I106 @BASEBOARD_FAB2_LIB.BASEBOARD_FAB2(SCH_1):PAGE219

TP_PVDDQ_DEF_PH2_GL_0 @BASEBOARD_FAB2_LIB.BASEBOARD_FAB2(SCH_1):TP_PVDDQ_DEF_PH2_GL_0
 EU7A4    6  GL<0> IR354XX_SM-IR35411,IC,H73688-0A   I107 @BASEBOARD_FAB2_LIB.BASEBOARD_FAB2(SCH_1):PAGE219

TP_PVDDQ_DEF_PH2_GL_1 @BASEBOARD_FAB2_LIB.BASEBOARD_FAB2(SCH_1):TP_PVDDQ_DEF_PH2_GL_1
 EU7A4   41  GL<1> IR354XX_SM-IR35411,IC,H73688-0A   I107 @BASEBOARD_FAB2_LIB.BASEBOARD_FAB2(SCH_1):PAGE219

TP_PVDDQ_GHJ_MP1 @BASEBOARD_FAB2_LIB.BASEBOARD_FAB2(SCH_1):TP_PVDDQ_GHJ_MP1
R12W32    1      A RES_0402-0.0,5%,1/16W,EMPTY,G2A    I45 @BASEBOARD_FAB2_LIB.BASEBOARD_FAB2(SCH_1):PAGE223
 EU1G2   14    MP1 PXM1310B_QFN-IC,H89186-001    I69 @BASEBOARD_FAB2_LIB.BASEBOARD_FAB2(SCH_1):PAGE223

TP_PVDDQ_GHJ_MP2 @BASEBOARD_FAB2_LIB.BASEBOARD_FAB2(SCH_1):TP_PVDDQ_GHJ_MP2
R12W33    1      A RES_0402-0.0,5%,1/16W,EMPTY,G2A    I53 @BASEBOARD_FAB2_LIB.BASEBOARD_FAB2(SCH_1):PAGE223
 EU1G2   18    MP2 PXM1310B_QFN-IC,H89186-001    I69 @BASEBOARD_FAB2_LIB.BASEBOARD_FAB2(SCH_1):PAGE223

TP_PVDDQ_GHJ_PH1_GL_0 @BASEBOARD_FAB2_LIB.BASEBOARD_FAB2(SCH_1):TP_PVDDQ_GHJ_PH1_GL_0
 EU1G1    6  GL<0> IR354XX_SM-IR35411,IC,H73688-0A   I110 @BASEBOARD_FAB2_LIB.BASEBOARD_FAB2(SCH_1):PAGE224

TP_PVDDQ_GHJ_PH1_GL_1 @BASEBOARD_FAB2_LIB.BASEBOARD_FAB2(SCH_1):TP_PVDDQ_GHJ_PH1_GL_1
 EU1G1   41  GL<1> IR354XX_SM-IR35411,IC,H73688-0A   I110 @BASEBOARD_FAB2_LIB.BASEBOARD_FAB2(SCH_1):PAGE224

TP_PVDDQ_GHJ_PH2_GL_0 @BASEBOARD_FAB2_LIB.BASEBOARD_FAB2(SCH_1):TP_PVDDQ_GHJ_PH2_GL_0
 EU1F1    6  GL<0> IR354XX_SM-IR35411,IC,H73688-0A   I111 @BASEBOARD_FAB2_LIB.BASEBOARD_FAB2(SCH_1):PAGE224

TP_PVDDQ_GHJ_PH2_GL_1 @BASEBOARD_FAB2_LIB.BASEBOARD_FAB2(SCH_1):TP_PVDDQ_GHJ_PH2_GL_1
 EU1F1   41  GL<1> IR354XX_SM-IR35411,IC,H73688-0A   I111 @BASEBOARD_FAB2_LIB.BASEBOARD_FAB2(SCH_1):PAGE224

TP_PVDDQ_KLM_PH1_GL_0 @BASEBOARD_FAB2_LIB.BASEBOARD_FAB2(SCH_1):TP_PVDDQ_KLM_PH1_GL_0
 EU1A2    6  GL<0> IR354XX_SM-IR35411,IC,H73688-0A   I101 @BASEBOARD_FAB2_LIB.BASEBOARD_FAB2(SCH_1):PAGE227

TP_PVDDQ_KLM_PH1_GL_1 @BASEBOARD_FAB2_LIB.BASEBOARD_FAB2(SCH_1):TP_PVDDQ_KLM_PH1_GL_1
 EU1A2   41  GL<1> IR354XX_SM-IR35411,IC,H73688-0A   I101 @BASEBOARD_FAB2_LIB.BASEBOARD_FAB2(SCH_1):PAGE227

TP_PVDDQ_KLM_PH2_GL_0 @BASEBOARD_FAB2_LIB.BASEBOARD_FAB2(SCH_1):TP_PVDDQ_KLM_PH2_GL_0
 EU1A1    6  GL<0> IR354XX_SM-IR35411,IC,H73688-0A   I102 @BASEBOARD_FAB2_LIB.BASEBOARD_FAB2(SCH_1):PAGE227

TP_PVDDQ_KLM_PH2_GL_1 @BASEBOARD_FAB2_LIB.BASEBOARD_FAB2(SCH_1):TP_PVDDQ_KLM_PH2_GL_1
 EU1A1   41  GL<1> IR354XX_SM-IR35411,IC,H73688-0A   I102 @BASEBOARD_FAB2_LIB.BASEBOARD_FAB2(SCH_1):PAGE227

TP_PVNN_PCH_GL_0 @BASEBOARD_FAB2_LIB.BASEBOARD_FAB2(SCH_1):TP_PVNN_PCH_GL_0
 EU7A3    6  GL<0> IR354XX_SM-IR35412,IC,H73684-0A   I116 @BASEBOARD_FAB2_LIB.BASEBOARD_FAB2(SCH_1):PAGE236

TP_PVNN_PCH_GL_1 @BASEBOARD_FAB2_LIB.BASEBOARD_FAB2(SCH_1):TP_PVNN_PCH_GL_1
 EU7A3   41  GL<1> IR354XX_SM-IR35412,IC,H73684-0A   I116 @BASEBOARD_FAB2_LIB.BASEBOARD_FAB2(SCH_1):PAGE236

TP_PVSA_CPU0_GL_0 @BASEBOARD_FAB2_LIB.BASEBOARD_FAB2(SCH_1):TP_PVSA_CPU0_GL_0
 EU4C1    6  GL<0> IR354XX_SM-IR35412,IC,H73684-0A    I46 @BASEBOARD_FAB2_LIB.BASEBOARD_FAB2(SCH_1):PAGE205

TP_PVSA_CPU0_GL_1 @BASEBOARD_FAB2_LIB.BASEBOARD_FAB2(SCH_1):TP_PVSA_CPU0_GL_1
 EU4C1   41  GL<1> IR354XX_SM-IR35412,IC,H73684-0A    I46 @BASEBOARD_FAB2_LIB.BASEBOARD_FAB2(SCH_1):PAGE205

TP_PVSA_CPU1_GL_0 @BASEBOARD_FAB2_LIB.BASEBOARD_FAB2(SCH_1):TP_PVSA_CPU1_GL_0
 EU1C1    6  GL<0> IR354XX_SM-IR35412,IC,H73684-0A    I51 @BASEBOARD_FAB2_LIB.BASEBOARD_FAB2(SCH_1):PAGE210

TP_PVSA_CPU1_GL_1 @BASEBOARD_FAB2_LIB.BASEBOARD_FAB2(SCH_1):TP_PVSA_CPU1_GL_1
 EU1C1   41  GL<1> IR354XX_SM-IR35412,IC,H73684-0A    I51 @BASEBOARD_FAB2_LIB.BASEBOARD_FAB2(SCH_1):PAGE210

TP_RGMII1TXD2_GPIOT4 @BASEBOARD_FAB2_LIB.BASEBOARD_FAB2(SCH_1):TP_RGMII1TXD2_GPIOT4
 U25W4   E7 RGMII1TXD2_GPIOT4 AST2520A1-GP-GP_ASIC2-GB1-AST2A   I106 @BASEBOARD_FAB2_LIB.BASEBOARD_FAB2(SCH_1):PAGE147
R25W114    2      B RES_0402-4.75K,1%,1/16W,EMPTY,A   I218 @BASEBOARD_FAB2_LIB.BASEBOARD_FAB2(SCH_1):PAGE150
R25W149    2      B RES_0402-4.75K,1%,1/16W,CHIP,GA   I219 @BASEBOARD_FAB2_LIB.BASEBOARD_FAB2(SCH_1):PAGE150

TP_RGMII1TXD3_GPIOT5 @BASEBOARD_FAB2_LIB.BASEBOARD_FAB2(SCH_1):TP_RGMII1TXD3_GPIOT5
 U25W4   D7 RGMII1TXD3_GPIOT5 AST2520A1-GP-GP_ASIC2-GB1-AST2A   I106 @BASEBOARD_FAB2_LIB.BASEBOARD_FAB2(SCH_1):PAGE147
R25W115    2      B RES_0402-4.75K,1%,1/16W,EMPTY,A   I242 @BASEBOARD_FAB2_LIB.BASEBOARD_FAB2(SCH_1):PAGE150

TP_RGMII2TXD2_GPIOU2 @BASEBOARD_FAB2_LIB.BASEBOARD_FAB2(SCH_1):TP_RGMII2TXD2_GPIOU2
 U25W4   D5 RGMII2TXD2_GPIOU2 AST2520A1-GP-GP_ASIC2-GB1-AST2A   I106 @BASEBOARD_FAB2_LIB.BASEBOARD_FAB2(SCH_1):PAGE147
R25W110    2      B RES_0402-4.75K,1%,1/16W,EMPTY,A   I233 @BASEBOARD_FAB2_LIB.BASEBOARD_FAB2(SCH_1):PAGE150
R25W152    2      B RES_0402-4.75K,1%,1/16W,CHIP,GA   I234 @BASEBOARD_FAB2_LIB.BASEBOARD_FAB2(SCH_1):PAGE150

TP_RGMII2TXD3_GPIOU3 @BASEBOARD_FAB2_LIB.BASEBOARD_FAB2(SCH_1):TP_RGMII2TXD3_GPIOU3
 U25W4   D4 RGMII2TXD3_GPIOU3 AST2520A1-GP-GP_ASIC2-GB1-AST2A   I106 @BASEBOARD_FAB2_LIB.BASEBOARD_FAB2(SCH_1):PAGE147
R25W109    2      B RES_0402-4.75K,1%,1/16W,CHIP,GA   I236 @BASEBOARD_FAB2_LIB.BASEBOARD_FAB2(SCH_1):PAGE150

TP_RST_CPU1_CD_HFI0_N @BASEBOARD_FAB2_LIB.BASEBOARD_FAB2(SCH_1):TP_RST_CPU1_CD_HFI0_N
  U2D1 BN24 CD_HFI0_RESET_N SKX_EXT_B_BGA1-IC,TBD    I23 @BASEBOARD_FAB2_LIB.BASEBOARD_FAB2(SCH_1):PAGE63

TP_RST_RTCRST_N @BASEBOARD_FAB2_LIB.BASEBOARD_FAB2(SCH_1):TP_RST_RTCRST_N
  J9G1    2    IO2 CONN12_C73564003_PIP-CONN,C735A   I128 @BASEBOARD_FAB2_LIB.BASEBOARD_FAB2(SCH_1):PAGE137

TP_RSVD<0> @BASEBOARD_FAB2_LIB.BASEBOARD_FAB2(SCH_1):TP_RSVD(0)
  J8E4   36   IO36 SCONN64_H87568002_A_SMT-CONN,HA    I27 @BASEBOARD_FAB2_LIB.BASEBOARD_FAB2(SCH_1):PAGE188

TP_RSVD_B1 @BASEBOARD_FAB2_LIB.BASEBOARD_FAB2(SCH_1):TP_RSVD_B1
  J8E3    6    IO6 SCONN80_E67482007_SM-CONN,E674A   I119 @BASEBOARD_FAB2_LIB.BASEBOARD_FAB2(SCH_1):PAGE187

TP_SGPIO_SATA_CLOCK1_R @BASEBOARD_FAB2_LIB.BASEBOARD_FAB2(SCH_1):TP_SGPIO_SATA_CLOCK1_R
  J8A1  2A2 SIDEBANDB_0 CONN72_G97614002_A_CP-CONN,G97A   I163 @BASEBOARD_FAB2_LIB.BASEBOARD_FAB2(SCH_1):PAGE173

TP_SGPIO_SATA_DATA1_R @BASEBOARD_FAB2_LIB.BASEBOARD_FAB2(SCH_1):TP_SGPIO_SATA_DATA1_R
  J8A1  2C1 SIDEBANDB_4 CONN72_G97614002_A_CP-CONN,G97A   I163 @BASEBOARD_FAB2_LIB.BASEBOARD_FAB2(SCH_1):PAGE173

TP_SGPIO_SATA_LOAD1_R @BASEBOARD_FAB2_LIB.BASEBOARD_FAB2(SCH_1):TP_SGPIO_SATA_LOAD1_R
  J8A1  2B2 SIDEBANDB_1 CONN72_G97614002_A_CP-CONN,G97A   I163 @BASEBOARD_FAB2_LIB.BASEBOARD_FAB2(SCH_1):PAGE173

TP_SHARED_KR_MDC_0 @BASEBOARD_FAB2_LIB.BASEBOARD_FAB2(SCH_1):TP_SHARED_KR_MDC_0
  J8E4   49   IO49 SCONN64_H87568002_A_SMT-CONN,HA    I27 @BASEBOARD_FAB2_LIB.BASEBOARD_FAB2(SCH_1):PAGE188

TP_SHARED_KR_MDIO_0 @BASEBOARD_FAB2_LIB.BASEBOARD_FAB2(SCH_1):TP_SHARED_KR_MDIO_0
  J8E4   50   IO50 SCONN64_H87568002_A_SMT-CONN,HA    I27 @BASEBOARD_FAB2_LIB.BASEBOARD_FAB2(SCH_1):PAGE188

TP_SLG55021_P12V_FAN_8 @BASEBOARD_FAB2_LIB.BASEBOARD_FAB2(SCH_1):TP_SLG55021_P12V_FAN_8
 EU9M1    8     PG SLG55021_SM-IC,G56246-001    I69 @BASEBOARD_FAB2_LIB.BASEBOARD_FAB2(SCH_1):PAGE198

TP_SLG55021_P12V_MAIN_8 @BASEBOARD_FAB2_LIB.BASEBOARD_FAB2(SCH_1):TP_SLG55021_P12V_MAIN_8
 EU7E1    8     PG SLG55021_SM-IC,G56246-001    I19 @BASEBOARD_FAB2_LIB.BASEBOARD_FAB2(SCH_1):PAGE198

TP_SLG55021_P3V3_8 @BASEBOARD_FAB2_LIB.BASEBOARD_FAB2(SCH_1):TP_SLG55021_P3V3_8
 EU2T1    8     PG SLG55021_SM-IC,G56246-001     I1 @BASEBOARD_FAB2_LIB.BASEBOARD_FAB2(SCH_1):PAGE198

TP_SLG55021_P5V_8 @BASEBOARD_FAB2_LIB.BASEBOARD_FAB2(SCH_1):TP_SLG55021_P5V_8
 EU8B1    8     PG SLG55021_SM-IC,G56246-001    I13 @BASEBOARD_FAB2_LIB.BASEBOARD_FAB2(SCH_1):PAGE198

TP_SLOTX24_RSVD63 @BASEBOARD_FAB2_LIB.BASEBOARD_FAB2(SCH_1):TP_SLOTX24_RSVD63
  J8G1   63   IO63 SCONN200_H68296001_SM-CONN,H68A   I258 @BASEBOARD_FAB2_LIB.BASEBOARD_FAB2(SCH_1):PAGE108

TP_SLOTX24_RSVD66 @BASEBOARD_FAB2_LIB.BASEBOARD_FAB2(SCH_1):TP_SLOTX24_RSVD66
  J8G1   66   IO66 SCONN200_H68296001_SM-CONN,H68A   I258 @BASEBOARD_FAB2_LIB.BASEBOARD_FAB2(SCH_1):PAGE108

TP_SLP_LAN_N @BASEBOARD_FAB2_LIB.BASEBOARD_FAB2(SCH_1):TP_SLP_LAN_N
  U7C1  M15 SLP_GBE_N LBG_CORE_QAT_EXT_D_BGA1-IC,H91A    I73 @BASEBOARD_FAB2_LIB.BASEBOARD_FAB2(SCH_1):PAGE118

TP_SMB_CPU1_CD_HFI0_I2CCLK @BASEBOARD_FAB2_LIB.BASEBOARD_FAB2(SCH_1):TP_SMB_CPU1_CD_HFI0_I2CCLK
  U2D1 BN22 CD_HFI0_I2CCLK SKX_EXT_B_BGA1-IC,TBD    I23 @BASEBOARD_FAB2_LIB.BASEBOARD_FAB2(SCH_1):PAGE63

TP_SMB_CPU1_CD_HFI0_I2CDAT @BASEBOARD_FAB2_LIB.BASEBOARD_FAB2(SCH_1):TP_SMB_CPU1_CD_HFI0_I2CDAT
  U2D1 BP23 CD_HFI0_I2CDAT SKX_EXT_B_BGA1-IC,TBD    I23 @BASEBOARD_FAB2_LIB.BASEBOARD_FAB2(SCH_1):PAGE63

TP_SMB_DDR_ABC_EN @BASEBOARD_FAB2_LIB.BASEBOARD_FAB2(SCH_1):TP_SMB_DDR_ABC_EN
  U6F1    5     EN PCA9617_SSOP-IC,G81764-001-GNDA    I15 @BASEBOARD_FAB2_LIB.BASEBOARD_FAB2(SCH_1):PAGE99

TP_SMB_DDR_DEF_EN @BASEBOARD_FAB2_LIB.BASEBOARD_FAB2(SCH_1):TP_SMB_DDR_DEF_EN
  U7E1    5     EN PCA9617_SSOP-IC,G81764-001-GNDA    I61 @BASEBOARD_FAB2_LIB.BASEBOARD_FAB2(SCH_1):PAGE99

TP_SMB_DDR_GHJ_EN @BASEBOARD_FAB2_LIB.BASEBOARD_FAB2(SCH_1):TP_SMB_DDR_GHJ_EN
  U4G1    5     EN PCA9617_SSOP-IC,G81764-001-GNDA    I63 @BASEBOARD_FAB2_LIB.BASEBOARD_FAB2(SCH_1):PAGE99

TP_SMB_DDR_KLM_EN @BASEBOARD_FAB2_LIB.BASEBOARD_FAB2(SCH_1):TP_SMB_DDR_KLM_EN
  U3B1    5     EN PCA9617_SSOP-IC,G81764-001-GNDA    I75 @BASEBOARD_FAB2_LIB.BASEBOARD_FAB2(SCH_1):PAGE99

TP_SMB_PEHPCPU0_EN @BASEBOARD_FAB2_LIB.BASEBOARD_FAB2(SCH_1):TP_SMB_PEHPCPU0_EN
  U1W2    5     EN TCA9517DGKR-GP_DISCRET-G8-TCA9A    I49 @BASEBOARD_FAB2_LIB.BASEBOARD_FAB2(SCH_1):PAGE248

TP_SMB_PEHPCPU1_EN @BASEBOARD_FAB2_LIB.BASEBOARD_FAB2(SCH_1):TP_SMB_PEHPCPU1_EN
  U1B2    5     EN TCA9517DGKR-GP_DISCRET-G8-TCA9A    I28 @BASEBOARD_FAB2_LIB.BASEBOARD_FAB2(SCH_1):PAGE163

TP_SPI_0_0 @BASEBOARD_FAB2_LIB.BASEBOARD_FAB2(SCH_1):TP_SPI_0_0
  U7F1   14  NC<0> W25Q256_XSOI-IC,H25002-001   I146 @BASEBOARD_FAB2_LIB.BASEBOARD_FAB2(SCH_1):PAGE153

TP_SPI_0_1 @BASEBOARD_FAB2_LIB.BASEBOARD_FAB2(SCH_1):TP_SPI_0_1
  U7F1   13  NC<1> W25Q256_XSOI-IC,H25002-001   I146 @BASEBOARD_FAB2_LIB.BASEBOARD_FAB2(SCH_1):PAGE153

TP_SPI_0_2 @BASEBOARD_FAB2_LIB.BASEBOARD_FAB2(SCH_1):TP_SPI_0_2
  U7F1   12  NC<2> W25Q256_XSOI-IC,H25002-001   I146 @BASEBOARD_FAB2_LIB.BASEBOARD_FAB2(SCH_1):PAGE153

TP_SPI_0_3 @BASEBOARD_FAB2_LIB.BASEBOARD_FAB2(SCH_1):TP_SPI_0_3
  U7F1   11  NC<3> W25Q256_XSOI-IC,H25002-001   I146 @BASEBOARD_FAB2_LIB.BASEBOARD_FAB2(SCH_1):PAGE153

TP_SPI_0_4 @BASEBOARD_FAB2_LIB.BASEBOARD_FAB2(SCH_1):TP_SPI_0_4
  U7F1    6  NC<4> W25Q256_XSOI-IC,H25002-001   I146 @BASEBOARD_FAB2_LIB.BASEBOARD_FAB2(SCH_1):PAGE153

TP_SPI_0_5 @BASEBOARD_FAB2_LIB.BASEBOARD_FAB2(SCH_1):TP_SPI_0_5
  U7F1    5  NC<5> W25Q256_XSOI-IC,H25002-001   I146 @BASEBOARD_FAB2_LIB.BASEBOARD_FAB2(SCH_1):PAGE153

TP_SPI_0_6 @BASEBOARD_FAB2_LIB.BASEBOARD_FAB2(SCH_1):TP_SPI_0_6
  U7F1    4  NC<6> W25Q256_XSOI-IC,H25002-001   I146 @BASEBOARD_FAB2_LIB.BASEBOARD_FAB2(SCH_1):PAGE153

TP_SPI_1_0 @BASEBOARD_FAB2_LIB.BASEBOARD_FAB2(SCH_1):TP_SPI_1_0
  U3T1   14  NC#14 W25Q256FVFIG-GP_MEMORY-G4-W25QA   I185 @BASEBOARD_FAB2_LIB.BASEBOARD_FAB2(SCH_1):PAGE153

TP_SPI_1_1 @BASEBOARD_FAB2_LIB.BASEBOARD_FAB2(SCH_1):TP_SPI_1_1
  U3T1   13  NC#13 W25Q256FVFIG-GP_MEMORY-G4-W25QA   I185 @BASEBOARD_FAB2_LIB.BASEBOARD_FAB2(SCH_1):PAGE153

TP_SPI_1_2 @BASEBOARD_FAB2_LIB.BASEBOARD_FAB2(SCH_1):TP_SPI_1_2
  U3T1   12  NC#12 W25Q256FVFIG-GP_MEMORY-G4-W25QA   I185 @BASEBOARD_FAB2_LIB.BASEBOARD_FAB2(SCH_1):PAGE153

TP_SPI_1_3 @BASEBOARD_FAB2_LIB.BASEBOARD_FAB2(SCH_1):TP_SPI_1_3
  U3T1   11  NC#11 W25Q256FVFIG-GP_MEMORY-G4-W25QA   I185 @BASEBOARD_FAB2_LIB.BASEBOARD_FAB2(SCH_1):PAGE153

TP_SPI_1_4 @BASEBOARD_FAB2_LIB.BASEBOARD_FAB2(SCH_1):TP_SPI_1_4
  U3T1    6   NC#6 W25Q256FVFIG-GP_MEMORY-G4-W25QA   I185 @BASEBOARD_FAB2_LIB.BASEBOARD_FAB2(SCH_1):PAGE153

TP_SPI_1_5 @BASEBOARD_FAB2_LIB.BASEBOARD_FAB2(SCH_1):TP_SPI_1_5
  U3T1    5   NC#5 W25Q256FVFIG-GP_MEMORY-G4-W25QA   I185 @BASEBOARD_FAB2_LIB.BASEBOARD_FAB2(SCH_1):PAGE153

TP_SPI_1_6 @BASEBOARD_FAB2_LIB.BASEBOARD_FAB2(SCH_1):TP_SPI_1_6
  U3T1    4   NC#4 W25Q256FVFIG-GP_MEMORY-G4-W25QA   I185 @BASEBOARD_FAB2_LIB.BASEBOARD_FAB2(SCH_1):PAGE153

TP_SPI_2_0 @BASEBOARD_FAB2_LIB.BASEBOARD_FAB2(SCH_1):TP_SPI_2_0
  U8F2    4  NC<0> W25Q128_SKT16-IC,H12709-001    I32 @BASEBOARD_FAB2_LIB.BASEBOARD_FAB2(SCH_1):PAGE162

TP_SPI_2_1 @BASEBOARD_FAB2_LIB.BASEBOARD_FAB2(SCH_1):TP_SPI_2_1
  U8F2    5  NC<1> W25Q128_SKT16-IC,H12709-001    I32 @BASEBOARD_FAB2_LIB.BASEBOARD_FAB2(SCH_1):PAGE162

TP_SPI_2_2 @BASEBOARD_FAB2_LIB.BASEBOARD_FAB2(SCH_1):TP_SPI_2_2
  U8F2    6  NC<2> W25Q128_SKT16-IC,H12709-001    I32 @BASEBOARD_FAB2_LIB.BASEBOARD_FAB2(SCH_1):PAGE162

TP_SPI_2_3 @BASEBOARD_FAB2_LIB.BASEBOARD_FAB2(SCH_1):TP_SPI_2_3
  U8F2   11  NC<3> W25Q128_SKT16-IC,H12709-001    I32 @BASEBOARD_FAB2_LIB.BASEBOARD_FAB2(SCH_1):PAGE162

TP_SPI_2_4 @BASEBOARD_FAB2_LIB.BASEBOARD_FAB2(SCH_1):TP_SPI_2_4
  U8F2   12  NC<4> W25Q128_SKT16-IC,H12709-001    I32 @BASEBOARD_FAB2_LIB.BASEBOARD_FAB2(SCH_1):PAGE162

TP_SPI_2_5 @BASEBOARD_FAB2_LIB.BASEBOARD_FAB2(SCH_1):TP_SPI_2_5
  U8F2   13  NC<5> W25Q128_SKT16-IC,H12709-001    I32 @BASEBOARD_FAB2_LIB.BASEBOARD_FAB2(SCH_1):PAGE162

TP_SPI_2_6 @BASEBOARD_FAB2_LIB.BASEBOARD_FAB2(SCH_1):TP_SPI_2_6
  U8F2   14  NC<6> W25Q128_SKT16-IC,H12709-001    I32 @BASEBOARD_FAB2_LIB.BASEBOARD_FAB2(SCH_1):PAGE162

TP_SPI_PCH_CS1_R1_N @BASEBOARD_FAB2_LIB.BASEBOARD_FAB2(SCH_1):TP_SPI_PCH_CS1_R1_N
  U7C1   G7 SPI0_FLASH_CS1_N LBG_CORE_QAT_EXT_D_BGA1-IC,H91A    I34 @BASEBOARD_FAB2_LIB.BASEBOARD_FAB2(SCH_1):PAGE121

TP_SPI_SWITCH1_10 @BASEBOARD_FAB2_LIB.BASEBOARD_FAB2(SCH_1):TP_SPI_SWITCH1_10
  U2T1   10    IC1 PI3B3257A_TSSOPLF-IC,E16801-001    I75 @BASEBOARD_FAB2_LIB.BASEBOARD_FAB2(SCH_1):PAGE154

TP_SPI_SWITCH1_11 @BASEBOARD_FAB2_LIB.BASEBOARD_FAB2(SCH_1):TP_SPI_SWITCH1_11
  U2T1   11    IC0 PI3B3257A_TSSOPLF-IC,E16801-001    I75 @BASEBOARD_FAB2_LIB.BASEBOARD_FAB2(SCH_1):PAGE154

TP_SPI_SWITCH1_12 @BASEBOARD_FAB2_LIB.BASEBOARD_FAB2(SCH_1):TP_SPI_SWITCH1_12
  U2T1   12     YD PI3B3257A_TSSOPLF-IC,E16801-001    I75 @BASEBOARD_FAB2_LIB.BASEBOARD_FAB2(SCH_1):PAGE154

TP_SPI_SWITCH1_13 @BASEBOARD_FAB2_LIB.BASEBOARD_FAB2(SCH_1):TP_SPI_SWITCH1_13
  U2T1   13    ID1 PI3B3257A_TSSOPLF-IC,E16801-001    I75 @BASEBOARD_FAB2_LIB.BASEBOARD_FAB2(SCH_1):PAGE154

TP_SPI_SWITCH1_14 @BASEBOARD_FAB2_LIB.BASEBOARD_FAB2(SCH_1):TP_SPI_SWITCH1_14
  U2T1   14    ID0 PI3B3257A_TSSOPLF-IC,E16801-001    I75 @BASEBOARD_FAB2_LIB.BASEBOARD_FAB2(SCH_1):PAGE154

TP_SPI_SWITCH1_3 @BASEBOARD_FAB2_LIB.BASEBOARD_FAB2(SCH_1):TP_SPI_SWITCH1_3
  U2T1    3    IA1 PI3B3257A_TSSOPLF-IC,E16801-001    I75 @BASEBOARD_FAB2_LIB.BASEBOARD_FAB2(SCH_1):PAGE154

TP_SPI_SWITCH1_6 @BASEBOARD_FAB2_LIB.BASEBOARD_FAB2(SCH_1):TP_SPI_SWITCH1_6
  U2T1    6    IB1 PI3B3257A_TSSOPLF-IC,E16801-001    I75 @BASEBOARD_FAB2_LIB.BASEBOARD_FAB2(SCH_1):PAGE154

TP_SPI_SWITCH1_9 @BASEBOARD_FAB2_LIB.BASEBOARD_FAB2(SCH_1):TP_SPI_SWITCH1_9
  U2T1    9     YC PI3B3257A_TSSOPLF-IC,E16801-001    I75 @BASEBOARD_FAB2_LIB.BASEBOARD_FAB2(SCH_1):PAGE154

TP_SPRV_SDP0 @BASEBOARD_FAB2_LIB.BASEBOARD_FAB2(SCH_1):TP_SPRV_SDP0
 EU9E1   63   SDP0 SPRINGVILLE_SM1-IC,G47144-004    I72 @BASEBOARD_FAB2_LIB.BASEBOARD_FAB2(SCH_1):PAGE139

TP_SPRV_SDP2 @BASEBOARD_FAB2_LIB.BASEBOARD_FAB2(SCH_1):TP_SPRV_SDP2
 EU9E1   62   SDP2 SPRINGVILLE_SM1-IC,G47144-004    I72 @BASEBOARD_FAB2_LIB.BASEBOARD_FAB2(SCH_1):PAGE139

TP_SPRV_SDP3 @BASEBOARD_FAB2_LIB.BASEBOARD_FAB2(SCH_1):TP_SPRV_SDP3
 EU9E1   60   SDP3 SPRINGVILLE_SM1-IC,G47144-004    I72 @BASEBOARD_FAB2_LIB.BASEBOARD_FAB2(SCH_1):PAGE139

TP_TPM_SPI_0 @BASEBOARD_FAB2_LIB.BASEBOARD_FAB2(SCH_1):TP_TPM_SPI_0
 UN8F2   14  NC<0> W25Q256_XSOI-IC,H25002-001    I17 @BASEBOARD_FAB2_LIB.BASEBOARD_FAB2(SCH_1):PAGE246

TP_TPM_SPI_1 @BASEBOARD_FAB2_LIB.BASEBOARD_FAB2(SCH_1):TP_TPM_SPI_1
 UN8F2   13  NC<1> W25Q256_XSOI-IC,H25002-001    I17 @BASEBOARD_FAB2_LIB.BASEBOARD_FAB2(SCH_1):PAGE246

TP_TPM_SPI_2 @BASEBOARD_FAB2_LIB.BASEBOARD_FAB2(SCH_1):TP_TPM_SPI_2
 UN8F2   12  NC<2> W25Q256_XSOI-IC,H25002-001    I17 @BASEBOARD_FAB2_LIB.BASEBOARD_FAB2(SCH_1):PAGE246

TP_TPM_SPI_3 @BASEBOARD_FAB2_LIB.BASEBOARD_FAB2(SCH_1):TP_TPM_SPI_3
 UN8F2   11  NC<3> W25Q256_XSOI-IC,H25002-001    I17 @BASEBOARD_FAB2_LIB.BASEBOARD_FAB2(SCH_1):PAGE246

TP_TPM_SPI_4 @BASEBOARD_FAB2_LIB.BASEBOARD_FAB2(SCH_1):TP_TPM_SPI_4
 UN8F2    6  NC<4> W25Q256_XSOI-IC,H25002-001    I17 @BASEBOARD_FAB2_LIB.BASEBOARD_FAB2(SCH_1):PAGE246

TP_TPM_SPI_5 @BASEBOARD_FAB2_LIB.BASEBOARD_FAB2(SCH_1):TP_TPM_SPI_5
 UN8F2    5  NC<5> W25Q256_XSOI-IC,H25002-001    I17 @BASEBOARD_FAB2_LIB.BASEBOARD_FAB2(SCH_1):PAGE246

TP_TPM_SPI_6 @BASEBOARD_FAB2_LIB.BASEBOARD_FAB2(SCH_1):TP_TPM_SPI_6
 UN8F2    4  NC<6> W25Q256_XSOI-IC,H25002-001    I17 @BASEBOARD_FAB2_LIB.BASEBOARD_FAB2(SCH_1):PAGE246

TP_USB2_P03_DN @BASEBOARD_FAB2_LIB.BASEBOARD_FAB2(SCH_1):TP_USB2_P03_DN
  U7C1 CA59 USB2N_3 LBG_CORE_QAT_EXT_D_BGA1-IC,H91A    I74 @BASEBOARD_FAB2_LIB.BASEBOARD_FAB2(SCH_1):PAGE115

TP_USB2_P03_DP @BASEBOARD_FAB2_LIB.BASEBOARD_FAB2(SCH_1):TP_USB2_P03_DP
  U7C1 BW59 USB2P_3 LBG_CORE_QAT_EXT_D_BGA1-IC,H91A    I74 @BASEBOARD_FAB2_LIB.BASEBOARD_FAB2(SCH_1):PAGE115

TP_USB2_P06_DN @BASEBOARD_FAB2_LIB.BASEBOARD_FAB2(SCH_1):TP_USB2_P06_DN
  U7C1 CA63 USB2N_6 LBG_CORE_QAT_EXT_D_BGA1-IC,H91A    I74 @BASEBOARD_FAB2_LIB.BASEBOARD_FAB2(SCH_1):PAGE115

TP_USB2_P06_DP @BASEBOARD_FAB2_LIB.BASEBOARD_FAB2(SCH_1):TP_USB2_P06_DP
  U7C1 BW63 USB2P_6 LBG_CORE_QAT_EXT_D_BGA1-IC,H91A    I74 @BASEBOARD_FAB2_LIB.BASEBOARD_FAB2(SCH_1):PAGE115

TP_USB2_P07_DN @BASEBOARD_FAB2_LIB.BASEBOARD_FAB2(SCH_1):TP_USB2_P07_DN
  U7C1 CA57 USB2N_7 LBG_CORE_QAT_EXT_D_BGA1-IC,H91A    I74 @BASEBOARD_FAB2_LIB.BASEBOARD_FAB2(SCH_1):PAGE115

TP_USB2_P07_DP @BASEBOARD_FAB2_LIB.BASEBOARD_FAB2(SCH_1):TP_USB2_P07_DP
  U7C1 BW57 USB2P_7 LBG_CORE_QAT_EXT_D_BGA1-IC,H91A    I74 @BASEBOARD_FAB2_LIB.BASEBOARD_FAB2(SCH_1):PAGE115

TP_USB2_P10_DN @BASEBOARD_FAB2_LIB.BASEBOARD_FAB2(SCH_1):TP_USB2_P10_DN
  U7C1 BW65 USB2N_10 LBG_CORE_QAT_EXT_D_BGA1-IC,H91A    I74 @BASEBOARD_FAB2_LIB.BASEBOARD_FAB2(SCH_1):PAGE115

TP_USB2_P10_DP @BASEBOARD_FAB2_LIB.BASEBOARD_FAB2(SCH_1):TP_USB2_P10_DP
  U7C1 BU65 USB2P_10 LBG_CORE_QAT_EXT_D_BGA1-IC,H91A    I74 @BASEBOARD_FAB2_LIB.BASEBOARD_FAB2(SCH_1):PAGE115

TP_USB2_P11_DN @BASEBOARD_FAB2_LIB.BASEBOARD_FAB2(SCH_1):TP_USB2_P11_DN
  U7C1 CA54 USB2N_11 LBG_CORE_QAT_EXT_D_BGA1-IC,H91A    I74 @BASEBOARD_FAB2_LIB.BASEBOARD_FAB2(SCH_1):PAGE115

TP_USB2_P11_DP @BASEBOARD_FAB2_LIB.BASEBOARD_FAB2(SCH_1):TP_USB2_P11_DP
  U7C1 BW54 USB2P_11 LBG_CORE_QAT_EXT_D_BGA1-IC,H91A    I74 @BASEBOARD_FAB2_LIB.BASEBOARD_FAB2(SCH_1):PAGE115

TP_USB2_P12_DN @BASEBOARD_FAB2_LIB.BASEBOARD_FAB2(SCH_1):TP_USB2_P12_DN
  U7C1 BW67 USB2N_12 LBG_CORE_QAT_EXT_D_BGA1-IC,H91A    I74 @BASEBOARD_FAB2_LIB.BASEBOARD_FAB2(SCH_1):PAGE115

TP_USB2_P12_DP @BASEBOARD_FAB2_LIB.BASEBOARD_FAB2(SCH_1):TP_USB2_P12_DP
  U7C1 BV66 USB2P_12 LBG_CORE_QAT_EXT_D_BGA1-IC,H91A    I74 @BASEBOARD_FAB2_LIB.BASEBOARD_FAB2(SCH_1):PAGE115

TP_USB2_P13_DN @BASEBOARD_FAB2_LIB.BASEBOARD_FAB2(SCH_1):TP_USB2_P13_DN
  U7C1 BY53 USB2N_13 LBG_CORE_QAT_EXT_D_BGA1-IC,H91A    I74 @BASEBOARD_FAB2_LIB.BASEBOARD_FAB2(SCH_1):PAGE115

TP_USB2_P13_DP @BASEBOARD_FAB2_LIB.BASEBOARD_FAB2(SCH_1):TP_USB2_P13_DP
  U7C1 BV53 USB2P_13 LBG_CORE_QAT_EXT_D_BGA1-IC,H91A    I74 @BASEBOARD_FAB2_LIB.BASEBOARD_FAB2(SCH_1):PAGE115

TP_USB2_P14_DN @BASEBOARD_FAB2_LIB.BASEBOARD_FAB2(SCH_1):TP_USB2_P14_DN
  U7C1 BW68 USB2N_14 LBG_CORE_QAT_EXT_D_BGA1-IC,H91A    I74 @BASEBOARD_FAB2_LIB.BASEBOARD_FAB2(SCH_1):PAGE115

TP_USB2_P14_DP @BASEBOARD_FAB2_LIB.BASEBOARD_FAB2(SCH_1):TP_USB2_P14_DP
  U7C1 BU67 USB2P_14 LBG_CORE_QAT_EXT_D_BGA1-IC,H91A    I74 @BASEBOARD_FAB2_LIB.BASEBOARD_FAB2(SCH_1):PAGE115

TP_USB2_P8_DN @BASEBOARD_FAB2_LIB.BASEBOARD_FAB2(SCH_1):TP_USB2_P8_DN
  U7C1 BY64 USB2N_8 LBG_CORE_QAT_EXT_D_BGA1-IC,H91A    I74 @BASEBOARD_FAB2_LIB.BASEBOARD_FAB2(SCH_1):PAGE115

TP_USB2_P8_DP @BASEBOARD_FAB2_LIB.BASEBOARD_FAB2(SCH_1):TP_USB2_P8_DP
  U7C1 BV64 USB2P_8 LBG_CORE_QAT_EXT_D_BGA1-IC,H91A    I74 @BASEBOARD_FAB2_LIB.BASEBOARD_FAB2(SCH_1):PAGE115

TP_USB2_P9_DN @BASEBOARD_FAB2_LIB.BASEBOARD_FAB2(SCH_1):TP_USB2_P9_DN
  U7C1 BY55 USB2N_9 LBG_CORE_QAT_EXT_D_BGA1-IC,H91A    I74 @BASEBOARD_FAB2_LIB.BASEBOARD_FAB2(SCH_1):PAGE115

TP_USB2_P9_DP @BASEBOARD_FAB2_LIB.BASEBOARD_FAB2(SCH_1):TP_USB2_P9_DP
  U7C1 BV55 USB2P_9 LBG_CORE_QAT_EXT_D_BGA1-IC,H91A    I74 @BASEBOARD_FAB2_LIB.BASEBOARD_FAB2(SCH_1):PAGE115

TP_USB3_P02_RXN @BASEBOARD_FAB2_LIB.BASEBOARD_FAB2(SCH_1):TP_USB3_P02_RXN
  U7C1 BJ72 USB3_2_RXN LBG_CORE_QAT_EXT_D_BGA1-IC,H91A    I74 @BASEBOARD_FAB2_LIB.BASEBOARD_FAB2(SCH_1):PAGE115

TP_USB3_P02_RXP @BASEBOARD_FAB2_LIB.BASEBOARD_FAB2(SCH_1):TP_USB3_P02_RXP
  U7C1 BJ70 USB3_2_RXP LBG_CORE_QAT_EXT_D_BGA1-IC,H91A    I74 @BASEBOARD_FAB2_LIB.BASEBOARD_FAB2(SCH_1):PAGE115

TP_USB3_P02_TXN @BASEBOARD_FAB2_LIB.BASEBOARD_FAB2(SCH_1):TP_USB3_P02_TXN
  U7C1 BL56 USB3_2_TXN LBG_CORE_QAT_EXT_D_BGA1-IC,H91A    I74 @BASEBOARD_FAB2_LIB.BASEBOARD_FAB2(SCH_1):PAGE115

TP_USB3_P02_TXP @BASEBOARD_FAB2_LIB.BASEBOARD_FAB2(SCH_1):TP_USB3_P02_TXP
  U7C1 BJ56 USB3_2_TXP LBG_CORE_QAT_EXT_D_BGA1-IC,H91A    I74 @BASEBOARD_FAB2_LIB.BASEBOARD_FAB2(SCH_1):PAGE115

TP_USB3_P03_RXN @BASEBOARD_FAB2_LIB.BASEBOARD_FAB2(SCH_1):TP_USB3_P03_RXN
  U7C1 BH71 USB3_3_RXN LBG_CORE_QAT_EXT_D_BGA1-IC,H91A    I74 @BASEBOARD_FAB2_LIB.BASEBOARD_FAB2(SCH_1):PAGE115

TP_USB3_P03_RXP @BASEBOARD_FAB2_LIB.BASEBOARD_FAB2(SCH_1):TP_USB3_P03_RXP
  U7C1 BH69 USB3_3_RXP LBG_CORE_QAT_EXT_D_BGA1-IC,H91A    I74 @BASEBOARD_FAB2_LIB.BASEBOARD_FAB2(SCH_1):PAGE115

TP_USB3_P03_TXN @BASEBOARD_FAB2_LIB.BASEBOARD_FAB2(SCH_1):TP_USB3_P03_TXN
  U7C1 BM54 USB3_3_TXN LBG_CORE_QAT_EXT_D_BGA1-IC,H91A    I74 @BASEBOARD_FAB2_LIB.BASEBOARD_FAB2(SCH_1):PAGE115

TP_USB3_P03_TXP @BASEBOARD_FAB2_LIB.BASEBOARD_FAB2(SCH_1):TP_USB3_P03_TXP
  U7C1 BN56 USB3_3_TXP LBG_CORE_QAT_EXT_D_BGA1-IC,H91A    I74 @BASEBOARD_FAB2_LIB.BASEBOARD_FAB2(SCH_1):PAGE115

TP_USB3_P04_RXN @BASEBOARD_FAB2_LIB.BASEBOARD_FAB2(SCH_1):TP_USB3_P04_RXN
  U7C1 BF72 USB3_4_RXN LBG_CORE_QAT_EXT_D_BGA1-IC,H91A    I74 @BASEBOARD_FAB2_LIB.BASEBOARD_FAB2(SCH_1):PAGE115

TP_USB3_P04_RXP @BASEBOARD_FAB2_LIB.BASEBOARD_FAB2(SCH_1):TP_USB3_P04_RXP
  U7C1 BF70 USB3_4_RXP LBG_CORE_QAT_EXT_D_BGA1-IC,H91A    I74 @BASEBOARD_FAB2_LIB.BASEBOARD_FAB2(SCH_1):PAGE115

TP_USB3_P04_TXN @BASEBOARD_FAB2_LIB.BASEBOARD_FAB2(SCH_1):TP_USB3_P04_TXN
  U7C1 BH58 USB3_4_TXN LBG_CORE_QAT_EXT_D_BGA1-IC,H91A    I74 @BASEBOARD_FAB2_LIB.BASEBOARD_FAB2(SCH_1):PAGE115

TP_USB3_P04_TXP @BASEBOARD_FAB2_LIB.BASEBOARD_FAB2(SCH_1):TP_USB3_P04_TXP
  U7C1 BG56 USB3_4_TXP LBG_CORE_QAT_EXT_D_BGA1-IC,H91A    I74 @BASEBOARD_FAB2_LIB.BASEBOARD_FAB2(SCH_1):PAGE115

TP_USB3_P05_RXN @BASEBOARD_FAB2_LIB.BASEBOARD_FAB2(SCH_1):TP_USB3_P05_RXN
  U7C1 BE71 USB3_5_RXN LBG_CORE_QAT_EXT_D_BGA1-IC,H91A    I74 @BASEBOARD_FAB2_LIB.BASEBOARD_FAB2(SCH_1):PAGE115

TP_USB3_P05_RXP @BASEBOARD_FAB2_LIB.BASEBOARD_FAB2(SCH_1):TP_USB3_P05_RXP
  U7C1 BE69 USB3_5_RXP LBG_CORE_QAT_EXT_D_BGA1-IC,H91A    I74 @BASEBOARD_FAB2_LIB.BASEBOARD_FAB2(SCH_1):PAGE115

TP_USB3_P05_TXN @BASEBOARD_FAB2_LIB.BASEBOARD_FAB2(SCH_1):TP_USB3_P05_TXN
  U7C1 BK58 USB3_5_TXN LBG_CORE_QAT_EXT_D_BGA1-IC,H91A    I74 @BASEBOARD_FAB2_LIB.BASEBOARD_FAB2(SCH_1):PAGE115

TP_USB3_P05_TXP @BASEBOARD_FAB2_LIB.BASEBOARD_FAB2(SCH_1):TP_USB3_P05_TXP
  U7C1 BJ59 USB3_5_TXP LBG_CORE_QAT_EXT_D_BGA1-IC,H91A    I74 @BASEBOARD_FAB2_LIB.BASEBOARD_FAB2(SCH_1):PAGE115

TP_USB3_P06_RXN @BASEBOARD_FAB2_LIB.BASEBOARD_FAB2(SCH_1):TP_USB3_P06_RXN
  U7C1 BD72 USB3_6_RXN LBG_CORE_QAT_EXT_D_BGA1-IC,H91A    I74 @BASEBOARD_FAB2_LIB.BASEBOARD_FAB2(SCH_1):PAGE115

TP_USB3_P06_RXP @BASEBOARD_FAB2_LIB.BASEBOARD_FAB2(SCH_1):TP_USB3_P06_RXP
  U7C1 BD70 USB3_6_RXP LBG_CORE_QAT_EXT_D_BGA1-IC,H91A    I74 @BASEBOARD_FAB2_LIB.BASEBOARD_FAB2(SCH_1):PAGE115

TP_USB3_P06_TXN @BASEBOARD_FAB2_LIB.BASEBOARD_FAB2(SCH_1):TP_USB3_P06_TXN
  U7C1 BL59 USB3_6_TXN LBG_CORE_QAT_EXT_D_BGA1-IC,H91A    I74 @BASEBOARD_FAB2_LIB.BASEBOARD_FAB2(SCH_1):PAGE115

TP_USB3_P06_TXP @BASEBOARD_FAB2_LIB.BASEBOARD_FAB2(SCH_1):TP_USB3_P06_TXP
  U7C1 BM61 USB3_6_TXP LBG_CORE_QAT_EXT_D_BGA1-IC,H91A    I74 @BASEBOARD_FAB2_LIB.BASEBOARD_FAB2(SCH_1):PAGE115

TP_USB_ESD_AC2 @BASEBOARD_FAB2_LIB.BASEBOARD_FAB2(SCH_1):TP_USB_ESD_AC2
 CR1M2    4    AC2 DIODEAC_DUAL_ARRAY_SM9-ESD3V3UA    I98 @BASEBOARD_FAB2_LIB.BASEBOARD_FAB2(SCH_1):PAGE176

TP_USB_ESD_AC3 @BASEBOARD_FAB2_LIB.BASEBOARD_FAB2(SCH_1):TP_USB_ESD_AC3
 CR1M2    5    AC3 DIODEAC_DUAL_ARRAY_SM9-ESD3V3UA    I98 @BASEBOARD_FAB2_LIB.BASEBOARD_FAB2(SCH_1):PAGE176

TP_USB_ESD_OUT2 @BASEBOARD_FAB2_LIB.BASEBOARD_FAB2(SCH_1):TP_USB_ESD_OUT2
 CR1M2    7   OUT2 DIODEAC_DUAL_ARRAY_SM9-ESD3V3UA    I98 @BASEBOARD_FAB2_LIB.BASEBOARD_FAB2(SCH_1):PAGE176

TP_USB_ESD_OUT3 @BASEBOARD_FAB2_LIB.BASEBOARD_FAB2(SCH_1):TP_USB_ESD_OUT3
 CR1M2    6   OUT3 DIODEAC_DUAL_ARRAY_SM9-ESD3V3UA    I98 @BASEBOARD_FAB2_LIB.BASEBOARD_FAB2(SCH_1):PAGE176

TP_XDP_CPU0_OBSDATA_A0_MBP2_N @BASEBOARD_FAB2_LIB.BASEBOARD_FAB2(SCH_1):TP_XDP_CPU0_OBSDATA_A0_MBP2_N
  U5D1 AG10 BPM_N<2> SKX_EXT_B_BGA1-IC,TBD   I259 @BASEBOARD_FAB2_LIB.BASEBOARD_FAB2(SCH_1):PAGE21

TP_XDP_CPU0_OBSDATA_A1_MBP3_N @BASEBOARD_FAB2_LIB.BASEBOARD_FAB2(SCH_1):TP_XDP_CPU0_OBSDATA_A1_MBP3_N
  U5D1 AF11 BPM_N<3> SKX_EXT_B_BGA1-IC,TBD   I259 @BASEBOARD_FAB2_LIB.BASEBOARD_FAB2(SCH_1):PAGE21

TP_XDP_CPU0_OBSDATA_A2_MBP4_N @BASEBOARD_FAB2_LIB.BASEBOARD_FAB2(SCH_1):TP_XDP_CPU0_OBSDATA_A2_MBP4_N
  U5D1 AA12 BPM_N<4> SKX_EXT_B_BGA1-IC,TBD   I259 @BASEBOARD_FAB2_LIB.BASEBOARD_FAB2(SCH_1):PAGE21

TP_XDP_CPU0_OBSDATA_A3_MBP5_N @BASEBOARD_FAB2_LIB.BASEBOARD_FAB2(SCH_1):TP_XDP_CPU0_OBSDATA_A3_MBP5_N
  U5D1  Y11 BPM_N<5> SKX_EXT_B_BGA1-IC,TBD   I259 @BASEBOARD_FAB2_LIB.BASEBOARD_FAB2(SCH_1):PAGE21

TP_XDP_CPU1_OBSDATA_B0_MBP2_N @BASEBOARD_FAB2_LIB.BASEBOARD_FAB2(SCH_1):TP_XDP_CPU1_OBSDATA_B0_MBP2_N
  U2D1 AG10 BPM_N<2> SKX_EXT_B_BGA1-IC,TBD   I172 @BASEBOARD_FAB2_LIB.BASEBOARD_FAB2(SCH_1):PAGE55

TP_XDP_CPU1_OBSDATA_B1_MBP3_N @BASEBOARD_FAB2_LIB.BASEBOARD_FAB2(SCH_1):TP_XDP_CPU1_OBSDATA_B1_MBP3_N
  U2D1 AF11 BPM_N<3> SKX_EXT_B_BGA1-IC,TBD   I172 @BASEBOARD_FAB2_LIB.BASEBOARD_FAB2(SCH_1):PAGE55

TP_XDP_CPU1_OBSDATA_B2_MBP4_N @BASEBOARD_FAB2_LIB.BASEBOARD_FAB2(SCH_1):TP_XDP_CPU1_OBSDATA_B2_MBP4_N
  U2D1 AA12 BPM_N<4> SKX_EXT_B_BGA1-IC,TBD   I172 @BASEBOARD_FAB2_LIB.BASEBOARD_FAB2(SCH_1):PAGE55

TP_XDP_CPU1_OBSDATA_B3_MBP5_N @BASEBOARD_FAB2_LIB.BASEBOARD_FAB2(SCH_1):TP_XDP_CPU1_OBSDATA_B3_MBP5_N
  U2D1  Y11 BPM_N<5> SKX_EXT_B_BGA1-IC,TBD   I172 @BASEBOARD_FAB2_LIB.BASEBOARD_FAB2(SCH_1):PAGE55

TP_XDP_CPU_OBSDATA_C0 @BASEBOARD_FAB2_LIB.BASEBOARD_FAB2(SCH_1):TP_XDP_CPU_OBSDATA_C0
  J9A3   10   IO10 SCONN60_C21100002_SMLF-CONN,C2A    I26 @BASEBOARD_FAB2_LIB.BASEBOARD_FAB2(SCH_1):PAGE111

TP_XDP_CPU_OBSDATA_C1 @BASEBOARD_FAB2_LIB.BASEBOARD_FAB2(SCH_1):TP_XDP_CPU_OBSDATA_C1
  J9A3   12   IO12 SCONN60_C21100002_SMLF-CONN,C2A    I26 @BASEBOARD_FAB2_LIB.BASEBOARD_FAB2(SCH_1):PAGE111

TP_XDP_CPU_OBSDATA_C2 @BASEBOARD_FAB2_LIB.BASEBOARD_FAB2(SCH_1):TP_XDP_CPU_OBSDATA_C2
  J9A3   16   IO16 SCONN60_C21100002_SMLF-CONN,C2A    I26 @BASEBOARD_FAB2_LIB.BASEBOARD_FAB2(SCH_1):PAGE111

TP_XDP_CPU_OBSDATA_C3 @BASEBOARD_FAB2_LIB.BASEBOARD_FAB2(SCH_1):TP_XDP_CPU_OBSDATA_C3
  J9A3   18   IO18 SCONN60_C21100002_SMLF-CONN,C2A    I26 @BASEBOARD_FAB2_LIB.BASEBOARD_FAB2(SCH_1):PAGE111

TP_XDP_CPU_OBSDATA_D0 @BASEBOARD_FAB2_LIB.BASEBOARD_FAB2(SCH_1):TP_XDP_CPU_OBSDATA_D0
  J9A3   28   IO28 SCONN60_C21100002_SMLF-CONN,C2A    I26 @BASEBOARD_FAB2_LIB.BASEBOARD_FAB2(SCH_1):PAGE111

TP_XDP_CPU_OBSDATA_D1 @BASEBOARD_FAB2_LIB.BASEBOARD_FAB2(SCH_1):TP_XDP_CPU_OBSDATA_D1
  J9A3   30   IO30 SCONN60_C21100002_SMLF-CONN,C2A    I26 @BASEBOARD_FAB2_LIB.BASEBOARD_FAB2(SCH_1):PAGE111

TP_XDP_CPU_OBSDATA_D2 @BASEBOARD_FAB2_LIB.BASEBOARD_FAB2(SCH_1):TP_XDP_CPU_OBSDATA_D2
  J9A3   34   IO34 SCONN60_C21100002_SMLF-CONN,C2A    I26 @BASEBOARD_FAB2_LIB.BASEBOARD_FAB2(SCH_1):PAGE111

TP_XDP_CPU_OBSDATA_D3 @BASEBOARD_FAB2_LIB.BASEBOARD_FAB2(SCH_1):TP_XDP_CPU_OBSDATA_D3
  J9A3   36   IO36 SCONN60_C21100002_SMLF-CONN,C2A    I26 @BASEBOARD_FAB2_LIB.BASEBOARD_FAB2(SCH_1):PAGE111

TP_XDP_CPU_OBSFN_C0 @BASEBOARD_FAB2_LIB.BASEBOARD_FAB2(SCH_1):TP_XDP_CPU_OBSFN_C0
  J9A3    4    IO4 SCONN60_C21100002_SMLF-CONN,C2A    I26 @BASEBOARD_FAB2_LIB.BASEBOARD_FAB2(SCH_1):PAGE111

TP_XDP_OBSDATA_A0 @BASEBOARD_FAB2_LIB.BASEBOARD_FAB2(SCH_1):TP_XDP_OBSDATA_A0
  J9A3    9    IO9 SCONN60_C21100002_SMLF-CONN,C2A    I26 @BASEBOARD_FAB2_LIB.BASEBOARD_FAB2(SCH_1):PAGE111

TP_XDP_OBSDATA_A1 @BASEBOARD_FAB2_LIB.BASEBOARD_FAB2(SCH_1):TP_XDP_OBSDATA_A1
  J9A3   11   IO11 SCONN60_C21100002_SMLF-CONN,C2A    I26 @BASEBOARD_FAB2_LIB.BASEBOARD_FAB2(SCH_1):PAGE111

TP_XDP_OBSDATA_A2 @BASEBOARD_FAB2_LIB.BASEBOARD_FAB2(SCH_1):TP_XDP_OBSDATA_A2
  J9A3   15   IO15 SCONN60_C21100002_SMLF-CONN,C2A    I26 @BASEBOARD_FAB2_LIB.BASEBOARD_FAB2(SCH_1):PAGE111

TP_XDP_OBSDATA_A3 @BASEBOARD_FAB2_LIB.BASEBOARD_FAB2(SCH_1):TP_XDP_OBSDATA_A3
  J9A3   17   IO17 SCONN60_C21100002_SMLF-CONN,C2A    I26 @BASEBOARD_FAB2_LIB.BASEBOARD_FAB2(SCH_1):PAGE111

TP_XDP_OBSDATA_B0 @BASEBOARD_FAB2_LIB.BASEBOARD_FAB2(SCH_1):TP_XDP_OBSDATA_B0
  J9A3   27   IO27 SCONN60_C21100002_SMLF-CONN,C2A    I26 @BASEBOARD_FAB2_LIB.BASEBOARD_FAB2(SCH_1):PAGE111

TP_XDP_OBSDATA_B1 @BASEBOARD_FAB2_LIB.BASEBOARD_FAB2(SCH_1):TP_XDP_OBSDATA_B1
  J9A3   29   IO29 SCONN60_C21100002_SMLF-CONN,C2A    I26 @BASEBOARD_FAB2_LIB.BASEBOARD_FAB2(SCH_1):PAGE111

TP_XDP_OBSDATA_B2 @BASEBOARD_FAB2_LIB.BASEBOARD_FAB2(SCH_1):TP_XDP_OBSDATA_B2
  J9A3   33   IO33 SCONN60_C21100002_SMLF-CONN,C2A    I26 @BASEBOARD_FAB2_LIB.BASEBOARD_FAB2(SCH_1):PAGE111

TP_XDP_OBSDATA_B3 @BASEBOARD_FAB2_LIB.BASEBOARD_FAB2(SCH_1):TP_XDP_OBSDATA_B3
  J9A3   35   IO35 SCONN60_C21100002_SMLF-CONN,C2A    I26 @BASEBOARD_FAB2_LIB.BASEBOARD_FAB2(SCH_1):PAGE111

TP_XDP_OBSFN_B0 @BASEBOARD_FAB2_LIB.BASEBOARD_FAB2(SCH_1):TP_XDP_OBSFN_B0
  J9A3   21   IO21 SCONN60_C21100002_SMLF-CONN,C2A    I26 @BASEBOARD_FAB2_LIB.BASEBOARD_FAB2(SCH_1):PAGE111

TP_XDP_OBSFN_B1 @BASEBOARD_FAB2_LIB.BASEBOARD_FAB2(SCH_1):TP_XDP_OBSFN_B1
  J9A3   23   IO23 SCONN60_C21100002_SMLF-CONN,C2A    I26 @BASEBOARD_FAB2_LIB.BASEBOARD_FAB2(SCH_1):PAGE111

UART_BMC_RXD5 @BASEBOARD_FAB2_LIB.BASEBOARD_FAB2(SCH_1):UART_BMC_RXD5
  U9F1    2     B1 FSA3357_SM-IC,C63273-001    I75 @BASEBOARD_FAB2_LIB.BASEBOARD_FAB2(SCH_1):PAGE158
  U8D7   J5  PL10C LCMXO2_A_256BGA-IC,H63395-001   I179 @BASEBOARD_FAB2_LIB.BASEBOARD_FAB2(SCH_1):PAGE190
 U25W4   K2   RXD5 AST2520A1-GP-GP_ASIC2-GB1-AST2A   I117 @BASEBOARD_FAB2_LIB.BASEBOARD_FAB2(SCH_1):PAGE145
 R9W34    2      B RES_0402-4.75K,1%,1/16W,CHIP,GA   I154 @BASEBOARD_FAB2_LIB.BASEBOARD_FAB2(SCH_1):PAGE158

UART_BMC_TXD5 @BASEBOARD_FAB2_LIB.BASEBOARD_FAB2(SCH_1):UART_BMC_TXD5
  U9F2    2     B1 FSA3357_SM-IC,C63273-001    I74 @BASEBOARD_FAB2_LIB.BASEBOARD_FAB2(SCH_1):PAGE158
  U8D7   K6  PL10D LCMXO2_A_256BGA-IC,H63395-001   I179 @BASEBOARD_FAB2_LIB.BASEBOARD_FAB2(SCH_1):PAGE190
 U25W4   K1   TXD5 AST2520A1-GP-GP_ASIC2-GB1-AST2A   I117 @BASEBOARD_FAB2_LIB.BASEBOARD_FAB2(SCH_1):PAGE145
R25W116    2      B RES_0402-3.32K,1%,1/16W,EMPTY,A   I189 @BASEBOARD_FAB2_LIB.BASEBOARD_FAB2(SCH_1):PAGE150
R25W156    2      B RES_0402-3.32K,1%,1/16W,EMPTY,A   I240 @BASEBOARD_FAB2_LIB.BASEBOARD_FAB2(SCH_1):PAGE150

UART_MUX_IN_R @BASEBOARD_FAB2_LIB.BASEBOARD_FAB2(SCH_1):UART_MUX_IN_R
  U9F1    7      A FSA3357_SM-IC,C63273-001    I75 @BASEBOARD_FAB2_LIB.BASEBOARD_FAB2(SCH_1):PAGE158
 R9F25    2      B RES_0402-100.0,1%,1/16W,CHIP,GA    I86 @BASEBOARD_FAB2_LIB.BASEBOARD_FAB2(SCH_1):PAGE158

UART_MUX_OUT_R @BASEBOARD_FAB2_LIB.BASEBOARD_FAB2(SCH_1):UART_MUX_OUT_R
  U9F2    7      A FSA3357_SM-IC,C63273-001    I74 @BASEBOARD_FAB2_LIB.BASEBOARD_FAB2(SCH_1):PAGE158
 R9F27    1      A RES_0402-0.0,5%,1/16W,CHIP,G21A    I91 @BASEBOARD_FAB2_LIB.BASEBOARD_FAB2(SCH_1):PAGE158

UPI_CPU0_CPU1_P0P0_DN<0> @BASEBOARD_FAB2_LIB.BASEBOARD_FAB2(SCH_1):UPI_CPU0_CPU1_P0P0_DN(0)
  U5D1  BG4 UPI0_TX_DN<19> SKX_EXT_B_BGA1-IC,TBD    I86 @BASEBOARD_FAB2_LIB.BASEBOARD_FAB2(SCH_1):PAGE33
  U2D1  AB9 UPI0_RX_DP<0> SKX_EXT_B_BGA1-IC,TBD   I132 @BASEBOARD_FAB2_LIB.BASEBOARD_FAB2(SCH_1):PAGE67

UPI_CPU0_CPU1_P0P0_DN<10> @BASEBOARD_FAB2_LIB.BASEBOARD_FAB2(SCH_1):UPI_CPU0_CPU1_P0P0_DN(10)
  U5D1  AL2 UPI0_TX_DN<9> SKX_EXT_B_BGA1-IC,TBD    I86 @BASEBOARD_FAB2_LIB.BASEBOARD_FAB2(SCH_1):PAGE33
  U2D1  AP7 UPI0_RX_DN<10> SKX_EXT_B_BGA1-IC,TBD   I132 @BASEBOARD_FAB2_LIB.BASEBOARD_FAB2(SCH_1):PAGE67

UPI_CPU0_CPU1_P0P0_DN<11> @BASEBOARD_FAB2_LIB.BASEBOARD_FAB2(SCH_1):UPI_CPU0_CPU1_P0P0_DN(11)
  U5D1  AH3 UPI0_TX_DN<8> SKX_EXT_B_BGA1-IC,TBD    I86 @BASEBOARD_FAB2_LIB.BASEBOARD_FAB2(SCH_1):PAGE33
  U2D1  AU8 UPI0_RX_DP<11> SKX_EXT_B_BGA1-IC,TBD   I132 @BASEBOARD_FAB2_LIB.BASEBOARD_FAB2(SCH_1):PAGE67

UPI_CPU0_CPU1_P0P0_DN<12> @BASEBOARD_FAB2_LIB.BASEBOARD_FAB2(SCH_1):UPI_CPU0_CPU1_P0P0_DN(12)
  U5D1  AE2 UPI0_TX_DN<7> SKX_EXT_B_BGA1-IC,TBD    I86 @BASEBOARD_FAB2_LIB.BASEBOARD_FAB2(SCH_1):PAGE33
  U2D1 AU10 UPI0_RX_DN<12> SKX_EXT_B_BGA1-IC,TBD   I132 @BASEBOARD_FAB2_LIB.BASEBOARD_FAB2(SCH_1):PAGE67

UPI_CPU0_CPU1_P0P0_DN<13> @BASEBOARD_FAB2_LIB.BASEBOARD_FAB2(SCH_1):UPI_CPU0_CPU1_P0P0_DN(13)
  U5D1  AG4 UPI0_TX_DN<6> SKX_EXT_B_BGA1-IC,TBD    I86 @BASEBOARD_FAB2_LIB.BASEBOARD_FAB2(SCH_1):PAGE33
  U2D1  BA8 UPI0_RX_DN<13> SKX_EXT_B_BGA1-IC,TBD   I132 @BASEBOARD_FAB2_LIB.BASEBOARD_FAB2(SCH_1):PAGE67

UPI_CPU0_CPU1_P0P0_DN<14> @BASEBOARD_FAB2_LIB.BASEBOARD_FAB2(SCH_1):UPI_CPU0_CPU1_P0P0_DN(14)
  U5D1  AC2 UPI0_TX_DN<5> SKX_EXT_B_BGA1-IC,TBD    I86 @BASEBOARD_FAB2_LIB.BASEBOARD_FAB2(SCH_1):PAGE33
  U2D1  BB7 UPI0_RX_DP<14> SKX_EXT_B_BGA1-IC,TBD   I132 @BASEBOARD_FAB2_LIB.BASEBOARD_FAB2(SCH_1):PAGE67

UPI_CPU0_CPU1_P0P0_DN<15> @BASEBOARD_FAB2_LIB.BASEBOARD_FAB2(SCH_1):UPI_CPU0_CPU1_P0P0_DN(15)
  U5D1  AB3 UPI0_TX_DN<4> SKX_EXT_B_BGA1-IC,TBD    I86 @BASEBOARD_FAB2_LIB.BASEBOARD_FAB2(SCH_1):PAGE33
  U2D1  BD7 UPI0_RX_DN<15> SKX_EXT_B_BGA1-IC,TBD   I132 @BASEBOARD_FAB2_LIB.BASEBOARD_FAB2(SCH_1):PAGE67

UPI_CPU0_CPU1_P0P0_DN<16> @BASEBOARD_FAB2_LIB.BASEBOARD_FAB2(SCH_1):UPI_CPU0_CPU1_P0P0_DN(16)
  U5D1   Y1 UPI0_TX_DN<3> SKX_EXT_B_BGA1-IC,TBD    I86 @BASEBOARD_FAB2_LIB.BASEBOARD_FAB2(SCH_1):PAGE33
  U2D1  AW8 UPI0_RX_DN<16> SKX_EXT_B_BGA1-IC,TBD   I132 @BASEBOARD_FAB2_LIB.BASEBOARD_FAB2(SCH_1):PAGE67

UPI_CPU0_CPU1_P0P0_DN<17> @BASEBOARD_FAB2_LIB.BASEBOARD_FAB2(SCH_1):UPI_CPU0_CPU1_P0P0_DN(17)
  U5D1   V3 UPI0_TX_DN<2> SKX_EXT_B_BGA1-IC,TBD    I86 @BASEBOARD_FAB2_LIB.BASEBOARD_FAB2(SCH_1):PAGE33
  U2D1  AY9 UPI0_RX_DN<17> SKX_EXT_B_BGA1-IC,TBD   I132 @BASEBOARD_FAB2_LIB.BASEBOARD_FAB2(SCH_1):PAGE67

UPI_CPU0_CPU1_P0P0_DN<18> @BASEBOARD_FAB2_LIB.BASEBOARD_FAB2(SCH_1):UPI_CPU0_CPU1_P0P0_DN(18)
  U5D1   P1 UPI0_TX_DN<1> SKX_EXT_B_BGA1-IC,TBD    I86 @BASEBOARD_FAB2_LIB.BASEBOARD_FAB2(SCH_1):PAGE33
  U2D1 BC10 UPI0_RX_DP<18> SKX_EXT_B_BGA1-IC,TBD   I132 @BASEBOARD_FAB2_LIB.BASEBOARD_FAB2(SCH_1):PAGE67

UPI_CPU0_CPU1_P0P0_DN<19> @BASEBOARD_FAB2_LIB.BASEBOARD_FAB2(SCH_1):UPI_CPU0_CPU1_P0P0_DN(19)
  U5D1   N2 UPI0_TX_DN<0> SKX_EXT_B_BGA1-IC,TBD    I86 @BASEBOARD_FAB2_LIB.BASEBOARD_FAB2(SCH_1):PAGE33
  U2D1 BA10 UPI0_RX_DP<19> SKX_EXT_B_BGA1-IC,TBD   I132 @BASEBOARD_FAB2_LIB.BASEBOARD_FAB2(SCH_1):PAGE67

UPI_CPU0_CPU1_P0P0_DN<1> @BASEBOARD_FAB2_LIB.BASEBOARD_FAB2(SCH_1):UPI_CPU0_CPU1_P0P0_DN(1)
  U5D1  BF3 UPI0_TX_DN<18> SKX_EXT_B_BGA1-IC,TBD    I86 @BASEBOARD_FAB2_LIB.BASEBOARD_FAB2(SCH_1):PAGE33
  U2D1  AA8 UPI0_RX_DN<1> SKX_EXT_B_BGA1-IC,TBD   I132 @BASEBOARD_FAB2_LIB.BASEBOARD_FAB2(SCH_1):PAGE67

UPI_CPU0_CPU1_P0P0_DN<2> @BASEBOARD_FAB2_LIB.BASEBOARD_FAB2(SCH_1):UPI_CPU0_CPU1_P0P0_DN(2)
  U5D1  BB3 UPI0_TX_DN<17> SKX_EXT_B_BGA1-IC,TBD    I86 @BASEBOARD_FAB2_LIB.BASEBOARD_FAB2(SCH_1):PAGE33
  U2D1  AB7 UPI0_RX_DN<2> SKX_EXT_B_BGA1-IC,TBD   I132 @BASEBOARD_FAB2_LIB.BASEBOARD_FAB2(SCH_1):PAGE67

UPI_CPU0_CPU1_P0P0_DN<3> @BASEBOARD_FAB2_LIB.BASEBOARD_FAB2(SCH_1):UPI_CPU0_CPU1_P0P0_DN(3)
  U5D1  BA4 UPI0_TX_DN<16> SKX_EXT_B_BGA1-IC,TBD    I86 @BASEBOARD_FAB2_LIB.BASEBOARD_FAB2(SCH_1):PAGE33
  U2D1  AC6 UPI0_RX_DP<3> SKX_EXT_B_BGA1-IC,TBD   I132 @BASEBOARD_FAB2_LIB.BASEBOARD_FAB2(SCH_1):PAGE67

UPI_CPU0_CPU1_P0P0_DN<4> @BASEBOARD_FAB2_LIB.BASEBOARD_FAB2(SCH_1):UPI_CPU0_CPU1_P0P0_DN(4)
  U5D1  AV5 UPI0_TX_DN<15> SKX_EXT_B_BGA1-IC,TBD    I86 @BASEBOARD_FAB2_LIB.BASEBOARD_FAB2(SCH_1):PAGE33
  U2D1  AG6 UPI0_RX_DP<4> SKX_EXT_B_BGA1-IC,TBD   I132 @BASEBOARD_FAB2_LIB.BASEBOARD_FAB2(SCH_1):PAGE67

UPI_CPU0_CPU1_P0P0_DN<5> @BASEBOARD_FAB2_LIB.BASEBOARD_FAB2(SCH_1):UPI_CPU0_CPU1_P0P0_DN(5)
  U5D1  AU4 UPI0_TX_DN<14> SKX_EXT_B_BGA1-IC,TBD    I86 @BASEBOARD_FAB2_LIB.BASEBOARD_FAB2(SCH_1):PAGE33
  U2D1  AF7 UPI0_RX_DP<5> SKX_EXT_B_BGA1-IC,TBD   I132 @BASEBOARD_FAB2_LIB.BASEBOARD_FAB2(SCH_1):PAGE67

UPI_CPU0_CPU1_P0P0_DN<6> @BASEBOARD_FAB2_LIB.BASEBOARD_FAB2(SCH_1):UPI_CPU0_CPU1_P0P0_DN(6)
  U5D1  AT3 UPI0_TX_DN<13> SKX_EXT_B_BGA1-IC,TBD    I86 @BASEBOARD_FAB2_LIB.BASEBOARD_FAB2(SCH_1):PAGE33
  U2D1  AH7 UPI0_RX_DP<6> SKX_EXT_B_BGA1-IC,TBD   I132 @BASEBOARD_FAB2_LIB.BASEBOARD_FAB2(SCH_1):PAGE67

UPI_CPU0_CPU1_P0P0_DN<7> @BASEBOARD_FAB2_LIB.BASEBOARD_FAB2(SCH_1):UPI_CPU0_CPU1_P0P0_DN(7)
  U5D1  AT1 UPI0_TX_DN<12> SKX_EXT_B_BGA1-IC,TBD    I86 @BASEBOARD_FAB2_LIB.BASEBOARD_FAB2(SCH_1):PAGE33
  U2D1  AK5 UPI0_RX_DP<7> SKX_EXT_B_BGA1-IC,TBD   I132 @BASEBOARD_FAB2_LIB.BASEBOARD_FAB2(SCH_1):PAGE67

UPI_CPU0_CPU1_P0P0_DN<8> @BASEBOARD_FAB2_LIB.BASEBOARD_FAB2(SCH_1):UPI_CPU0_CPU1_P0P0_DN(8)
  U5D1  AN4 UPI0_TX_DN<11> SKX_EXT_B_BGA1-IC,TBD    I86 @BASEBOARD_FAB2_LIB.BASEBOARD_FAB2(SCH_1):PAGE33
  U2D1  AM7 UPI0_RX_DP<8> SKX_EXT_B_BGA1-IC,TBD   I132 @BASEBOARD_FAB2_LIB.BASEBOARD_FAB2(SCH_1):PAGE67

UPI_CPU0_CPU1_P0P0_DN<9> @BASEBOARD_FAB2_LIB.BASEBOARD_FAB2(SCH_1):UPI_CPU0_CPU1_P0P0_DN(9)
  U5D1  AM3 UPI0_TX_DN<10> SKX_EXT_B_BGA1-IC,TBD    I86 @BASEBOARD_FAB2_LIB.BASEBOARD_FAB2(SCH_1):PAGE33
  U2D1  AL8 UPI0_RX_DP<9> SKX_EXT_B_BGA1-IC,TBD   I132 @BASEBOARD_FAB2_LIB.BASEBOARD_FAB2(SCH_1):PAGE67

UPI_CPU0_CPU1_P0P0_DP<0> @BASEBOARD_FAB2_LIB.BASEBOARD_FAB2(SCH_1):UPI_CPU0_CPU1_P0P0_DP(0)
  U5D1  BH3 UPI0_TX_DP<19> SKX_EXT_B_BGA1-IC,TBD    I86 @BASEBOARD_FAB2_LIB.BASEBOARD_FAB2(SCH_1):PAGE33
  U2D1 AC10 UPI0_RX_DN<0> SKX_EXT_B_BGA1-IC,TBD   I132 @BASEBOARD_FAB2_LIB.BASEBOARD_FAB2(SCH_1):PAGE67

UPI_CPU0_CPU1_P0P0_DP<10> @BASEBOARD_FAB2_LIB.BASEBOARD_FAB2(SCH_1):UPI_CPU0_CPU1_P0P0_DP(10)
  U5D1  AK1 UPI0_TX_DP<9> SKX_EXT_B_BGA1-IC,TBD    I86 @BASEBOARD_FAB2_LIB.BASEBOARD_FAB2(SCH_1):PAGE33
  U2D1  AN8 UPI0_RX_DP<10> SKX_EXT_B_BGA1-IC,TBD   I132 @BASEBOARD_FAB2_LIB.BASEBOARD_FAB2(SCH_1):PAGE67

UPI_CPU0_CPU1_P0P0_DP<11> @BASEBOARD_FAB2_LIB.BASEBOARD_FAB2(SCH_1):UPI_CPU0_CPU1_P0P0_DP(11)
  U5D1  AJ2 UPI0_TX_DP<8> SKX_EXT_B_BGA1-IC,TBD    I86 @BASEBOARD_FAB2_LIB.BASEBOARD_FAB2(SCH_1):PAGE33
  U2D1  AR8 UPI0_RX_DN<11> SKX_EXT_B_BGA1-IC,TBD   I132 @BASEBOARD_FAB2_LIB.BASEBOARD_FAB2(SCH_1):PAGE67

UPI_CPU0_CPU1_P0P0_DP<12> @BASEBOARD_FAB2_LIB.BASEBOARD_FAB2(SCH_1):UPI_CPU0_CPU1_P0P0_DP(12)
  U5D1  AG2 UPI0_TX_DP<7> SKX_EXT_B_BGA1-IC,TBD    I86 @BASEBOARD_FAB2_LIB.BASEBOARD_FAB2(SCH_1):PAGE33
  U2D1  AT9 UPI0_RX_DP<12> SKX_EXT_B_BGA1-IC,TBD   I132 @BASEBOARD_FAB2_LIB.BASEBOARD_FAB2(SCH_1):PAGE67

UPI_CPU0_CPU1_P0P0_DP<13> @BASEBOARD_FAB2_LIB.BASEBOARD_FAB2(SCH_1):UPI_CPU0_CPU1_P0P0_DP(13)
  U5D1  AF3 UPI0_TX_DP<6> SKX_EXT_B_BGA1-IC,TBD    I86 @BASEBOARD_FAB2_LIB.BASEBOARD_FAB2(SCH_1):PAGE33
  U2D1  AY7 UPI0_RX_DP<13> SKX_EXT_B_BGA1-IC,TBD   I132 @BASEBOARD_FAB2_LIB.BASEBOARD_FAB2(SCH_1):PAGE67

UPI_CPU0_CPU1_P0P0_DP<14> @BASEBOARD_FAB2_LIB.BASEBOARD_FAB2(SCH_1):UPI_CPU0_CPU1_P0P0_DP(14)
  U5D1  AD1 UPI0_TX_DP<5> SKX_EXT_B_BGA1-IC,TBD    I86 @BASEBOARD_FAB2_LIB.BASEBOARD_FAB2(SCH_1):PAGE33
  U2D1  BC6 UPI0_RX_DN<14> SKX_EXT_B_BGA1-IC,TBD   I132 @BASEBOARD_FAB2_LIB.BASEBOARD_FAB2(SCH_1):PAGE67

UPI_CPU0_CPU1_P0P0_DP<15> @BASEBOARD_FAB2_LIB.BASEBOARD_FAB2(SCH_1):UPI_CPU0_CPU1_P0P0_DP(15)
  U5D1  AA2 UPI0_TX_DP<4> SKX_EXT_B_BGA1-IC,TBD    I86 @BASEBOARD_FAB2_LIB.BASEBOARD_FAB2(SCH_1):PAGE33
  U2D1  BF7 UPI0_RX_DP<15> SKX_EXT_B_BGA1-IC,TBD   I132 @BASEBOARD_FAB2_LIB.BASEBOARD_FAB2(SCH_1):PAGE67

UPI_CPU0_CPU1_P0P0_DP<16> @BASEBOARD_FAB2_LIB.BASEBOARD_FAB2(SCH_1):UPI_CPU0_CPU1_P0P0_DP(16)
  U5D1   W2 UPI0_TX_DP<3> SKX_EXT_B_BGA1-IC,TBD    I86 @BASEBOARD_FAB2_LIB.BASEBOARD_FAB2(SCH_1):PAGE33
  U2D1  AV9 UPI0_RX_DP<16> SKX_EXT_B_BGA1-IC,TBD   I132 @BASEBOARD_FAB2_LIB.BASEBOARD_FAB2(SCH_1):PAGE67

UPI_CPU0_CPU1_P0P0_DP<17> @BASEBOARD_FAB2_LIB.BASEBOARD_FAB2(SCH_1):UPI_CPU0_CPU1_P0P0_DP(17)
  U5D1   Y3 UPI0_TX_DP<2> SKX_EXT_B_BGA1-IC,TBD    I86 @BASEBOARD_FAB2_LIB.BASEBOARD_FAB2(SCH_1):PAGE33
  U2D1  BB9 UPI0_RX_DP<17> SKX_EXT_B_BGA1-IC,TBD   I132 @BASEBOARD_FAB2_LIB.BASEBOARD_FAB2(SCH_1):PAGE67

UPI_CPU0_CPU1_P0P0_DP<18> @BASEBOARD_FAB2_LIB.BASEBOARD_FAB2(SCH_1):UPI_CPU0_CPU1_P0P0_DP(18)
  U5D1   T1 UPI0_TX_DP<1> SKX_EXT_B_BGA1-IC,TBD    I86 @BASEBOARD_FAB2_LIB.BASEBOARD_FAB2(SCH_1):PAGE33
  U2D1  BD9 UPI0_RX_DN<18> SKX_EXT_B_BGA1-IC,TBD   I132 @BASEBOARD_FAB2_LIB.BASEBOARD_FAB2(SCH_1):PAGE67

UPI_CPU0_CPU1_P0P0_DP<19> @BASEBOARD_FAB2_LIB.BASEBOARD_FAB2(SCH_1):UPI_CPU0_CPU1_P0P0_DP(19)
  U5D1   M1 UPI0_TX_DP<0> SKX_EXT_B_BGA1-IC,TBD    I86 @BASEBOARD_FAB2_LIB.BASEBOARD_FAB2(SCH_1):PAGE33
  U2D1 BB11 UPI0_RX_DN<19> SKX_EXT_B_BGA1-IC,TBD   I132 @BASEBOARD_FAB2_LIB.BASEBOARD_FAB2(SCH_1):PAGE67

UPI_CPU0_CPU1_P0P0_DP<1> @BASEBOARD_FAB2_LIB.BASEBOARD_FAB2(SCH_1):UPI_CPU0_CPU1_P0P0_DP(1)
  U5D1  BD3 UPI0_TX_DP<18> SKX_EXT_B_BGA1-IC,TBD    I86 @BASEBOARD_FAB2_LIB.BASEBOARD_FAB2(SCH_1):PAGE33
  U2D1  AC8 UPI0_RX_DP<1> SKX_EXT_B_BGA1-IC,TBD   I132 @BASEBOARD_FAB2_LIB.BASEBOARD_FAB2(SCH_1):PAGE67

UPI_CPU0_CPU1_P0P0_DP<2> @BASEBOARD_FAB2_LIB.BASEBOARD_FAB2(SCH_1):UPI_CPU0_CPU1_P0P0_DP(2)
  U5D1  BC2 UPI0_TX_DP<17> SKX_EXT_B_BGA1-IC,TBD    I86 @BASEBOARD_FAB2_LIB.BASEBOARD_FAB2(SCH_1):PAGE33
  U2D1  AA6 UPI0_RX_DP<2> SKX_EXT_B_BGA1-IC,TBD   I132 @BASEBOARD_FAB2_LIB.BASEBOARD_FAB2(SCH_1):PAGE67

UPI_CPU0_CPU1_P0P0_DP<3> @BASEBOARD_FAB2_LIB.BASEBOARD_FAB2(SCH_1):UPI_CPU0_CPU1_P0P0_DP(3)
  U5D1  AY3 UPI0_TX_DP<16> SKX_EXT_B_BGA1-IC,TBD    I86 @BASEBOARD_FAB2_LIB.BASEBOARD_FAB2(SCH_1):PAGE33
  U2D1  AD5 UPI0_RX_DN<3> SKX_EXT_B_BGA1-IC,TBD   I132 @BASEBOARD_FAB2_LIB.BASEBOARD_FAB2(SCH_1):PAGE67

UPI_CPU0_CPU1_P0P0_DP<4> @BASEBOARD_FAB2_LIB.BASEBOARD_FAB2(SCH_1):UPI_CPU0_CPU1_P0P0_DP(4)
  U5D1  AW4 UPI0_TX_DP<15> SKX_EXT_B_BGA1-IC,TBD    I86 @BASEBOARD_FAB2_LIB.BASEBOARD_FAB2(SCH_1):PAGE33
  U2D1  AE6 UPI0_RX_DN<4> SKX_EXT_B_BGA1-IC,TBD   I132 @BASEBOARD_FAB2_LIB.BASEBOARD_FAB2(SCH_1):PAGE67

UPI_CPU0_CPU1_P0P0_DP<5> @BASEBOARD_FAB2_LIB.BASEBOARD_FAB2(SCH_1):UPI_CPU0_CPU1_P0P0_DP(5)
  U5D1  AR4 UPI0_TX_DP<14> SKX_EXT_B_BGA1-IC,TBD    I86 @BASEBOARD_FAB2_LIB.BASEBOARD_FAB2(SCH_1):PAGE33
  U2D1  AG8 UPI0_RX_DN<5> SKX_EXT_B_BGA1-IC,TBD   I132 @BASEBOARD_FAB2_LIB.BASEBOARD_FAB2(SCH_1):PAGE67

UPI_CPU0_CPU1_P0P0_DP<6> @BASEBOARD_FAB2_LIB.BASEBOARD_FAB2(SCH_1):UPI_CPU0_CPU1_P0P0_DP(6)
  U5D1  AR2 UPI0_TX_DP<13> SKX_EXT_B_BGA1-IC,TBD    I86 @BASEBOARD_FAB2_LIB.BASEBOARD_FAB2(SCH_1):PAGE33
  U2D1  AJ6 UPI0_RX_DN<6> SKX_EXT_B_BGA1-IC,TBD   I132 @BASEBOARD_FAB2_LIB.BASEBOARD_FAB2(SCH_1):PAGE67

UPI_CPU0_CPU1_P0P0_DP<7> @BASEBOARD_FAB2_LIB.BASEBOARD_FAB2(SCH_1):UPI_CPU0_CPU1_P0P0_DP(7)
  U5D1  AP1 UPI0_TX_DP<12> SKX_EXT_B_BGA1-IC,TBD    I86 @BASEBOARD_FAB2_LIB.BASEBOARD_FAB2(SCH_1):PAGE33
  U2D1  AL6 UPI0_RX_DN<7> SKX_EXT_B_BGA1-IC,TBD   I132 @BASEBOARD_FAB2_LIB.BASEBOARD_FAB2(SCH_1):PAGE67

UPI_CPU0_CPU1_P0P0_DP<8> @BASEBOARD_FAB2_LIB.BASEBOARD_FAB2(SCH_1):UPI_CPU0_CPU1_P0P0_DP(8)
  U5D1  AP3 UPI0_TX_DP<11> SKX_EXT_B_BGA1-IC,TBD    I86 @BASEBOARD_FAB2_LIB.BASEBOARD_FAB2(SCH_1):PAGE33
  U2D1  AK7 UPI0_RX_DN<8> SKX_EXT_B_BGA1-IC,TBD   I132 @BASEBOARD_FAB2_LIB.BASEBOARD_FAB2(SCH_1):PAGE67

UPI_CPU0_CPU1_P0P0_DP<9> @BASEBOARD_FAB2_LIB.BASEBOARD_FAB2(SCH_1):UPI_CPU0_CPU1_P0P0_DP(9)
  U5D1  AK3 UPI0_TX_DP<10> SKX_EXT_B_BGA1-IC,TBD    I86 @BASEBOARD_FAB2_LIB.BASEBOARD_FAB2(SCH_1):PAGE33
  U2D1  AM9 UPI0_RX_DN<9> SKX_EXT_B_BGA1-IC,TBD   I132 @BASEBOARD_FAB2_LIB.BASEBOARD_FAB2(SCH_1):PAGE67

UPI_CPU0_CPU1_P1P1_DN<0> @BASEBOARD_FAB2_LIB.BASEBOARD_FAB2(SCH_1):UPI_CPU0_CPU1_P1P1_DN(0)
  U5D1  H21 UPI1_TX_DN<19> SKX_EXT_B_BGA1-IC,TBD    I86 @BASEBOARD_FAB2_LIB.BASEBOARD_FAB2(SCH_1):PAGE34
  U2D1   R6 UPI1_RX_DP<0> SKX_EXT_B_BGA1-IC,TBD   I125 @BASEBOARD_FAB2_LIB.BASEBOARD_FAB2(SCH_1):PAGE68

UPI_CPU0_CPU1_P1P1_DN<10> @BASEBOARD_FAB2_LIB.BASEBOARD_FAB2(SCH_1):UPI_CPU0_CPU1_P1P1_DN(10)
  U5D1  G10 UPI1_TX_DN<9> SKX_EXT_B_BGA1-IC,TBD    I86 @BASEBOARD_FAB2_LIB.BASEBOARD_FAB2(SCH_1):PAGE34
  U2D1  R16 UPI1_RX_DN<10> SKX_EXT_B_BGA1-IC,TBD   I125 @BASEBOARD_FAB2_LIB.BASEBOARD_FAB2(SCH_1):PAGE68

UPI_CPU0_CPU1_P1P1_DN<11> @BASEBOARD_FAB2_LIB.BASEBOARD_FAB2(SCH_1):UPI_CPU0_CPU1_P1P1_DN(11)
  U5D1  F11 UPI1_TX_DN<8> SKX_EXT_B_BGA1-IC,TBD    I86 @BASEBOARD_FAB2_LIB.BASEBOARD_FAB2(SCH_1):PAGE34
  U2D1  N16 UPI1_RX_DP<11> SKX_EXT_B_BGA1-IC,TBD   I125 @BASEBOARD_FAB2_LIB.BASEBOARD_FAB2(SCH_1):PAGE68

UPI_CPU0_CPU1_P1P1_DN<12> @BASEBOARD_FAB2_LIB.BASEBOARD_FAB2(SCH_1):UPI_CPU0_CPU1_P1P1_DN(12)
  U5D1   D9 UPI1_TX_DN<7> SKX_EXT_B_BGA1-IC,TBD    I86 @BASEBOARD_FAB2_LIB.BASEBOARD_FAB2(SCH_1):PAGE34
  U2D1  W16 UPI1_RX_DP<12> SKX_EXT_B_BGA1-IC,TBD   I125 @BASEBOARD_FAB2_LIB.BASEBOARD_FAB2(SCH_1):PAGE68

UPI_CPU0_CPU1_P1P1_DN<13> @BASEBOARD_FAB2_LIB.BASEBOARD_FAB2(SCH_1):UPI_CPU0_CPU1_P1P1_DN(13)
  U5D1   K9 UPI1_TX_DN<6> SKX_EXT_B_BGA1-IC,TBD    I86 @BASEBOARD_FAB2_LIB.BASEBOARD_FAB2(SCH_1):PAGE34
  U2D1  V17 UPI1_RX_DP<13> SKX_EXT_B_BGA1-IC,TBD   I125 @BASEBOARD_FAB2_LIB.BASEBOARD_FAB2(SCH_1):PAGE68

UPI_CPU0_CPU1_P1P1_DN<14> @BASEBOARD_FAB2_LIB.BASEBOARD_FAB2(SCH_1):UPI_CPU0_CPU1_P1P1_DN(14)
  U5D1   H7 UPI1_TX_DN<5> SKX_EXT_B_BGA1-IC,TBD    I86 @BASEBOARD_FAB2_LIB.BASEBOARD_FAB2(SCH_1):PAGE34
  U2D1  R20 UPI1_RX_DN<14> SKX_EXT_B_BGA1-IC,TBD   I125 @BASEBOARD_FAB2_LIB.BASEBOARD_FAB2(SCH_1):PAGE68

UPI_CPU0_CPU1_P1P1_DN<15> @BASEBOARD_FAB2_LIB.BASEBOARD_FAB2(SCH_1):UPI_CPU0_CPU1_P1P1_DN(15)
  U5D1   G6 UPI1_TX_DN<4> SKX_EXT_B_BGA1-IC,TBD    I86 @BASEBOARD_FAB2_LIB.BASEBOARD_FAB2(SCH_1):PAGE34
  U2D1  U18 UPI1_RX_DN<15> SKX_EXT_B_BGA1-IC,TBD   I125 @BASEBOARD_FAB2_LIB.BASEBOARD_FAB2(SCH_1):PAGE68

UPI_CPU0_CPU1_P1P1_DN<16> @BASEBOARD_FAB2_LIB.BASEBOARD_FAB2(SCH_1):UPI_CPU0_CPU1_P1P1_DN(16)
  U5D1   J6 UPI1_TX_DN<3> SKX_EXT_B_BGA1-IC,TBD    I86 @BASEBOARD_FAB2_LIB.BASEBOARD_FAB2(SCH_1):PAGE34
  U2D1  P21 UPI1_RX_DN<16> SKX_EXT_B_BGA1-IC,TBD   I125 @BASEBOARD_FAB2_LIB.BASEBOARD_FAB2(SCH_1):PAGE68

UPI_CPU0_CPU1_P1P1_DN<17> @BASEBOARD_FAB2_LIB.BASEBOARD_FAB2(SCH_1):UPI_CPU0_CPU1_P1P1_DN(17)
  U5D1   K5 UPI1_TX_DN<2> SKX_EXT_B_BGA1-IC,TBD    I86 @BASEBOARD_FAB2_LIB.BASEBOARD_FAB2(SCH_1):PAGE34
  U2D1  V19 UPI1_RX_DN<17> SKX_EXT_B_BGA1-IC,TBD   I125 @BASEBOARD_FAB2_LIB.BASEBOARD_FAB2(SCH_1):PAGE68

UPI_CPU0_CPU1_P1P1_DN<18> @BASEBOARD_FAB2_LIB.BASEBOARD_FAB2(SCH_1):UPI_CPU0_CPU1_P1P1_DN(18)
  U5D1   L4 UPI1_TX_DN<1> SKX_EXT_B_BGA1-IC,TBD    I86 @BASEBOARD_FAB2_LIB.BASEBOARD_FAB2(SCH_1):PAGE34
  U2D1  W20 UPI1_RX_DP<18> SKX_EXT_B_BGA1-IC,TBD   I125 @BASEBOARD_FAB2_LIB.BASEBOARD_FAB2(SCH_1):PAGE68

UPI_CPU0_CPU1_P1P1_DN<19> @BASEBOARD_FAB2_LIB.BASEBOARD_FAB2(SCH_1):UPI_CPU0_CPU1_P1P1_DN(19)
  U5D1   M3 UPI1_TX_DN<0> SKX_EXT_B_BGA1-IC,TBD    I86 @BASEBOARD_FAB2_LIB.BASEBOARD_FAB2(SCH_1):PAGE34
  U2D1 AA20 UPI1_RX_DP<19> SKX_EXT_B_BGA1-IC,TBD   I125 @BASEBOARD_FAB2_LIB.BASEBOARD_FAB2(SCH_1):PAGE68

UPI_CPU0_CPU1_P1P1_DN<1> @BASEBOARD_FAB2_LIB.BASEBOARD_FAB2(SCH_1):UPI_CPU0_CPU1_P1P1_DN(1)
  U5D1  F21 UPI1_TX_DN<18> SKX_EXT_B_BGA1-IC,TBD    I86 @BASEBOARD_FAB2_LIB.BASEBOARD_FAB2(SCH_1):PAGE34
  U2D1   P7 UPI1_RX_DN<1> SKX_EXT_B_BGA1-IC,TBD   I125 @BASEBOARD_FAB2_LIB.BASEBOARD_FAB2(SCH_1):PAGE68

UPI_CPU0_CPU1_P1P1_DN<2> @BASEBOARD_FAB2_LIB.BASEBOARD_FAB2(SCH_1):UPI_CPU0_CPU1_P1P1_DN(2)
  U5D1  J20 UPI1_TX_DN<17> SKX_EXT_B_BGA1-IC,TBD    I86 @BASEBOARD_FAB2_LIB.BASEBOARD_FAB2(SCH_1):PAGE34
  U2D1   V7 UPI1_RX_DN<2> SKX_EXT_B_BGA1-IC,TBD   I125 @BASEBOARD_FAB2_LIB.BASEBOARD_FAB2(SCH_1):PAGE68

UPI_CPU0_CPU1_P1P1_DN<3> @BASEBOARD_FAB2_LIB.BASEBOARD_FAB2(SCH_1):UPI_CPU0_CPU1_P1P1_DN(3)
  U5D1  G18 UPI1_TX_DN<16> SKX_EXT_B_BGA1-IC,TBD    I86 @BASEBOARD_FAB2_LIB.BASEBOARD_FAB2(SCH_1):PAGE34
  U2D1   T9 UPI1_RX_DN<3> SKX_EXT_B_BGA1-IC,TBD   I125 @BASEBOARD_FAB2_LIB.BASEBOARD_FAB2(SCH_1):PAGE68

UPI_CPU0_CPU1_P1P1_DN<4> @BASEBOARD_FAB2_LIB.BASEBOARD_FAB2(SCH_1):UPI_CPU0_CPU1_P1P1_DN(4)
  U5D1  K19 UPI1_TX_DN<15> SKX_EXT_B_BGA1-IC,TBD    I86 @BASEBOARD_FAB2_LIB.BASEBOARD_FAB2(SCH_1):PAGE34
  U2D1   P9 UPI1_RX_DN<4> SKX_EXT_B_BGA1-IC,TBD   I125 @BASEBOARD_FAB2_LIB.BASEBOARD_FAB2(SCH_1):PAGE68

UPI_CPU0_CPU1_P1P1_DN<5> @BASEBOARD_FAB2_LIB.BASEBOARD_FAB2(SCH_1):UPI_CPU0_CPU1_P1P1_DN(5)
  U5D1  H17 UPI1_TX_DN<14> SKX_EXT_B_BGA1-IC,TBD    I86 @BASEBOARD_FAB2_LIB.BASEBOARD_FAB2(SCH_1):PAGE34
  U2D1  R10 UPI1_RX_DN<5> SKX_EXT_B_BGA1-IC,TBD   I125 @BASEBOARD_FAB2_LIB.BASEBOARD_FAB2(SCH_1):PAGE68

UPI_CPU0_CPU1_P1P1_DN<6> @BASEBOARD_FAB2_LIB.BASEBOARD_FAB2(SCH_1):UPI_CPU0_CPU1_P1P1_DN(6)
  U5D1  F15 UPI1_TX_DN<13> SKX_EXT_B_BGA1-IC,TBD    I86 @BASEBOARD_FAB2_LIB.BASEBOARD_FAB2(SCH_1):PAGE34
  U2D1  U12 UPI1_RX_DN<6> SKX_EXT_B_BGA1-IC,TBD   I125 @BASEBOARD_FAB2_LIB.BASEBOARD_FAB2(SCH_1):PAGE68

UPI_CPU0_CPU1_P1P1_DN<7> @BASEBOARD_FAB2_LIB.BASEBOARD_FAB2(SCH_1):UPI_CPU0_CPU1_P1P1_DN(7)
  U5D1  D15 UPI1_TX_DN<12> SKX_EXT_B_BGA1-IC,TBD    I86 @BASEBOARD_FAB2_LIB.BASEBOARD_FAB2(SCH_1):PAGE34
  U2D1  L12 UPI1_RX_DN<7> SKX_EXT_B_BGA1-IC,TBD   I125 @BASEBOARD_FAB2_LIB.BASEBOARD_FAB2(SCH_1):PAGE68

UPI_CPU0_CPU1_P1P1_DN<8> @BASEBOARD_FAB2_LIB.BASEBOARD_FAB2(SCH_1):UPI_CPU0_CPU1_P1P1_DN(8)
  U5D1  G14 UPI1_TX_DN<11> SKX_EXT_B_BGA1-IC,TBD    I86 @BASEBOARD_FAB2_LIB.BASEBOARD_FAB2(SCH_1):PAGE34
  U2D1  M13 UPI1_RX_DP<8> SKX_EXT_B_BGA1-IC,TBD   I125 @BASEBOARD_FAB2_LIB.BASEBOARD_FAB2(SCH_1):PAGE68

UPI_CPU0_CPU1_P1P1_DN<9> @BASEBOARD_FAB2_LIB.BASEBOARD_FAB2(SCH_1):UPI_CPU0_CPU1_P1P1_DN(9)
  U5D1  E12 UPI1_TX_DN<10> SKX_EXT_B_BGA1-IC,TBD    I86 @BASEBOARD_FAB2_LIB.BASEBOARD_FAB2(SCH_1):PAGE34
  U2D1  R12 UPI1_RX_DN<9> SKX_EXT_B_BGA1-IC,TBD   I125 @BASEBOARD_FAB2_LIB.BASEBOARD_FAB2(SCH_1):PAGE68

UPI_CPU0_CPU1_P1P1_DP<0> @BASEBOARD_FAB2_LIB.BASEBOARD_FAB2(SCH_1):UPI_CPU0_CPU1_P1P1_DP(0)
  U5D1  K21 UPI1_TX_DP<19> SKX_EXT_B_BGA1-IC,TBD    I86 @BASEBOARD_FAB2_LIB.BASEBOARD_FAB2(SCH_1):PAGE34
  U2D1   T5 UPI1_RX_DN<0> SKX_EXT_B_BGA1-IC,TBD   I125 @BASEBOARD_FAB2_LIB.BASEBOARD_FAB2(SCH_1):PAGE68

UPI_CPU0_CPU1_P1P1_DP<10> @BASEBOARD_FAB2_LIB.BASEBOARD_FAB2(SCH_1):UPI_CPU0_CPU1_P1P1_DP(10)
  U5D1   H9 UPI1_TX_DP<9> SKX_EXT_B_BGA1-IC,TBD    I86 @BASEBOARD_FAB2_LIB.BASEBOARD_FAB2(SCH_1):PAGE34
  U2D1  T15 UPI1_RX_DP<10> SKX_EXT_B_BGA1-IC,TBD   I125 @BASEBOARD_FAB2_LIB.BASEBOARD_FAB2(SCH_1):PAGE68

UPI_CPU0_CPU1_P1P1_DP<11> @BASEBOARD_FAB2_LIB.BASEBOARD_FAB2(SCH_1):UPI_CPU0_CPU1_P1P1_DP(11)
  U5D1  E10 UPI1_TX_DP<8> SKX_EXT_B_BGA1-IC,TBD    I86 @BASEBOARD_FAB2_LIB.BASEBOARD_FAB2(SCH_1):PAGE34
  U2D1  P17 UPI1_RX_DN<11> SKX_EXT_B_BGA1-IC,TBD   I125 @BASEBOARD_FAB2_LIB.BASEBOARD_FAB2(SCH_1):PAGE68

UPI_CPU0_CPU1_P1P1_DP<12> @BASEBOARD_FAB2_LIB.BASEBOARD_FAB2(SCH_1):UPI_CPU0_CPU1_P1P1_DP(12)
  U5D1   F9 UPI1_TX_DP<7> SKX_EXT_B_BGA1-IC,TBD    I86 @BASEBOARD_FAB2_LIB.BASEBOARD_FAB2(SCH_1):PAGE34
  U2D1  U16 UPI1_RX_DN<12> SKX_EXT_B_BGA1-IC,TBD   I125 @BASEBOARD_FAB2_LIB.BASEBOARD_FAB2(SCH_1):PAGE68

UPI_CPU0_CPU1_P1P1_DP<13> @BASEBOARD_FAB2_LIB.BASEBOARD_FAB2(SCH_1):UPI_CPU0_CPU1_P1P1_DP(13)
  U5D1   J8 UPI1_TX_DP<6> SKX_EXT_B_BGA1-IC,TBD    I86 @BASEBOARD_FAB2_LIB.BASEBOARD_FAB2(SCH_1):PAGE34
  U2D1  W18 UPI1_RX_DN<13> SKX_EXT_B_BGA1-IC,TBD   I125 @BASEBOARD_FAB2_LIB.BASEBOARD_FAB2(SCH_1):PAGE68

UPI_CPU0_CPU1_P1P1_DP<14> @BASEBOARD_FAB2_LIB.BASEBOARD_FAB2(SCH_1):UPI_CPU0_CPU1_P1P1_DP(14)
  U5D1   K7 UPI1_TX_DP<5> SKX_EXT_B_BGA1-IC,TBD    I86 @BASEBOARD_FAB2_LIB.BASEBOARD_FAB2(SCH_1):PAGE34
  U2D1  P19 UPI1_RX_DP<14> SKX_EXT_B_BGA1-IC,TBD   I125 @BASEBOARD_FAB2_LIB.BASEBOARD_FAB2(SCH_1):PAGE68

UPI_CPU0_CPU1_P1P1_DP<15> @BASEBOARD_FAB2_LIB.BASEBOARD_FAB2(SCH_1):UPI_CPU0_CPU1_P1P1_DP(15)
  U5D1   F7 UPI1_TX_DP<4> SKX_EXT_B_BGA1-IC,TBD    I86 @BASEBOARD_FAB2_LIB.BASEBOARD_FAB2(SCH_1):PAGE34
  U2D1  T19 UPI1_RX_DP<15> SKX_EXT_B_BGA1-IC,TBD   I125 @BASEBOARD_FAB2_LIB.BASEBOARD_FAB2(SCH_1):PAGE68

UPI_CPU0_CPU1_P1P1_DP<16> @BASEBOARD_FAB2_LIB.BASEBOARD_FAB2(SCH_1):UPI_CPU0_CPU1_P1P1_DP(16)
  U5D1   H5 UPI1_TX_DP<3> SKX_EXT_B_BGA1-IC,TBD    I86 @BASEBOARD_FAB2_LIB.BASEBOARD_FAB2(SCH_1):PAGE34
  U2D1  T21 UPI1_RX_DP<16> SKX_EXT_B_BGA1-IC,TBD   I125 @BASEBOARD_FAB2_LIB.BASEBOARD_FAB2(SCH_1):PAGE68

UPI_CPU0_CPU1_P1P1_DP<17> @BASEBOARD_FAB2_LIB.BASEBOARD_FAB2(SCH_1):UPI_CPU0_CPU1_P1P1_DP(17)
  U5D1   M5 UPI1_TX_DP<2> SKX_EXT_B_BGA1-IC,TBD    I86 @BASEBOARD_FAB2_LIB.BASEBOARD_FAB2(SCH_1):PAGE34
  U2D1  Y19 UPI1_RX_DP<17> SKX_EXT_B_BGA1-IC,TBD   I125 @BASEBOARD_FAB2_LIB.BASEBOARD_FAB2(SCH_1):PAGE68

UPI_CPU0_CPU1_P1P1_DP<18> @BASEBOARD_FAB2_LIB.BASEBOARD_FAB2(SCH_1):UPI_CPU0_CPU1_P1P1_DP(18)
  U5D1   K3 UPI1_TX_DP<1> SKX_EXT_B_BGA1-IC,TBD    I86 @BASEBOARD_FAB2_LIB.BASEBOARD_FAB2(SCH_1):PAGE34
  U2D1  Y21 UPI1_RX_DN<18> SKX_EXT_B_BGA1-IC,TBD   I125 @BASEBOARD_FAB2_LIB.BASEBOARD_FAB2(SCH_1):PAGE68

UPI_CPU0_CPU1_P1P1_DP<19> @BASEBOARD_FAB2_LIB.BASEBOARD_FAB2(SCH_1):UPI_CPU0_CPU1_P1P1_DP(19)
  U5D1   P3 UPI1_TX_DP<0> SKX_EXT_B_BGA1-IC,TBD    I86 @BASEBOARD_FAB2_LIB.BASEBOARD_FAB2(SCH_1):PAGE34
  U2D1 AB19 UPI1_RX_DN<19> SKX_EXT_B_BGA1-IC,TBD   I125 @BASEBOARD_FAB2_LIB.BASEBOARD_FAB2(SCH_1):PAGE68

UPI_CPU0_CPU1_P1P1_DP<1> @BASEBOARD_FAB2_LIB.BASEBOARD_FAB2(SCH_1):UPI_CPU0_CPU1_P1P1_DP(1)
  U5D1  G20 UPI1_TX_DP<18> SKX_EXT_B_BGA1-IC,TBD    I86 @BASEBOARD_FAB2_LIB.BASEBOARD_FAB2(SCH_1):PAGE34
  U2D1   T7 UPI1_RX_DP<1> SKX_EXT_B_BGA1-IC,TBD   I125 @BASEBOARD_FAB2_LIB.BASEBOARD_FAB2(SCH_1):PAGE68

UPI_CPU0_CPU1_P1P1_DP<2> @BASEBOARD_FAB2_LIB.BASEBOARD_FAB2(SCH_1):UPI_CPU0_CPU1_P1P1_DP(2)
  U5D1  H19 UPI1_TX_DP<17> SKX_EXT_B_BGA1-IC,TBD    I86 @BASEBOARD_FAB2_LIB.BASEBOARD_FAB2(SCH_1):PAGE34
  U2D1   U8 UPI1_RX_DP<2> SKX_EXT_B_BGA1-IC,TBD   I125 @BASEBOARD_FAB2_LIB.BASEBOARD_FAB2(SCH_1):PAGE68

UPI_CPU0_CPU1_P1P1_DP<3> @BASEBOARD_FAB2_LIB.BASEBOARD_FAB2(SCH_1):UPI_CPU0_CPU1_P1P1_DP(3)
  U5D1  J18 UPI1_TX_DP<16> SKX_EXT_B_BGA1-IC,TBD    I86 @BASEBOARD_FAB2_LIB.BASEBOARD_FAB2(SCH_1):PAGE34
  U2D1   R8 UPI1_RX_DP<3> SKX_EXT_B_BGA1-IC,TBD   I125 @BASEBOARD_FAB2_LIB.BASEBOARD_FAB2(SCH_1):PAGE68

UPI_CPU0_CPU1_P1P1_DP<4> @BASEBOARD_FAB2_LIB.BASEBOARD_FAB2(SCH_1):UPI_CPU0_CPU1_P1P1_DP(4)
  U5D1  L18 UPI1_TX_DP<15> SKX_EXT_B_BGA1-IC,TBD    I86 @BASEBOARD_FAB2_LIB.BASEBOARD_FAB2(SCH_1):PAGE34
  U2D1  N10 UPI1_RX_DP<4> SKX_EXT_B_BGA1-IC,TBD   I125 @BASEBOARD_FAB2_LIB.BASEBOARD_FAB2(SCH_1):PAGE68

UPI_CPU0_CPU1_P1P1_DP<5> @BASEBOARD_FAB2_LIB.BASEBOARD_FAB2(SCH_1):UPI_CPU0_CPU1_P1P1_DP(5)
  U5D1  G16 UPI1_TX_DP<14> SKX_EXT_B_BGA1-IC,TBD    I86 @BASEBOARD_FAB2_LIB.BASEBOARD_FAB2(SCH_1):PAGE34
  U2D1  U10 UPI1_RX_DP<5> SKX_EXT_B_BGA1-IC,TBD   I125 @BASEBOARD_FAB2_LIB.BASEBOARD_FAB2(SCH_1):PAGE68

UPI_CPU0_CPU1_P1P1_DP<6> @BASEBOARD_FAB2_LIB.BASEBOARD_FAB2(SCH_1):UPI_CPU0_CPU1_P1P1_DP(6)
  U5D1  H15 UPI1_TX_DP<13> SKX_EXT_B_BGA1-IC,TBD    I86 @BASEBOARD_FAB2_LIB.BASEBOARD_FAB2(SCH_1):PAGE34
  U2D1  T11 UPI1_RX_DP<6> SKX_EXT_B_BGA1-IC,TBD   I125 @BASEBOARD_FAB2_LIB.BASEBOARD_FAB2(SCH_1):PAGE68

UPI_CPU0_CPU1_P1P1_DP<7> @BASEBOARD_FAB2_LIB.BASEBOARD_FAB2(SCH_1):UPI_CPU0_CPU1_P1P1_DP(7)
  U5D1  E14 UPI1_TX_DP<12> SKX_EXT_B_BGA1-IC,TBD    I86 @BASEBOARD_FAB2_LIB.BASEBOARD_FAB2(SCH_1):PAGE34
  U2D1  N12 UPI1_RX_DP<7> SKX_EXT_B_BGA1-IC,TBD   I125 @BASEBOARD_FAB2_LIB.BASEBOARD_FAB2(SCH_1):PAGE68

UPI_CPU0_CPU1_P1P1_DP<8> @BASEBOARD_FAB2_LIB.BASEBOARD_FAB2(SCH_1):UPI_CPU0_CPU1_P1P1_DP(8)
  U5D1  F13 UPI1_TX_DP<11> SKX_EXT_B_BGA1-IC,TBD    I86 @BASEBOARD_FAB2_LIB.BASEBOARD_FAB2(SCH_1):PAGE34
  U2D1  N14 UPI1_RX_DN<8> SKX_EXT_B_BGA1-IC,TBD   I125 @BASEBOARD_FAB2_LIB.BASEBOARD_FAB2(SCH_1):PAGE68

UPI_CPU0_CPU1_P1P1_DP<9> @BASEBOARD_FAB2_LIB.BASEBOARD_FAB2(SCH_1):UPI_CPU0_CPU1_P1P1_DP(9)
  U5D1  G12 UPI1_TX_DP<10> SKX_EXT_B_BGA1-IC,TBD    I86 @BASEBOARD_FAB2_LIB.BASEBOARD_FAB2(SCH_1):PAGE34
  U2D1  P13 UPI1_RX_DP<9> SKX_EXT_B_BGA1-IC,TBD   I125 @BASEBOARD_FAB2_LIB.BASEBOARD_FAB2(SCH_1):PAGE68

UPI_CPU1_CPU0_P0P0_DN<0> @BASEBOARD_FAB2_LIB.BASEBOARD_FAB2(SCH_1):UPI_CPU1_CPU0_P0P0_DN(0)
  U5D1 BB11 UPI0_RX_DN<19> SKX_EXT_B_BGA1-IC,TBD    I86 @BASEBOARD_FAB2_LIB.BASEBOARD_FAB2(SCH_1):PAGE33
  U2D1   M1 UPI0_TX_DP<0> SKX_EXT_B_BGA1-IC,TBD   I132 @BASEBOARD_FAB2_LIB.BASEBOARD_FAB2(SCH_1):PAGE67

UPI_CPU1_CPU0_P0P0_DN<10> @BASEBOARD_FAB2_LIB.BASEBOARD_FAB2(SCH_1):UPI_CPU1_CPU0_P0P0_DN(10)
  U5D1  AM9 UPI0_RX_DN<9> SKX_EXT_B_BGA1-IC,TBD    I86 @BASEBOARD_FAB2_LIB.BASEBOARD_FAB2(SCH_1):PAGE33
  U2D1  AK3 UPI0_TX_DP<10> SKX_EXT_B_BGA1-IC,TBD   I132 @BASEBOARD_FAB2_LIB.BASEBOARD_FAB2(SCH_1):PAGE67

UPI_CPU1_CPU0_P0P0_DN<11> @BASEBOARD_FAB2_LIB.BASEBOARD_FAB2(SCH_1):UPI_CPU1_CPU0_P0P0_DN(11)
  U5D1  AK7 UPI0_RX_DN<8> SKX_EXT_B_BGA1-IC,TBD    I86 @BASEBOARD_FAB2_LIB.BASEBOARD_FAB2(SCH_1):PAGE33
  U2D1  AP3 UPI0_TX_DP<11> SKX_EXT_B_BGA1-IC,TBD   I132 @BASEBOARD_FAB2_LIB.BASEBOARD_FAB2(SCH_1):PAGE67

UPI_CPU1_CPU0_P0P0_DN<12> @BASEBOARD_FAB2_LIB.BASEBOARD_FAB2(SCH_1):UPI_CPU1_CPU0_P0P0_DN(12)
  U5D1  AL6 UPI0_RX_DN<7> SKX_EXT_B_BGA1-IC,TBD    I86 @BASEBOARD_FAB2_LIB.BASEBOARD_FAB2(SCH_1):PAGE33
  U2D1  AP1 UPI0_TX_DP<12> SKX_EXT_B_BGA1-IC,TBD   I132 @BASEBOARD_FAB2_LIB.BASEBOARD_FAB2(SCH_1):PAGE67

UPI_CPU1_CPU0_P0P0_DN<13> @BASEBOARD_FAB2_LIB.BASEBOARD_FAB2(SCH_1):UPI_CPU1_CPU0_P0P0_DN(13)
  U5D1  AJ6 UPI0_RX_DN<6> SKX_EXT_B_BGA1-IC,TBD    I86 @BASEBOARD_FAB2_LIB.BASEBOARD_FAB2(SCH_1):PAGE33
  U2D1  AR2 UPI0_TX_DP<13> SKX_EXT_B_BGA1-IC,TBD   I132 @BASEBOARD_FAB2_LIB.BASEBOARD_FAB2(SCH_1):PAGE67

UPI_CPU1_CPU0_P0P0_DN<14> @BASEBOARD_FAB2_LIB.BASEBOARD_FAB2(SCH_1):UPI_CPU1_CPU0_P0P0_DN(14)
  U5D1  AG8 UPI0_RX_DN<5> SKX_EXT_B_BGA1-IC,TBD    I86 @BASEBOARD_FAB2_LIB.BASEBOARD_FAB2(SCH_1):PAGE33
  U2D1  AR4 UPI0_TX_DP<14> SKX_EXT_B_BGA1-IC,TBD   I132 @BASEBOARD_FAB2_LIB.BASEBOARD_FAB2(SCH_1):PAGE67

UPI_CPU1_CPU0_P0P0_DN<15> @BASEBOARD_FAB2_LIB.BASEBOARD_FAB2(SCH_1):UPI_CPU1_CPU0_P0P0_DN(15)
  U5D1  AE6 UPI0_RX_DN<4> SKX_EXT_B_BGA1-IC,TBD    I86 @BASEBOARD_FAB2_LIB.BASEBOARD_FAB2(SCH_1):PAGE33
  U2D1  AW4 UPI0_TX_DP<15> SKX_EXT_B_BGA1-IC,TBD   I132 @BASEBOARD_FAB2_LIB.BASEBOARD_FAB2(SCH_1):PAGE67

UPI_CPU1_CPU0_P0P0_DN<16> @BASEBOARD_FAB2_LIB.BASEBOARD_FAB2(SCH_1):UPI_CPU1_CPU0_P0P0_DN(16)
  U5D1  AD5 UPI0_RX_DN<3> SKX_EXT_B_BGA1-IC,TBD    I86 @BASEBOARD_FAB2_LIB.BASEBOARD_FAB2(SCH_1):PAGE33
  U2D1  AY3 UPI0_TX_DP<16> SKX_EXT_B_BGA1-IC,TBD   I132 @BASEBOARD_FAB2_LIB.BASEBOARD_FAB2(SCH_1):PAGE67

UPI_CPU1_CPU0_P0P0_DN<17> @BASEBOARD_FAB2_LIB.BASEBOARD_FAB2(SCH_1):UPI_CPU1_CPU0_P0P0_DN(17)
  U5D1  AB7 UPI0_RX_DN<2> SKX_EXT_B_BGA1-IC,TBD    I86 @BASEBOARD_FAB2_LIB.BASEBOARD_FAB2(SCH_1):PAGE33
  U2D1  BB3 UPI0_TX_DN<17> SKX_EXT_B_BGA1-IC,TBD   I132 @BASEBOARD_FAB2_LIB.BASEBOARD_FAB2(SCH_1):PAGE67

UPI_CPU1_CPU0_P0P0_DN<18> @BASEBOARD_FAB2_LIB.BASEBOARD_FAB2(SCH_1):UPI_CPU1_CPU0_P0P0_DN(18)
  U5D1  AA8 UPI0_RX_DN<1> SKX_EXT_B_BGA1-IC,TBD    I86 @BASEBOARD_FAB2_LIB.BASEBOARD_FAB2(SCH_1):PAGE33
  U2D1  BF3 UPI0_TX_DN<18> SKX_EXT_B_BGA1-IC,TBD   I132 @BASEBOARD_FAB2_LIB.BASEBOARD_FAB2(SCH_1):PAGE67

UPI_CPU1_CPU0_P0P0_DN<19> @BASEBOARD_FAB2_LIB.BASEBOARD_FAB2(SCH_1):UPI_CPU1_CPU0_P0P0_DN(19)
  U5D1 AC10 UPI0_RX_DN<0> SKX_EXT_B_BGA1-IC,TBD    I86 @BASEBOARD_FAB2_LIB.BASEBOARD_FAB2(SCH_1):PAGE33
  U2D1  BH3 UPI0_TX_DP<19> SKX_EXT_B_BGA1-IC,TBD   I132 @BASEBOARD_FAB2_LIB.BASEBOARD_FAB2(SCH_1):PAGE67

UPI_CPU1_CPU0_P0P0_DN<1> @BASEBOARD_FAB2_LIB.BASEBOARD_FAB2(SCH_1):UPI_CPU1_CPU0_P0P0_DN(1)
  U5D1  BD9 UPI0_RX_DN<18> SKX_EXT_B_BGA1-IC,TBD    I86 @BASEBOARD_FAB2_LIB.BASEBOARD_FAB2(SCH_1):PAGE33
  U2D1   T1 UPI0_TX_DP<1> SKX_EXT_B_BGA1-IC,TBD   I132 @BASEBOARD_FAB2_LIB.BASEBOARD_FAB2(SCH_1):PAGE67

UPI_CPU1_CPU0_P0P0_DN<2> @BASEBOARD_FAB2_LIB.BASEBOARD_FAB2(SCH_1):UPI_CPU1_CPU0_P0P0_DN(2)
  U5D1  AY9 UPI0_RX_DN<17> SKX_EXT_B_BGA1-IC,TBD    I86 @BASEBOARD_FAB2_LIB.BASEBOARD_FAB2(SCH_1):PAGE33
  U2D1   V3 UPI0_TX_DN<2> SKX_EXT_B_BGA1-IC,TBD   I132 @BASEBOARD_FAB2_LIB.BASEBOARD_FAB2(SCH_1):PAGE67

UPI_CPU1_CPU0_P0P0_DN<3> @BASEBOARD_FAB2_LIB.BASEBOARD_FAB2(SCH_1):UPI_CPU1_CPU0_P0P0_DN(3)
  U5D1  AW8 UPI0_RX_DN<16> SKX_EXT_B_BGA1-IC,TBD    I86 @BASEBOARD_FAB2_LIB.BASEBOARD_FAB2(SCH_1):PAGE33
  U2D1   Y1 UPI0_TX_DN<3> SKX_EXT_B_BGA1-IC,TBD   I132 @BASEBOARD_FAB2_LIB.BASEBOARD_FAB2(SCH_1):PAGE67

UPI_CPU1_CPU0_P0P0_DN<4> @BASEBOARD_FAB2_LIB.BASEBOARD_FAB2(SCH_1):UPI_CPU1_CPU0_P0P0_DN(4)
  U5D1  BD7 UPI0_RX_DN<15> SKX_EXT_B_BGA1-IC,TBD    I86 @BASEBOARD_FAB2_LIB.BASEBOARD_FAB2(SCH_1):PAGE33
  U2D1  AB3 UPI0_TX_DN<4> SKX_EXT_B_BGA1-IC,TBD   I132 @BASEBOARD_FAB2_LIB.BASEBOARD_FAB2(SCH_1):PAGE67

UPI_CPU1_CPU0_P0P0_DN<5> @BASEBOARD_FAB2_LIB.BASEBOARD_FAB2(SCH_1):UPI_CPU1_CPU0_P0P0_DN(5)
  U5D1  BC6 UPI0_RX_DN<14> SKX_EXT_B_BGA1-IC,TBD    I86 @BASEBOARD_FAB2_LIB.BASEBOARD_FAB2(SCH_1):PAGE33
  U2D1  AD1 UPI0_TX_DP<5> SKX_EXT_B_BGA1-IC,TBD   I132 @BASEBOARD_FAB2_LIB.BASEBOARD_FAB2(SCH_1):PAGE67

UPI_CPU1_CPU0_P0P0_DN<6> @BASEBOARD_FAB2_LIB.BASEBOARD_FAB2(SCH_1):UPI_CPU1_CPU0_P0P0_DN(6)
  U5D1  BA8 UPI0_RX_DN<13> SKX_EXT_B_BGA1-IC,TBD    I86 @BASEBOARD_FAB2_LIB.BASEBOARD_FAB2(SCH_1):PAGE33
  U2D1  AG4 UPI0_TX_DN<6> SKX_EXT_B_BGA1-IC,TBD   I132 @BASEBOARD_FAB2_LIB.BASEBOARD_FAB2(SCH_1):PAGE67

UPI_CPU1_CPU0_P0P0_DN<7> @BASEBOARD_FAB2_LIB.BASEBOARD_FAB2(SCH_1):UPI_CPU1_CPU0_P0P0_DN(7)
  U5D1 AU10 UPI0_RX_DN<12> SKX_EXT_B_BGA1-IC,TBD    I86 @BASEBOARD_FAB2_LIB.BASEBOARD_FAB2(SCH_1):PAGE33
  U2D1  AE2 UPI0_TX_DN<7> SKX_EXT_B_BGA1-IC,TBD   I132 @BASEBOARD_FAB2_LIB.BASEBOARD_FAB2(SCH_1):PAGE67

UPI_CPU1_CPU0_P0P0_DN<8> @BASEBOARD_FAB2_LIB.BASEBOARD_FAB2(SCH_1):UPI_CPU1_CPU0_P0P0_DN(8)
  U5D1  AR8 UPI0_RX_DN<11> SKX_EXT_B_BGA1-IC,TBD    I86 @BASEBOARD_FAB2_LIB.BASEBOARD_FAB2(SCH_1):PAGE33
  U2D1  AJ2 UPI0_TX_DP<8> SKX_EXT_B_BGA1-IC,TBD   I132 @BASEBOARD_FAB2_LIB.BASEBOARD_FAB2(SCH_1):PAGE67

UPI_CPU1_CPU0_P0P0_DN<9> @BASEBOARD_FAB2_LIB.BASEBOARD_FAB2(SCH_1):UPI_CPU1_CPU0_P0P0_DN(9)
  U5D1  AP7 UPI0_RX_DN<10> SKX_EXT_B_BGA1-IC,TBD    I86 @BASEBOARD_FAB2_LIB.BASEBOARD_FAB2(SCH_1):PAGE33
  U2D1  AL2 UPI0_TX_DN<9> SKX_EXT_B_BGA1-IC,TBD   I132 @BASEBOARD_FAB2_LIB.BASEBOARD_FAB2(SCH_1):PAGE67

UPI_CPU1_CPU0_P0P0_DP<0> @BASEBOARD_FAB2_LIB.BASEBOARD_FAB2(SCH_1):UPI_CPU1_CPU0_P0P0_DP(0)
  U5D1 BA10 UPI0_RX_DP<19> SKX_EXT_B_BGA1-IC,TBD    I86 @BASEBOARD_FAB2_LIB.BASEBOARD_FAB2(SCH_1):PAGE33
  U2D1   N2 UPI0_TX_DN<0> SKX_EXT_B_BGA1-IC,TBD   I132 @BASEBOARD_FAB2_LIB.BASEBOARD_FAB2(SCH_1):PAGE67

UPI_CPU1_CPU0_P0P0_DP<10> @BASEBOARD_FAB2_LIB.BASEBOARD_FAB2(SCH_1):UPI_CPU1_CPU0_P0P0_DP(10)
  U5D1  AL8 UPI0_RX_DP<9> SKX_EXT_B_BGA1-IC,TBD    I86 @BASEBOARD_FAB2_LIB.BASEBOARD_FAB2(SCH_1):PAGE33
  U2D1  AM3 UPI0_TX_DN<10> SKX_EXT_B_BGA1-IC,TBD   I132 @BASEBOARD_FAB2_LIB.BASEBOARD_FAB2(SCH_1):PAGE67

UPI_CPU1_CPU0_P0P0_DP<11> @BASEBOARD_FAB2_LIB.BASEBOARD_FAB2(SCH_1):UPI_CPU1_CPU0_P0P0_DP(11)
  U5D1  AM7 UPI0_RX_DP<8> SKX_EXT_B_BGA1-IC,TBD    I86 @BASEBOARD_FAB2_LIB.BASEBOARD_FAB2(SCH_1):PAGE33
  U2D1  AN4 UPI0_TX_DN<11> SKX_EXT_B_BGA1-IC,TBD   I132 @BASEBOARD_FAB2_LIB.BASEBOARD_FAB2(SCH_1):PAGE67

UPI_CPU1_CPU0_P0P0_DP<12> @BASEBOARD_FAB2_LIB.BASEBOARD_FAB2(SCH_1):UPI_CPU1_CPU0_P0P0_DP(12)
  U5D1  AK5 UPI0_RX_DP<7> SKX_EXT_B_BGA1-IC,TBD    I86 @BASEBOARD_FAB2_LIB.BASEBOARD_FAB2(SCH_1):PAGE33
  U2D1  AT1 UPI0_TX_DN<12> SKX_EXT_B_BGA1-IC,TBD   I132 @BASEBOARD_FAB2_LIB.BASEBOARD_FAB2(SCH_1):PAGE67

UPI_CPU1_CPU0_P0P0_DP<13> @BASEBOARD_FAB2_LIB.BASEBOARD_FAB2(SCH_1):UPI_CPU1_CPU0_P0P0_DP(13)
  U5D1  AH7 UPI0_RX_DP<6> SKX_EXT_B_BGA1-IC,TBD    I86 @BASEBOARD_FAB2_LIB.BASEBOARD_FAB2(SCH_1):PAGE33
  U2D1  AT3 UPI0_TX_DN<13> SKX_EXT_B_BGA1-IC,TBD   I132 @BASEBOARD_FAB2_LIB.BASEBOARD_FAB2(SCH_1):PAGE67

UPI_CPU1_CPU0_P0P0_DP<14> @BASEBOARD_FAB2_LIB.BASEBOARD_FAB2(SCH_1):UPI_CPU1_CPU0_P0P0_DP(14)
  U5D1  AF7 UPI0_RX_DP<5> SKX_EXT_B_BGA1-IC,TBD    I86 @BASEBOARD_FAB2_LIB.BASEBOARD_FAB2(SCH_1):PAGE33
  U2D1  AU4 UPI0_TX_DN<14> SKX_EXT_B_BGA1-IC,TBD   I132 @BASEBOARD_FAB2_LIB.BASEBOARD_FAB2(SCH_1):PAGE67

UPI_CPU1_CPU0_P0P0_DP<15> @BASEBOARD_FAB2_LIB.BASEBOARD_FAB2(SCH_1):UPI_CPU1_CPU0_P0P0_DP(15)
  U5D1  AG6 UPI0_RX_DP<4> SKX_EXT_B_BGA1-IC,TBD    I86 @BASEBOARD_FAB2_LIB.BASEBOARD_FAB2(SCH_1):PAGE33
  U2D1  AV5 UPI0_TX_DN<15> SKX_EXT_B_BGA1-IC,TBD   I132 @BASEBOARD_FAB2_LIB.BASEBOARD_FAB2(SCH_1):PAGE67

UPI_CPU1_CPU0_P0P0_DP<16> @BASEBOARD_FAB2_LIB.BASEBOARD_FAB2(SCH_1):UPI_CPU1_CPU0_P0P0_DP(16)
  U5D1  AC6 UPI0_RX_DP<3> SKX_EXT_B_BGA1-IC,TBD    I86 @BASEBOARD_FAB2_LIB.BASEBOARD_FAB2(SCH_1):PAGE33
  U2D1  BA4 UPI0_TX_DN<16> SKX_EXT_B_BGA1-IC,TBD   I132 @BASEBOARD_FAB2_LIB.BASEBOARD_FAB2(SCH_1):PAGE67

UPI_CPU1_CPU0_P0P0_DP<17> @BASEBOARD_FAB2_LIB.BASEBOARD_FAB2(SCH_1):UPI_CPU1_CPU0_P0P0_DP(17)
  U5D1  AA6 UPI0_RX_DP<2> SKX_EXT_B_BGA1-IC,TBD    I86 @BASEBOARD_FAB2_LIB.BASEBOARD_FAB2(SCH_1):PAGE33
  U2D1  BC2 UPI0_TX_DP<17> SKX_EXT_B_BGA1-IC,TBD   I132 @BASEBOARD_FAB2_LIB.BASEBOARD_FAB2(SCH_1):PAGE67

UPI_CPU1_CPU0_P0P0_DP<18> @BASEBOARD_FAB2_LIB.BASEBOARD_FAB2(SCH_1):UPI_CPU1_CPU0_P0P0_DP(18)
  U5D1  AC8 UPI0_RX_DP<1> SKX_EXT_B_BGA1-IC,TBD    I86 @BASEBOARD_FAB2_LIB.BASEBOARD_FAB2(SCH_1):PAGE33
  U2D1  BD3 UPI0_TX_DP<18> SKX_EXT_B_BGA1-IC,TBD   I132 @BASEBOARD_FAB2_LIB.BASEBOARD_FAB2(SCH_1):PAGE67

UPI_CPU1_CPU0_P0P0_DP<19> @BASEBOARD_FAB2_LIB.BASEBOARD_FAB2(SCH_1):UPI_CPU1_CPU0_P0P0_DP(19)
  U5D1  AB9 UPI0_RX_DP<0> SKX_EXT_B_BGA1-IC,TBD    I86 @BASEBOARD_FAB2_LIB.BASEBOARD_FAB2(SCH_1):PAGE33
  U2D1  BG4 UPI0_TX_DN<19> SKX_EXT_B_BGA1-IC,TBD   I132 @BASEBOARD_FAB2_LIB.BASEBOARD_FAB2(SCH_1):PAGE67

UPI_CPU1_CPU0_P0P0_DP<1> @BASEBOARD_FAB2_LIB.BASEBOARD_FAB2(SCH_1):UPI_CPU1_CPU0_P0P0_DP(1)
  U5D1 BC10 UPI0_RX_DP<18> SKX_EXT_B_BGA1-IC,TBD    I86 @BASEBOARD_FAB2_LIB.BASEBOARD_FAB2(SCH_1):PAGE33
  U2D1   P1 UPI0_TX_DN<1> SKX_EXT_B_BGA1-IC,TBD   I132 @BASEBOARD_FAB2_LIB.BASEBOARD_FAB2(SCH_1):PAGE67

UPI_CPU1_CPU0_P0P0_DP<2> @BASEBOARD_FAB2_LIB.BASEBOARD_FAB2(SCH_1):UPI_CPU1_CPU0_P0P0_DP(2)
  U5D1  BB9 UPI0_RX_DP<17> SKX_EXT_B_BGA1-IC,TBD    I86 @BASEBOARD_FAB2_LIB.BASEBOARD_FAB2(SCH_1):PAGE33
  U2D1   Y3 UPI0_TX_DP<2> SKX_EXT_B_BGA1-IC,TBD   I132 @BASEBOARD_FAB2_LIB.BASEBOARD_FAB2(SCH_1):PAGE67

UPI_CPU1_CPU0_P0P0_DP<3> @BASEBOARD_FAB2_LIB.BASEBOARD_FAB2(SCH_1):UPI_CPU1_CPU0_P0P0_DP(3)
  U5D1  AV9 UPI0_RX_DP<16> SKX_EXT_B_BGA1-IC,TBD    I86 @BASEBOARD_FAB2_LIB.BASEBOARD_FAB2(SCH_1):PAGE33
  U2D1   W2 UPI0_TX_DP<3> SKX_EXT_B_BGA1-IC,TBD   I132 @BASEBOARD_FAB2_LIB.BASEBOARD_FAB2(SCH_1):PAGE67

UPI_CPU1_CPU0_P0P0_DP<4> @BASEBOARD_FAB2_LIB.BASEBOARD_FAB2(SCH_1):UPI_CPU1_CPU0_P0P0_DP(4)
  U5D1  BF7 UPI0_RX_DP<15> SKX_EXT_B_BGA1-IC,TBD    I86 @BASEBOARD_FAB2_LIB.BASEBOARD_FAB2(SCH_1):PAGE33
  U2D1  AA2 UPI0_TX_DP<4> SKX_EXT_B_BGA1-IC,TBD   I132 @BASEBOARD_FAB2_LIB.BASEBOARD_FAB2(SCH_1):PAGE67

UPI_CPU1_CPU0_P0P0_DP<5> @BASEBOARD_FAB2_LIB.BASEBOARD_FAB2(SCH_1):UPI_CPU1_CPU0_P0P0_DP(5)
  U5D1  BB7 UPI0_RX_DP<14> SKX_EXT_B_BGA1-IC,TBD    I86 @BASEBOARD_FAB2_LIB.BASEBOARD_FAB2(SCH_1):PAGE33
  U2D1  AC2 UPI0_TX_DN<5> SKX_EXT_B_BGA1-IC,TBD   I132 @BASEBOARD_FAB2_LIB.BASEBOARD_FAB2(SCH_1):PAGE67

UPI_CPU1_CPU0_P0P0_DP<6> @BASEBOARD_FAB2_LIB.BASEBOARD_FAB2(SCH_1):UPI_CPU1_CPU0_P0P0_DP(6)
  U5D1  AY7 UPI0_RX_DP<13> SKX_EXT_B_BGA1-IC,TBD    I86 @BASEBOARD_FAB2_LIB.BASEBOARD_FAB2(SCH_1):PAGE33
  U2D1  AF3 UPI0_TX_DP<6> SKX_EXT_B_BGA1-IC,TBD   I132 @BASEBOARD_FAB2_LIB.BASEBOARD_FAB2(SCH_1):PAGE67

UPI_CPU1_CPU0_P0P0_DP<7> @BASEBOARD_FAB2_LIB.BASEBOARD_FAB2(SCH_1):UPI_CPU1_CPU0_P0P0_DP(7)
  U5D1  AT9 UPI0_RX_DP<12> SKX_EXT_B_BGA1-IC,TBD    I86 @BASEBOARD_FAB2_LIB.BASEBOARD_FAB2(SCH_1):PAGE33
  U2D1  AG2 UPI0_TX_DP<7> SKX_EXT_B_BGA1-IC,TBD   I132 @BASEBOARD_FAB2_LIB.BASEBOARD_FAB2(SCH_1):PAGE67

UPI_CPU1_CPU0_P0P0_DP<8> @BASEBOARD_FAB2_LIB.BASEBOARD_FAB2(SCH_1):UPI_CPU1_CPU0_P0P0_DP(8)
  U5D1  AU8 UPI0_RX_DP<11> SKX_EXT_B_BGA1-IC,TBD    I86 @BASEBOARD_FAB2_LIB.BASEBOARD_FAB2(SCH_1):PAGE33
  U2D1  AH3 UPI0_TX_DN<8> SKX_EXT_B_BGA1-IC,TBD   I132 @BASEBOARD_FAB2_LIB.BASEBOARD_FAB2(SCH_1):PAGE67

UPI_CPU1_CPU0_P0P0_DP<9> @BASEBOARD_FAB2_LIB.BASEBOARD_FAB2(SCH_1):UPI_CPU1_CPU0_P0P0_DP(9)
  U5D1  AN8 UPI0_RX_DP<10> SKX_EXT_B_BGA1-IC,TBD    I86 @BASEBOARD_FAB2_LIB.BASEBOARD_FAB2(SCH_1):PAGE33
  U2D1  AK1 UPI0_TX_DP<9> SKX_EXT_B_BGA1-IC,TBD   I132 @BASEBOARD_FAB2_LIB.BASEBOARD_FAB2(SCH_1):PAGE67

UPI_CPU1_CPU0_P1P1_DN<0> @BASEBOARD_FAB2_LIB.BASEBOARD_FAB2(SCH_1):UPI_CPU1_CPU0_P1P1_DN(0)
  U5D1 AB19 UPI1_RX_DN<19> SKX_EXT_B_BGA1-IC,TBD    I86 @BASEBOARD_FAB2_LIB.BASEBOARD_FAB2(SCH_1):PAGE34
  U2D1   P3 UPI1_TX_DP<0> SKX_EXT_B_BGA1-IC,TBD   I125 @BASEBOARD_FAB2_LIB.BASEBOARD_FAB2(SCH_1):PAGE68

UPI_CPU1_CPU0_P1P1_DN<10> @BASEBOARD_FAB2_LIB.BASEBOARD_FAB2(SCH_1):UPI_CPU1_CPU0_P1P1_DN(10)
  U5D1  R12 UPI1_RX_DN<9> SKX_EXT_B_BGA1-IC,TBD    I86 @BASEBOARD_FAB2_LIB.BASEBOARD_FAB2(SCH_1):PAGE34
  U2D1  E12 UPI1_TX_DN<10> SKX_EXT_B_BGA1-IC,TBD   I125 @BASEBOARD_FAB2_LIB.BASEBOARD_FAB2(SCH_1):PAGE68

UPI_CPU1_CPU0_P1P1_DN<11> @BASEBOARD_FAB2_LIB.BASEBOARD_FAB2(SCH_1):UPI_CPU1_CPU0_P1P1_DN(11)
  U5D1  N14 UPI1_RX_DN<8> SKX_EXT_B_BGA1-IC,TBD    I86 @BASEBOARD_FAB2_LIB.BASEBOARD_FAB2(SCH_1):PAGE34
  U2D1  F13 UPI1_TX_DP<11> SKX_EXT_B_BGA1-IC,TBD   I125 @BASEBOARD_FAB2_LIB.BASEBOARD_FAB2(SCH_1):PAGE68

UPI_CPU1_CPU0_P1P1_DN<12> @BASEBOARD_FAB2_LIB.BASEBOARD_FAB2(SCH_1):UPI_CPU1_CPU0_P1P1_DN(12)
  U5D1  L12 UPI1_RX_DN<7> SKX_EXT_B_BGA1-IC,TBD    I86 @BASEBOARD_FAB2_LIB.BASEBOARD_FAB2(SCH_1):PAGE34
  U2D1  D15 UPI1_TX_DN<12> SKX_EXT_B_BGA1-IC,TBD   I125 @BASEBOARD_FAB2_LIB.BASEBOARD_FAB2(SCH_1):PAGE68

UPI_CPU1_CPU0_P1P1_DN<13> @BASEBOARD_FAB2_LIB.BASEBOARD_FAB2(SCH_1):UPI_CPU1_CPU0_P1P1_DN(13)
  U5D1  U12 UPI1_RX_DN<6> SKX_EXT_B_BGA1-IC,TBD    I86 @BASEBOARD_FAB2_LIB.BASEBOARD_FAB2(SCH_1):PAGE34
  U2D1  F15 UPI1_TX_DN<13> SKX_EXT_B_BGA1-IC,TBD   I125 @BASEBOARD_FAB2_LIB.BASEBOARD_FAB2(SCH_1):PAGE68

UPI_CPU1_CPU0_P1P1_DN<14> @BASEBOARD_FAB2_LIB.BASEBOARD_FAB2(SCH_1):UPI_CPU1_CPU0_P1P1_DN(14)
  U5D1  R10 UPI1_RX_DN<5> SKX_EXT_B_BGA1-IC,TBD    I86 @BASEBOARD_FAB2_LIB.BASEBOARD_FAB2(SCH_1):PAGE34
  U2D1  H17 UPI1_TX_DN<14> SKX_EXT_B_BGA1-IC,TBD   I125 @BASEBOARD_FAB2_LIB.BASEBOARD_FAB2(SCH_1):PAGE68

UPI_CPU1_CPU0_P1P1_DN<15> @BASEBOARD_FAB2_LIB.BASEBOARD_FAB2(SCH_1):UPI_CPU1_CPU0_P1P1_DN(15)
  U5D1   P9 UPI1_RX_DN<4> SKX_EXT_B_BGA1-IC,TBD    I86 @BASEBOARD_FAB2_LIB.BASEBOARD_FAB2(SCH_1):PAGE34
  U2D1  K19 UPI1_TX_DN<15> SKX_EXT_B_BGA1-IC,TBD   I125 @BASEBOARD_FAB2_LIB.BASEBOARD_FAB2(SCH_1):PAGE68

UPI_CPU1_CPU0_P1P1_DN<16> @BASEBOARD_FAB2_LIB.BASEBOARD_FAB2(SCH_1):UPI_CPU1_CPU0_P1P1_DN(16)
  U5D1   T9 UPI1_RX_DN<3> SKX_EXT_B_BGA1-IC,TBD    I86 @BASEBOARD_FAB2_LIB.BASEBOARD_FAB2(SCH_1):PAGE34
  U2D1  G18 UPI1_TX_DN<16> SKX_EXT_B_BGA1-IC,TBD   I125 @BASEBOARD_FAB2_LIB.BASEBOARD_FAB2(SCH_1):PAGE68

UPI_CPU1_CPU0_P1P1_DN<17> @BASEBOARD_FAB2_LIB.BASEBOARD_FAB2(SCH_1):UPI_CPU1_CPU0_P1P1_DN(17)
  U5D1   V7 UPI1_RX_DN<2> SKX_EXT_B_BGA1-IC,TBD    I86 @BASEBOARD_FAB2_LIB.BASEBOARD_FAB2(SCH_1):PAGE34
  U2D1  J20 UPI1_TX_DN<17> SKX_EXT_B_BGA1-IC,TBD   I125 @BASEBOARD_FAB2_LIB.BASEBOARD_FAB2(SCH_1):PAGE68

UPI_CPU1_CPU0_P1P1_DN<18> @BASEBOARD_FAB2_LIB.BASEBOARD_FAB2(SCH_1):UPI_CPU1_CPU0_P1P1_DN(18)
  U5D1   P7 UPI1_RX_DN<1> SKX_EXT_B_BGA1-IC,TBD    I86 @BASEBOARD_FAB2_LIB.BASEBOARD_FAB2(SCH_1):PAGE34
  U2D1  G20 UPI1_TX_DP<18> SKX_EXT_B_BGA1-IC,TBD   I125 @BASEBOARD_FAB2_LIB.BASEBOARD_FAB2(SCH_1):PAGE68

UPI_CPU1_CPU0_P1P1_DN<19> @BASEBOARD_FAB2_LIB.BASEBOARD_FAB2(SCH_1):UPI_CPU1_CPU0_P1P1_DN(19)
  U5D1   T5 UPI1_RX_DN<0> SKX_EXT_B_BGA1-IC,TBD    I86 @BASEBOARD_FAB2_LIB.BASEBOARD_FAB2(SCH_1):PAGE34
  U2D1  K21 UPI1_TX_DP<19> SKX_EXT_B_BGA1-IC,TBD   I125 @BASEBOARD_FAB2_LIB.BASEBOARD_FAB2(SCH_1):PAGE68

UPI_CPU1_CPU0_P1P1_DN<1> @BASEBOARD_FAB2_LIB.BASEBOARD_FAB2(SCH_1):UPI_CPU1_CPU0_P1P1_DN(1)
  U5D1  Y21 UPI1_RX_DN<18> SKX_EXT_B_BGA1-IC,TBD    I86 @BASEBOARD_FAB2_LIB.BASEBOARD_FAB2(SCH_1):PAGE34
  U2D1   K3 UPI1_TX_DP<1> SKX_EXT_B_BGA1-IC,TBD   I125 @BASEBOARD_FAB2_LIB.BASEBOARD_FAB2(SCH_1):PAGE68

UPI_CPU1_CPU0_P1P1_DN<2> @BASEBOARD_FAB2_LIB.BASEBOARD_FAB2(SCH_1):UPI_CPU1_CPU0_P1P1_DN(2)
  U5D1  V19 UPI1_RX_DN<17> SKX_EXT_B_BGA1-IC,TBD    I86 @BASEBOARD_FAB2_LIB.BASEBOARD_FAB2(SCH_1):PAGE34
  U2D1   K5 UPI1_TX_DN<2> SKX_EXT_B_BGA1-IC,TBD   I125 @BASEBOARD_FAB2_LIB.BASEBOARD_FAB2(SCH_1):PAGE68

UPI_CPU1_CPU0_P1P1_DN<3> @BASEBOARD_FAB2_LIB.BASEBOARD_FAB2(SCH_1):UPI_CPU1_CPU0_P1P1_DN(3)
  U5D1  P21 UPI1_RX_DN<16> SKX_EXT_B_BGA1-IC,TBD    I86 @BASEBOARD_FAB2_LIB.BASEBOARD_FAB2(SCH_1):PAGE34
  U2D1   J6 UPI1_TX_DN<3> SKX_EXT_B_BGA1-IC,TBD   I125 @BASEBOARD_FAB2_LIB.BASEBOARD_FAB2(SCH_1):PAGE68

UPI_CPU1_CPU0_P1P1_DN<4> @BASEBOARD_FAB2_LIB.BASEBOARD_FAB2(SCH_1):UPI_CPU1_CPU0_P1P1_DN(4)
  U5D1  U18 UPI1_RX_DN<15> SKX_EXT_B_BGA1-IC,TBD    I86 @BASEBOARD_FAB2_LIB.BASEBOARD_FAB2(SCH_1):PAGE34
  U2D1   G6 UPI1_TX_DN<4> SKX_EXT_B_BGA1-IC,TBD   I125 @BASEBOARD_FAB2_LIB.BASEBOARD_FAB2(SCH_1):PAGE68

UPI_CPU1_CPU0_P1P1_DN<5> @BASEBOARD_FAB2_LIB.BASEBOARD_FAB2(SCH_1):UPI_CPU1_CPU0_P1P1_DN(5)
  U5D1  R20 UPI1_RX_DN<14> SKX_EXT_B_BGA1-IC,TBD    I86 @BASEBOARD_FAB2_LIB.BASEBOARD_FAB2(SCH_1):PAGE34
  U2D1   H7 UPI1_TX_DN<5> SKX_EXT_B_BGA1-IC,TBD   I125 @BASEBOARD_FAB2_LIB.BASEBOARD_FAB2(SCH_1):PAGE68

UPI_CPU1_CPU0_P1P1_DN<6> @BASEBOARD_FAB2_LIB.BASEBOARD_FAB2(SCH_1):UPI_CPU1_CPU0_P1P1_DN(6)
  U5D1  W18 UPI1_RX_DN<13> SKX_EXT_B_BGA1-IC,TBD    I86 @BASEBOARD_FAB2_LIB.BASEBOARD_FAB2(SCH_1):PAGE34
  U2D1   J8 UPI1_TX_DP<6> SKX_EXT_B_BGA1-IC,TBD   I125 @BASEBOARD_FAB2_LIB.BASEBOARD_FAB2(SCH_1):PAGE68

UPI_CPU1_CPU0_P1P1_DN<7> @BASEBOARD_FAB2_LIB.BASEBOARD_FAB2(SCH_1):UPI_CPU1_CPU0_P1P1_DN(7)
  U5D1  U16 UPI1_RX_DN<12> SKX_EXT_B_BGA1-IC,TBD    I86 @BASEBOARD_FAB2_LIB.BASEBOARD_FAB2(SCH_1):PAGE34
  U2D1   F9 UPI1_TX_DP<7> SKX_EXT_B_BGA1-IC,TBD   I125 @BASEBOARD_FAB2_LIB.BASEBOARD_FAB2(SCH_1):PAGE68

UPI_CPU1_CPU0_P1P1_DN<8> @BASEBOARD_FAB2_LIB.BASEBOARD_FAB2(SCH_1):UPI_CPU1_CPU0_P1P1_DN(8)
  U5D1  P17 UPI1_RX_DN<11> SKX_EXT_B_BGA1-IC,TBD    I86 @BASEBOARD_FAB2_LIB.BASEBOARD_FAB2(SCH_1):PAGE34
  U2D1  E10 UPI1_TX_DP<8> SKX_EXT_B_BGA1-IC,TBD   I125 @BASEBOARD_FAB2_LIB.BASEBOARD_FAB2(SCH_1):PAGE68

UPI_CPU1_CPU0_P1P1_DN<9> @BASEBOARD_FAB2_LIB.BASEBOARD_FAB2(SCH_1):UPI_CPU1_CPU0_P1P1_DN(9)
  U5D1  R16 UPI1_RX_DN<10> SKX_EXT_B_BGA1-IC,TBD    I86 @BASEBOARD_FAB2_LIB.BASEBOARD_FAB2(SCH_1):PAGE34
  U2D1  G10 UPI1_TX_DN<9> SKX_EXT_B_BGA1-IC,TBD   I125 @BASEBOARD_FAB2_LIB.BASEBOARD_FAB2(SCH_1):PAGE68

UPI_CPU1_CPU0_P1P1_DP<0> @BASEBOARD_FAB2_LIB.BASEBOARD_FAB2(SCH_1):UPI_CPU1_CPU0_P1P1_DP(0)
  U5D1 AA20 UPI1_RX_DP<19> SKX_EXT_B_BGA1-IC,TBD    I86 @BASEBOARD_FAB2_LIB.BASEBOARD_FAB2(SCH_1):PAGE34
  U2D1   M3 UPI1_TX_DN<0> SKX_EXT_B_BGA1-IC,TBD   I125 @BASEBOARD_FAB2_LIB.BASEBOARD_FAB2(SCH_1):PAGE68

UPI_CPU1_CPU0_P1P1_DP<10> @BASEBOARD_FAB2_LIB.BASEBOARD_FAB2(SCH_1):UPI_CPU1_CPU0_P1P1_DP(10)
  U5D1  P13 UPI1_RX_DP<9> SKX_EXT_B_BGA1-IC,TBD    I86 @BASEBOARD_FAB2_LIB.BASEBOARD_FAB2(SCH_1):PAGE34
  U2D1  G12 UPI1_TX_DP<10> SKX_EXT_B_BGA1-IC,TBD   I125 @BASEBOARD_FAB2_LIB.BASEBOARD_FAB2(SCH_1):PAGE68

UPI_CPU1_CPU0_P1P1_DP<11> @BASEBOARD_FAB2_LIB.BASEBOARD_FAB2(SCH_1):UPI_CPU1_CPU0_P1P1_DP(11)
  U5D1  M13 UPI1_RX_DP<8> SKX_EXT_B_BGA1-IC,TBD    I86 @BASEBOARD_FAB2_LIB.BASEBOARD_FAB2(SCH_1):PAGE34
  U2D1  G14 UPI1_TX_DN<11> SKX_EXT_B_BGA1-IC,TBD   I125 @BASEBOARD_FAB2_LIB.BASEBOARD_FAB2(SCH_1):PAGE68

UPI_CPU1_CPU0_P1P1_DP<12> @BASEBOARD_FAB2_LIB.BASEBOARD_FAB2(SCH_1):UPI_CPU1_CPU0_P1P1_DP(12)
  U5D1  N12 UPI1_RX_DP<7> SKX_EXT_B_BGA1-IC,TBD    I86 @BASEBOARD_FAB2_LIB.BASEBOARD_FAB2(SCH_1):PAGE34
  U2D1  E14 UPI1_TX_DP<12> SKX_EXT_B_BGA1-IC,TBD   I125 @BASEBOARD_FAB2_LIB.BASEBOARD_FAB2(SCH_1):PAGE68

UPI_CPU1_CPU0_P1P1_DP<13> @BASEBOARD_FAB2_LIB.BASEBOARD_FAB2(SCH_1):UPI_CPU1_CPU0_P1P1_DP(13)
  U5D1  T11 UPI1_RX_DP<6> SKX_EXT_B_BGA1-IC,TBD    I86 @BASEBOARD_FAB2_LIB.BASEBOARD_FAB2(SCH_1):PAGE34
  U2D1  H15 UPI1_TX_DP<13> SKX_EXT_B_BGA1-IC,TBD   I125 @BASEBOARD_FAB2_LIB.BASEBOARD_FAB2(SCH_1):PAGE68

UPI_CPU1_CPU0_P1P1_DP<14> @BASEBOARD_FAB2_LIB.BASEBOARD_FAB2(SCH_1):UPI_CPU1_CPU0_P1P1_DP(14)
  U5D1  U10 UPI1_RX_DP<5> SKX_EXT_B_BGA1-IC,TBD    I86 @BASEBOARD_FAB2_LIB.BASEBOARD_FAB2(SCH_1):PAGE34
  U2D1  G16 UPI1_TX_DP<14> SKX_EXT_B_BGA1-IC,TBD   I125 @BASEBOARD_FAB2_LIB.BASEBOARD_FAB2(SCH_1):PAGE68

UPI_CPU1_CPU0_P1P1_DP<15> @BASEBOARD_FAB2_LIB.BASEBOARD_FAB2(SCH_1):UPI_CPU1_CPU0_P1P1_DP(15)
  U5D1  N10 UPI1_RX_DP<4> SKX_EXT_B_BGA1-IC,TBD    I86 @BASEBOARD_FAB2_LIB.BASEBOARD_FAB2(SCH_1):PAGE34
  U2D1  L18 UPI1_TX_DP<15> SKX_EXT_B_BGA1-IC,TBD   I125 @BASEBOARD_FAB2_LIB.BASEBOARD_FAB2(SCH_1):PAGE68

UPI_CPU1_CPU0_P1P1_DP<16> @BASEBOARD_FAB2_LIB.BASEBOARD_FAB2(SCH_1):UPI_CPU1_CPU0_P1P1_DP(16)
  U5D1   R8 UPI1_RX_DP<3> SKX_EXT_B_BGA1-IC,TBD    I86 @BASEBOARD_FAB2_LIB.BASEBOARD_FAB2(SCH_1):PAGE34
  U2D1  J18 UPI1_TX_DP<16> SKX_EXT_B_BGA1-IC,TBD   I125 @BASEBOARD_FAB2_LIB.BASEBOARD_FAB2(SCH_1):PAGE68

UPI_CPU1_CPU0_P1P1_DP<17> @BASEBOARD_FAB2_LIB.BASEBOARD_FAB2(SCH_1):UPI_CPU1_CPU0_P1P1_DP(17)
  U5D1   U8 UPI1_RX_DP<2> SKX_EXT_B_BGA1-IC,TBD    I86 @BASEBOARD_FAB2_LIB.BASEBOARD_FAB2(SCH_1):PAGE34
  U2D1  H19 UPI1_TX_DP<17> SKX_EXT_B_BGA1-IC,TBD   I125 @BASEBOARD_FAB2_LIB.BASEBOARD_FAB2(SCH_1):PAGE68

UPI_CPU1_CPU0_P1P1_DP<18> @BASEBOARD_FAB2_LIB.BASEBOARD_FAB2(SCH_1):UPI_CPU1_CPU0_P1P1_DP(18)
  U5D1   T7 UPI1_RX_DP<1> SKX_EXT_B_BGA1-IC,TBD    I86 @BASEBOARD_FAB2_LIB.BASEBOARD_FAB2(SCH_1):PAGE34
  U2D1  F21 UPI1_TX_DN<18> SKX_EXT_B_BGA1-IC,TBD   I125 @BASEBOARD_FAB2_LIB.BASEBOARD_FAB2(SCH_1):PAGE68

UPI_CPU1_CPU0_P1P1_DP<19> @BASEBOARD_FAB2_LIB.BASEBOARD_FAB2(SCH_1):UPI_CPU1_CPU0_P1P1_DP(19)
  U5D1   R6 UPI1_RX_DP<0> SKX_EXT_B_BGA1-IC,TBD    I86 @BASEBOARD_FAB2_LIB.BASEBOARD_FAB2(SCH_1):PAGE34
  U2D1  H21 UPI1_TX_DN<19> SKX_EXT_B_BGA1-IC,TBD   I125 @BASEBOARD_FAB2_LIB.BASEBOARD_FAB2(SCH_1):PAGE68

UPI_CPU1_CPU0_P1P1_DP<1> @BASEBOARD_FAB2_LIB.BASEBOARD_FAB2(SCH_1):UPI_CPU1_CPU0_P1P1_DP(1)
  U5D1  W20 UPI1_RX_DP<18> SKX_EXT_B_BGA1-IC,TBD    I86 @BASEBOARD_FAB2_LIB.BASEBOARD_FAB2(SCH_1):PAGE34
  U2D1   L4 UPI1_TX_DN<1> SKX_EXT_B_BGA1-IC,TBD   I125 @BASEBOARD_FAB2_LIB.BASEBOARD_FAB2(SCH_1):PAGE68

UPI_CPU1_CPU0_P1P1_DP<2> @BASEBOARD_FAB2_LIB.BASEBOARD_FAB2(SCH_1):UPI_CPU1_CPU0_P1P1_DP(2)
  U5D1  Y19 UPI1_RX_DP<17> SKX_EXT_B_BGA1-IC,TBD    I86 @BASEBOARD_FAB2_LIB.BASEBOARD_FAB2(SCH_1):PAGE34
  U2D1   M5 UPI1_TX_DP<2> SKX_EXT_B_BGA1-IC,TBD   I125 @BASEBOARD_FAB2_LIB.BASEBOARD_FAB2(SCH_1):PAGE68

UPI_CPU1_CPU0_P1P1_DP<3> @BASEBOARD_FAB2_LIB.BASEBOARD_FAB2(SCH_1):UPI_CPU1_CPU0_P1P1_DP(3)
  U5D1  T21 UPI1_RX_DP<16> SKX_EXT_B_BGA1-IC,TBD    I86 @BASEBOARD_FAB2_LIB.BASEBOARD_FAB2(SCH_1):PAGE34
  U2D1   H5 UPI1_TX_DP<3> SKX_EXT_B_BGA1-IC,TBD   I125 @BASEBOARD_FAB2_LIB.BASEBOARD_FAB2(SCH_1):PAGE68

UPI_CPU1_CPU0_P1P1_DP<4> @BASEBOARD_FAB2_LIB.BASEBOARD_FAB2(SCH_1):UPI_CPU1_CPU0_P1P1_DP(4)
  U5D1  T19 UPI1_RX_DP<15> SKX_EXT_B_BGA1-IC,TBD    I86 @BASEBOARD_FAB2_LIB.BASEBOARD_FAB2(SCH_1):PAGE34
  U2D1   F7 UPI1_TX_DP<4> SKX_EXT_B_BGA1-IC,TBD   I125 @BASEBOARD_FAB2_LIB.BASEBOARD_FAB2(SCH_1):PAGE68

UPI_CPU1_CPU0_P1P1_DP<5> @BASEBOARD_FAB2_LIB.BASEBOARD_FAB2(SCH_1):UPI_CPU1_CPU0_P1P1_DP(5)
  U5D1  P19 UPI1_RX_DP<14> SKX_EXT_B_BGA1-IC,TBD    I86 @BASEBOARD_FAB2_LIB.BASEBOARD_FAB2(SCH_1):PAGE34
  U2D1   K7 UPI1_TX_DP<5> SKX_EXT_B_BGA1-IC,TBD   I125 @BASEBOARD_FAB2_LIB.BASEBOARD_FAB2(SCH_1):PAGE68

UPI_CPU1_CPU0_P1P1_DP<6> @BASEBOARD_FAB2_LIB.BASEBOARD_FAB2(SCH_1):UPI_CPU1_CPU0_P1P1_DP(6)
  U5D1  V17 UPI1_RX_DP<13> SKX_EXT_B_BGA1-IC,TBD    I86 @BASEBOARD_FAB2_LIB.BASEBOARD_FAB2(SCH_1):PAGE34
  U2D1   K9 UPI1_TX_DN<6> SKX_EXT_B_BGA1-IC,TBD   I125 @BASEBOARD_FAB2_LIB.BASEBOARD_FAB2(SCH_1):PAGE68

UPI_CPU1_CPU0_P1P1_DP<7> @BASEBOARD_FAB2_LIB.BASEBOARD_FAB2(SCH_1):UPI_CPU1_CPU0_P1P1_DP(7)
  U5D1  W16 UPI1_RX_DP<12> SKX_EXT_B_BGA1-IC,TBD    I86 @BASEBOARD_FAB2_LIB.BASEBOARD_FAB2(SCH_1):PAGE34
  U2D1   D9 UPI1_TX_DN<7> SKX_EXT_B_BGA1-IC,TBD   I125 @BASEBOARD_FAB2_LIB.BASEBOARD_FAB2(SCH_1):PAGE68

UPI_CPU1_CPU0_P1P1_DP<8> @BASEBOARD_FAB2_LIB.BASEBOARD_FAB2(SCH_1):UPI_CPU1_CPU0_P1P1_DP(8)
  U5D1  N16 UPI1_RX_DP<11> SKX_EXT_B_BGA1-IC,TBD    I86 @BASEBOARD_FAB2_LIB.BASEBOARD_FAB2(SCH_1):PAGE34
  U2D1  F11 UPI1_TX_DN<8> SKX_EXT_B_BGA1-IC,TBD   I125 @BASEBOARD_FAB2_LIB.BASEBOARD_FAB2(SCH_1):PAGE68

UPI_CPU1_CPU0_P1P1_DP<9> @BASEBOARD_FAB2_LIB.BASEBOARD_FAB2(SCH_1):UPI_CPU1_CPU0_P1P1_DP(9)
  U5D1  T15 UPI1_RX_DP<10> SKX_EXT_B_BGA1-IC,TBD    I86 @BASEBOARD_FAB2_LIB.BASEBOARD_FAB2(SCH_1):PAGE34
  U2D1   H9 UPI1_TX_DP<9> SKX_EXT_B_BGA1-IC,TBD   I125 @BASEBOARD_FAB2_LIB.BASEBOARD_FAB2(SCH_1):PAGE68

USB2_P01_DN @BASEBOARD_FAB2_LIB.BASEBOARD_FAB2(SCH_1):USB2_P01_DN
  U7C1 BY60 USB2N_1 LBG_CORE_QAT_EXT_D_BGA1-IC,H91A    I74 @BASEBOARD_FAB2_LIB.BASEBOARD_FAB2(SCH_1):PAGE115
  R1M6    1      A RES_0402-0.0,5%,1/16W,CHIP,G21A    I31 @BASEBOARD_FAB2_LIB.BASEBOARD_FAB2(SCH_1):PAGE176
  L1M2    1     A1 CHOKE_4PIN_SMLF-90 OHM,IND,752A   I181 @BASEBOARD_FAB2_LIB.BASEBOARD_FAB2(SCH_1):PAGE176

USB2_P01_DP @BASEBOARD_FAB2_LIB.BASEBOARD_FAB2(SCH_1):USB2_P01_DP
  U7C1 BV60 USB2P_1 LBG_CORE_QAT_EXT_D_BGA1-IC,H91A    I74 @BASEBOARD_FAB2_LIB.BASEBOARD_FAB2(SCH_1):PAGE115
  R1M5    1      A RES_0402-0.0,5%,1/16W,CHIP,G21A    I16 @BASEBOARD_FAB2_LIB.BASEBOARD_FAB2(SCH_1):PAGE176
  L1M2    2     A2 CHOKE_4PIN_SMLF-90 OHM,IND,752A   I181 @BASEBOARD_FAB2_LIB.BASEBOARD_FAB2(SCH_1):PAGE176

USB2_P01_ESD_DN @BASEBOARD_FAB2_LIB.BASEBOARD_FAB2(SCH_1):USB2_P01_ESD_DN
  R1M6    2      B RES_0402-0.0,5%,1/16W,CHIP,G21A    I31 @BASEBOARD_FAB2_LIB.BASEBOARD_FAB2(SCH_1):PAGE176
  J9B1    2     DN CONN9_H51826001_PIP2-CONN,H518A    I69 @BASEBOARD_FAB2_LIB.BASEBOARD_FAB2(SCH_1):PAGE176
 CR1M2    2    AC1 DIODEAC_DUAL_ARRAY_SM9-ESD3V3UA    I98 @BASEBOARD_FAB2_LIB.BASEBOARD_FAB2(SCH_1):PAGE176
 CR1M2    8   OUT1 DIODEAC_DUAL_ARRAY_SM9-ESD3V3UA    I98 @BASEBOARD_FAB2_LIB.BASEBOARD_FAB2(SCH_1):PAGE176
  L1M2    4     B2 CHOKE_4PIN_SMLF-90 OHM,IND,752A   I181 @BASEBOARD_FAB2_LIB.BASEBOARD_FAB2(SCH_1):PAGE176

USB2_P01_ESD_DP @BASEBOARD_FAB2_LIB.BASEBOARD_FAB2(SCH_1):USB2_P01_ESD_DP
  R1M5    2      B RES_0402-0.0,5%,1/16W,CHIP,G21A    I16 @BASEBOARD_FAB2_LIB.BASEBOARD_FAB2(SCH_1):PAGE176
  J9B1    3     DP CONN9_H51826001_PIP2-CONN,H518A    I69 @BASEBOARD_FAB2_LIB.BASEBOARD_FAB2(SCH_1):PAGE176
 CR1M2    1    AC0 DIODEAC_DUAL_ARRAY_SM9-ESD3V3UA    I98 @BASEBOARD_FAB2_LIB.BASEBOARD_FAB2(SCH_1):PAGE176
 CR1M2    9   OUT0 DIODEAC_DUAL_ARRAY_SM9-ESD3V3UA    I98 @BASEBOARD_FAB2_LIB.BASEBOARD_FAB2(SCH_1):PAGE176
  L1M2    3     B1 CHOKE_4PIN_SMLF-90 OHM,IND,752A   I181 @BASEBOARD_FAB2_LIB.BASEBOARD_FAB2(SCH_1):PAGE176

USB2_P02_DN @BASEBOARD_FAB2_LIB.BASEBOARD_FAB2(SCH_1):USB2_P02_DN
 CONX8   57     57 SMC-CONN60A-22-GP_CONN-G7-SMC-A    I48 @BASEBOARD_FAB2_LIB.BASEBOARD_FAB2(SCH_1):PAGE245
 R1W19    2      B RES_0402-0.0,5%,1/16W,CHIP,G21A   I122 @BASEBOARD_FAB2_LIB.BASEBOARD_FAB2(SCH_1):PAGE115

USB2_P02_DN_R @BASEBOARD_FAB2_LIB.BASEBOARD_FAB2(SCH_1):USB2_P02_DN_R
  U7C1 CA61 USB2N_2 LBG_CORE_QAT_EXT_D_BGA1-IC,H91A    I74 @BASEBOARD_FAB2_LIB.BASEBOARD_FAB2(SCH_1):PAGE115
 R1W19    1      A RES_0402-0.0,5%,1/16W,CHIP,G21A   I122 @BASEBOARD_FAB2_LIB.BASEBOARD_FAB2(SCH_1):PAGE115

USB2_P02_DP @BASEBOARD_FAB2_LIB.BASEBOARD_FAB2(SCH_1):USB2_P02_DP
 CONX8   59     59 SMC-CONN60A-22-GP_CONN-G7-SMC-A    I48 @BASEBOARD_FAB2_LIB.BASEBOARD_FAB2(SCH_1):PAGE245
 R1W18    2      B RES_0402-0.0,5%,1/16W,CHIP,G21A   I123 @BASEBOARD_FAB2_LIB.BASEBOARD_FAB2(SCH_1):PAGE115

USB2_P02_DP_R @BASEBOARD_FAB2_LIB.BASEBOARD_FAB2(SCH_1):USB2_P02_DP_R
  U7C1 BW61 USB2P_2 LBG_CORE_QAT_EXT_D_BGA1-IC,H91A    I74 @BASEBOARD_FAB2_LIB.BASEBOARD_FAB2(SCH_1):PAGE115
 R1W18    1      A RES_0402-0.0,5%,1/16W,CHIP,G21A   I123 @BASEBOARD_FAB2_LIB.BASEBOARD_FAB2(SCH_1):PAGE115

USB2_PCH_BMC_P5_DN @BASEBOARD_FAB2_LIB.BASEBOARD_FAB2(SCH_1):USB2_PCH_BMC_P5_DN
 U25W4   A6 USB2B_DN AST2520A1-GP-GP_ASIC2-GB1-AST2A   I104 @BASEBOARD_FAB2_LIB.BASEBOARD_FAB2(SCH_1):PAGE146
 R1W15    2      B RES_0402-0.0,5%,1/16W,CHIP,G21A   I119 @BASEBOARD_FAB2_LIB.BASEBOARD_FAB2(SCH_1):PAGE115

USB2_PCH_BMC_P5_DN_R @BASEBOARD_FAB2_LIB.BASEBOARD_FAB2(SCH_1):USB2_PCH_BMC_P5_DN_R
  U7C1 BY58 USB2N_5 LBG_CORE_QAT_EXT_D_BGA1-IC,H91A    I74 @BASEBOARD_FAB2_LIB.BASEBOARD_FAB2(SCH_1):PAGE115
 R1W15    1      A RES_0402-0.0,5%,1/16W,CHIP,G21A   I119 @BASEBOARD_FAB2_LIB.BASEBOARD_FAB2(SCH_1):PAGE115

USB2_PCH_BMC_P5_DP @BASEBOARD_FAB2_LIB.BASEBOARD_FAB2(SCH_1):USB2_PCH_BMC_P5_DP
 U25W4   B6 USB2B_DP AST2520A1-GP-GP_ASIC2-GB1-AST2A   I104 @BASEBOARD_FAB2_LIB.BASEBOARD_FAB2(SCH_1):PAGE146
 R1W14    2      B RES_0402-0.0,5%,1/16W,CHIP,G21A   I118 @BASEBOARD_FAB2_LIB.BASEBOARD_FAB2(SCH_1):PAGE115

USB2_PCH_BMC_P5_DP_R @BASEBOARD_FAB2_LIB.BASEBOARD_FAB2(SCH_1):USB2_PCH_BMC_P5_DP_R
  U7C1 BV58 USB2P_5 LBG_CORE_QAT_EXT_D_BGA1-IC,H91A    I74 @BASEBOARD_FAB2_LIB.BASEBOARD_FAB2(SCH_1):PAGE115
 R1W14    1      A RES_0402-0.0,5%,1/16W,CHIP,G21A   I118 @BASEBOARD_FAB2_LIB.BASEBOARD_FAB2(SCH_1):PAGE115

USB3_P01_C_TXN @BASEBOARD_FAB2_LIB.BASEBOARD_FAB2(SCH_1):USB3_P01_C_TXN
 L30W2    4      4 CHOKE_4PIN_SM_B-67 OHM,EMPTY,7A    I11 @BASEBOARD_FAB2_LIB.BASEBOARD_FAB2(SCH_1):PAGE253
 R30W3    1      A RES_0402-0.0,5%,1/16W,CHIP,G21A    I15 @BASEBOARD_FAB2_LIB.BASEBOARD_FAB2(SCH_1):PAGE253
 C30W1    2      B CAP_A_0402V-0.1UF,16V,10%,X7R,A    I20 @BASEBOARD_FAB2_LIB.BASEBOARD_FAB2(SCH_1):PAGE253

USB3_P01_C_TXP @BASEBOARD_FAB2_LIB.BASEBOARD_FAB2(SCH_1):USB3_P01_C_TXP
 L30W2    1      1 CHOKE_4PIN_SM_B-67 OHM,EMPTY,7A    I11 @BASEBOARD_FAB2_LIB.BASEBOARD_FAB2(SCH_1):PAGE253
 R30W4    1      A RES_0402-0.0,5%,1/16W,CHIP,G21A    I14 @BASEBOARD_FAB2_LIB.BASEBOARD_FAB2(SCH_1):PAGE253
 C30W2    2      B CAP_A_0402V-0.1UF,16V,10%,X7R,A    I19 @BASEBOARD_FAB2_LIB.BASEBOARD_FAB2(SCH_1):PAGE253

USB3_P01_FB_RXN @BASEBOARD_FAB2_LIB.BASEBOARD_FAB2(SCH_1):USB3_P01_FB_RXN
CR30W1    4    AC2 DIODEAC_DUAL_ARRAY_SM9-ESD3V3UA     I5 @BASEBOARD_FAB2_LIB.BASEBOARD_FAB2(SCH_1):PAGE253
CR30W1    7   OUT2 DIODEAC_DUAL_ARRAY_SM9-ESD3V3UA     I5 @BASEBOARD_FAB2_LIB.BASEBOARD_FAB2(SCH_1):PAGE253
 R30W1    2      B RES_0402-0.0,5%,1/16W,CHIP,G21A    I13 @BASEBOARD_FAB2_LIB.BASEBOARD_FAB2(SCH_1):PAGE253
 L30W1    3      3 CHOKE_4PIN_SM_B-67 OHM,EMPTY,7A    I16 @BASEBOARD_FAB2_LIB.BASEBOARD_FAB2(SCH_1):PAGE253
 J30W1  B10 SSRXN1 SKT-USB32-8-GP_SOCKET-G4-SKT-UA    I26 @BASEBOARD_FAB2_LIB.BASEBOARD_FAB2(SCH_1):PAGE253

USB3_P01_FB_RXP @BASEBOARD_FAB2_LIB.BASEBOARD_FAB2(SCH_1):USB3_P01_FB_RXP
CR30W1    5    AC3 DIODEAC_DUAL_ARRAY_SM9-ESD3V3UA     I5 @BASEBOARD_FAB2_LIB.BASEBOARD_FAB2(SCH_1):PAGE253
CR30W1    6   OUT3 DIODEAC_DUAL_ARRAY_SM9-ESD3V3UA     I5 @BASEBOARD_FAB2_LIB.BASEBOARD_FAB2(SCH_1):PAGE253
 R30W2    2      B RES_0402-0.0,5%,1/16W,CHIP,G21A    I12 @BASEBOARD_FAB2_LIB.BASEBOARD_FAB2(SCH_1):PAGE253
 L30W1    2      2 CHOKE_4PIN_SM_B-67 OHM,EMPTY,7A    I16 @BASEBOARD_FAB2_LIB.BASEBOARD_FAB2(SCH_1):PAGE253
 J30W1  B11 SSRXP1 SKT-USB32-8-GP_SOCKET-G4-SKT-UA    I26 @BASEBOARD_FAB2_LIB.BASEBOARD_FAB2(SCH_1):PAGE253

USB3_P01_FB_TXN @BASEBOARD_FAB2_LIB.BASEBOARD_FAB2(SCH_1):USB3_P01_FB_TXN
CR30W1    1    AC0 DIODEAC_DUAL_ARRAY_SM9-ESD3V3UA     I5 @BASEBOARD_FAB2_LIB.BASEBOARD_FAB2(SCH_1):PAGE253
CR30W1    9   OUT0 DIODEAC_DUAL_ARRAY_SM9-ESD3V3UA     I5 @BASEBOARD_FAB2_LIB.BASEBOARD_FAB2(SCH_1):PAGE253
 L30W2    3      3 CHOKE_4PIN_SM_B-67 OHM,EMPTY,7A    I11 @BASEBOARD_FAB2_LIB.BASEBOARD_FAB2(SCH_1):PAGE253
 R30W3    2      B RES_0402-0.0,5%,1/16W,CHIP,G21A    I15 @BASEBOARD_FAB2_LIB.BASEBOARD_FAB2(SCH_1):PAGE253
 J30W1   A3 SSTXN1 SKT-USB32-8-GP_SOCKET-G4-SKT-UA    I26 @BASEBOARD_FAB2_LIB.BASEBOARD_FAB2(SCH_1):PAGE253

USB3_P01_FB_TXP @BASEBOARD_FAB2_LIB.BASEBOARD_FAB2(SCH_1):USB3_P01_FB_TXP
CR30W1    2    AC1 DIODEAC_DUAL_ARRAY_SM9-ESD3V3UA     I5 @BASEBOARD_FAB2_LIB.BASEBOARD_FAB2(SCH_1):PAGE253
CR30W1    8   OUT1 DIODEAC_DUAL_ARRAY_SM9-ESD3V3UA     I5 @BASEBOARD_FAB2_LIB.BASEBOARD_FAB2(SCH_1):PAGE253
 L30W2    2      2 CHOKE_4PIN_SM_B-67 OHM,EMPTY,7A    I11 @BASEBOARD_FAB2_LIB.BASEBOARD_FAB2(SCH_1):PAGE253
 R30W4    2      B RES_0402-0.0,5%,1/16W,CHIP,G21A    I14 @BASEBOARD_FAB2_LIB.BASEBOARD_FAB2(SCH_1):PAGE253
 J30W1   A2 SSTXP1 SKT-USB32-8-GP_SOCKET-G4-SKT-UA    I26 @BASEBOARD_FAB2_LIB.BASEBOARD_FAB2(SCH_1):PAGE253

USB3_P01_RXN @BASEBOARD_FAB2_LIB.BASEBOARD_FAB2(SCH_1):USB3_P01_RXN
  U7C1 BK71 USB3_1_RXN LBG_CORE_QAT_EXT_D_BGA1-IC,H91A    I74 @BASEBOARD_FAB2_LIB.BASEBOARD_FAB2(SCH_1):PAGE115
 R30W1    1      A RES_0402-0.0,5%,1/16W,CHIP,G21A    I13 @BASEBOARD_FAB2_LIB.BASEBOARD_FAB2(SCH_1):PAGE253
 L30W1    4      4 CHOKE_4PIN_SM_B-67 OHM,EMPTY,7A    I16 @BASEBOARD_FAB2_LIB.BASEBOARD_FAB2(SCH_1):PAGE253

USB3_P01_RXP @BASEBOARD_FAB2_LIB.BASEBOARD_FAB2(SCH_1):USB3_P01_RXP
  U7C1 BK69 USB3_1_RXP LBG_CORE_QAT_EXT_D_BGA1-IC,H91A    I74 @BASEBOARD_FAB2_LIB.BASEBOARD_FAB2(SCH_1):PAGE115
 R30W2    1      A RES_0402-0.0,5%,1/16W,CHIP,G21A    I12 @BASEBOARD_FAB2_LIB.BASEBOARD_FAB2(SCH_1):PAGE253
 L30W1    1      1 CHOKE_4PIN_SM_B-67 OHM,EMPTY,7A    I16 @BASEBOARD_FAB2_LIB.BASEBOARD_FAB2(SCH_1):PAGE253

USB3_P01_TXN @BASEBOARD_FAB2_LIB.BASEBOARD_FAB2(SCH_1):USB3_P01_TXN
  U7C1 BL52 USB3_1_TXN LBG_CORE_QAT_EXT_D_BGA1-IC,H91A    I74 @BASEBOARD_FAB2_LIB.BASEBOARD_FAB2(SCH_1):PAGE115
 C30W1    1      A CAP_A_0402V-0.1UF,16V,10%,X7R,A    I20 @BASEBOARD_FAB2_LIB.BASEBOARD_FAB2(SCH_1):PAGE253

USB3_P01_TXP @BASEBOARD_FAB2_LIB.BASEBOARD_FAB2(SCH_1):USB3_P01_TXP
  U7C1 BK54 USB3_1_TXP LBG_CORE_QAT_EXT_D_BGA1-IC,H91A    I74 @BASEBOARD_FAB2_LIB.BASEBOARD_FAB2(SCH_1):PAGE115
 C30W2    1      A CAP_A_0402V-0.1UF,16V,10%,X7R,A    I19 @BASEBOARD_FAB2_LIB.BASEBOARD_FAB2(SCH_1):PAGE253

USB_PCH_BMC_P4_DN @BASEBOARD_FAB2_LIB.BASEBOARD_FAB2(SCH_1):USB_PCH_BMC_P4_DN
 U25W4   A8 USB2A_DN AST2520A1-GP-GP_ASIC2-GB1-AST2A   I104 @BASEBOARD_FAB2_LIB.BASEBOARD_FAB2(SCH_1):PAGE146
 R1W17    2      B RES_0402-0.0,5%,1/16W,CHIP,G21A   I120 @BASEBOARD_FAB2_LIB.BASEBOARD_FAB2(SCH_1):PAGE115

USB_PCH_BMC_P4_DN_R @BASEBOARD_FAB2_LIB.BASEBOARD_FAB2(SCH_1):USB_PCH_BMC_P4_DN_R
  U7C1 BY62 USB2N_4 LBG_CORE_QAT_EXT_D_BGA1-IC,H91A    I74 @BASEBOARD_FAB2_LIB.BASEBOARD_FAB2(SCH_1):PAGE115
 R1W17    1      A RES_0402-0.0,5%,1/16W,CHIP,G21A   I120 @BASEBOARD_FAB2_LIB.BASEBOARD_FAB2(SCH_1):PAGE115

USB_PCH_BMC_P4_DP @BASEBOARD_FAB2_LIB.BASEBOARD_FAB2(SCH_1):USB_PCH_BMC_P4_DP
 U25W4   A7 USB2A_DP AST2520A1-GP-GP_ASIC2-GB1-AST2A   I104 @BASEBOARD_FAB2_LIB.BASEBOARD_FAB2(SCH_1):PAGE146
 R1W16    2      B RES_0402-0.0,5%,1/16W,CHIP,G21A   I121 @BASEBOARD_FAB2_LIB.BASEBOARD_FAB2(SCH_1):PAGE115

USB_PCH_BMC_P4_DP_R @BASEBOARD_FAB2_LIB.BASEBOARD_FAB2(SCH_1):USB_PCH_BMC_P4_DP_R
  U7C1 BV62 USB2P_4 LBG_CORE_QAT_EXT_D_BGA1-IC,H91A    I74 @BASEBOARD_FAB2_LIB.BASEBOARD_FAB2(SCH_1):PAGE115
 R1W16    1      A RES_0402-0.0,5%,1/16W,CHIP,G21A   I121 @BASEBOARD_FAB2_LIB.BASEBOARD_FAB2(SCH_1):PAGE115

UV_HIGH_SET @BASEBOARD_FAB2_LIB.BASEBOARD_FAB2(SCH_1):UV_HIGH_SET
  J9G1    3    IO3 CONN12_C73564003_PIP-CONN,C735A   I128 @BASEBOARD_FAB2_LIB.BASEBOARD_FAB2(SCH_1):PAGE137
  Q6W1    1   GATE FET_N_SOT23LF-2N7002,FET,C7925A   I225 @BASEBOARD_FAB2_LIB.BASEBOARD_FAB2(SCH_1):PAGE200
 U25W4  T20 GPIOAA5_VPOR7_NORD5_SALT12 AST2520A1-GP-GP_ASIC2-GB1-AST2A   I104 @BASEBOARD_FAB2_LIB.BASEBOARD_FAB2(SCH_1):PAGE146

UV_HIGH_SET_N @BASEBOARD_FAB2_LIB.BASEBOARD_FAB2(SCH_1):UV_HIGH_SET_N
  Q6W1    3    DRN FET_N_SOT23LF-2N7002,FET,C7925A   I225 @BASEBOARD_FAB2_LIB.BASEBOARD_FAB2(SCH_1):PAGE200
  R6W3    1      1 232KR2F-2-GP_SMD-RG1-232KR2F-2A   I250 @BASEBOARD_FAB2_LIB.BASEBOARD_FAB2(SCH_1):PAGE200

VCCBAT_TW12 @BASEBOARD_FAB2_LIB.BASEBOARD_FAB2(SCH_1):VCCBAT_TW12
R25W59    2      B RES_0402-0.0,5%,1/16W,CHIP,G21A    I16 @BASEBOARD_FAB2_LIB.BASEBOARD_FAB2(SCH_1):PAGE148
 U25W4   E4 BATVDD AST2520A1-GP-GP_ASIC2-GB1-AST2A    I28 @BASEBOARD_FAB2_LIB.BASEBOARD_FAB2(SCH_1):PAGE148

VCC_ADCAV3V3 @BASEBOARD_FAB2_LIB.BASEBOARD_FAB2(SCH_1):VCC_ADCAV3V3
 U25W4   J6 ADCAV33 AST2520A1-GP-GP_ASIC2-GB1-AST2A    I28 @BASEBOARD_FAB2_LIB.BASEBOARD_FAB2(SCH_1):PAGE148
 FB2T3    2      2 HCB1608KF-800T30-GP_DISCRET-G9A    I85 @BASEBOARD_FAB2_LIB.BASEBOARD_FAB2(SCH_1):PAGE149
C25W32    1      A CAP_0402-1.0UF,16V,10%,X6S,D97A    I99 @BASEBOARD_FAB2_LIB.BASEBOARD_FAB2(SCH_1):PAGE149
C25W33    1      A CAP_0402-1.0UF,16V,10%,X6S,D97A   I102 @BASEBOARD_FAB2_LIB.BASEBOARD_FAB2(SCH_1):PAGE149
C25W31    1      A CAP_A_0402V-0.1UF,16V,10%,X7R,A   I119 @BASEBOARD_FAB2_LIB.BASEBOARD_FAB2(SCH_1):PAGE149
 C25W7    2      B CAP_A_0402V-0.1UF,16V,10%,X7R,A   I161 @BASEBOARD_FAB2_LIB.BASEBOARD_FAB2(SCH_1):PAGE147

VCC_A_1V1 @BASEBOARD_FAB2_LIB.BASEBOARD_FAB2(SCH_1):VCC_A_1V1
 U25W4   L5 VPLLAV110 AST2520A1-GP-GP_ASIC2-GB1-AST2A    I28 @BASEBOARD_FAB2_LIB.BASEBOARD_FAB2(SCH_1):PAGE148
 U25W4   L6 VPLLAV111 AST2520A1-GP-GP_ASIC2-GB1-AST2A    I28 @BASEBOARD_FAB2_LIB.BASEBOARD_FAB2(SCH_1):PAGE148
C25W39    1      A CAP_0603-4.7UF,6.3V,10%,X6S,E1A    I25 @BASEBOARD_FAB2_LIB.BASEBOARD_FAB2(SCH_1):PAGE149
 FB2T7    2      2 HCB1608KF-800T30-GP_DISCRET-G9A    I42 @BASEBOARD_FAB2_LIB.BASEBOARD_FAB2(SCH_1):PAGE149
C25W37    1      A CAP_0402-1.0UF,16V,10%,X6S,D97A   I113 @BASEBOARD_FAB2_LIB.BASEBOARD_FAB2(SCH_1):PAGE149
C25W38    1      A CAP_A_0402V-0.1UF,16V,10%,X7R,A   I121 @BASEBOARD_FAB2_LIB.BASEBOARD_FAB2(SCH_1):PAGE149

VCC_DACAV3V3 @BASEBOARD_FAB2_LIB.BASEBOARD_FAB2(SCH_1):VCC_DACAV3V3
 U25W4   K6 DACAV33 AST2520A1-GP-GP_ASIC2-GB1-AST2A    I28 @BASEBOARD_FAB2_LIB.BASEBOARD_FAB2(SCH_1):PAGE148
 U25W4   K5 DACDV33 AST2520A1-GP-GP_ASIC2-GB1-AST2A    I28 @BASEBOARD_FAB2_LIB.BASEBOARD_FAB2(SCH_1):PAGE148
C25W36    1      A CAP_0603-4.7UF,6.3V,10%,X6S,E1A    I46 @BASEBOARD_FAB2_LIB.BASEBOARD_FAB2(SCH_1):PAGE149
R25W93    2      B RES_0603-0,5.0%,1/10W,CHIP,G22A    I90 @BASEBOARD_FAB2_LIB.BASEBOARD_FAB2(SCH_1):PAGE149
C25W35    1      A CAP_0402-1.0UF,16V,10%,X6S,D97A   I110 @BASEBOARD_FAB2_LIB.BASEBOARD_FAB2(SCH_1):PAGE149
C25W34    1      A CAP_A_0402V-0.1UF,16V,10%,X7R,A   I120 @BASEBOARD_FAB2_LIB.BASEBOARD_FAB2(SCH_1):PAGE149

VCC_D_3V3 @BASEBOARD_FAB2_LIB.BASEBOARD_FAB2(SCH_1):VCC_D_3V3
 U25W4  L16 PEAV33 AST2520A1-GP-GP_ASIC2-GB1-AST2A    I28 @BASEBOARD_FAB2_LIB.BASEBOARD_FAB2(SCH_1):PAGE148
 U25W4  F12 PV33D0 AST2520A1-GP-GP_ASIC2-GB1-AST2A    I28 @BASEBOARD_FAB2_LIB.BASEBOARD_FAB2(SCH_1):PAGE148
 U25W4  F13 PV33D1 AST2520A1-GP-GP_ASIC2-GB1-AST2A    I28 @BASEBOARD_FAB2_LIB.BASEBOARD_FAB2(SCH_1):PAGE148
 U25W4  F14 PV33D2 AST2520A1-GP-GP_ASIC2-GB1-AST2A    I28 @BASEBOARD_FAB2_LIB.BASEBOARD_FAB2(SCH_1):PAGE148
 U25W4  F15 PV33D3 AST2520A1-GP-GP_ASIC2-GB1-AST2A    I28 @BASEBOARD_FAB2_LIB.BASEBOARD_FAB2(SCH_1):PAGE148
 U25W4  G16 PV33D4 AST2520A1-GP-GP_ASIC2-GB1-AST2A    I28 @BASEBOARD_FAB2_LIB.BASEBOARD_FAB2(SCH_1):PAGE148
 U25W4  H17 PV33D5 AST2520A1-GP-GP_ASIC2-GB1-AST2A    I28 @BASEBOARD_FAB2_LIB.BASEBOARD_FAB2(SCH_1):PAGE148
 U25W4   K7 PV33D6 AST2520A1-GP-GP_ASIC2-GB1-AST2A    I28 @BASEBOARD_FAB2_LIB.BASEBOARD_FAB2(SCH_1):PAGE148
 U25W4  N17 PV33D7 AST2520A1-GP-GP_ASIC2-GB1-AST2A    I28 @BASEBOARD_FAB2_LIB.BASEBOARD_FAB2(SCH_1):PAGE148
 U25W4   N6 PV33D8 AST2520A1-GP-GP_ASIC2-GB1-AST2A    I28 @BASEBOARD_FAB2_LIB.BASEBOARD_FAB2(SCH_1):PAGE148
 U25W4  P17 PV33D9 AST2520A1-GP-GP_ASIC2-GB1-AST2A    I28 @BASEBOARD_FAB2_LIB.BASEBOARD_FAB2(SCH_1):PAGE148
 U25W4   P6 PV33D10 AST2520A1-GP-GP_ASIC2-GB1-AST2A    I28 @BASEBOARD_FAB2_LIB.BASEBOARD_FAB2(SCH_1):PAGE148
 U25W4  R17 PV33D11 AST2520A1-GP-GP_ASIC2-GB1-AST2A    I28 @BASEBOARD_FAB2_LIB.BASEBOARD_FAB2(SCH_1):PAGE148
 U25W4   R6 PV33D12 AST2520A1-GP-GP_ASIC2-GB1-AST2A    I28 @BASEBOARD_FAB2_LIB.BASEBOARD_FAB2(SCH_1):PAGE148
 U25W4  T15 PV33D14 AST2520A1-GP-GP_ASIC2-GB1-AST2A    I28 @BASEBOARD_FAB2_LIB.BASEBOARD_FAB2(SCH_1):PAGE148
C25W47    1      A CAP_0603-4.7UF,6.3V,10%,X6S,E1A    I50 @BASEBOARD_FAB2_LIB.BASEBOARD_FAB2(SCH_1):PAGE149
C25W46    1      A CAP_0805-10UF,16V,10%,X6S,C953A    I51 @BASEBOARD_FAB2_LIB.BASEBOARD_FAB2(SCH_1):PAGE149
 FB2T4    2      2 HCB1608KF-800T30-GP_DISCRET-G9A    I86 @BASEBOARD_FAB2_LIB.BASEBOARD_FAB2(SCH_1):PAGE149
C25W40    1      A CAP_0402-1.0UF,16V,10%,X6S,D97A    I96 @BASEBOARD_FAB2_LIB.BASEBOARD_FAB2(SCH_1):PAGE149
C25W41    1      A CAP_0402-1.0UF,16V,10%,X6S,D97A    I97 @BASEBOARD_FAB2_LIB.BASEBOARD_FAB2(SCH_1):PAGE149
C25W42    1      A CAP_0402-1.0UF,16V,10%,X6S,D97A    I98 @BASEBOARD_FAB2_LIB.BASEBOARD_FAB2(SCH_1):PAGE149
C25W43    1      A CAP_0402-1.0UF,16V,10%,X6S,D97A   I100 @BASEBOARD_FAB2_LIB.BASEBOARD_FAB2(SCH_1):PAGE149
C25W44    1      A CAP_0402-1.0UF,16V,10%,X6S,D97A   I101 @BASEBOARD_FAB2_LIB.BASEBOARD_FAB2(SCH_1):PAGE149
C25W45    1      A CAP_A_0402V-0.1UF,16V,10%,X7R,A   I122 @BASEBOARD_FAB2_LIB.BASEBOARD_FAB2(SCH_1):PAGE149

VCC_PA_3V3 @BASEBOARD_FAB2_LIB.BASEBOARD_FAB2(SCH_1):VCC_PA_3V3
 U25W4  Y17 PLLAV330 AST2520A1-GP-GP_ASIC2-GB1-AST2A    I28 @BASEBOARD_FAB2_LIB.BASEBOARD_FAB2(SCH_1):PAGE148
 U25W4  W17 PLLAV331 AST2520A1-GP-GP_ASIC2-GB1-AST2A    I28 @BASEBOARD_FAB2_LIB.BASEBOARD_FAB2(SCH_1):PAGE148
 U25W4  T11 PV33D13 AST2520A1-GP-GP_ASIC2-GB1-AST2A    I28 @BASEBOARD_FAB2_LIB.BASEBOARD_FAB2(SCH_1):PAGE148
C25W59    1      A CAP_0603-4.7UF,6.3V,10%,X6S,E1A    I79 @BASEBOARD_FAB2_LIB.BASEBOARD_FAB2(SCH_1):PAGE149
 FB2T5    2      2 HCB1608KF-800T30-GP_DISCRET-G9A    I88 @BASEBOARD_FAB2_LIB.BASEBOARD_FAB2(SCH_1):PAGE149
C25W56    1      A CAP_0402-1.0UF,16V,10%,X6S,D97A    I93 @BASEBOARD_FAB2_LIB.BASEBOARD_FAB2(SCH_1):PAGE149
C25W58    1      A CAP_A_0402V-0.1UF,16V,10%,X7R,A   I125 @BASEBOARD_FAB2_LIB.BASEBOARD_FAB2(SCH_1):PAGE149
C25W57    1      A CAP_0402LF-100.0PF,50V,5%,COG,A   I130 @BASEBOARD_FAB2_LIB.BASEBOARD_FAB2(SCH_1):PAGE149

VCC_VA_3V3 @BASEBOARD_FAB2_LIB.BASEBOARD_FAB2(SCH_1):VCC_VA_3V3
 U25W4   J7 VPLLAV330 AST2520A1-GP-GP_ASIC2-GB1-AST2A    I28 @BASEBOARD_FAB2_LIB.BASEBOARD_FAB2(SCH_1):PAGE148
 U25W4   H7 VPLLAV331 AST2520A1-GP-GP_ASIC2-GB1-AST2A    I28 @BASEBOARD_FAB2_LIB.BASEBOARD_FAB2(SCH_1):PAGE148
C25W69    1      A CAP_0603-4.7UF,6.3V,10%,X6S,E1A    I17 @BASEBOARD_FAB2_LIB.BASEBOARD_FAB2(SCH_1):PAGE149
 FB2T1    2      2 HCB1608KF-800T30-GP_DISCRET-G9A    I22 @BASEBOARD_FAB2_LIB.BASEBOARD_FAB2(SCH_1):PAGE149
C25W66    1      A CAP_0402-1.0UF,16V,10%,X6S,D97A   I116 @BASEBOARD_FAB2_LIB.BASEBOARD_FAB2(SCH_1):PAGE149
C25W67    1      A CAP_0402-1.0UF,16V,10%,X6S,D97A   I117 @BASEBOARD_FAB2_LIB.BASEBOARD_FAB2(SCH_1):PAGE149
C25W68    1      A CAP_A_0402V-0.1UF,16V,10%,X7R,A   I128 @BASEBOARD_FAB2_LIB.BASEBOARD_FAB2(SCH_1):PAGE149

VGA_REAR_HSYNC_S @BASEBOARD_FAB2_LIB.BASEBOARD_FAB2(SCH_1):VGA_REAR_HSYNC_S
R25W138    1      A RES_0402-33.2,1%,1/16W,CHIP,G2A    I49 @BASEBOARD_FAB2_LIB.BASEBOARD_FAB2(SCH_1):PAGE255
 U25W7    4      Y U74AHCT1G125G-AL5-R-GP-U_TTL-GA   I111 @BASEBOARD_FAB2_LIB.BASEBOARD_FAB2(SCH_1):PAGE255

VGA_REAR_VSYNC_S @BASEBOARD_FAB2_LIB.BASEBOARD_FAB2(SCH_1):VGA_REAR_VSYNC_S
R25W139    1      A RES_0402-33.2,1%,1/16W,CHIP,G2A    I59 @BASEBOARD_FAB2_LIB.BASEBOARD_FAB2(SCH_1):PAGE255
 U25W8    4      Y U74AHCT1G125G-AL5-R-GP-U_TTL-GA   I112 @BASEBOARD_FAB2_LIB.BASEBOARD_FAB2(SCH_1):PAGE255

VID_PCH_CORE_PVNN_AUX_VID_0 @BASEBOARD_FAB2_LIB.BASEBOARD_FAB2(SCH_1):VID_PCH_CORE_PVNN_AUX_VID_0
  U7C1  BL7 GPP_B0_CORE_VID0 LBG_CORE_QAT_EXT_D_BGA1-IC,H91A   I115 @BASEBOARD_FAB2_LIB.BASEBOARD_FAB2(SCH_1):PAGE119
 EU8A1   13    MP0 PXE1110B_QFN-IC,H89187-001   I229 @BASEBOARD_FAB2_LIB.BASEBOARD_FAB2(SCH_1):PAGE235
 R2L26    2      B RES_0402-100.0K,1%,1/16W,CHIP,A   I253 @BASEBOARD_FAB2_LIB.BASEBOARD_FAB2(SCH_1):PAGE235

VID_PCH_CORE_PVNN_AUX_VID_1 @BASEBOARD_FAB2_LIB.BASEBOARD_FAB2(SCH_1):VID_PCH_CORE_PVNN_AUX_VID_1
  U7C1  BH9 GPP_B1_CORE_VID1 LBG_CORE_QAT_EXT_D_BGA1-IC,H91A   I115 @BASEBOARD_FAB2_LIB.BASEBOARD_FAB2(SCH_1):PAGE119
 EU8A1   14    MP1 PXE1110B_QFN-IC,H89187-001   I229 @BASEBOARD_FAB2_LIB.BASEBOARD_FAB2(SCH_1):PAGE235
 R2L25    2      B RES_0402-100.0K,1%,1/16W,CHIP,A   I252 @BASEBOARD_FAB2_LIB.BASEBOARD_FAB2(SCH_1):PAGE235

VREF_2V2 @BASEBOARD_FAB2_LIB.BASEBOARD_FAB2(SCH_1):VREF_2V2
  R3W9    1      A RES_0402-10.0K,1%,1/16W,CHIP,GA     I7 @BASEBOARD_FAB2_LIB.BASEBOARD_FAB2(SCH_1):PAGE249
  R3W7    2      B RES_0402-4.75K,1%,1/16W,CHIP,GA     I8 @BASEBOARD_FAB2_LIB.BASEBOARD_FAB2(SCH_1):PAGE249
  Q9W4    3    -IN LMV331IDCKRG4-GP_DISCRET-G-LMVA    I15 @BASEBOARD_FAB2_LIB.BASEBOARD_FAB2(SCH_1):PAGE249

VREF_LMV431_1V42 @BASEBOARD_FAB2_LIB.BASEBOARD_FAB2(SCH_1):VREF_LMV431_1V42
 R32W3    1      A RES_0402-3.3K,5%,1/16W,CHIP,G2A   I206 @BASEBOARD_FAB2_LIB.BASEBOARD_FAB2(SCH_1):PAGE185
 R32W2    2      B RES_0402-1.5K,1%,1/16W,CHIP,G2A   I207 @BASEBOARD_FAB2_LIB.BASEBOARD_FAB2(SCH_1):PAGE185
VR32W1    1    REF LMV431AIMFX-GP_DISCRET-G5-LMV4A   I213 @BASEBOARD_FAB2_LIB.BASEBOARD_FAB2(SCH_1):PAGE185

VR_COMP_PVPP_ABC @BASEBOARD_FAB2_LIB.BASEBOARD_FAB2(SCH_1):VR_COMP_PVPP_ABC
 R7F17    2      B RES_0402-1.0K,0.1%,1/16W,CHIP,A   I218 @BASEBOARD_FAB2_LIB.BASEBOARD_FAB2(SCH_1):PAGE231
 C7F13    1      A CAP_0402LF-2200PF,50V,10%,X7R,A   I219 @BASEBOARD_FAB2_LIB.BASEBOARD_FAB2(SCH_1):PAGE231

VR_COMP_PVPP_ABC_3 @BASEBOARD_FAB2_LIB.BASEBOARD_FAB2(SCH_1):VR_COMP_PVPP_ABC_3
 EU7F1    3   COMP NCP3232L_SM-IC,H86355-001   I193 @BASEBOARD_FAB2_LIB.BASEBOARD_FAB2(SCH_1):PAGE231
  C7F9    2      B CAP_0402LF-100.0PF,50V,5%,COG,A   I199 @BASEBOARD_FAB2_LIB.BASEBOARD_FAB2(SCH_1):PAGE231
 C7F12    2      B CAP_0402LF-2200PF,50V,10%,X7R,A   I200 @BASEBOARD_FAB2_LIB.BASEBOARD_FAB2(SCH_1):PAGE231

VR_COMP_PVPP_DEF @BASEBOARD_FAB2_LIB.BASEBOARD_FAB2(SCH_1):VR_COMP_PVPP_DEF
 R7B18    2      B RES_0402-1.0K,0.1%,1/16W,CHIP,A   I298 @BASEBOARD_FAB2_LIB.BASEBOARD_FAB2(SCH_1):PAGE232
 C7B13    1      A CAP_0402LF-2200PF,50V,10%,X7R,A   I302 @BASEBOARD_FAB2_LIB.BASEBOARD_FAB2(SCH_1):PAGE232

VR_COMP_PVPP_DEF_3 @BASEBOARD_FAB2_LIB.BASEBOARD_FAB2(SCH_1):VR_COMP_PVPP_DEF_3
 EU7B1    3   COMP NCP3232L_SM-IC,H86355-001   I214 @BASEBOARD_FAB2_LIB.BASEBOARD_FAB2(SCH_1):PAGE232
 C7B10    2      B CAP_0402LF-100.0PF,50V,5%,COG,A   I301 @BASEBOARD_FAB2_LIB.BASEBOARD_FAB2(SCH_1):PAGE232
 C7B14    2      B CAP_0402LF-2200PF,50V,10%,X7R,A   I306 @BASEBOARD_FAB2_LIB.BASEBOARD_FAB2(SCH_1):PAGE232

VR_COMP_PVPP_GHJ @BASEBOARD_FAB2_LIB.BASEBOARD_FAB2(SCH_1):VR_COMP_PVPP_GHJ
 R4G10    2      B RES_0402-1.0K,0.1%,1/16W,CHIP,A   I266 @BASEBOARD_FAB2_LIB.BASEBOARD_FAB2(SCH_1):PAGE233
 C4G11    1      A CAP_0402LF-2200PF,50V,10%,X7R,A   I267 @BASEBOARD_FAB2_LIB.BASEBOARD_FAB2(SCH_1):PAGE233

VR_COMP_PVPP_GHJ_3 @BASEBOARD_FAB2_LIB.BASEBOARD_FAB2(SCH_1):VR_COMP_PVPP_GHJ_3
 EU4G1    3   COMP NCP3232L_SM-IC,H86355-001   I225 @BASEBOARD_FAB2_LIB.BASEBOARD_FAB2(SCH_1):PAGE233
  C4G6    2      B CAP_0402LF-100.0PF,50V,5%,COG,A   I273 @BASEBOARD_FAB2_LIB.BASEBOARD_FAB2(SCH_1):PAGE233
 C4G10    2      B CAP_0402LF-2200PF,50V,10%,X7R,A   I274 @BASEBOARD_FAB2_LIB.BASEBOARD_FAB2(SCH_1):PAGE233

VR_COMP_PVPP_KLM @BASEBOARD_FAB2_LIB.BASEBOARD_FAB2(SCH_1):VR_COMP_PVPP_KLM
  C4B7    1      A CAP_0402LF-2200PF,50V,10%,X7R,A   I218 @BASEBOARD_FAB2_LIB.BASEBOARD_FAB2(SCH_1):PAGE234
  R4B9    2      B RES_0402-1.0K,0.1%,1/16W,CHIP,A   I219 @BASEBOARD_FAB2_LIB.BASEBOARD_FAB2(SCH_1):PAGE234

VR_COMP_PVPP_KLM_3 @BASEBOARD_FAB2_LIB.BASEBOARD_FAB2(SCH_1):VR_COMP_PVPP_KLM_3
 EU4A3    3   COMP NCP3232L_SM-IC,H86355-001   I184 @BASEBOARD_FAB2_LIB.BASEBOARD_FAB2(SCH_1):PAGE234
  C4B9    2      B CAP_0402LF-2200PF,50V,10%,X7R,A   I211 @BASEBOARD_FAB2_LIB.BASEBOARD_FAB2(SCH_1):PAGE234
  C4B4    2      B CAP_0402LF-100.0PF,50V,5%,COG,A   I212 @BASEBOARD_FAB2_LIB.BASEBOARD_FAB2(SCH_1):PAGE234

VR_COMP_RC_PVPP_ABC @BASEBOARD_FAB2_LIB.BASEBOARD_FAB2(SCH_1):VR_COMP_RC_PVPP_ABC
 C7F12    1      A CAP_0402LF-2200PF,50V,10%,X7R,A   I200 @BASEBOARD_FAB2_LIB.BASEBOARD_FAB2(SCH_1):PAGE231
 R7F18    1      A RES_0402-7.87K,1.0%,1/16W,CHIPA   I201 @BASEBOARD_FAB2_LIB.BASEBOARD_FAB2(SCH_1):PAGE231

VR_COMP_RC_PVPP_DEF @BASEBOARD_FAB2_LIB.BASEBOARD_FAB2(SCH_1):VR_COMP_RC_PVPP_DEF
 R7B16    1      A RES_0402-7.87K,1.0%,1/16W,CHIPA   I300 @BASEBOARD_FAB2_LIB.BASEBOARD_FAB2(SCH_1):PAGE232
 C7B14    1      A CAP_0402LF-2200PF,50V,10%,X7R,A   I306 @BASEBOARD_FAB2_LIB.BASEBOARD_FAB2(SCH_1):PAGE232

VR_COMP_RC_PVPP_GHJ @BASEBOARD_FAB2_LIB.BASEBOARD_FAB2(SCH_1):VR_COMP_RC_PVPP_GHJ
 R4G13    1      A RES_0402-7.87K,1.0%,1/16W,CHIPA   I272 @BASEBOARD_FAB2_LIB.BASEBOARD_FAB2(SCH_1):PAGE233
 C4G10    1      A CAP_0402LF-2200PF,50V,10%,X7R,A   I274 @BASEBOARD_FAB2_LIB.BASEBOARD_FAB2(SCH_1):PAGE233

VR_COMP_RC_PVPP_KLM @BASEBOARD_FAB2_LIB.BASEBOARD_FAB2(SCH_1):VR_COMP_RC_PVPP_KLM
  C4B9    1      A CAP_0402LF-2200PF,50V,10%,X7R,A   I211 @BASEBOARD_FAB2_LIB.BASEBOARD_FAB2(SCH_1):PAGE234
  R4B8    1      A RES_0402-7.87K,1.0%,1/16W,CHIPA   I213 @BASEBOARD_FAB2_LIB.BASEBOARD_FAB2(SCH_1):PAGE234

VR_FB_PVPP_ABC @BASEBOARD_FAB2_LIB.BASEBOARD_FAB2(SCH_1):VR_FB_PVPP_ABC
 R7F13    2      B RES_0402-20.0K,1%,1/16W,CHIP,GA   I167 @BASEBOARD_FAB2_LIB.BASEBOARD_FAB2(SCH_1):PAGE231
 EU7F1    2     FB NCP3232L_SM-IC,H86355-001   I193 @BASEBOARD_FAB2_LIB.BASEBOARD_FAB2(SCH_1):PAGE231
  C7F9    1      A CAP_0402LF-100.0PF,50V,5%,COG,A   I199 @BASEBOARD_FAB2_LIB.BASEBOARD_FAB2(SCH_1):PAGE231
 R7F18    2      B RES_0402-7.87K,1.0%,1/16W,CHIPA   I201 @BASEBOARD_FAB2_LIB.BASEBOARD_FAB2(SCH_1):PAGE231
 C7F13    2      B CAP_0402LF-2200PF,50V,10%,X7R,A   I219 @BASEBOARD_FAB2_LIB.BASEBOARD_FAB2(SCH_1):PAGE231
 R7F11    1      A RES_0402-6.19K,1%,1/16W,CHIP,GA   I230 @BASEBOARD_FAB2_LIB.BASEBOARD_FAB2(SCH_1):PAGE231

VR_FB_PVPP_DEF @BASEBOARD_FAB2_LIB.BASEBOARD_FAB2(SCH_1):VR_FB_PVPP_DEF
 EU7B1    2     FB NCP3232L_SM-IC,H86355-001   I214 @BASEBOARD_FAB2_LIB.BASEBOARD_FAB2(SCH_1):PAGE232
 R7B16    2      B RES_0402-7.87K,1.0%,1/16W,CHIPA   I300 @BASEBOARD_FAB2_LIB.BASEBOARD_FAB2(SCH_1):PAGE232
 C7B10    1      A CAP_0402LF-100.0PF,50V,5%,COG,A   I301 @BASEBOARD_FAB2_LIB.BASEBOARD_FAB2(SCH_1):PAGE232
 C7B13    2      B CAP_0402LF-2200PF,50V,10%,X7R,A   I302 @BASEBOARD_FAB2_LIB.BASEBOARD_FAB2(SCH_1):PAGE232
 R7B15    2      B RES_0402-20.0K,1%,1/16W,CHIP,GA   I303 @BASEBOARD_FAB2_LIB.BASEBOARD_FAB2(SCH_1):PAGE232
 R7B13    1      A RES_0402-6.19K,1%,1/16W,CHIP,GA   I314 @BASEBOARD_FAB2_LIB.BASEBOARD_FAB2(SCH_1):PAGE232

VR_FB_PVPP_GHJ @BASEBOARD_FAB2_LIB.BASEBOARD_FAB2(SCH_1):VR_FB_PVPP_GHJ
 EU4G1    2     FB NCP3232L_SM-IC,H86355-001   I225 @BASEBOARD_FAB2_LIB.BASEBOARD_FAB2(SCH_1):PAGE233
 C4G11    2      B CAP_0402LF-2200PF,50V,10%,X7R,A   I267 @BASEBOARD_FAB2_LIB.BASEBOARD_FAB2(SCH_1):PAGE233
  R4G7    2      B RES_0402-20.0K,1%,1/16W,CHIP,GA   I270 @BASEBOARD_FAB2_LIB.BASEBOARD_FAB2(SCH_1):PAGE233
 R4G13    2      B RES_0402-7.87K,1.0%,1/16W,CHIPA   I272 @BASEBOARD_FAB2_LIB.BASEBOARD_FAB2(SCH_1):PAGE233
  C4G6    1      A CAP_0402LF-100.0PF,50V,5%,COG,A   I273 @BASEBOARD_FAB2_LIB.BASEBOARD_FAB2(SCH_1):PAGE233
  R4G9    1      A RES_0402-6.19K,1%,1/16W,CHIP,GA   I283 @BASEBOARD_FAB2_LIB.BASEBOARD_FAB2(SCH_1):PAGE233

VR_FB_PVPP_KLM @BASEBOARD_FAB2_LIB.BASEBOARD_FAB2(SCH_1):VR_FB_PVPP_KLM
 EU4A3    2     FB NCP3232L_SM-IC,H86355-001   I184 @BASEBOARD_FAB2_LIB.BASEBOARD_FAB2(SCH_1):PAGE234
  C4B4    1      A CAP_0402LF-100.0PF,50V,5%,COG,A   I212 @BASEBOARD_FAB2_LIB.BASEBOARD_FAB2(SCH_1):PAGE234
  R4B8    2      B RES_0402-7.87K,1.0%,1/16W,CHIPA   I213 @BASEBOARD_FAB2_LIB.BASEBOARD_FAB2(SCH_1):PAGE234
  R4B5    2      B RES_0402-20.0K,1%,1/16W,CHIP,GA   I215 @BASEBOARD_FAB2_LIB.BASEBOARD_FAB2(SCH_1):PAGE234
  C4B7    2      B CAP_0402LF-2200PF,50V,10%,X7R,A   I218 @BASEBOARD_FAB2_LIB.BASEBOARD_FAB2(SCH_1):PAGE234
  R4B4    1      A RES_0402-6.19K,1%,1/16W,CHIP,GA   I227 @BASEBOARD_FAB2_LIB.BASEBOARD_FAB2(SCH_1):PAGE234

VR_FET_SW_P12V_STBY_P3V3_STBY @BASEBOARD_FAB2_LIB.BASEBOARD_FAB2(SCH_1):VR_FET_SW_P12V_STBY_P3V3_STBY
 C8E10    1      A CAP_1206LF-22UF,16V,10%,X6S,D3A   I137 @BASEBOARD_FAB2_LIB.BASEBOARD_FAB2(SCH_1):PAGE240
 C8E14    1      A CAP_0402-1.0UF,16V,10%,X6S,D97A   I139 @BASEBOARD_FAB2_LIB.BASEBOARD_FAB2(SCH_1):PAGE240
 EU8E1    2    VIN CSD87384M_SM-IC,H66258-001   I170 @BASEBOARD_FAB2_LIB.BASEBOARD_FAB2(SCH_1):PAGE240
  C9F1    1      1 SC22U16V5MX-4-GP_SMD-BCG5-SC22A   I181 @BASEBOARD_FAB2_LIB.BASEBOARD_FAB2(SCH_1):PAGE240
C22W11    1      1 SC22U16V5MX-4-GP_SMD-BCG5-SC22A   I182 @BASEBOARD_FAB2_LIB.BASEBOARD_FAB2(SCH_1):PAGE240
 C8E11    1      1 SC22U16V5MX-4-GP_SMD-BCG5-SC22A   I183 @BASEBOARD_FAB2_LIB.BASEBOARD_FAB2(SCH_1):PAGE240
C22W12    1      1 SC22U16V5MX-4-GP_SMD-BCG5-SC22A   I186 @BASEBOARD_FAB2_LIB.BASEBOARD_FAB2(SCH_1):PAGE240
 FB9E1    2      2 BLM31SN500SN1L-GP_DISCRET-GB1-A   I193 @BASEBOARD_FAB2_LIB.BASEBOARD_FAB2(SCH_1):PAGE240

VR_FET_SW_P12V_STBY_PVCCIN_CPU0 @BASEBOARD_FAB2_LIB.BASEBOARD_FAB2(SCH_1):VR_FET_SW_P12V_STBY_PVCCIN_CPU0
 R4D27    1      A RES_0402-100.0K,1%,1/16W,CHIP,B    I54 @BASEBOARD_FAB2_LIB.BASEBOARD_FAB2(SCH_1):PAGE201
 C4E20    1      A CAP_A_0402V-0.1UF,16V,10%,X7R,A    I35 @BASEBOARD_FAB2_LIB.BASEBOARD_FAB2(SCH_1):PAGE202
 C4E19    1      A CAP_0402-1.0UF,16V,10%,X6S,D97A    I36 @BASEBOARD_FAB2_LIB.BASEBOARD_FAB2(SCH_1):PAGE202
 C6R11    1      A CAP_0805-10UF,16V,10%,X6S,C953A    I37 @BASEBOARD_FAB2_LIB.BASEBOARD_FAB2(SCH_1):PAGE202
 C6P13    1      A CAP_0805-10UF,16V,10%,X6S,C953A    I38 @BASEBOARD_FAB2_LIB.BASEBOARD_FAB2(SCH_1):PAGE202
 C6R13    1      A CAP_0805-10UF,16V,10%,X6S,C953A    I42 @BASEBOARD_FAB2_LIB.BASEBOARD_FAB2(SCH_1):PAGE202
 C4D49    1      A CAP_A_0402V-0.1UF,16V,10%,X7R,A    I46 @BASEBOARD_FAB2_LIB.BASEBOARD_FAB2(SCH_1):PAGE202
 C4D48    1      A CAP_0402-1.0UF,16V,10%,X6S,D97A    I47 @BASEBOARD_FAB2_LIB.BASEBOARD_FAB2(SCH_1):PAGE202
  C6R4    1      A CAP_0805-10UF,16V,10%,X6S,C953A    I48 @BASEBOARD_FAB2_LIB.BASEBOARD_FAB2(SCH_1):PAGE202
 C6P22    1      A CAP_0805-10UF,16V,10%,X6S,C953A    I49 @BASEBOARD_FAB2_LIB.BASEBOARD_FAB2(SCH_1):PAGE202
  C6N8    1      A CAP_0805-10UF,16V,10%,X6S,C953A    I51 @BASEBOARD_FAB2_LIB.BASEBOARD_FAB2(SCH_1):PAGE202
 EU4E1   25 VIN<0> IR354XX_SM-IR35411,IC,H73688-0A    I63 @BASEBOARD_FAB2_LIB.BASEBOARD_FAB2(SCH_1):PAGE202
 EU4E1   30 VIN<1> IR354XX_SM-IR35411,IC,H73688-0A    I63 @BASEBOARD_FAB2_LIB.BASEBOARD_FAB2(SCH_1):PAGE202
 EU4D6   25 VIN<0> IR354XX_SM-IR35411,IC,H73688-0A    I64 @BASEBOARD_FAB2_LIB.BASEBOARD_FAB2(SCH_1):PAGE202
 EU4D6   30 VIN<1> IR354XX_SM-IR35411,IC,H73688-0A    I64 @BASEBOARD_FAB2_LIB.BASEBOARD_FAB2(SCH_1):PAGE202
 C6P24    1      A CAP_0805-10UF,16V,10%,X6S,C953A     I1 @BASEBOARD_FAB2_LIB.BASEBOARD_FAB2(SCH_1):PAGE203
  C6R6    1      A CAP_0805-10UF,16V,10%,X6S,C953A     I2 @BASEBOARD_FAB2_LIB.BASEBOARD_FAB2(SCH_1):PAGE203
 C4D35    1      A CAP_A_0402V-0.1UF,16V,10%,X7R,A    I46 @BASEBOARD_FAB2_LIB.BASEBOARD_FAB2(SCH_1):PAGE203
 C4D30    1      A CAP_0402-1.0UF,16V,10%,X6S,D97A    I47 @BASEBOARD_FAB2_LIB.BASEBOARD_FAB2(SCH_1):PAGE203
 C4D11    1      A CAP_A_0402V-0.1UF,16V,10%,X7R,A    I52 @BASEBOARD_FAB2_LIB.BASEBOARD_FAB2(SCH_1):PAGE203
 C4D10    1      A CAP_0402-1.0UF,16V,10%,X6S,D97A    I53 @BASEBOARD_FAB2_LIB.BASEBOARD_FAB2(SCH_1):PAGE203
 C6P19    1      A CAP_0805-10UF,16V,10%,X6S,C953A    I54 @BASEBOARD_FAB2_LIB.BASEBOARD_FAB2(SCH_1):PAGE203
 C6P20    1      A CAP_0805-10UF,16V,10%,X6S,C953A    I57 @BASEBOARD_FAB2_LIB.BASEBOARD_FAB2(SCH_1):PAGE203
 C6P15    1      A CAP_0805-10UF,16V,10%,X6S,C953A    I58 @BASEBOARD_FAB2_LIB.BASEBOARD_FAB2(SCH_1):PAGE203
  C6P7    1      A CAP_0805-10UF,16V,10%,X6S,C953A    I59 @BASEBOARD_FAB2_LIB.BASEBOARD_FAB2(SCH_1):PAGE203
 EU4D3   25 VIN<0> IR354XX_SM-IR35411,IC,H73688-0A    I70 @BASEBOARD_FAB2_LIB.BASEBOARD_FAB2(SCH_1):PAGE203
 EU4D3   30 VIN<1> IR354XX_SM-IR35411,IC,H73688-0A    I70 @BASEBOARD_FAB2_LIB.BASEBOARD_FAB2(SCH_1):PAGE203
 EU4D1   25 VIN<0> IR354XX_SM-IR35411,IC,H73688-0A    I71 @BASEBOARD_FAB2_LIB.BASEBOARD_FAB2(SCH_1):PAGE203
 EU4D1   30 VIN<1> IR354XX_SM-IR35411,IC,H73688-0A    I71 @BASEBOARD_FAB2_LIB.BASEBOARD_FAB2(SCH_1):PAGE203
 C4C19    1      A CAP_A_0402V-0.1UF,16V,10%,X7R,A    I35 @BASEBOARD_FAB2_LIB.BASEBOARD_FAB2(SCH_1):PAGE204
 C4C18    1      A CAP_0402-1.0UF,16V,10%,X6S,D97A    I36 @BASEBOARD_FAB2_LIB.BASEBOARD_FAB2(SCH_1):PAGE204
 C6N10    1      A CAP_0805-10UF,16V,10%,X6S,C953A    I37 @BASEBOARD_FAB2_LIB.BASEBOARD_FAB2(SCH_1):PAGE204
 C6P17    1      A CAP_0805-10UF,16V,10%,X6S,C953A    I38 @BASEBOARD_FAB2_LIB.BASEBOARD_FAB2(SCH_1):PAGE204
 C6N11    1      A CAP_0805-10UF,16V,10%,X6S,C953A    I42 @BASEBOARD_FAB2_LIB.BASEBOARD_FAB2(SCH_1):PAGE204
  C4D2    1      A CAPP_2626-270UF,16V,20%,OSCON,A    I48 @BASEBOARD_FAB2_LIB.BASEBOARD_FAB2(SCH_1):PAGE204
 C4E16    1      A CAPP_2626-270UF,16V,20%,OSCON,A    I50 @BASEBOARD_FAB2_LIB.BASEBOARD_FAB2(SCH_1):PAGE204
 C4C12    1      A CAPP_2626-270UF,16V,20%,OSCON,A    I67 @BASEBOARD_FAB2_LIB.BASEBOARD_FAB2(SCH_1):PAGE204
 EU4C2   25 VIN<0> IR354XX_SM-IR35411,IC,H73688-0A    I71 @BASEBOARD_FAB2_LIB.BASEBOARD_FAB2(SCH_1):PAGE204
 EU4C2   30 VIN<1> IR354XX_SM-IR35411,IC,H73688-0A    I71 @BASEBOARD_FAB2_LIB.BASEBOARD_FAB2(SCH_1):PAGE204
 C4C10    1      A CAP_A_0402V-0.1UF,16V,10%,X7R,A    I31 @BASEBOARD_FAB2_LIB.BASEBOARD_FAB2(SCH_1):PAGE205
  C4C9    1      A CAP_0402-1.0UF,16V,10%,X6S,D97A    I32 @BASEBOARD_FAB2_LIB.BASEBOARD_FAB2(SCH_1):PAGE205
  C6N2    1      A CAP_0805-10UF,16V,10%,X6S,C953A    I33 @BASEBOARD_FAB2_LIB.BASEBOARD_FAB2(SCH_1):PAGE205
  C6N3    1      A CAP_0805-10UF,16V,10%,X6S,C953A    I34 @BASEBOARD_FAB2_LIB.BASEBOARD_FAB2(SCH_1):PAGE205
  C6N6    1      A CAP_0805-10UF,16V,10%,X6S,C953A    I35 @BASEBOARD_FAB2_LIB.BASEBOARD_FAB2(SCH_1):PAGE205
 EU4C1   25 VIN<0> IR354XX_SM-IR35412,IC,H73684-0A    I46 @BASEBOARD_FAB2_LIB.BASEBOARD_FAB2(SCH_1):PAGE205
 EU4C1   30 VIN<1> IR354XX_SM-IR35412,IC,H73684-0A    I46 @BASEBOARD_FAB2_LIB.BASEBOARD_FAB2(SCH_1):PAGE205
 R4D60    1      A RES_0402-100.0K,1%,1/16W,CHIP,B    I31 @BASEBOARD_FAB2_LIB.BASEBOARD_FAB2(SCH_1):PAGE213
 C4E13    1      A CAP_A_0402V-0.1UF,16V,10%,X7R,A    I77 @BASEBOARD_FAB2_LIB.BASEBOARD_FAB2(SCH_1):PAGE214
 C4E15    1      A CAP_0402-1.0UF,16V,10%,X6S,D97A    I79 @BASEBOARD_FAB2_LIB.BASEBOARD_FAB2(SCH_1):PAGE214
 C6R14    1      A CAP_0805-10UF,16V,10%,X6S,C953A    I80 @BASEBOARD_FAB2_LIB.BASEBOARD_FAB2(SCH_1):PAGE214
 C6R10    1      A CAP_0805-10UF,16V,10%,X6S,C953A    I81 @BASEBOARD_FAB2_LIB.BASEBOARD_FAB2(SCH_1):PAGE214
  C6R8    1      A CAP_0805-10UF,16V,10%,X6S,C953A    I83 @BASEBOARD_FAB2_LIB.BASEBOARD_FAB2(SCH_1):PAGE214
 EU4E2   25 VIN<0> IR354XX_SM-IR35412,IC,H73684-0A   I126 @BASEBOARD_FAB2_LIB.BASEBOARD_FAB2(SCH_1):PAGE214
 EU4E2   30 VIN<1> IR354XX_SM-IR35412,IC,H73684-0A   I126 @BASEBOARD_FAB2_LIB.BASEBOARD_FAB2(SCH_1):PAGE214
 C4E14    1      1 SC22U16V5MX-4-GP_SMD-BCG5-SC22A   I148 @BASEBOARD_FAB2_LIB.BASEBOARD_FAB2(SCH_1):PAGE214
C22W13    1      1 SC22U16V5MX-4-GP_SMD-BCG5-SC22A   I149 @BASEBOARD_FAB2_LIB.BASEBOARD_FAB2(SCH_1):PAGE214
C22W14    1      1 SC22U16V5MX-4-GP_SMD-BCG5-SC22A   I152 @BASEBOARD_FAB2_LIB.BASEBOARD_FAB2(SCH_1):PAGE214
C22W15    1      1 SC22U16V5MX-4-GP_SMD-BCG5-SC22A   I154 @BASEBOARD_FAB2_LIB.BASEBOARD_FAB2(SCH_1):PAGE214
C22W18    1      1 SC22U16V5MX-4-GP_SMD-BCG5-SC22A   I156 @BASEBOARD_FAB2_LIB.BASEBOARD_FAB2(SCH_1):PAGE214
C22W17    1      1 SC22U16V5MX-4-GP_SMD-BCG5-SC22A   I158 @BASEBOARD_FAB2_LIB.BASEBOARD_FAB2(SCH_1):PAGE214
C22W16    1      1 SC22U16V5MX-4-GP_SMD-BCG5-SC22A   I160 @BASEBOARD_FAB2_LIB.BASEBOARD_FAB2(SCH_1):PAGE214
  C4E8    1      1 SC22U16V5MX-4-GP_SMD-BCG5-SC22A   I161 @BASEBOARD_FAB2_LIB.BASEBOARD_FAB2(SCH_1):PAGE214
  C4E9    1      1 SC22U16V5MX-4-GP_SMD-BCG5-SC22A   I164 @BASEBOARD_FAB2_LIB.BASEBOARD_FAB2(SCH_1):PAGE214
C22W21    1      1 SC22U16V5MX-4-GP_SMD-BCG5-SC22A   I166 @BASEBOARD_FAB2_LIB.BASEBOARD_FAB2(SCH_1):PAGE214
C22W20    1      1 SC22U16V5MX-4-GP_SMD-BCG5-SC22A   I168 @BASEBOARD_FAB2_LIB.BASEBOARD_FAB2(SCH_1):PAGE214
C22W19    1      1 SC22U16V5MX-4-GP_SMD-BCG5-SC22A   I169 @BASEBOARD_FAB2_LIB.BASEBOARD_FAB2(SCH_1):PAGE214
  L4C1    2      F IND-80NH-1-GP_DISCRET-GC2-IND-A   I105 @BASEBOARD_FAB2_LIB.BASEBOARD_FAB2(SCH_1):PAGE204

VR_FET_SW_P12V_STBY_PVCCIN_CPU1 @BASEBOARD_FAB2_LIB.BASEBOARD_FAB2(SCH_1):VR_FET_SW_P12V_STBY_PVCCIN_CPU1
 R1C13    1      A RES_0402-100.0K,1%,1/16W,CHIP,B    I49 @BASEBOARD_FAB2_LIB.BASEBOARD_FAB2(SCH_1):PAGE206
 EU1E2   25 VIN<0> IR354XX_SM-IR35411,IC,H73688-0A    I20 @BASEBOARD_FAB2_LIB.BASEBOARD_FAB2(SCH_1):PAGE207
 EU1E2   30 VIN<1> IR354XX_SM-IR35411,IC,H73688-0A    I20 @BASEBOARD_FAB2_LIB.BASEBOARD_FAB2(SCH_1):PAGE207
 C1E14    1      A CAP_A_0402V-0.1UF,16V,10%,X7R,A    I33 @BASEBOARD_FAB2_LIB.BASEBOARD_FAB2(SCH_1):PAGE207
 C1E13    1      A CAP_0402-1.0UF,16V,10%,X6S,D97A    I34 @BASEBOARD_FAB2_LIB.BASEBOARD_FAB2(SCH_1):PAGE207
 C1D34    1      A CAP_A_0402V-0.1UF,16V,10%,X7R,A    I41 @BASEBOARD_FAB2_LIB.BASEBOARD_FAB2(SCH_1):PAGE207
 C1D35    1      A CAP_0402-1.0UF,16V,10%,X6S,D97A    I42 @BASEBOARD_FAB2_LIB.BASEBOARD_FAB2(SCH_1):PAGE207
  C9R7    1      A CAP_0805-10UF,16V,10%,X6S,C953A    I43 @BASEBOARD_FAB2_LIB.BASEBOARD_FAB2(SCH_1):PAGE207
 C9R10    1      A CAP_0805-10UF,16V,10%,X6S,C953A    I44 @BASEBOARD_FAB2_LIB.BASEBOARD_FAB2(SCH_1):PAGE207
 C9R11    1      A CAP_0805-10UF,16V,10%,X6S,C953A    I48 @BASEBOARD_FAB2_LIB.BASEBOARD_FAB2(SCH_1):PAGE207
 C9P22    1      A CAP_0805-10UF,16V,10%,X6S,C953A    I50 @BASEBOARD_FAB2_LIB.BASEBOARD_FAB2(SCH_1):PAGE207
 C9P25    1      A CAP_0805-10UF,16V,10%,X6S,C953A    I51 @BASEBOARD_FAB2_LIB.BASEBOARD_FAB2(SCH_1):PAGE207
 C9P26    1      A CAP_0805-10UF,16V,10%,X6S,C953A    I54 @BASEBOARD_FAB2_LIB.BASEBOARD_FAB2(SCH_1):PAGE207
 EU1D3   25 VIN<0> IR354XX_SM-IR35411,IC,H73688-0A    I27 @BASEBOARD_FAB2_LIB.BASEBOARD_FAB2(SCH_1):PAGE208
 EU1D3   30 VIN<1> IR354XX_SM-IR35411,IC,H73688-0A    I27 @BASEBOARD_FAB2_LIB.BASEBOARD_FAB2(SCH_1):PAGE208
 C1D28    1      A CAP_A_0402V-0.1UF,16V,10%,X7R,A    I44 @BASEBOARD_FAB2_LIB.BASEBOARD_FAB2(SCH_1):PAGE208
 C1D23    1      A CAP_0402-1.0UF,16V,10%,X6S,D97A    I45 @BASEBOARD_FAB2_LIB.BASEBOARD_FAB2(SCH_1):PAGE208
 C1D13    1      A CAP_A_0402V-0.1UF,16V,10%,X7R,A    I51 @BASEBOARD_FAB2_LIB.BASEBOARD_FAB2(SCH_1):PAGE208
 C1D12    1      A CAP_0402-1.0UF,16V,10%,X6S,D97A    I52 @BASEBOARD_FAB2_LIB.BASEBOARD_FAB2(SCH_1):PAGE208
  C9P4    1      A CAP_0805-10UF,16V,10%,X6S,C953A    I53 @BASEBOARD_FAB2_LIB.BASEBOARD_FAB2(SCH_1):PAGE208
  C9P7    1      A CAP_0805-10UF,16V,10%,X6S,C953A    I54 @BASEBOARD_FAB2_LIB.BASEBOARD_FAB2(SCH_1):PAGE208
  C9P9    1      A CAP_0805-10UF,16V,10%,X6S,C953A    I55 @BASEBOARD_FAB2_LIB.BASEBOARD_FAB2(SCH_1):PAGE208
 C9P24    1      A CAP_0805-10UF,16V,10%,X6S,C953A    I58 @BASEBOARD_FAB2_LIB.BASEBOARD_FAB2(SCH_1):PAGE208
  C9P1    1      A CAP_0805-10UF,16V,10%,X6S,C953A    I59 @BASEBOARD_FAB2_LIB.BASEBOARD_FAB2(SCH_1):PAGE208
  C9P2    1      A CAP_0805-10UF,16V,10%,X6S,C953A    I60 @BASEBOARD_FAB2_LIB.BASEBOARD_FAB2(SCH_1):PAGE208
 EU1D1   25 VIN<0> IR354XX_SM-IR35411,IC,H73688-0A    I71 @BASEBOARD_FAB2_LIB.BASEBOARD_FAB2(SCH_1):PAGE208
 EU1D1   30 VIN<1> IR354XX_SM-IR35411,IC,H73688-0A    I71 @BASEBOARD_FAB2_LIB.BASEBOARD_FAB2(SCH_1):PAGE208
 C9N27    1      A CAP_0805-10UF,16V,10%,X6S,C953A     I5 @BASEBOARD_FAB2_LIB.BASEBOARD_FAB2(SCH_1):PAGE209
 C9N26    1      A CAP_0805-10UF,16V,10%,X6S,C953A     I7 @BASEBOARD_FAB2_LIB.BASEBOARD_FAB2(SCH_1):PAGE209
 C9N25    1      A CAP_0805-10UF,16V,10%,X6S,C953A     I8 @BASEBOARD_FAB2_LIB.BASEBOARD_FAB2(SCH_1):PAGE209
 C1C26    1      A CAP_0402-1.0UF,16V,10%,X6S,D97A    I16 @BASEBOARD_FAB2_LIB.BASEBOARD_FAB2(SCH_1):PAGE209
 C1C25    1      A CAP_A_0402V-0.1UF,16V,10%,X7R,A    I17 @BASEBOARD_FAB2_LIB.BASEBOARD_FAB2(SCH_1):PAGE209
  C1C1    1      A CAPP_2626-270UF,16V,20%,OSCON,A    I35 @BASEBOARD_FAB2_LIB.BASEBOARD_FAB2(SCH_1):PAGE209
 C1E18    1      A CAPP_2626-270UF,16V,20%,OSCON,A    I37 @BASEBOARD_FAB2_LIB.BASEBOARD_FAB2(SCH_1):PAGE209
  C1C2    1      A CAPP_2626-270UF,16V,20%,OSCON,A    I38 @BASEBOARD_FAB2_LIB.BASEBOARD_FAB2(SCH_1):PAGE209
 EU1C3   25 VIN<0> IR354XX_SM-IR35411,IC,H73688-0A    I56 @BASEBOARD_FAB2_LIB.BASEBOARD_FAB2(SCH_1):PAGE209
 EU1C3   30 VIN<1> IR354XX_SM-IR35411,IC,H73688-0A    I56 @BASEBOARD_FAB2_LIB.BASEBOARD_FAB2(SCH_1):PAGE209
 C1C17    1      A CAP_A_0402V-0.1UF,16V,10%,X7R,A    I27 @BASEBOARD_FAB2_LIB.BASEBOARD_FAB2(SCH_1):PAGE210
 C1C15    1      A CAP_0402-1.0UF,16V,10%,X6S,D97A    I28 @BASEBOARD_FAB2_LIB.BASEBOARD_FAB2(SCH_1):PAGE210
 C9N13    1      A CAP_0805-10UF,16V,10%,X6S,C953A    I35 @BASEBOARD_FAB2_LIB.BASEBOARD_FAB2(SCH_1):PAGE210
 C9N19    1      A CAP_0805-10UF,16V,10%,X6S,C953A    I36 @BASEBOARD_FAB2_LIB.BASEBOARD_FAB2(SCH_1):PAGE210
 C9N21    1      A CAP_0805-10UF,16V,10%,X6S,C953A    I38 @BASEBOARD_FAB2_LIB.BASEBOARD_FAB2(SCH_1):PAGE210
 EU1C1   25 VIN<0> IR354XX_SM-IR35412,IC,H73684-0A    I51 @BASEBOARD_FAB2_LIB.BASEBOARD_FAB2(SCH_1):PAGE210
 EU1C1   30 VIN<1> IR354XX_SM-IR35412,IC,H73684-0A    I51 @BASEBOARD_FAB2_LIB.BASEBOARD_FAB2(SCH_1):PAGE210
  L1B2    2      F IND-80NH-1-GP_DISCRET-GC2-IND-A    I81 @BASEBOARD_FAB2_LIB.BASEBOARD_FAB2(SCH_1):PAGE209
 EU1D4   25 VIN<0> IR354XX_SM-IR35411,IC,H73688-0A   I113 @BASEBOARD_FAB2_LIB.BASEBOARD_FAB2(SCH_1):PAGE207
 EU1D4   30 VIN<1> IR354XX_SM-IR35411,IC,H73688-0A   I113 @BASEBOARD_FAB2_LIB.BASEBOARD_FAB2(SCH_1):PAGE207

VR_FET_SW_P12V_STBY_PVCCIO_CPU0 @BASEBOARD_FAB2_LIB.BASEBOARD_FAB2(SCH_1):VR_FET_SW_P12V_STBY_PVCCIO_CPU0
 R3P12    1      A RES_0402-100.0K,1%,1/16W,CHIP,B    I31 @BASEBOARD_FAB2_LIB.BASEBOARD_FAB2(SCH_1):PAGE211
 C7C11    1      A CAP_A_0402V-0.1UF,16V,10%,X7R,A    I38 @BASEBOARD_FAB2_LIB.BASEBOARD_FAB2(SCH_1):PAGE212
 C7C12    1      A CAP_0402-1.0UF,16V,10%,X6S,D97A    I39 @BASEBOARD_FAB2_LIB.BASEBOARD_FAB2(SCH_1):PAGE212
 C3N36    1      A CAP_0805-10UF,16V,10%,X6S,C953A    I40 @BASEBOARD_FAB2_LIB.BASEBOARD_FAB2(SCH_1):PAGE212
 C3N33    1      A CAP_0805-10UF,16V,10%,X6S,C953A    I41 @BASEBOARD_FAB2_LIB.BASEBOARD_FAB2(SCH_1):PAGE212
 C3N34    1      A CAP_0805-10UF,16V,10%,X6S,C953A    I43 @BASEBOARD_FAB2_LIB.BASEBOARD_FAB2(SCH_1):PAGE212
 EU7C1   25 VIN<0> IR354XX_SM-IR35412,IC,H73684-0A   I101 @BASEBOARD_FAB2_LIB.BASEBOARD_FAB2(SCH_1):PAGE212
 EU7C1   30 VIN<1> IR354XX_SM-IR35412,IC,H73684-0A   I101 @BASEBOARD_FAB2_LIB.BASEBOARD_FAB2(SCH_1):PAGE212
C22W33    1      1 SC22U16V5MX-4-GP_SMD-BCG5-SC22A   I124 @BASEBOARD_FAB2_LIB.BASEBOARD_FAB2(SCH_1):PAGE212
C22W32    1      1 SC22U16V5MX-4-GP_SMD-BCG5-SC22A   I126 @BASEBOARD_FAB2_LIB.BASEBOARD_FAB2(SCH_1):PAGE212
C22W31    1      1 SC22U16V5MX-4-GP_SMD-BCG5-SC22A   I129 @BASEBOARD_FAB2_LIB.BASEBOARD_FAB2(SCH_1):PAGE212
  C7C8    1      1 SC22U16V5MX-4-GP_SMD-BCG5-SC22A   I130 @BASEBOARD_FAB2_LIB.BASEBOARD_FAB2(SCH_1):PAGE212
C22W30    1      1 SC22U16V5MX-4-GP_SMD-BCG5-SC22A   I132 @BASEBOARD_FAB2_LIB.BASEBOARD_FAB2(SCH_1):PAGE212
C22W29    1      1 SC22U16V5MX-4-GP_SMD-BCG5-SC22A   I134 @BASEBOARD_FAB2_LIB.BASEBOARD_FAB2(SCH_1):PAGE212
C22W28    1      1 SC22U16V5MX-4-GP_SMD-BCG5-SC22A   I136 @BASEBOARD_FAB2_LIB.BASEBOARD_FAB2(SCH_1):PAGE212
  C7C7    1      1 SC22U16V5MX-4-GP_SMD-BCG5-SC22A   I138 @BASEBOARD_FAB2_LIB.BASEBOARD_FAB2(SCH_1):PAGE212
  L7C1    2      F IND-100NH-35-GP_DISCRET-G8-INDA   I142 @BASEBOARD_FAB2_LIB.BASEBOARD_FAB2(SCH_1):PAGE212

VR_FET_SW_P12V_STBY_PVDDQ_ABC @BASEBOARD_FAB2_LIB.BASEBOARD_FAB2(SCH_1):VR_FET_SW_P12V_STBY_PVDDQ_ABC
  C3U2    1      A CAP_0805-10UF,16V,10%,X6S,C953A    I45 @BASEBOARD_FAB2_LIB.BASEBOARD_FAB2(SCH_1):PAGE216
  C3U3    1      A CAP_0805-10UF,16V,10%,X6S,C953A    I46 @BASEBOARD_FAB2_LIB.BASEBOARD_FAB2(SCH_1):PAGE216
  C3U4    1      A CAP_0805-10UF,16V,10%,X6S,C953A    I47 @BASEBOARD_FAB2_LIB.BASEBOARD_FAB2(SCH_1):PAGE216
 C7G37    1      A CAP_0402-1.0UF,16V,10%,X6S,D97A    I48 @BASEBOARD_FAB2_LIB.BASEBOARD_FAB2(SCH_1):PAGE216
 C7G29    1      A CAP_A_0402V-0.1UF,16V,10%,X7R,A    I51 @BASEBOARD_FAB2_LIB.BASEBOARD_FAB2(SCH_1):PAGE216
 C7G36    1      A CAP_A_0402V-0.1UF,16V,10%,X7R,A    I78 @BASEBOARD_FAB2_LIB.BASEBOARD_FAB2(SCH_1):PAGE216
 C7G30    1      A CAP_0402-1.0UF,16V,10%,X6S,D97A    I79 @BASEBOARD_FAB2_LIB.BASEBOARD_FAB2(SCH_1):PAGE216
  C3U9    1      A CAP_0805-10UF,16V,10%,X6S,C953A    I80 @BASEBOARD_FAB2_LIB.BASEBOARD_FAB2(SCH_1):PAGE216
  C3U7    1      A CAP_0805-10UF,16V,10%,X6S,C953A    I81 @BASEBOARD_FAB2_LIB.BASEBOARD_FAB2(SCH_1):PAGE216
  C3U6    1      A CAP_0805-10UF,16V,10%,X6S,C953A    I84 @BASEBOARD_FAB2_LIB.BASEBOARD_FAB2(SCH_1):PAGE216
 EU7G2   25 VIN<0> IR354XX_SM-IR35411,IC,H73688-0A   I102 @BASEBOARD_FAB2_LIB.BASEBOARD_FAB2(SCH_1):PAGE216
 EU7G2   30 VIN<1> IR354XX_SM-IR35411,IC,H73688-0A   I102 @BASEBOARD_FAB2_LIB.BASEBOARD_FAB2(SCH_1):PAGE216
 EU7G3   25 VIN<0> IR354XX_SM-IR35411,IC,H73688-0A   I103 @BASEBOARD_FAB2_LIB.BASEBOARD_FAB2(SCH_1):PAGE216
 EU7G3   30 VIN<1> IR354XX_SM-IR35411,IC,H73688-0A   I103 @BASEBOARD_FAB2_LIB.BASEBOARD_FAB2(SCH_1):PAGE216
  C7G2    1      A CAPP_2626-270UF,16V,20%,OSCON,A   I175 @BASEBOARD_FAB2_LIB.BASEBOARD_FAB2(SCH_1):PAGE217
  L7F2    2      F IND-100NH-35-GP_DISCRET-G8-INDA   I261 @BASEBOARD_FAB2_LIB.BASEBOARD_FAB2(SCH_1):PAGE217

VR_FET_SW_P12V_STBY_PVDDQ_DEF @BASEBOARD_FAB2_LIB.BASEBOARD_FAB2(SCH_1):VR_FET_SW_P12V_STBY_PVDDQ_DEF
  C3L2    1      A CAP_0805-10UF,16V,10%,X6S,C953A    I45 @BASEBOARD_FAB2_LIB.BASEBOARD_FAB2(SCH_1):PAGE219
  C3L4    1      A CAP_0805-10UF,16V,10%,X6S,C953A    I46 @BASEBOARD_FAB2_LIB.BASEBOARD_FAB2(SCH_1):PAGE219
 C3L13    1      A CAP_0805-10UF,16V,10%,X6S,C953A    I47 @BASEBOARD_FAB2_LIB.BASEBOARD_FAB2(SCH_1):PAGE219
 C7A11    1      A CAP_0402-1.0UF,16V,10%,X6S,D97A    I48 @BASEBOARD_FAB2_LIB.BASEBOARD_FAB2(SCH_1):PAGE219
  C7A5    1      A CAP_A_0402V-0.1UF,16V,10%,X7R,A    I51 @BASEBOARD_FAB2_LIB.BASEBOARD_FAB2(SCH_1):PAGE219
 C7A20    1      A CAP_A_0402V-0.1UF,16V,10%,X7R,A    I78 @BASEBOARD_FAB2_LIB.BASEBOARD_FAB2(SCH_1):PAGE219
 C7A21    1      A CAP_0402-1.0UF,16V,10%,X6S,D97A    I79 @BASEBOARD_FAB2_LIB.BASEBOARD_FAB2(SCH_1):PAGE219
 C3L17    1      A CAP_0805-10UF,16V,10%,X6S,C953A    I80 @BASEBOARD_FAB2_LIB.BASEBOARD_FAB2(SCH_1):PAGE219
 C3L16    1      A CAP_0805-10UF,16V,10%,X6S,C953A    I81 @BASEBOARD_FAB2_LIB.BASEBOARD_FAB2(SCH_1):PAGE219
 C3L15    1      A CAP_0805-10UF,16V,10%,X6S,C953A    I84 @BASEBOARD_FAB2_LIB.BASEBOARD_FAB2(SCH_1):PAGE219
 EU7A1   25 VIN<0> IR354XX_SM-IR35411,IC,H73688-0A   I106 @BASEBOARD_FAB2_LIB.BASEBOARD_FAB2(SCH_1):PAGE219
 EU7A1   30 VIN<1> IR354XX_SM-IR35411,IC,H73688-0A   I106 @BASEBOARD_FAB2_LIB.BASEBOARD_FAB2(SCH_1):PAGE219
 EU7A4   25 VIN<0> IR354XX_SM-IR35411,IC,H73688-0A   I107 @BASEBOARD_FAB2_LIB.BASEBOARD_FAB2(SCH_1):PAGE219
 EU7A4   30 VIN<1> IR354XX_SM-IR35411,IC,H73688-0A   I107 @BASEBOARD_FAB2_LIB.BASEBOARD_FAB2(SCH_1):PAGE219
  R8A4    1      A RES_0402-100.0K,1%,1/16W,CHIP,B   I165 @BASEBOARD_FAB2_LIB.BASEBOARD_FAB2(SCH_1):PAGE235
 C7A39    1      A CAP_A_0402V-0.1UF,16V,10%,X7R,A    I20 @BASEBOARD_FAB2_LIB.BASEBOARD_FAB2(SCH_1):PAGE236
  C7A7    1      A CAP_0402-1.0UF,16V,10%,X6S,D97A    I22 @BASEBOARD_FAB2_LIB.BASEBOARD_FAB2(SCH_1):PAGE236
 C3L12    1      A CAP_0805-10UF,16V,10%,X6S,C953A    I23 @BASEBOARD_FAB2_LIB.BASEBOARD_FAB2(SCH_1):PAGE236
 C3L11    1      A CAP_0805-10UF,16V,10%,X6S,C953A    I24 @BASEBOARD_FAB2_LIB.BASEBOARD_FAB2(SCH_1):PAGE236
  C3L8    1      A CAP_0805-10UF,16V,10%,X6S,C953A    I26 @BASEBOARD_FAB2_LIB.BASEBOARD_FAB2(SCH_1):PAGE236
  C3L9    1      A CAP_0805-10UF,16V,10%,X6S,C953A    I29 @BASEBOARD_FAB2_LIB.BASEBOARD_FAB2(SCH_1):PAGE236
  C3L7    1      A CAP_0805-10UF,16V,10%,X6S,C953A    I31 @BASEBOARD_FAB2_LIB.BASEBOARD_FAB2(SCH_1):PAGE236
 C3L10    1      A CAP_0805-10UF,16V,10%,X6S,C953A    I32 @BASEBOARD_FAB2_LIB.BASEBOARD_FAB2(SCH_1):PAGE236
  C7A9    1      A CAP_0402-1.0UF,16V,10%,X6S,D97A    I33 @BASEBOARD_FAB2_LIB.BASEBOARD_FAB2(SCH_1):PAGE236
 C7A40    1      A CAP_A_0402V-0.1UF,16V,10%,X7R,A    I35 @BASEBOARD_FAB2_LIB.BASEBOARD_FAB2(SCH_1):PAGE236
 EU7A3   25 VIN<0> IR354XX_SM-IR35412,IC,H73684-0A   I116 @BASEBOARD_FAB2_LIB.BASEBOARD_FAB2(SCH_1):PAGE236
 EU7A3   30 VIN<1> IR354XX_SM-IR35412,IC,H73684-0A   I116 @BASEBOARD_FAB2_LIB.BASEBOARD_FAB2(SCH_1):PAGE236
 EU7A2   25 VIN<0> IR354XX_SM-IR35412,IC,H73684-0A   I117 @BASEBOARD_FAB2_LIB.BASEBOARD_FAB2(SCH_1):PAGE236
 EU7A2   30 VIN<1> IR354XX_SM-IR35412,IC,H73684-0A   I117 @BASEBOARD_FAB2_LIB.BASEBOARD_FAB2(SCH_1):PAGE236
C22W23    1      1 SC22U16V5MX-4-GP_SMD-BCG5-SC22A   I159 @BASEBOARD_FAB2_LIB.BASEBOARD_FAB2(SCH_1):PAGE236
C22W24    1      1 SC22U16V5MX-4-GP_SMD-BCG5-SC22A   I160 @BASEBOARD_FAB2_LIB.BASEBOARD_FAB2(SCH_1):PAGE236
 C7A13    1      1 SC22U16V5MX-4-GP_SMD-BCG5-SC22A   I161 @BASEBOARD_FAB2_LIB.BASEBOARD_FAB2(SCH_1):PAGE236
C22W25    1      1 SC22U16V5MX-4-GP_SMD-BCG5-SC22A   I162 @BASEBOARD_FAB2_LIB.BASEBOARD_FAB2(SCH_1):PAGE236
C22W27    1      1 SC22U16V5MX-4-GP_SMD-BCG5-SC22A   I163 @BASEBOARD_FAB2_LIB.BASEBOARD_FAB2(SCH_1):PAGE236
C22W26    1      1 SC22U16V5MX-4-GP_SMD-BCG5-SC22A   I165 @BASEBOARD_FAB2_LIB.BASEBOARD_FAB2(SCH_1):PAGE236
C22W22    1      1 SC22U16V5MX-4-GP_SMD-BCG5-SC22A   I171 @BASEBOARD_FAB2_LIB.BASEBOARD_FAB2(SCH_1):PAGE236
 C7A14    1      1 SC22U16V5MX-4-GP_SMD-BCG5-SC22A   I172 @BASEBOARD_FAB2_LIB.BASEBOARD_FAB2(SCH_1):PAGE236
  L7A5    2      F IND-100NH-35-GP_DISCRET-G8-INDA   I241 @BASEBOARD_FAB2_LIB.BASEBOARD_FAB2(SCH_1):PAGE220
  C7W5    1      1 SC22U16V5MX-4-GP_SMD-BCG5-SC22A   I298 @BASEBOARD_FAB2_LIB.BASEBOARD_FAB2(SCH_1):PAGE220
  C7W9    1      1 SC22U16V5MX-4-GP_SMD-BCG5-SC22A   I299 @BASEBOARD_FAB2_LIB.BASEBOARD_FAB2(SCH_1):PAGE220
  C7W8    1      1 SC22U16V5MX-4-GP_SMD-BCG5-SC22A   I300 @BASEBOARD_FAB2_LIB.BASEBOARD_FAB2(SCH_1):PAGE220
  C7W7    1      1 SC22U16V5MX-4-GP_SMD-BCG5-SC22A   I301 @BASEBOARD_FAB2_LIB.BASEBOARD_FAB2(SCH_1):PAGE220
  C7W6    1      1 SC22U16V5MX-4-GP_SMD-BCG5-SC22A   I302 @BASEBOARD_FAB2_LIB.BASEBOARD_FAB2(SCH_1):PAGE220
 C7W13    1      1 SC22U16V5MX-4-GP_SMD-BCG5-SC22A   I303 @BASEBOARD_FAB2_LIB.BASEBOARD_FAB2(SCH_1):PAGE220
 C7W12    1      1 SC22U16V5MX-4-GP_SMD-BCG5-SC22A   I304 @BASEBOARD_FAB2_LIB.BASEBOARD_FAB2(SCH_1):PAGE220
 C7W11    1      1 SC22U16V5MX-4-GP_SMD-BCG5-SC22A   I305 @BASEBOARD_FAB2_LIB.BASEBOARD_FAB2(SCH_1):PAGE220
 C7W10    1      1 SC22U16V5MX-4-GP_SMD-BCG5-SC22A   I306 @BASEBOARD_FAB2_LIB.BASEBOARD_FAB2(SCH_1):PAGE220
  C7W2    1      1 SE100U16VM-48-GP_SMD-TCG2-SE10A   I324 @BASEBOARD_FAB2_LIB.BASEBOARD_FAB2(SCH_1):PAGE220

VR_FET_SW_P12V_STBY_PVDDQ_GHJ @BASEBOARD_FAB2_LIB.BASEBOARD_FAB2(SCH_1):VR_FET_SW_P12V_STBY_PVDDQ_GHJ
  C9U6    1      A CAP_0805-10UF,16V,10%,X6S,C953A    I45 @BASEBOARD_FAB2_LIB.BASEBOARD_FAB2(SCH_1):PAGE224
  C9U4    1      A CAP_0805-10UF,16V,10%,X6S,C953A    I46 @BASEBOARD_FAB2_LIB.BASEBOARD_FAB2(SCH_1):PAGE224
  C9T4    1      A CAP_0805-10UF,16V,10%,X6S,C953A    I47 @BASEBOARD_FAB2_LIB.BASEBOARD_FAB2(SCH_1):PAGE224
 C1F27    1      A CAP_0402-1.0UF,16V,10%,X6S,D97A    I48 @BASEBOARD_FAB2_LIB.BASEBOARD_FAB2(SCH_1):PAGE224
 C1G14    1      A CAP_A_0402V-0.1UF,16V,10%,X7R,A    I51 @BASEBOARD_FAB2_LIB.BASEBOARD_FAB2(SCH_1):PAGE224
 C1F28    1      A CAP_A_0402V-0.1UF,16V,10%,X7R,A    I78 @BASEBOARD_FAB2_LIB.BASEBOARD_FAB2(SCH_1):PAGE224
 C1G13    1      A CAP_0402-1.0UF,16V,10%,X6S,D97A    I79 @BASEBOARD_FAB2_LIB.BASEBOARD_FAB2(SCH_1):PAGE224
  C9U3    1      A CAP_0805-10UF,16V,10%,X6S,C953A    I80 @BASEBOARD_FAB2_LIB.BASEBOARD_FAB2(SCH_1):PAGE224
  C9T6    1      A CAP_0805-10UF,16V,10%,X6S,C953A    I81 @BASEBOARD_FAB2_LIB.BASEBOARD_FAB2(SCH_1):PAGE224
  C9T9    1      A CAP_0805-10UF,16V,10%,X6S,C953A    I84 @BASEBOARD_FAB2_LIB.BASEBOARD_FAB2(SCH_1):PAGE224
 EU1G1   25 VIN<0> IR354XX_SM-IR35411,IC,H73688-0A   I110 @BASEBOARD_FAB2_LIB.BASEBOARD_FAB2(SCH_1):PAGE224
 EU1G1   30 VIN<1> IR354XX_SM-IR35411,IC,H73688-0A   I110 @BASEBOARD_FAB2_LIB.BASEBOARD_FAB2(SCH_1):PAGE224
 EU1F1   25 VIN<0> IR354XX_SM-IR35411,IC,H73688-0A   I111 @BASEBOARD_FAB2_LIB.BASEBOARD_FAB2(SCH_1):PAGE224
 EU1F1   30 VIN<1> IR354XX_SM-IR35411,IC,H73688-0A   I111 @BASEBOARD_FAB2_LIB.BASEBOARD_FAB2(SCH_1):PAGE224
 C22W1    1      1 SC22U16V5MX-4-GP_SMD-BCG5-SC22A   I246 @BASEBOARD_FAB2_LIB.BASEBOARD_FAB2(SCH_1):PAGE225
 C22W2    1      1 SC22U16V5MX-4-GP_SMD-BCG5-SC22A   I247 @BASEBOARD_FAB2_LIB.BASEBOARD_FAB2(SCH_1):PAGE225
 C22W3    1      1 SC22U16V5MX-4-GP_SMD-BCG5-SC22A   I249 @BASEBOARD_FAB2_LIB.BASEBOARD_FAB2(SCH_1):PAGE225
  C1G2    1      1 SC22U16V5MX-4-GP_SMD-BCG5-SC22A   I250 @BASEBOARD_FAB2_LIB.BASEBOARD_FAB2(SCH_1):PAGE225
 C22W4    1      1 SC22U16V5MX-4-GP_SMD-BCG5-SC22A   I251 @BASEBOARD_FAB2_LIB.BASEBOARD_FAB2(SCH_1):PAGE225
  L1F1    2      F IND-100NH-35-GP_DISCRET-G8-INDA   I253 @BASEBOARD_FAB2_LIB.BASEBOARD_FAB2(SCH_1):PAGE225
 C1G15    1      1 ST270U2D5VBM-GP_SMD-TCG2-ST270A   I327 @BASEBOARD_FAB2_LIB.BASEBOARD_FAB2(SCH_1):PAGE225
 C1G12    1      1 ST270U2D5VBM-GP_SMD-TCG2-ST270A   I328 @BASEBOARD_FAB2_LIB.BASEBOARD_FAB2(SCH_1):PAGE225
  C1G7    1      1 ST270U2D5VBM-GP_SMD-TCG2-ST270A   I329 @BASEBOARD_FAB2_LIB.BASEBOARD_FAB2(SCH_1):PAGE225

VR_FET_SW_P12V_STBY_PVDDQ_KLM @BASEBOARD_FAB2_LIB.BASEBOARD_FAB2(SCH_1):VR_FET_SW_P12V_STBY_PVDDQ_KLM
 C9L11    1      A CAP_0805-10UF,16V,10%,X6S,C953A    I45 @BASEBOARD_FAB2_LIB.BASEBOARD_FAB2(SCH_1):PAGE227
 C9L10    1      A CAP_0805-10UF,16V,10%,X6S,C953A    I46 @BASEBOARD_FAB2_LIB.BASEBOARD_FAB2(SCH_1):PAGE227
  C9L6    1      A CAP_0805-10UF,16V,10%,X6S,C953A    I47 @BASEBOARD_FAB2_LIB.BASEBOARD_FAB2(SCH_1):PAGE227
 C1A19    1      A CAP_0402-1.0UF,16V,10%,X6S,D97A    I48 @BASEBOARD_FAB2_LIB.BASEBOARD_FAB2(SCH_1):PAGE227
 C1A10    1      A CAP_A_0402V-0.1UF,16V,10%,X7R,A    I51 @BASEBOARD_FAB2_LIB.BASEBOARD_FAB2(SCH_1):PAGE227
 C1A20    1      A CAP_A_0402V-0.1UF,16V,10%,X7R,A    I78 @BASEBOARD_FAB2_LIB.BASEBOARD_FAB2(SCH_1):PAGE227
  C1A9    1      A CAP_0402-1.0UF,16V,10%,X6S,D97A    I79 @BASEBOARD_FAB2_LIB.BASEBOARD_FAB2(SCH_1):PAGE227
  C9L5    1      A CAP_0805-10UF,16V,10%,X6S,C953A    I80 @BASEBOARD_FAB2_LIB.BASEBOARD_FAB2(SCH_1):PAGE227
 C9L13    1      A CAP_0805-10UF,16V,10%,X6S,C953A    I81 @BASEBOARD_FAB2_LIB.BASEBOARD_FAB2(SCH_1):PAGE227
 C9L14    1      A CAP_0805-10UF,16V,10%,X6S,C953A    I84 @BASEBOARD_FAB2_LIB.BASEBOARD_FAB2(SCH_1):PAGE227
 EU1A2   25 VIN<0> IR354XX_SM-IR35411,IC,H73688-0A   I101 @BASEBOARD_FAB2_LIB.BASEBOARD_FAB2(SCH_1):PAGE227
 EU1A2   30 VIN<1> IR354XX_SM-IR35411,IC,H73688-0A   I101 @BASEBOARD_FAB2_LIB.BASEBOARD_FAB2(SCH_1):PAGE227
 EU1A1   25 VIN<0> IR354XX_SM-IR35411,IC,H73688-0A   I102 @BASEBOARD_FAB2_LIB.BASEBOARD_FAB2(SCH_1):PAGE227
 EU1A1   30 VIN<1> IR354XX_SM-IR35411,IC,H73688-0A   I102 @BASEBOARD_FAB2_LIB.BASEBOARD_FAB2(SCH_1):PAGE227
 C1B10    1      A CAPP_2626-270UF,16V,20%,OSCON,A   I175 @BASEBOARD_FAB2_LIB.BASEBOARD_FAB2(SCH_1):PAGE228
  L1B1    2      F IND-100NH-35-GP_DISCRET-G8-INDA   I247 @BASEBOARD_FAB2_LIB.BASEBOARD_FAB2(SCH_1):PAGE228

VR_FET_SW_P12V_STBY_PVPP_ABC @BASEBOARD_FAB2_LIB.BASEBOARD_FAB2(SCH_1):VR_FET_SW_P12V_STBY_PVPP_ABC
 C3T10    1      A CAP_0402-1.0UF,16V,10%,X6S,D97A   I161 @BASEBOARD_FAB2_LIB.BASEBOARD_FAB2(SCH_1):PAGE231
 FB7F1    2      B FERRITE_SM-22,FB,656554-051   I162 @BASEBOARD_FAB2_LIB.BASEBOARD_FAB2(SCH_1):PAGE231
 EU7F1   39    VCC NCP3232L_SM-IC,H86355-001   I193 @BASEBOARD_FAB2_LIB.BASEBOARD_FAB2(SCH_1):PAGE231
 EU7F1    8 VIN<0> NCP3232L_SM-IC,H86355-001   I193 @BASEBOARD_FAB2_LIB.BASEBOARD_FAB2(SCH_1):PAGE231
 EU7F1    9 VIN<1> NCP3232L_SM-IC,H86355-001   I193 @BASEBOARD_FAB2_LIB.BASEBOARD_FAB2(SCH_1):PAGE231
 EU7F1   10 VIN<2> NCP3232L_SM-IC,H86355-001   I193 @BASEBOARD_FAB2_LIB.BASEBOARD_FAB2(SCH_1):PAGE231
 EU7F1   11 VIN<3> NCP3232L_SM-IC,H86355-001   I193 @BASEBOARD_FAB2_LIB.BASEBOARD_FAB2(SCH_1):PAGE231
 EU7F1   12 VIN<4> NCP3232L_SM-IC,H86355-001   I193 @BASEBOARD_FAB2_LIB.BASEBOARD_FAB2(SCH_1):PAGE231
 EU7F1   13 VIN<5> NCP3232L_SM-IC,H86355-001   I193 @BASEBOARD_FAB2_LIB.BASEBOARD_FAB2(SCH_1):PAGE231
 EU7F1   14 VIN<6> NCP3232L_SM-IC,H86355-001   I193 @BASEBOARD_FAB2_LIB.BASEBOARD_FAB2(SCH_1):PAGE231
 EU7F1   42 VIN<7> NCP3232L_SM-IC,H86355-001   I193 @BASEBOARD_FAB2_LIB.BASEBOARD_FAB2(SCH_1):PAGE231
  C7F6    1      A CAP_A_0402V-0.1UF,16V,10%,X7R,A   I205 @BASEBOARD_FAB2_LIB.BASEBOARD_FAB2(SCH_1):PAGE231
  C7F5    1      A CAP_0805-10UF,16V,10%,X6S,C953A   I209 @BASEBOARD_FAB2_LIB.BASEBOARD_FAB2(SCH_1):PAGE231
  C3T8    1      A CAP_0805-10UF,16V,10%,X6S,C953A   I210 @BASEBOARD_FAB2_LIB.BASEBOARD_FAB2(SCH_1):PAGE231
 C3T14    1      A CAP_0805-10UF,16V,10%,X6S,C953A   I211 @BASEBOARD_FAB2_LIB.BASEBOARD_FAB2(SCH_1):PAGE231
 C3T12    1      A CAP_0805-10UF,16V,10%,X6S,C953A   I215 @BASEBOARD_FAB2_LIB.BASEBOARD_FAB2(SCH_1):PAGE231
C22W10    1      1 SC22U16V5MX-4-GP_SMD-BCG5-SC22A   I225 @BASEBOARD_FAB2_LIB.BASEBOARD_FAB2(SCH_1):PAGE231
  C7F7    1      1 SC22U16V5MX-4-GP_SMD-BCG5-SC22A   I226 @BASEBOARD_FAB2_LIB.BASEBOARD_FAB2(SCH_1):PAGE231

VR_FET_SW_P12V_STBY_PVPP_DEF @BASEBOARD_FAB2_LIB.BASEBOARD_FAB2(SCH_1):VR_FET_SW_P12V_STBY_PVPP_DEF
 FB7B1    2      B FERRITE_SM-22,FB,656554-051   I200 @BASEBOARD_FAB2_LIB.BASEBOARD_FAB2(SCH_1):PAGE232
  C3M9    1      A CAP_0402-1.0UF,16V,10%,X6S,D97A   I207 @BASEBOARD_FAB2_LIB.BASEBOARD_FAB2(SCH_1):PAGE232
 EU7B1   39    VCC NCP3232L_SM-IC,H86355-001   I214 @BASEBOARD_FAB2_LIB.BASEBOARD_FAB2(SCH_1):PAGE232
 EU7B1    8 VIN<0> NCP3232L_SM-IC,H86355-001   I214 @BASEBOARD_FAB2_LIB.BASEBOARD_FAB2(SCH_1):PAGE232
 EU7B1    9 VIN<1> NCP3232L_SM-IC,H86355-001   I214 @BASEBOARD_FAB2_LIB.BASEBOARD_FAB2(SCH_1):PAGE232
 EU7B1   10 VIN<2> NCP3232L_SM-IC,H86355-001   I214 @BASEBOARD_FAB2_LIB.BASEBOARD_FAB2(SCH_1):PAGE232
 EU7B1   11 VIN<3> NCP3232L_SM-IC,H86355-001   I214 @BASEBOARD_FAB2_LIB.BASEBOARD_FAB2(SCH_1):PAGE232
 EU7B1   12 VIN<4> NCP3232L_SM-IC,H86355-001   I214 @BASEBOARD_FAB2_LIB.BASEBOARD_FAB2(SCH_1):PAGE232
 EU7B1   13 VIN<5> NCP3232L_SM-IC,H86355-001   I214 @BASEBOARD_FAB2_LIB.BASEBOARD_FAB2(SCH_1):PAGE232
 EU7B1   14 VIN<6> NCP3232L_SM-IC,H86355-001   I214 @BASEBOARD_FAB2_LIB.BASEBOARD_FAB2(SCH_1):PAGE232
 EU7B1   42 VIN<7> NCP3232L_SM-IC,H86355-001   I214 @BASEBOARD_FAB2_LIB.BASEBOARD_FAB2(SCH_1):PAGE232
  C7B6    1      A CAP_A_0402V-0.1UF,16V,10%,X7R,A   I252 @BASEBOARD_FAB2_LIB.BASEBOARD_FAB2(SCH_1):PAGE232
  C3M8    1      A CAP_0805-10UF,16V,10%,X6S,C953A   I259 @BASEBOARD_FAB2_LIB.BASEBOARD_FAB2(SCH_1):PAGE232
 C3M15    1      A CAP_0805-10UF,16V,10%,X6S,C953A   I260 @BASEBOARD_FAB2_LIB.BASEBOARD_FAB2(SCH_1):PAGE232
 C3M16    1      A CAP_0805-10UF,16V,10%,X6S,C953A   I261 @BASEBOARD_FAB2_LIB.BASEBOARD_FAB2(SCH_1):PAGE232
  C7B5    1      A CAP_0805-10UF,16V,10%,X6S,C953A   I262 @BASEBOARD_FAB2_LIB.BASEBOARD_FAB2(SCH_1):PAGE232
  C7B8    1      1 SC22U16V5MX-4-GP_SMD-BCG5-SC22A   I309 @BASEBOARD_FAB2_LIB.BASEBOARD_FAB2(SCH_1):PAGE232
 C22W7    1      1 SC22U16V5MX-4-GP_SMD-BCG5-SC22A   I311 @BASEBOARD_FAB2_LIB.BASEBOARD_FAB2(SCH_1):PAGE232

VR_FET_SW_P12V_STBY_PVPP_GHJ @BASEBOARD_FAB2_LIB.BASEBOARD_FAB2(SCH_1):VR_FET_SW_P12V_STBY_PVPP_GHJ
  C4G4    1      A CAP_0402-1.0UF,16V,10%,X6S,D97A   I196 @BASEBOARD_FAB2_LIB.BASEBOARD_FAB2(SCH_1):PAGE233
 FB4G1    2      B FERRITE_SM-22,FB,656554-051   I198 @BASEBOARD_FAB2_LIB.BASEBOARD_FAB2(SCH_1):PAGE233
 EU4G1   39    VCC NCP3232L_SM-IC,H86355-001   I225 @BASEBOARD_FAB2_LIB.BASEBOARD_FAB2(SCH_1):PAGE233
 EU4G1    8 VIN<0> NCP3232L_SM-IC,H86355-001   I225 @BASEBOARD_FAB2_LIB.BASEBOARD_FAB2(SCH_1):PAGE233
 EU4G1    9 VIN<1> NCP3232L_SM-IC,H86355-001   I225 @BASEBOARD_FAB2_LIB.BASEBOARD_FAB2(SCH_1):PAGE233
 EU4G1   10 VIN<2> NCP3232L_SM-IC,H86355-001   I225 @BASEBOARD_FAB2_LIB.BASEBOARD_FAB2(SCH_1):PAGE233
 EU4G1   11 VIN<3> NCP3232L_SM-IC,H86355-001   I225 @BASEBOARD_FAB2_LIB.BASEBOARD_FAB2(SCH_1):PAGE233
 EU4G1   12 VIN<4> NCP3232L_SM-IC,H86355-001   I225 @BASEBOARD_FAB2_LIB.BASEBOARD_FAB2(SCH_1):PAGE233
 EU4G1   13 VIN<5> NCP3232L_SM-IC,H86355-001   I225 @BASEBOARD_FAB2_LIB.BASEBOARD_FAB2(SCH_1):PAGE233
 EU4G1   14 VIN<6> NCP3232L_SM-IC,H86355-001   I225 @BASEBOARD_FAB2_LIB.BASEBOARD_FAB2(SCH_1):PAGE233
 EU4G1   42 VIN<7> NCP3232L_SM-IC,H86355-001   I225 @BASEBOARD_FAB2_LIB.BASEBOARD_FAB2(SCH_1):PAGE233
  C6U5    1      A CAP_A_0402V-0.1UF,16V,10%,X7R,A   I242 @BASEBOARD_FAB2_LIB.BASEBOARD_FAB2(SCH_1):PAGE233
  C6U4    1      A CAP_0805-10UF,16V,10%,X6S,C953A   I248 @BASEBOARD_FAB2_LIB.BASEBOARD_FAB2(SCH_1):PAGE233
  C4G2    1      A CAP_0805-10UF,16V,10%,X6S,C953A   I253 @BASEBOARD_FAB2_LIB.BASEBOARD_FAB2(SCH_1):PAGE233
  C6U7    1      A CAP_0805-10UF,16V,10%,X6S,C953A   I254 @BASEBOARD_FAB2_LIB.BASEBOARD_FAB2(SCH_1):PAGE233
  C6U8    1      A CAP_0805-10UF,16V,10%,X6S,C953A   I255 @BASEBOARD_FAB2_LIB.BASEBOARD_FAB2(SCH_1):PAGE233
 C22W6    1      1 SC22U16V5MX-4-GP_SMD-BCG5-SC22A   I278 @BASEBOARD_FAB2_LIB.BASEBOARD_FAB2(SCH_1):PAGE233
  C4G5    1      1 SC22U16V5MX-4-GP_SMD-BCG5-SC22A   I280 @BASEBOARD_FAB2_LIB.BASEBOARD_FAB2(SCH_1):PAGE233

VR_FET_SW_P12V_STBY_PVPP_KLM @BASEBOARD_FAB2_LIB.BASEBOARD_FAB2(SCH_1):VR_FET_SW_P12V_STBY_PVPP_KLM
 C6L11    1      A CAP_0402-1.0UF,16V,10%,X6S,D97A   I152 @BASEBOARD_FAB2_LIB.BASEBOARD_FAB2(SCH_1):PAGE234
 FB4A1    2      B FERRITE_SM-22,FB,656554-051   I154 @BASEBOARD_FAB2_LIB.BASEBOARD_FAB2(SCH_1):PAGE234
 EU4A3   39    VCC NCP3232L_SM-IC,H86355-001   I184 @BASEBOARD_FAB2_LIB.BASEBOARD_FAB2(SCH_1):PAGE234
 EU4A3    8 VIN<0> NCP3232L_SM-IC,H86355-001   I184 @BASEBOARD_FAB2_LIB.BASEBOARD_FAB2(SCH_1):PAGE234
 EU4A3    9 VIN<1> NCP3232L_SM-IC,H86355-001   I184 @BASEBOARD_FAB2_LIB.BASEBOARD_FAB2(SCH_1):PAGE234
 EU4A3   10 VIN<2> NCP3232L_SM-IC,H86355-001   I184 @BASEBOARD_FAB2_LIB.BASEBOARD_FAB2(SCH_1):PAGE234
 EU4A3   11 VIN<3> NCP3232L_SM-IC,H86355-001   I184 @BASEBOARD_FAB2_LIB.BASEBOARD_FAB2(SCH_1):PAGE234
 EU4A3   12 VIN<4> NCP3232L_SM-IC,H86355-001   I184 @BASEBOARD_FAB2_LIB.BASEBOARD_FAB2(SCH_1):PAGE234
 EU4A3   13 VIN<5> NCP3232L_SM-IC,H86355-001   I184 @BASEBOARD_FAB2_LIB.BASEBOARD_FAB2(SCH_1):PAGE234
 EU4A3   14 VIN<6> NCP3232L_SM-IC,H86355-001   I184 @BASEBOARD_FAB2_LIB.BASEBOARD_FAB2(SCH_1):PAGE234
 EU4A3   42 VIN<7> NCP3232L_SM-IC,H86355-001   I184 @BASEBOARD_FAB2_LIB.BASEBOARD_FAB2(SCH_1):PAGE234
 C4A20    1      A CAP_A_0402V-0.1UF,16V,10%,X7R,A   I199 @BASEBOARD_FAB2_LIB.BASEBOARD_FAB2(SCH_1):PAGE234
 C6L10    1      A CAP_0805-10UF,16V,10%,X6S,C953A   I202 @BASEBOARD_FAB2_LIB.BASEBOARD_FAB2(SCH_1):PAGE234
  C6M3    1      A CAP_0805-10UF,16V,10%,X6S,C953A   I203 @BASEBOARD_FAB2_LIB.BASEBOARD_FAB2(SCH_1):PAGE234
  C6M5    1      A CAP_0805-10UF,16V,10%,X6S,C953A   I204 @BASEBOARD_FAB2_LIB.BASEBOARD_FAB2(SCH_1):PAGE234
 C4A19    1      A CAP_0805-10UF,16V,10%,X6S,C953A   I205 @BASEBOARD_FAB2_LIB.BASEBOARD_FAB2(SCH_1):PAGE234
 C22W5    1      1 SC22U16V5MX-4-GP_SMD-BCG5-SC22A   I222 @BASEBOARD_FAB2_LIB.BASEBOARD_FAB2(SCH_1):PAGE234
  C4B1    1      1 SC22U16V5MX-4-GP_SMD-BCG5-SC22A   I223 @BASEBOARD_FAB2_LIB.BASEBOARD_FAB2(SCH_1):PAGE234

VR_FET_SW_P5V_STBY_PVIN @BASEBOARD_FAB2_LIB.BASEBOARD_FAB2(SCH_1):VR_FET_SW_P5V_STBY_PVIN
 R7E17    1      A RES_0402-0.0,5%,1/16W,CHIP,G21A    I37 @BASEBOARD_FAB2_LIB.BASEBOARD_FAB2(SCH_1):PAGE241
 C7E11    1      A CAP_1206LF-22UF,16V,10%,X6S,D3A    I39 @BASEBOARD_FAB2_LIB.BASEBOARD_FAB2(SCH_1):PAGE241
 FB7E1    2      B FERRITE_SM-22,FB,656554-051    I82 @BASEBOARD_FAB2_LIB.BASEBOARD_FAB2(SCH_1):PAGE241
 EU7E2    4 PVIN<0> TPS54821_LCC-IC,H63269-001    I83 @BASEBOARD_FAB2_LIB.BASEBOARD_FAB2(SCH_1):PAGE241
 EU7E2    5 PVIN<1> TPS54821_LCC-IC,H63269-001    I83 @BASEBOARD_FAB2_LIB.BASEBOARD_FAB2(SCH_1):PAGE241
 C7E13    1      1 SC22U16V5MX-4-GP_SMD-BCG5-SC22A    I92 @BASEBOARD_FAB2_LIB.BASEBOARD_FAB2(SCH_1):PAGE241
 C22W9    1      1 SC22U16V5MX-4-GP_SMD-BCG5-SC22A    I95 @BASEBOARD_FAB2_LIB.BASEBOARD_FAB2(SCH_1):PAGE241
 C22W8    1      1 SC22U16V5MX-4-GP_SMD-BCG5-SC22A    I96 @BASEBOARD_FAB2_LIB.BASEBOARD_FAB2(SCH_1):PAGE241
 C7E12    1      1 SC22U16V5MX-4-GP_SMD-BCG5-SC22A    I98 @BASEBOARD_FAB2_LIB.BASEBOARD_FAB2(SCH_1):PAGE241

VR_P1V05_PCH_BIREF1 @BASEBOARD_FAB2_LIB.BASEBOARD_FAB2(SCH_1):VR_P1V05_PCH_BIREF1
 EU8A1   25 BIREF1 PXE1110B_QFN-IC,H89187-001   I229 @BASEBOARD_FAB2_LIB.BASEBOARD_FAB2(SCH_1):PAGE235
 EU7A2   39  REFIN IR354XX_SM-IR35412,IC,H73684-0A   I117 @BASEBOARD_FAB2_LIB.BASEBOARD_FAB2(SCH_1):PAGE236
  CT67    1      A CAP_A_0402V-0.1UF,16V,10%,X7R,A   I124 @BASEBOARD_FAB2_LIB.BASEBOARD_FAB2(SCH_1):PAGE236
  CF24    1      1 SC22P50V2JN-4GP_SMD-BCG-SC22P5A   I240 @BASEBOARD_FAB2_LIB.BASEBOARD_FAB2(SCH_1):PAGE235
  RF24    1      A RES_0402-1.0K,0.1%,1/16W,CHIP,A   I242 @BASEBOARD_FAB2_LIB.BASEBOARD_FAB2(SCH_1):PAGE235

VR_P1V05_PCH_STBY_AVSP @BASEBOARD_FAB2_LIB.BASEBOARD_FAB2(SCH_1):VR_P1V05_PCH_STBY_AVSP
  C2L2    1      A CAP_0402LF-220PF,50V,10%,X7R,AA   I153 @BASEBOARD_FAB2_LIB.BASEBOARD_FAB2(SCH_1):PAGE235
  R2L8    2      B RES_0603-10.0,1%,1/10W,CHIP,G2A   I154 @BASEBOARD_FAB2_LIB.BASEBOARD_FAB2(SCH_1):PAGE235
 EU8A1   29  BVSEN PXE1110B_QFN-IC,H89187-001   I229 @BASEBOARD_FAB2_LIB.BASEBOARD_FAB2(SCH_1):PAGE235

VR_P1V05_PCH_STBY_OCSET @BASEBOARD_FAB2_LIB.BASEBOARD_FAB2(SCH_1):VR_P1V05_PCH_STBY_OCSET
 EU7A2   37  OCSET IR354XX_SM-IR35412,IC,H73684-0A   I117 @BASEBOARD_FAB2_LIB.BASEBOARD_FAB2(SCH_1):PAGE236
 R3L14    1      A RES_0402-68.1K,1%,1/16W,EMPTY,A   I120 @BASEBOARD_FAB2_LIB.BASEBOARD_FAB2(SCH_1):PAGE236

VR_P1V05_PCH_STBY_PH1_BOOT @BASEBOARD_FAB2_LIB.BASEBOARD_FAB2(SCH_1):VR_P1V05_PCH_STBY_PH1_BOOT
 C7A44    1      A CAP_0402-0.220UF,16V,10%,X7R,AA    I34 @BASEBOARD_FAB2_LIB.BASEBOARD_FAB2(SCH_1):PAGE236
  RT46    1      A RES_0603-0,5.0%,1/10W,CHIP,G22A   I154 @BASEBOARD_FAB2_LIB.BASEBOARD_FAB2(SCH_1):PAGE236

VR_P1V05_PCH_STBY_PH1_BOOT_R @BASEBOARD_FAB2_LIB.BASEBOARD_FAB2(SCH_1):VR_P1V05_PCH_STBY_PH1_BOOT_R
 EU7A2   33  BOOST IR354XX_SM-IR35412,IC,H73684-0A   I117 @BASEBOARD_FAB2_LIB.BASEBOARD_FAB2(SCH_1):PAGE236
  RT46    2      B RES_0603-0,5.0%,1/10W,CHIP,G22A   I154 @BASEBOARD_FAB2_LIB.BASEBOARD_FAB2(SCH_1):PAGE236

VR_P1V05_PCH_STBY_PH1_PHASE @BASEBOARD_FAB2_LIB.BASEBOARD_FAB2(SCH_1):VR_P1V05_PCH_STBY_PH1_PHASE
 C7A44    2      B CAP_0402-0.220UF,16V,10%,X7R,AA    I34 @BASEBOARD_FAB2_LIB.BASEBOARD_FAB2(SCH_1):PAGE236
 EU7A2   32  PHASE IR354XX_SM-IR35412,IC,H73684-0A   I117 @BASEBOARD_FAB2_LIB.BASEBOARD_FAB2(SCH_1):PAGE236

VR_P1V05_PCH_STBY_PH1_PHASE_SW @BASEBOARD_FAB2_LIB.BASEBOARD_FAB2(SCH_1):VR_P1V05_PCH_STBY_PH1_PHASE_SW
 EU7A2   10     SW IR354XX_SM-IR35412,IC,H73684-0A   I117 @BASEBOARD_FAB2_LIB.BASEBOARD_FAB2(SCH_1):PAGE236
  CT68    1      A CAP_0402LF-1000PF,50V,10%,X7R,A   I150 @BASEBOARD_FAB2_LIB.BASEBOARD_FAB2(SCH_1):PAGE236
  L7A4    1      S IND-300NH-20-GP_DISCRET-GB1-INA   I179 @BASEBOARD_FAB2_LIB.BASEBOARD_FAB2(SCH_1):PAGE236

VR_P1V05_PCH_STBY_PH1_SW_RC @BASEBOARD_FAB2_LIB.BASEBOARD_FAB2(SCH_1):VR_P1V05_PCH_STBY_PH1_SW_RC
  CT68    2      B CAP_0402LF-1000PF,50V,10%,X7R,A   I150 @BASEBOARD_FAB2_LIB.BASEBOARD_FAB2(SCH_1):PAGE236
  RT45    1      1 1R3F-GP_RCL_GP-1R3F-GP,64.1R00A   I183 @BASEBOARD_FAB2_LIB.BASEBOARD_FAB2(SCH_1):PAGE236

VR_P1V05_PCH_STBY_PH1_VCIN @BASEBOARD_FAB2_LIB.BASEBOARD_FAB2(SCH_1):VR_P1V05_PCH_STBY_PH1_VCIN
 C7A10    1      A CAP_0402-1.0UF,16V,10%,X6S,D97A    I36 @BASEBOARD_FAB2_LIB.BASEBOARD_FAB2(SCH_1):PAGE236
 EU7A2    3    VCC IR354XX_SM-IR35412,IC,H73684-0A   I117 @BASEBOARD_FAB2_LIB.BASEBOARD_FAB2(SCH_1):PAGE236
  R3L4    1      A RES_0402-0.0,5%,1/16W,CHIP,G21A   I177 @BASEBOARD_FAB2_LIB.BASEBOARD_FAB2(SCH_1):PAGE236

VR_P1V05_PCH_STBY_PWM1 @BASEBOARD_FAB2_LIB.BASEBOARD_FAB2(SCH_1):VR_P1V05_PCH_STBY_PWM1
 EU8A1    3  BPWM1 PXE1110B_QFN-IC,H89187-001   I229 @BASEBOARD_FAB2_LIB.BASEBOARD_FAB2(SCH_1):PAGE235
 EU7A2   34    PWM IR354XX_SM-IR35412,IC,H73684-0A   I117 @BASEBOARD_FAB2_LIB.BASEBOARD_FAB2(SCH_1):PAGE236

VR_P1V15_BMC_STBY_FB @BASEBOARD_FAB2_LIB.BASEBOARD_FAB2(SCH_1):VR_P1V15_BMC_STBY_FB
  R9F8    2      B RES_0402-10.0K,1%,1/16W,CHIP,GA    I14 @BASEBOARD_FAB2_LIB.BASEBOARD_FAB2(SCH_1):PAGE238
 EU9F1    4 ADJ_NC RT9059_DFN-IC,H65765-001    I40 @BASEBOARD_FAB2_LIB.BASEBOARD_FAB2(SCH_1):PAGE238
  R9F6    2      2 4K42R2F-GP_SMD-RG-4K42R2F-GP,6A    I45 @BASEBOARD_FAB2_LIB.BASEBOARD_FAB2(SCH_1):PAGE238

VR_P1V2_BMC_STBY_FB @BASEBOARD_FAB2_LIB.BASEBOARD_FAB2(SCH_1):VR_P1V2_BMC_STBY_FB
 EU9F2    4 ADJ_NC RT9059_DFN-IC,H65765-001    I70 @BASEBOARD_FAB2_LIB.BASEBOARD_FAB2(SCH_1):PAGE239
 R9F31    2      2 5K1R2F-2-GP_SMD-RG-5K1R2F-2-GPA    I98 @BASEBOARD_FAB2_LIB.BASEBOARD_FAB2(SCH_1):PAGE239
 R9F32    1      A RES_0402-10.0K,1%,1/16W,CHIP,GA   I100 @BASEBOARD_FAB2_LIB.BASEBOARD_FAB2(SCH_1):PAGE239

VR_P1V8_PCH_STBY_FB @BASEBOARD_FAB2_LIB.BASEBOARD_FAB2(SCH_1):VR_P1V8_PCH_STBY_FB
 R2L19    1      A RES_0402-49.9K,1%,1/16W,CHIP,GA    I80 @BASEBOARD_FAB2_LIB.BASEBOARD_FAB2(SCH_1):PAGE237
 R2L20    2      B RES_0402-63.4K,1.0%,1/16W,CHIPA    I81 @BASEBOARD_FAB2_LIB.BASEBOARD_FAB2(SCH_1):PAGE237
 EU8A2    4 ADJ_NC RT9059_DFN-IC,H65765-001    I86 @BASEBOARD_FAB2_LIB.BASEBOARD_FAB2(SCH_1):PAGE237

VR_P2V5_BMC_STBY_FB @BASEBOARD_FAB2_LIB.BASEBOARD_FAB2(SCH_1):VR_P2V5_BMC_STBY_FB
EU25F2    4 ADJ_NC RT9059_DFN-IC,H65765-001    I73 @BASEBOARD_FAB2_LIB.BASEBOARD_FAB2(SCH_1):PAGE239
 R9W32    1      A RES_0402-10.0K,1%,1/16W,CHIP,GA   I101 @BASEBOARD_FAB2_LIB.BASEBOARD_FAB2(SCH_1):PAGE239
 R9W31    2      2 21K5R2F-GP_RCL_GP-21K5R2F-GP,6A   I102 @BASEBOARD_FAB2_LIB.BASEBOARD_FAB2(SCH_1):PAGE239

VR_P3V3_STBY_BOOT @BASEBOARD_FAB2_LIB.BASEBOARD_FAB2(SCH_1):VR_P3V3_STBY_BOOT
 EU8F1    4   BOOT RT8240_QFN-IC,H66262-001   I125 @BASEBOARD_FAB2_LIB.BASEBOARD_FAB2(SCH_1):PAGE240
 R8E35    1      A RES_0402-0.0,5%,1/16W,CHIP,G21A   I127 @BASEBOARD_FAB2_LIB.BASEBOARD_FAB2(SCH_1):PAGE240

VR_P3V3_STBY_BOOT_R @BASEBOARD_FAB2_LIB.BASEBOARD_FAB2(SCH_1):VR_P3V3_STBY_BOOT_R
 R8E35    2      B RES_0402-0.0,5%,1/16W,CHIP,G21A   I127 @BASEBOARD_FAB2_LIB.BASEBOARD_FAB2(SCH_1):PAGE240
 C8E12    2      B CAP_0603LF-0.1UF,25V,10%,X7R,6A   I129 @BASEBOARD_FAB2_LIB.BASEBOARD_FAB2(SCH_1):PAGE240

VR_P3V3_STBY_EN @BASEBOARD_FAB2_LIB.BASEBOARD_FAB2(SCH_1):VR_P3V3_STBY_EN
 EU8F1    8     EN RT8240_QFN-IC,H66262-001   I125 @BASEBOARD_FAB2_LIB.BASEBOARD_FAB2(SCH_1):PAGE240
  R8F2    2      B RES_0402-0.0,5%,1/16W,CHIP,G21A   I176 @BASEBOARD_FAB2_LIB.BASEBOARD_FAB2(SCH_1):PAGE240
 R8E40    2      B RES_0402-100.0K,1%,1/16W,EMPTYA   I177 @BASEBOARD_FAB2_LIB.BASEBOARD_FAB2(SCH_1):PAGE240

VR_P3V3_STBY_LGATE @BASEBOARD_FAB2_LIB.BASEBOARD_FAB2(SCH_1):VR_P3V3_STBY_LGATE
 EU8F1    1  LGATE RT8240_QFN-IC,H66262-001   I125 @BASEBOARD_FAB2_LIB.BASEBOARD_FAB2(SCH_1):PAGE240
 EU8E1    4     BG CSD87384M_SM-IC,H66258-001   I170 @BASEBOARD_FAB2_LIB.BASEBOARD_FAB2(SCH_1):PAGE240

VR_P3V3_STBY_OCSELECT @BASEBOARD_FAB2_LIB.BASEBOARD_FAB2(SCH_1):VR_P3V3_STBY_OCSELECT
 EU8F1   10     CS RT8240_QFN-IC,H66262-001   I125 @BASEBOARD_FAB2_LIB.BASEBOARD_FAB2(SCH_1):PAGE240
  R8F9    1      A RES_0402-49.9K,1%,1/16W,CHIP,GA   I195 @BASEBOARD_FAB2_LIB.BASEBOARD_FAB2(SCH_1):PAGE240

VR_P3V3_STBY_PHASE @BASEBOARD_FAB2_LIB.BASEBOARD_FAB2(SCH_1):VR_P3V3_STBY_PHASE
 EU8F1    2  PHASE RT8240_QFN-IC,H66262-001   I125 @BASEBOARD_FAB2_LIB.BASEBOARD_FAB2(SCH_1):PAGE240
 C8E12    1      A CAP_0603LF-0.1UF,25V,10%,X7R,6A   I129 @BASEBOARD_FAB2_LIB.BASEBOARD_FAB2(SCH_1):PAGE240
  C8F3    1      A CAP_0402LF-3300PF,50V,10%,EMPTA   I163 @BASEBOARD_FAB2_LIB.BASEBOARD_FAB2(SCH_1):PAGE240
 EU8E1    5    VSW CSD87384M_SM-IC,H66258-001   I170 @BASEBOARD_FAB2_LIB.BASEBOARD_FAB2(SCH_1):PAGE240
  L8F1    1      1 IND-1UH-361-GP_DISCRET-GC1-INDA   I188 @BASEBOARD_FAB2_LIB.BASEBOARD_FAB2(SCH_1):PAGE240

VR_P3V3_STBY_SNUB @BASEBOARD_FAB2_LIB.BASEBOARD_FAB2(SCH_1):VR_P3V3_STBY_SNUB
  R8F3    1      A RES_0402-2.2,5%,1/16W,EMPTY,G2A   I148 @BASEBOARD_FAB2_LIB.BASEBOARD_FAB2(SCH_1):PAGE240
  C8F3    2      B CAP_0402LF-3300PF,50V,10%,EMPTA   I163 @BASEBOARD_FAB2_LIB.BASEBOARD_FAB2(SCH_1):PAGE240

VR_P3V3_STBY_UGATE @BASEBOARD_FAB2_LIB.BASEBOARD_FAB2(SCH_1):VR_P3V3_STBY_UGATE
 EU8F1    3  UGATE RT8240_QFN-IC,H66262-001   I125 @BASEBOARD_FAB2_LIB.BASEBOARD_FAB2(SCH_1):PAGE240
 EU8E1    1     TG CSD87384M_SM-IC,H66258-001   I170 @BASEBOARD_FAB2_LIB.BASEBOARD_FAB2(SCH_1):PAGE240

VR_P5V_STBY_BOOT @BASEBOARD_FAB2_LIB.BASEBOARD_FAB2(SCH_1):VR_P5V_STBY_BOOT
  C8E6    1      A CAP_0603LF-0.1UF,25V,10%,X7R,6A    I12 @BASEBOARD_FAB2_LIB.BASEBOARD_FAB2(SCH_1):PAGE241
 EU7E2   13   BOOT TPS54821_LCC-IC,H63269-001    I83 @BASEBOARD_FAB2_LIB.BASEBOARD_FAB2(SCH_1):PAGE241

VR_P5V_STBY_COMP @BASEBOARD_FAB2_LIB.BASEBOARD_FAB2(SCH_1):VR_P5V_STBY_COMP
 C8E16    1      A CAP_0402LF-270PF,50V,10%,X7R,AA    I53 @BASEBOARD_FAB2_LIB.BASEBOARD_FAB2(SCH_1):PAGE241
 R8E39    1      A RES_0402-24.9K,1%,1/16W,CHIP,GA    I54 @BASEBOARD_FAB2_LIB.BASEBOARD_FAB2(SCH_1):PAGE241
 EU7E2    8   COMP TPS54821_LCC-IC,H63269-001    I83 @BASEBOARD_FAB2_LIB.BASEBOARD_FAB2(SCH_1):PAGE241

VR_P5V_STBY_EN @BASEBOARD_FAB2_LIB.BASEBOARD_FAB2(SCH_1):VR_P5V_STBY_EN
 EU7E2   10     EN TPS54821_LCC-IC,H63269-001    I83 @BASEBOARD_FAB2_LIB.BASEBOARD_FAB2(SCH_1):PAGE241
 R8E33    2      B RES_0402-0.0,5%,1/16W,CHIP,G21A    I91 @BASEBOARD_FAB2_LIB.BASEBOARD_FAB2(SCH_1):PAGE241

VR_P5V_STBY_PHASE @BASEBOARD_FAB2_LIB.BASEBOARD_FAB2(SCH_1):VR_P5V_STBY_PHASE
  C8E6    2      B CAP_0603LF-0.1UF,25V,10%,X7R,6A    I12 @BASEBOARD_FAB2_LIB.BASEBOARD_FAB2(SCH_1):PAGE241
 EU7E2   11  PH<0> TPS54821_LCC-IC,H63269-001    I83 @BASEBOARD_FAB2_LIB.BASEBOARD_FAB2(SCH_1):PAGE241
 EU7E2   12  PH<1> TPS54821_LCC-IC,H63269-001    I83 @BASEBOARD_FAB2_LIB.BASEBOARD_FAB2(SCH_1):PAGE241
  L8E1    1    INA INDUCTOR_SM-2.2UH,IND,E98761-0A    I90 @BASEBOARD_FAB2_LIB.BASEBOARD_FAB2(SCH_1):PAGE241

VR_P5V_STBY_RC_COMP @BASEBOARD_FAB2_LIB.BASEBOARD_FAB2(SCH_1):VR_P5V_STBY_RC_COMP
 R8E39    2      B RES_0402-24.9K,1%,1/16W,CHIP,GA    I54 @BASEBOARD_FAB2_LIB.BASEBOARD_FAB2(SCH_1):PAGE241
  C8F1    1      A CAP_0402LF-2200PF,50V,10%,X7R,A    I57 @BASEBOARD_FAB2_LIB.BASEBOARD_FAB2(SCH_1):PAGE241

VR_P5V_STBY_RT @BASEBOARD_FAB2_LIB.BASEBOARD_FAB2(SCH_1):VR_P5V_STBY_RT
 R7E14    1      A RES_0402-75K,1%,1/16W,CHIP,G21A    I18 @BASEBOARD_FAB2_LIB.BASEBOARD_FAB2(SCH_1):PAGE241
 EU7E2    1 RT_CLK TPS54821_LCC-IC,H63269-001    I83 @BASEBOARD_FAB2_LIB.BASEBOARD_FAB2(SCH_1):PAGE241

VR_P5V_STBY_SS @BASEBOARD_FAB2_LIB.BASEBOARD_FAB2(SCH_1):VR_P5V_STBY_SS
 C8E15    1      A CAP_0402LF-0.022UF,16V,10%,X7RA    I63 @BASEBOARD_FAB2_LIB.BASEBOARD_FAB2(SCH_1):PAGE241
 EU7E2    9  SS_TR TPS54821_LCC-IC,H63269-001    I83 @BASEBOARD_FAB2_LIB.BASEBOARD_FAB2(SCH_1):PAGE241

VR_P5V_STBY_VIN @BASEBOARD_FAB2_LIB.BASEBOARD_FAB2(SCH_1):VR_P5V_STBY_VIN
 C7E14    1      A CAP_0402-1.0UF,16V,10%,X6S,D97A    I30 @BASEBOARD_FAB2_LIB.BASEBOARD_FAB2(SCH_1):PAGE241
 R7E17    2      B RES_0402-0.0,5%,1/16W,CHIP,G21A    I37 @BASEBOARD_FAB2_LIB.BASEBOARD_FAB2(SCH_1):PAGE241
 EU7E2    6    VIN TPS54821_LCC-IC,H63269-001    I83 @BASEBOARD_FAB2_LIB.BASEBOARD_FAB2(SCH_1):PAGE241

VR_P5V_STBY_VSENSE @BASEBOARD_FAB2_LIB.BASEBOARD_FAB2(SCH_1):VR_P5V_STBY_VSENSE
  R7F1    2      B RES_0402-10.0K,1%,1/16W,CHIP,GA    I50 @BASEBOARD_FAB2_LIB.BASEBOARD_FAB2(SCH_1):PAGE241
 R7E16    1      A RES_0402-1.37K,1%,1/16W,CHIP,GA    I51 @BASEBOARD_FAB2_LIB.BASEBOARD_FAB2(SCH_1):PAGE241
 EU7E2    7 VSENSE TPS54821_LCC-IC,H63269-001    I83 @BASEBOARD_FAB2_LIB.BASEBOARD_FAB2(SCH_1):PAGE241

VR_P5V_STBY_VSENSE_R @BASEBOARD_FAB2_LIB.BASEBOARD_FAB2(SCH_1):VR_P5V_STBY_VSENSE_R
  R7F1    1      A RES_0402-10.0K,1%,1/16W,CHIP,GA    I50 @BASEBOARD_FAB2_LIB.BASEBOARD_FAB2(SCH_1):PAGE241
 R8E37    1      A RES_0402-0.0,5%,1/16W,CHIP,G21A    I78 @BASEBOARD_FAB2_LIB.BASEBOARD_FAB2(SCH_1):PAGE241

VR_PVCCIN_CPU0_AIREF1 @BASEBOARD_FAB2_LIB.BASEBOARD_FAB2(SCH_1):VR_PVCCIN_CPU0_AIREF1
 EU4D4   23 AIREF1 PXE1610B_QFN-IC,H79206-001   I155 @BASEBOARD_FAB2_LIB.BASEBOARD_FAB2(SCH_1):PAGE201
 EU4E1   39  REFIN IR354XX_SM-IR35411,IC,H73688-0A    I63 @BASEBOARD_FAB2_LIB.BASEBOARD_FAB2(SCH_1):PAGE202
   CT1    1      A CAP_A_0402V-0.1UF,16V,10%,X7R,A    I70 @BASEBOARD_FAB2_LIB.BASEBOARD_FAB2(SCH_1):PAGE202
   CF1    1      1 SC22P50V2JN-4GP_SMD-BCG-SC22P5A   I168 @BASEBOARD_FAB2_LIB.BASEBOARD_FAB2(SCH_1):PAGE201
   RF1    1      A RES_0402-1.0K,0.1%,1/16W,CHIP,A   I182 @BASEBOARD_FAB2_LIB.BASEBOARD_FAB2(SCH_1):PAGE201

VR_PVCCIN_CPU0_AIREF2 @BASEBOARD_FAB2_LIB.BASEBOARD_FAB2(SCH_1):VR_PVCCIN_CPU0_AIREF2
 EU4D4   25 AIREF2 PXE1610B_QFN-IC,H79206-001   I155 @BASEBOARD_FAB2_LIB.BASEBOARD_FAB2(SCH_1):PAGE201
 EU4D6   39  REFIN IR354XX_SM-IR35411,IC,H73688-0A    I64 @BASEBOARD_FAB2_LIB.BASEBOARD_FAB2(SCH_1):PAGE202
   CT6    1      A CAP_A_0402V-0.1UF,16V,10%,X7R,A    I81 @BASEBOARD_FAB2_LIB.BASEBOARD_FAB2(SCH_1):PAGE202
   CF2    1      1 SC22P50V2JN-4GP_SMD-BCG-SC22P5A   I169 @BASEBOARD_FAB2_LIB.BASEBOARD_FAB2(SCH_1):PAGE201
   RF2    1      A RES_0402-1.0K,0.1%,1/16W,CHIP,A   I183 @BASEBOARD_FAB2_LIB.BASEBOARD_FAB2(SCH_1):PAGE201

VR_PVCCIN_CPU0_AIREF3 @BASEBOARD_FAB2_LIB.BASEBOARD_FAB2(SCH_1):VR_PVCCIN_CPU0_AIREF3
 EU4D4   27 AIREF3 PXE1610B_QFN-IC,H79206-001   I155 @BASEBOARD_FAB2_LIB.BASEBOARD_FAB2(SCH_1):PAGE201
 EU4D3   39  REFIN IR354XX_SM-IR35411,IC,H73688-0A    I70 @BASEBOARD_FAB2_LIB.BASEBOARD_FAB2(SCH_1):PAGE203
  CT39    1      A CAP_A_0402V-0.1UF,16V,10%,X7R,A    I96 @BASEBOARD_FAB2_LIB.BASEBOARD_FAB2(SCH_1):PAGE203
   CF3    1      1 SC22P50V2JN-4GP_SMD-BCG-SC22P5A   I170 @BASEBOARD_FAB2_LIB.BASEBOARD_FAB2(SCH_1):PAGE201
   RF3    1      A RES_0402-1.0K,0.1%,1/16W,CHIP,A   I184 @BASEBOARD_FAB2_LIB.BASEBOARD_FAB2(SCH_1):PAGE201

VR_PVCCIN_CPU0_AIREF4 @BASEBOARD_FAB2_LIB.BASEBOARD_FAB2(SCH_1):VR_PVCCIN_CPU0_AIREF4
 EU4D4   29 AIREF4 PXE1610B_QFN-IC,H79206-001   I155 @BASEBOARD_FAB2_LIB.BASEBOARD_FAB2(SCH_1):PAGE201
 EU4D1   39  REFIN IR354XX_SM-IR35411,IC,H73688-0A    I71 @BASEBOARD_FAB2_LIB.BASEBOARD_FAB2(SCH_1):PAGE203
  CT40    1      A CAP_A_0402V-0.1UF,16V,10%,X7R,A    I93 @BASEBOARD_FAB2_LIB.BASEBOARD_FAB2(SCH_1):PAGE203
   CF4    1      1 SC22P50V2JN-4GP_SMD-BCG-SC22P5A   I171 @BASEBOARD_FAB2_LIB.BASEBOARD_FAB2(SCH_1):PAGE201
   RF4    1      A RES_0402-1.0K,0.1%,1/16W,CHIP,A   I185 @BASEBOARD_FAB2_LIB.BASEBOARD_FAB2(SCH_1):PAGE201

VR_PVCCIN_CPU0_AIREF5 @BASEBOARD_FAB2_LIB.BASEBOARD_FAB2(SCH_1):VR_PVCCIN_CPU0_AIREF5
 EU4D4   31 AIREF5 PXE1610B_QFN-IC,H79206-001   I155 @BASEBOARD_FAB2_LIB.BASEBOARD_FAB2(SCH_1):PAGE201
 EU4C2   39  REFIN IR354XX_SM-IR35411,IC,H73688-0A    I71 @BASEBOARD_FAB2_LIB.BASEBOARD_FAB2(SCH_1):PAGE204
  CT36    1      A CAP_A_0402V-0.1UF,16V,10%,X7R,A    I85 @BASEBOARD_FAB2_LIB.BASEBOARD_FAB2(SCH_1):PAGE204
   CF5    1      1 SC22P50V2JN-4GP_SMD-BCG-SC22P5A   I172 @BASEBOARD_FAB2_LIB.BASEBOARD_FAB2(SCH_1):PAGE201
   RF5    1      A RES_0402-1.0K,0.1%,1/16W,CHIP,A   I186 @BASEBOARD_FAB2_LIB.BASEBOARD_FAB2(SCH_1):PAGE201

VR_PVCCIN_CPU0_AVINSEN @BASEBOARD_FAB2_LIB.BASEBOARD_FAB2(SCH_1):VR_PVCCIN_CPU0_AVINSEN
 R4D27    2      B RES_0402-100.0K,1%,1/16W,CHIP,B    I54 @BASEBOARD_FAB2_LIB.BASEBOARD_FAB2(SCH_1):PAGE201
 R4D32    1      A RES_0402-1.5K,1%,1/16W,CHIP,G2A    I55 @BASEBOARD_FAB2_LIB.BASEBOARD_FAB2(SCH_1):PAGE201
 EU4D4   45 VINSEN PXE1610B_QFN-IC,H79206-001   I155 @BASEBOARD_FAB2_LIB.BASEBOARD_FAB2(SCH_1):PAGE201
 C4D20    1      A CAP_A_0402V-0.1UF,16V,10%,X7R,A   I192 @BASEBOARD_FAB2_LIB.BASEBOARD_FAB2(SCH_1):PAGE201

VR_PVCCIN_CPU0_PH1_BOOT @BASEBOARD_FAB2_LIB.BASEBOARD_FAB2(SCH_1):VR_PVCCIN_CPU0_PH1_BOOT
 C4E17    1      A CAP_0402-0.220UF,16V,10%,X7R,AA    I22 @BASEBOARD_FAB2_LIB.BASEBOARD_FAB2(SCH_1):PAGE202
   RT1    1      A RES_0603-0,5.0%,1/10W,CHIP,G22A   I101 @BASEBOARD_FAB2_LIB.BASEBOARD_FAB2(SCH_1):PAGE202

VR_PVCCIN_CPU0_PH1_BOOT_R @BASEBOARD_FAB2_LIB.BASEBOARD_FAB2(SCH_1):VR_PVCCIN_CPU0_PH1_BOOT_R
 EU4E1   33  BOOST IR354XX_SM-IR35411,IC,H73688-0A    I63 @BASEBOARD_FAB2_LIB.BASEBOARD_FAB2(SCH_1):PAGE202
   RT1    2      B RES_0603-0,5.0%,1/10W,CHIP,G22A   I101 @BASEBOARD_FAB2_LIB.BASEBOARD_FAB2(SCH_1):PAGE202

VR_PVCCIN_CPU0_PH1_OCSET @BASEBOARD_FAB2_LIB.BASEBOARD_FAB2(SCH_1):VR_PVCCIN_CPU0_PH1_OCSET
 EU4E1   37  OCSET IR354XX_SM-IR35411,IC,H73688-0A    I63 @BASEBOARD_FAB2_LIB.BASEBOARD_FAB2(SCH_1):PAGE202
 R4E22    1      A RES_0402-68.1K,1%,1/16W,EMPTY,A    I65 @BASEBOARD_FAB2_LIB.BASEBOARD_FAB2(SCH_1):PAGE202

VR_PVCCIN_CPU0_PH1_PHASE @BASEBOARD_FAB2_LIB.BASEBOARD_FAB2(SCH_1):VR_PVCCIN_CPU0_PH1_PHASE
 C4E17    2      B CAP_0402-0.220UF,16V,10%,X7R,AA    I22 @BASEBOARD_FAB2_LIB.BASEBOARD_FAB2(SCH_1):PAGE202
 EU4E1   32  PHASE IR354XX_SM-IR35411,IC,H73688-0A    I63 @BASEBOARD_FAB2_LIB.BASEBOARD_FAB2(SCH_1):PAGE202

VR_PVCCIN_CPU0_PH1_VCIN @BASEBOARD_FAB2_LIB.BASEBOARD_FAB2(SCH_1):VR_PVCCIN_CPU0_PH1_VCIN
 C4E10    1      A CAP_0402-1.0UF,16V,10%,X6S,D97A    I34 @BASEBOARD_FAB2_LIB.BASEBOARD_FAB2(SCH_1):PAGE202
 EU4E1    3    VCC IR354XX_SM-IR35411,IC,H73688-0A    I63 @BASEBOARD_FAB2_LIB.BASEBOARD_FAB2(SCH_1):PAGE202
  R6R2    1      A RES_0402-0.0,5%,1/16W,CHIP,G21A   I107 @BASEBOARD_FAB2_LIB.BASEBOARD_FAB2(SCH_1):PAGE202

VR_PVCCIN_CPU0_PH2_BOOT @BASEBOARD_FAB2_LIB.BASEBOARD_FAB2(SCH_1):VR_PVCCIN_CPU0_PH2_BOOT
 C4D50    1      A CAP_0402-0.220UF,16V,10%,X7R,AA    I32 @BASEBOARD_FAB2_LIB.BASEBOARD_FAB2(SCH_1):PAGE202
   RT3    1      A RES_0603-0,5.0%,1/10W,CHIP,G22A   I102 @BASEBOARD_FAB2_LIB.BASEBOARD_FAB2(SCH_1):PAGE202

VR_PVCCIN_CPU0_PH2_BOOT_R @BASEBOARD_FAB2_LIB.BASEBOARD_FAB2(SCH_1):VR_PVCCIN_CPU0_PH2_BOOT_R
 EU4D6   33  BOOST IR354XX_SM-IR35411,IC,H73688-0A    I64 @BASEBOARD_FAB2_LIB.BASEBOARD_FAB2(SCH_1):PAGE202
   RT3    2      B RES_0603-0,5.0%,1/10W,CHIP,G22A   I102 @BASEBOARD_FAB2_LIB.BASEBOARD_FAB2(SCH_1):PAGE202

VR_PVCCIN_CPU0_PH2_OCSET @BASEBOARD_FAB2_LIB.BASEBOARD_FAB2(SCH_1):VR_PVCCIN_CPU0_PH2_OCSET
 EU4D6   37  OCSET IR354XX_SM-IR35411,IC,H73688-0A    I64 @BASEBOARD_FAB2_LIB.BASEBOARD_FAB2(SCH_1):PAGE202
 R4E19    1      A RES_0402-68.1K,1%,1/16W,EMPTY,A    I67 @BASEBOARD_FAB2_LIB.BASEBOARD_FAB2(SCH_1):PAGE202

VR_PVCCIN_CPU0_PH2_PHASE @BASEBOARD_FAB2_LIB.BASEBOARD_FAB2(SCH_1):VR_PVCCIN_CPU0_PH2_PHASE
 C4D50    2      B CAP_0402-0.220UF,16V,10%,X7R,AA    I32 @BASEBOARD_FAB2_LIB.BASEBOARD_FAB2(SCH_1):PAGE202
 EU4D6   32  PHASE IR354XX_SM-IR35411,IC,H73688-0A    I64 @BASEBOARD_FAB2_LIB.BASEBOARD_FAB2(SCH_1):PAGE202

VR_PVCCIN_CPU0_PH2_VCIN @BASEBOARD_FAB2_LIB.BASEBOARD_FAB2(SCH_1):VR_PVCCIN_CPU0_PH2_VCIN
 C4E26    1      A CAP_0402-1.0UF,16V,10%,X6S,D97A    I45 @BASEBOARD_FAB2_LIB.BASEBOARD_FAB2(SCH_1):PAGE202
 EU4D6    3    VCC IR354XX_SM-IR35411,IC,H73688-0A    I64 @BASEBOARD_FAB2_LIB.BASEBOARD_FAB2(SCH_1):PAGE202
  R6R6    1      A RES_0402-0.0,5%,1/16W,CHIP,G21A   I108 @BASEBOARD_FAB2_LIB.BASEBOARD_FAB2(SCH_1):PAGE202

VR_PVCCIN_CPU0_PH3_BOOT @BASEBOARD_FAB2_LIB.BASEBOARD_FAB2(SCH_1):VR_PVCCIN_CPU0_PH3_BOOT
 C4D28    1      A CAP_0402-0.220UF,16V,10%,X7R,AA    I42 @BASEBOARD_FAB2_LIB.BASEBOARD_FAB2(SCH_1):PAGE203
  RT25    1      A RES_0603-0,5.0%,1/10W,CHIP,G22A   I122 @BASEBOARD_FAB2_LIB.BASEBOARD_FAB2(SCH_1):PAGE203

VR_PVCCIN_CPU0_PH3_BOOT_R @BASEBOARD_FAB2_LIB.BASEBOARD_FAB2(SCH_1):VR_PVCCIN_CPU0_PH3_BOOT_R
 EU4D3   33  BOOST IR354XX_SM-IR35411,IC,H73688-0A    I70 @BASEBOARD_FAB2_LIB.BASEBOARD_FAB2(SCH_1):PAGE203
  RT25    2      B RES_0603-0,5.0%,1/10W,CHIP,G22A   I122 @BASEBOARD_FAB2_LIB.BASEBOARD_FAB2(SCH_1):PAGE203

VR_PVCCIN_CPU0_PH3_OCSET @BASEBOARD_FAB2_LIB.BASEBOARD_FAB2(SCH_1):VR_PVCCIN_CPU0_PH3_OCSET
 EU4D3   37  OCSET IR354XX_SM-IR35411,IC,H73688-0A    I70 @BASEBOARD_FAB2_LIB.BASEBOARD_FAB2(SCH_1):PAGE203
 R4D72    1      A RES_0402-68.1K,1%,1/16W,EMPTY,A    I89 @BASEBOARD_FAB2_LIB.BASEBOARD_FAB2(SCH_1):PAGE203

VR_PVCCIN_CPU0_PH3_PHASE @BASEBOARD_FAB2_LIB.BASEBOARD_FAB2(SCH_1):VR_PVCCIN_CPU0_PH3_PHASE
 C4D28    2      B CAP_0402-0.220UF,16V,10%,X7R,AA    I42 @BASEBOARD_FAB2_LIB.BASEBOARD_FAB2(SCH_1):PAGE203
 EU4D3   32  PHASE IR354XX_SM-IR35411,IC,H73688-0A    I70 @BASEBOARD_FAB2_LIB.BASEBOARD_FAB2(SCH_1):PAGE203

VR_PVCCIN_CPU0_PH3_VCIN @BASEBOARD_FAB2_LIB.BASEBOARD_FAB2(SCH_1):VR_PVCCIN_CPU0_PH3_VCIN
 C4D16    1      A CAP_0402-1.0UF,16V,10%,X6S,D97A    I45 @BASEBOARD_FAB2_LIB.BASEBOARD_FAB2(SCH_1):PAGE203
 EU4D3    3    VCC IR354XX_SM-IR35411,IC,H73688-0A    I70 @BASEBOARD_FAB2_LIB.BASEBOARD_FAB2(SCH_1):PAGE203
 R6P19    1      A RES_0402-0.0,5%,1/16W,CHIP,G21A   I128 @BASEBOARD_FAB2_LIB.BASEBOARD_FAB2(SCH_1):PAGE203

VR_PVCCIN_CPU0_PH4_BOOT @BASEBOARD_FAB2_LIB.BASEBOARD_FAB2(SCH_1):VR_PVCCIN_CPU0_PH4_BOOT
  C4D9    1      A CAP_0402-0.220UF,16V,10%,X7R,AA     I3 @BASEBOARD_FAB2_LIB.BASEBOARD_FAB2(SCH_1):PAGE203
  RT28    1      A RES_0603-0,5.0%,1/10W,CHIP,G22A   I123 @BASEBOARD_FAB2_LIB.BASEBOARD_FAB2(SCH_1):PAGE203

VR_PVCCIN_CPU0_PH4_BOOT_R @BASEBOARD_FAB2_LIB.BASEBOARD_FAB2(SCH_1):VR_PVCCIN_CPU0_PH4_BOOT_R
 EU4D1   33  BOOST IR354XX_SM-IR35411,IC,H73688-0A    I71 @BASEBOARD_FAB2_LIB.BASEBOARD_FAB2(SCH_1):PAGE203
  RT28    2      B RES_0603-0,5.0%,1/10W,CHIP,G22A   I123 @BASEBOARD_FAB2_LIB.BASEBOARD_FAB2(SCH_1):PAGE203

VR_PVCCIN_CPU0_PH4_OCSET @BASEBOARD_FAB2_LIB.BASEBOARD_FAB2(SCH_1):VR_PVCCIN_CPU0_PH4_OCSET
 EU4D1   37  OCSET IR354XX_SM-IR35411,IC,H73688-0A    I71 @BASEBOARD_FAB2_LIB.BASEBOARD_FAB2(SCH_1):PAGE203
 R4D71    1      A RES_0402-68.1K,1%,1/16W,EMPTY,A    I91 @BASEBOARD_FAB2_LIB.BASEBOARD_FAB2(SCH_1):PAGE203

VR_PVCCIN_CPU0_PH4_PHASE @BASEBOARD_FAB2_LIB.BASEBOARD_FAB2(SCH_1):VR_PVCCIN_CPU0_PH4_PHASE
  C4D9    2      B CAP_0402-0.220UF,16V,10%,X7R,AA     I3 @BASEBOARD_FAB2_LIB.BASEBOARD_FAB2(SCH_1):PAGE203
 EU4D1   32  PHASE IR354XX_SM-IR35411,IC,H73688-0A    I71 @BASEBOARD_FAB2_LIB.BASEBOARD_FAB2(SCH_1):PAGE203

VR_PVCCIN_CPU0_PH4_VCIN @BASEBOARD_FAB2_LIB.BASEBOARD_FAB2(SCH_1):VR_PVCCIN_CPU0_PH4_VCIN
  C4D7    1      A CAP_0402-1.0UF,16V,10%,X6S,D97A    I51 @BASEBOARD_FAB2_LIB.BASEBOARD_FAB2(SCH_1):PAGE203
 EU4D1    3    VCC IR354XX_SM-IR35411,IC,H73688-0A    I71 @BASEBOARD_FAB2_LIB.BASEBOARD_FAB2(SCH_1):PAGE203
 R6P10    1      A RES_0402-0.0,5%,1/16W,CHIP,G21A   I129 @BASEBOARD_FAB2_LIB.BASEBOARD_FAB2(SCH_1):PAGE203

VR_PVCCIN_CPU0_PH5_BOOT @BASEBOARD_FAB2_LIB.BASEBOARD_FAB2(SCH_1):VR_PVCCIN_CPU0_PH5_BOOT
 C4C17    1      A CAP_0402-0.220UF,16V,10%,X7R,AA    I22 @BASEBOARD_FAB2_LIB.BASEBOARD_FAB2(SCH_1):PAGE204
  RT23    1      A RES_0603-0,5.0%,1/10W,CHIP,G22A    I99 @BASEBOARD_FAB2_LIB.BASEBOARD_FAB2(SCH_1):PAGE204

VR_PVCCIN_CPU0_PH5_BOOT_R @BASEBOARD_FAB2_LIB.BASEBOARD_FAB2(SCH_1):VR_PVCCIN_CPU0_PH5_BOOT_R
 EU4C2   33  BOOST IR354XX_SM-IR35411,IC,H73688-0A    I71 @BASEBOARD_FAB2_LIB.BASEBOARD_FAB2(SCH_1):PAGE204
  RT23    2      B RES_0603-0,5.0%,1/10W,CHIP,G22A    I99 @BASEBOARD_FAB2_LIB.BASEBOARD_FAB2(SCH_1):PAGE204

VR_PVCCIN_CPU0_PH5_OCSET @BASEBOARD_FAB2_LIB.BASEBOARD_FAB2(SCH_1):VR_PVCCIN_CPU0_PH5_OCSET
 EU4C2   37  OCSET IR354XX_SM-IR35411,IC,H73688-0A    I71 @BASEBOARD_FAB2_LIB.BASEBOARD_FAB2(SCH_1):PAGE204
 R4D68    1      A RES_0402-68.1K,1%,1/16W,EMPTY,A    I83 @BASEBOARD_FAB2_LIB.BASEBOARD_FAB2(SCH_1):PAGE204

VR_PVCCIN_CPU0_PH5_PHASE @BASEBOARD_FAB2_LIB.BASEBOARD_FAB2(SCH_1):VR_PVCCIN_CPU0_PH5_PHASE
 C4C17    2      B CAP_0402-0.220UF,16V,10%,X7R,AA    I22 @BASEBOARD_FAB2_LIB.BASEBOARD_FAB2(SCH_1):PAGE204
 EU4C2   32  PHASE IR354XX_SM-IR35411,IC,H73688-0A    I71 @BASEBOARD_FAB2_LIB.BASEBOARD_FAB2(SCH_1):PAGE204

VR_PVCCIN_CPU0_PH5_VCIN @BASEBOARD_FAB2_LIB.BASEBOARD_FAB2(SCH_1):VR_PVCCIN_CPU0_PH5_VCIN
 C4D46    1      A CAP_0402-1.0UF,16V,10%,X6S,D97A    I34 @BASEBOARD_FAB2_LIB.BASEBOARD_FAB2(SCH_1):PAGE204
 EU4C2    3    VCC IR354XX_SM-IR35411,IC,H73688-0A    I71 @BASEBOARD_FAB2_LIB.BASEBOARD_FAB2(SCH_1):PAGE204
 R6P47    1      A RES_0402-0.0,5%,1/16W,CHIP,G21A   I103 @BASEBOARD_FAB2_LIB.BASEBOARD_FAB2(SCH_1):PAGE204

VR_PVCCIN_CPU0_PHASE1 @BASEBOARD_FAB2_LIB.BASEBOARD_FAB2(SCH_1):VR_PVCCIN_CPU0_PHASE1
 EU4E1   10     SW IR354XX_SM-IR35411,IC,H73688-0A    I63 @BASEBOARD_FAB2_LIB.BASEBOARD_FAB2(SCH_1):PAGE202
   CT3    1      A CAP_0402LF-1000PF,50V,10%,X7R,A    I97 @BASEBOARD_FAB2_LIB.BASEBOARD_FAB2(SCH_1):PAGE202
  L4E1    1      S IND-120NH-30-GP_DISCRET-GB2-INA   I109 @BASEBOARD_FAB2_LIB.BASEBOARD_FAB2(SCH_1):PAGE202

VR_PVCCIN_CPU0_PHASE1_RC @BASEBOARD_FAB2_LIB.BASEBOARD_FAB2(SCH_1):VR_PVCCIN_CPU0_PHASE1_RC
   CT3    2      B CAP_0402LF-1000PF,50V,10%,X7R,A    I97 @BASEBOARD_FAB2_LIB.BASEBOARD_FAB2(SCH_1):PAGE202
   RT2    1      1 1R3F-GP_RCL_GP-1R3F-GP,64.1R00A   I114 @BASEBOARD_FAB2_LIB.BASEBOARD_FAB2(SCH_1):PAGE202

VR_PVCCIN_CPU0_PHASE2 @BASEBOARD_FAB2_LIB.BASEBOARD_FAB2(SCH_1):VR_PVCCIN_CPU0_PHASE2
 EU4D6   10     SW IR354XX_SM-IR35411,IC,H73688-0A    I64 @BASEBOARD_FAB2_LIB.BASEBOARD_FAB2(SCH_1):PAGE202
   CT5    1      A CAP_0402LF-1000PF,50V,10%,X7R,A    I98 @BASEBOARD_FAB2_LIB.BASEBOARD_FAB2(SCH_1):PAGE202
  L4D3    1      S IND-120NH-30-GP_DISCRET-GB2-INA   I110 @BASEBOARD_FAB2_LIB.BASEBOARD_FAB2(SCH_1):PAGE202

VR_PVCCIN_CPU0_PHASE2_RC @BASEBOARD_FAB2_LIB.BASEBOARD_FAB2(SCH_1):VR_PVCCIN_CPU0_PHASE2_RC
   CT5    2      B CAP_0402LF-1000PF,50V,10%,X7R,A    I98 @BASEBOARD_FAB2_LIB.BASEBOARD_FAB2(SCH_1):PAGE202
   RT4    1      1 1R3F-GP_RCL_GP-1R3F-GP,64.1R00A   I115 @BASEBOARD_FAB2_LIB.BASEBOARD_FAB2(SCH_1):PAGE202

VR_PVCCIN_CPU0_PHASE3 @BASEBOARD_FAB2_LIB.BASEBOARD_FAB2(SCH_1):VR_PVCCIN_CPU0_PHASE3
 EU4D3   10     SW IR354XX_SM-IR35411,IC,H73688-0A    I70 @BASEBOARD_FAB2_LIB.BASEBOARD_FAB2(SCH_1):PAGE203
  CT38    1      A CAP_0402LF-1000PF,50V,10%,X7R,A   I118 @BASEBOARD_FAB2_LIB.BASEBOARD_FAB2(SCH_1):PAGE203
  L4D2    1      S IND-120NH-30-GP_DISCRET-GB2-INA   I130 @BASEBOARD_FAB2_LIB.BASEBOARD_FAB2(SCH_1):PAGE203

VR_PVCCIN_CPU0_PHASE3_RC @BASEBOARD_FAB2_LIB.BASEBOARD_FAB2(SCH_1):VR_PVCCIN_CPU0_PHASE3_RC
  CT38    2      B CAP_0402LF-1000PF,50V,10%,X7R,A   I118 @BASEBOARD_FAB2_LIB.BASEBOARD_FAB2(SCH_1):PAGE203
  RT26    1      1 1R3F-GP_RCL_GP-1R3F-GP,64.1R00A   I134 @BASEBOARD_FAB2_LIB.BASEBOARD_FAB2(SCH_1):PAGE203

VR_PVCCIN_CPU0_PHASE4 @BASEBOARD_FAB2_LIB.BASEBOARD_FAB2(SCH_1):VR_PVCCIN_CPU0_PHASE4
 EU4D1   10     SW IR354XX_SM-IR35411,IC,H73688-0A    I71 @BASEBOARD_FAB2_LIB.BASEBOARD_FAB2(SCH_1):PAGE203
  CT41    1      A CAP_0402LF-1000PF,50V,10%,X7R,A   I119 @BASEBOARD_FAB2_LIB.BASEBOARD_FAB2(SCH_1):PAGE203
  L4D1    1      S IND-120NH-30-GP_DISCRET-GB2-INA   I131 @BASEBOARD_FAB2_LIB.BASEBOARD_FAB2(SCH_1):PAGE203

VR_PVCCIN_CPU0_PHASE4_RC @BASEBOARD_FAB2_LIB.BASEBOARD_FAB2(SCH_1):VR_PVCCIN_CPU0_PHASE4_RC
  CT41    2      B CAP_0402LF-1000PF,50V,10%,X7R,A   I119 @BASEBOARD_FAB2_LIB.BASEBOARD_FAB2(SCH_1):PAGE203
  RT27    1      1 1R3F-GP_RCL_GP-1R3F-GP,64.1R00A   I135 @BASEBOARD_FAB2_LIB.BASEBOARD_FAB2(SCH_1):PAGE203

VR_PVCCIN_CPU0_PHASE5 @BASEBOARD_FAB2_LIB.BASEBOARD_FAB2(SCH_1):VR_PVCCIN_CPU0_PHASE5
 EU4C2   10     SW IR354XX_SM-IR35411,IC,H73688-0A    I71 @BASEBOARD_FAB2_LIB.BASEBOARD_FAB2(SCH_1):PAGE204
  CT35    1      A CAP_0402LF-1000PF,50V,10%,X7R,A    I97 @BASEBOARD_FAB2_LIB.BASEBOARD_FAB2(SCH_1):PAGE204
  L4C3    1      S IND-120NH-30-GP_DISCRET-GB2-INA   I104 @BASEBOARD_FAB2_LIB.BASEBOARD_FAB2(SCH_1):PAGE204

VR_PVCCIN_CPU0_PHASE5_RC @BASEBOARD_FAB2_LIB.BASEBOARD_FAB2(SCH_1):VR_PVCCIN_CPU0_PHASE5_RC
  CT35    2      B CAP_0402LF-1000PF,50V,10%,X7R,A    I97 @BASEBOARD_FAB2_LIB.BASEBOARD_FAB2(SCH_1):PAGE204
  RT24    1      1 1R3F-GP_RCL_GP-1R3F-GP,64.1R00A   I114 @BASEBOARD_FAB2_LIB.BASEBOARD_FAB2(SCH_1):PAGE204

VR_PVCCIN_CPU0_PWM1 @BASEBOARD_FAB2_LIB.BASEBOARD_FAB2(SCH_1):VR_PVCCIN_CPU0_PWM1
 EU4D4    7  APWM1 PXE1610B_QFN-IC,H79206-001   I155 @BASEBOARD_FAB2_LIB.BASEBOARD_FAB2(SCH_1):PAGE201
 EU4E1   34    PWM IR354XX_SM-IR35411,IC,H73688-0A    I63 @BASEBOARD_FAB2_LIB.BASEBOARD_FAB2(SCH_1):PAGE202

VR_PVCCIN_CPU0_PWM2 @BASEBOARD_FAB2_LIB.BASEBOARD_FAB2(SCH_1):VR_PVCCIN_CPU0_PWM2
 EU4D4    6  APWM2 PXE1610B_QFN-IC,H79206-001   I155 @BASEBOARD_FAB2_LIB.BASEBOARD_FAB2(SCH_1):PAGE201
 EU4D6   34    PWM IR354XX_SM-IR35411,IC,H73688-0A    I64 @BASEBOARD_FAB2_LIB.BASEBOARD_FAB2(SCH_1):PAGE202

VR_PVCCIN_CPU0_PWM3 @BASEBOARD_FAB2_LIB.BASEBOARD_FAB2(SCH_1):VR_PVCCIN_CPU0_PWM3
 EU4D4    5  APWM3 PXE1610B_QFN-IC,H79206-001   I155 @BASEBOARD_FAB2_LIB.BASEBOARD_FAB2(SCH_1):PAGE201
 EU4D3   34    PWM IR354XX_SM-IR35411,IC,H73688-0A    I70 @BASEBOARD_FAB2_LIB.BASEBOARD_FAB2(SCH_1):PAGE203

VR_PVCCIN_CPU0_PWM4 @BASEBOARD_FAB2_LIB.BASEBOARD_FAB2(SCH_1):VR_PVCCIN_CPU0_PWM4
 EU4D4    4  APWM4 PXE1610B_QFN-IC,H79206-001   I155 @BASEBOARD_FAB2_LIB.BASEBOARD_FAB2(SCH_1):PAGE201
 EU4D1   34    PWM IR354XX_SM-IR35411,IC,H73688-0A    I71 @BASEBOARD_FAB2_LIB.BASEBOARD_FAB2(SCH_1):PAGE203

VR_PVCCIN_CPU0_PWM5 @BASEBOARD_FAB2_LIB.BASEBOARD_FAB2(SCH_1):VR_PVCCIN_CPU0_PWM5
 EU4D4    3  APWM5 PXE1610B_QFN-IC,H79206-001   I155 @BASEBOARD_FAB2_LIB.BASEBOARD_FAB2(SCH_1):PAGE201
 EU4C2   34    PWM IR354XX_SM-IR35411,IC,H73688-0A    I71 @BASEBOARD_FAB2_LIB.BASEBOARD_FAB2(SCH_1):PAGE204

VR_PVCCIN_CPU0_VD12 @BASEBOARD_FAB2_LIB.BASEBOARD_FAB2(SCH_1):VR_PVCCIN_CPU0_VD12
 C4D25    1      A CAP_A_0402V-1.0UF,6.3V,10%,X6SA    I30 @BASEBOARD_FAB2_LIB.BASEBOARD_FAB2(SCH_1):PAGE201
 C4D26    1      A CAP_A_0402V-0.1UF,16V,10%,X7R,A    I32 @BASEBOARD_FAB2_LIB.BASEBOARD_FAB2(SCH_1):PAGE201
 EU4D4   48   VD12 PXE1610B_QFN-IC,H79206-001   I155 @BASEBOARD_FAB2_LIB.BASEBOARD_FAB2(SCH_1):PAGE201

VR_PVCCIN_CPU0_VDD @BASEBOARD_FAB2_LIB.BASEBOARD_FAB2(SCH_1):VR_PVCCIN_CPU0_VDD
 C4D15    1      A CAP_A_0402V-1.0UF,6.3V,10%,X6SA    I37 @BASEBOARD_FAB2_LIB.BASEBOARD_FAB2(SCH_1):PAGE201
 C4D19    1      A CAP_A_0402V-0.1UF,16V,10%,X7R,A    I39 @BASEBOARD_FAB2_LIB.BASEBOARD_FAB2(SCH_1):PAGE201
 R4D26    2      B RES_0402-0.0,5%,1/16W,CHIP,G21A    I40 @BASEBOARD_FAB2_LIB.BASEBOARD_FAB2(SCH_1):PAGE201
 EU4D4   47    VDD PXE1610B_QFN-IC,H79206-001   I155 @BASEBOARD_FAB2_LIB.BASEBOARD_FAB2(SCH_1):PAGE201

VR_PVCCIN_CPU0_VREN @BASEBOARD_FAB2_LIB.BASEBOARD_FAB2(SCH_1):VR_PVCCIN_CPU0_VREN
 R6P18    2      B RES_0402-0.0,5%,1/16W,CHIP,G21A   I131 @BASEBOARD_FAB2_LIB.BASEBOARD_FAB2(SCH_1):PAGE201
 R6P16    2      B RES_0402-1.00K,1%,1/16W,CHIP,GA   I132 @BASEBOARD_FAB2_LIB.BASEBOARD_FAB2(SCH_1):PAGE201
 EU4D4   12  AVREN PXE1610B_QFN-IC,H79206-001   I155 @BASEBOARD_FAB2_LIB.BASEBOARD_FAB2(SCH_1):PAGE201

VR_PVCCIN_CPU0_XADDR1 @BASEBOARD_FAB2_LIB.BASEBOARD_FAB2(SCH_1):VR_PVCCIN_CPU0_XADDR1
 R6P28    1      A RES_0402-4.02K,1%,1/16W,CHIP,GA   I121 @BASEBOARD_FAB2_LIB.BASEBOARD_FAB2(SCH_1):PAGE201
 EU4D4   44 XADDR1 PXE1610B_QFN-IC,H79206-001   I155 @BASEBOARD_FAB2_LIB.BASEBOARD_FAB2(SCH_1):PAGE201

VR_PVCCIN_CPU0_XADDR2 @BASEBOARD_FAB2_LIB.BASEBOARD_FAB2(SCH_1):VR_PVCCIN_CPU0_XADDR2
 R6P27    1      A RES_0402-4.02K,1%,1/16W,CHIP,GA   I120 @BASEBOARD_FAB2_LIB.BASEBOARD_FAB2(SCH_1):PAGE201
 EU4D4   41 XADDR2 PXE1610B_QFN-IC,H79206-001   I155 @BASEBOARD_FAB2_LIB.BASEBOARD_FAB2(SCH_1):PAGE201

VR_PVCCIN_CPU1_AIREF1 @BASEBOARD_FAB2_LIB.BASEBOARD_FAB2(SCH_1):VR_PVCCIN_CPU1_AIREF1
 EU1C2   23 AIREF1 PXE1610B_QFN-IC,H79206-001   I130 @BASEBOARD_FAB2_LIB.BASEBOARD_FAB2(SCH_1):PAGE206
 EU1E2   39  REFIN IR354XX_SM-IR35411,IC,H73688-0A    I20 @BASEBOARD_FAB2_LIB.BASEBOARD_FAB2(SCH_1):PAGE207
  CT24    1      A CAP_A_0402V-0.1UF,16V,10%,X7R,A    I71 @BASEBOARD_FAB2_LIB.BASEBOARD_FAB2(SCH_1):PAGE207
   CF7    1      1 SC22P50V2JN-4GP_SMD-BCG-SC22P5A   I137 @BASEBOARD_FAB2_LIB.BASEBOARD_FAB2(SCH_1):PAGE206
   RF7    1      A RES_0402-1.0K,0.1%,1/16W,CHIP,A   I150 @BASEBOARD_FAB2_LIB.BASEBOARD_FAB2(SCH_1):PAGE206

VR_PVCCIN_CPU1_AIREF2 @BASEBOARD_FAB2_LIB.BASEBOARD_FAB2(SCH_1):VR_PVCCIN_CPU1_AIREF2
 EU1C2   25 AIREF2 PXE1610B_QFN-IC,H79206-001   I130 @BASEBOARD_FAB2_LIB.BASEBOARD_FAB2(SCH_1):PAGE206
  CT25    1      A CAP_A_0402V-0.1UF,16V,10%,X7R,A    I81 @BASEBOARD_FAB2_LIB.BASEBOARD_FAB2(SCH_1):PAGE207
   CF8    1      1 SC22P50V2JN-4GP_SMD-BCG-SC22P5A   I138 @BASEBOARD_FAB2_LIB.BASEBOARD_FAB2(SCH_1):PAGE206
   RF8    1      A RES_0402-1.0K,0.1%,1/16W,CHIP,A   I151 @BASEBOARD_FAB2_LIB.BASEBOARD_FAB2(SCH_1):PAGE206
 EU1D4   39  REFIN IR354XX_SM-IR35411,IC,H73688-0A   I113 @BASEBOARD_FAB2_LIB.BASEBOARD_FAB2(SCH_1):PAGE207

VR_PVCCIN_CPU1_AIREF3 @BASEBOARD_FAB2_LIB.BASEBOARD_FAB2(SCH_1):VR_PVCCIN_CPU1_AIREF3
 EU1C2   27 AIREF3 PXE1610B_QFN-IC,H79206-001   I130 @BASEBOARD_FAB2_LIB.BASEBOARD_FAB2(SCH_1):PAGE206
 EU1D3   39  REFIN IR354XX_SM-IR35411,IC,H73688-0A    I27 @BASEBOARD_FAB2_LIB.BASEBOARD_FAB2(SCH_1):PAGE208
  CT16    1      A CAP_A_0402V-0.1UF,16V,10%,X7R,A    I80 @BASEBOARD_FAB2_LIB.BASEBOARD_FAB2(SCH_1):PAGE208
   CF9    1      1 SC22P50V2JN-4GP_SMD-BCG-SC22P5A   I139 @BASEBOARD_FAB2_LIB.BASEBOARD_FAB2(SCH_1):PAGE206
   RF9    1      A RES_0402-1.0K,0.1%,1/16W,CHIP,A   I152 @BASEBOARD_FAB2_LIB.BASEBOARD_FAB2(SCH_1):PAGE206

VR_PVCCIN_CPU1_AIREF4 @BASEBOARD_FAB2_LIB.BASEBOARD_FAB2(SCH_1):VR_PVCCIN_CPU1_AIREF4
 EU1C2   29 AIREF4 PXE1610B_QFN-IC,H79206-001   I130 @BASEBOARD_FAB2_LIB.BASEBOARD_FAB2(SCH_1):PAGE206
 EU1D1   39  REFIN IR354XX_SM-IR35411,IC,H73688-0A    I71 @BASEBOARD_FAB2_LIB.BASEBOARD_FAB2(SCH_1):PAGE208
  CT21    1      A CAP_A_0402V-0.1UF,16V,10%,X7R,A    I87 @BASEBOARD_FAB2_LIB.BASEBOARD_FAB2(SCH_1):PAGE208
  CF10    1      1 SC22P50V2JN-4GP_SMD-BCG-SC22P5A   I140 @BASEBOARD_FAB2_LIB.BASEBOARD_FAB2(SCH_1):PAGE206
  RF10    1      A RES_0402-1.0K,0.1%,1/16W,CHIP,A   I153 @BASEBOARD_FAB2_LIB.BASEBOARD_FAB2(SCH_1):PAGE206

VR_PVCCIN_CPU1_AIREF5 @BASEBOARD_FAB2_LIB.BASEBOARD_FAB2(SCH_1):VR_PVCCIN_CPU1_AIREF5
 EU1C2   31 AIREF5 PXE1610B_QFN-IC,H79206-001   I130 @BASEBOARD_FAB2_LIB.BASEBOARD_FAB2(SCH_1):PAGE206
 EU1C3   39  REFIN IR354XX_SM-IR35411,IC,H73688-0A    I56 @BASEBOARD_FAB2_LIB.BASEBOARD_FAB2(SCH_1):PAGE209
  CT13    1      A CAP_A_0402V-0.1UF,16V,10%,X7R,A    I62 @BASEBOARD_FAB2_LIB.BASEBOARD_FAB2(SCH_1):PAGE209
  CF11    1      1 SC22P50V2JN-4GP_SMD-BCG-SC22P5A   I141 @BASEBOARD_FAB2_LIB.BASEBOARD_FAB2(SCH_1):PAGE206
  RF11    1      A RES_0402-1.0K,0.1%,1/16W,CHIP,A   I154 @BASEBOARD_FAB2_LIB.BASEBOARD_FAB2(SCH_1):PAGE206

VR_PVCCIN_CPU1_AVINSEN @BASEBOARD_FAB2_LIB.BASEBOARD_FAB2(SCH_1):VR_PVCCIN_CPU1_AVINSEN
 R1C13    2      B RES_0402-100.0K,1%,1/16W,CHIP,B    I49 @BASEBOARD_FAB2_LIB.BASEBOARD_FAB2(SCH_1):PAGE206
 R1C16    1      A RES_0402-1.5K,1%,1/16W,CHIP,G2A    I56 @BASEBOARD_FAB2_LIB.BASEBOARD_FAB2(SCH_1):PAGE206
 EU1C2   45 VINSEN PXE1610B_QFN-IC,H79206-001   I130 @BASEBOARD_FAB2_LIB.BASEBOARD_FAB2(SCH_1):PAGE206
  C1C8    1      A CAP_A_0402V-0.1UF,16V,10%,X7R,A   I156 @BASEBOARD_FAB2_LIB.BASEBOARD_FAB2(SCH_1):PAGE206

VR_PVCCIN_CPU1_PH1_BOOT @BASEBOARD_FAB2_LIB.BASEBOARD_FAB2(SCH_1):VR_PVCCIN_CPU1_PH1_BOOT
 C1E11    1      A CAP_0402-0.220UF,16V,10%,X7R,AA    I30 @BASEBOARD_FAB2_LIB.BASEBOARD_FAB2(SCH_1):PAGE207
  RT15    1      A RES_0603-0,5.0%,1/10W,CHIP,G22A    I99 @BASEBOARD_FAB2_LIB.BASEBOARD_FAB2(SCH_1):PAGE207

VR_PVCCIN_CPU1_PH1_BOOT_R @BASEBOARD_FAB2_LIB.BASEBOARD_FAB2(SCH_1):VR_PVCCIN_CPU1_PH1_BOOT_R
 EU1E2   33  BOOST IR354XX_SM-IR35411,IC,H73688-0A    I20 @BASEBOARD_FAB2_LIB.BASEBOARD_FAB2(SCH_1):PAGE207
  RT15    2      B RES_0603-0,5.0%,1/10W,CHIP,G22A    I99 @BASEBOARD_FAB2_LIB.BASEBOARD_FAB2(SCH_1):PAGE207

VR_PVCCIN_CPU1_PH1_OCSET @BASEBOARD_FAB2_LIB.BASEBOARD_FAB2(SCH_1):VR_PVCCIN_CPU1_PH1_OCSET
 EU1E2   37  OCSET IR354XX_SM-IR35411,IC,H73688-0A    I20 @BASEBOARD_FAB2_LIB.BASEBOARD_FAB2(SCH_1):PAGE207
 R1E14    1      A RES_0402-68.1K,1%,1/16W,EMPTY,A    I68 @BASEBOARD_FAB2_LIB.BASEBOARD_FAB2(SCH_1):PAGE207

VR_PVCCIN_CPU1_PH1_PHASE @BASEBOARD_FAB2_LIB.BASEBOARD_FAB2(SCH_1):VR_PVCCIN_CPU1_PH1_PHASE
 EU1E2   32  PHASE IR354XX_SM-IR35411,IC,H73688-0A    I20 @BASEBOARD_FAB2_LIB.BASEBOARD_FAB2(SCH_1):PAGE207
 C1E11    2      B CAP_0402-0.220UF,16V,10%,X7R,AA    I30 @BASEBOARD_FAB2_LIB.BASEBOARD_FAB2(SCH_1):PAGE207

VR_PVCCIN_CPU1_PH1_VCIN @BASEBOARD_FAB2_LIB.BASEBOARD_FAB2(SCH_1):VR_PVCCIN_CPU1_PH1_VCIN
 EU1E2    3    VCC IR354XX_SM-IR35411,IC,H73688-0A    I20 @BASEBOARD_FAB2_LIB.BASEBOARD_FAB2(SCH_1):PAGE207
  C1E8    1      A CAP_0402-1.0UF,16V,10%,X6S,D97A    I32 @BASEBOARD_FAB2_LIB.BASEBOARD_FAB2(SCH_1):PAGE207
  R9R2    1      A RES_0402-0.0,5%,1/16W,CHIP,G21A   I106 @BASEBOARD_FAB2_LIB.BASEBOARD_FAB2(SCH_1):PAGE207

VR_PVCCIN_CPU1_PH2_BOOT @BASEBOARD_FAB2_LIB.BASEBOARD_FAB2(SCH_1):VR_PVCCIN_CPU1_PH2_BOOT
 C1D36    1      A CAP_0402-0.220UF,16V,10%,X7R,AA    I38 @BASEBOARD_FAB2_LIB.BASEBOARD_FAB2(SCH_1):PAGE207
  RT17    1      A RES_0603-0,5.0%,1/10W,CHIP,G22A   I100 @BASEBOARD_FAB2_LIB.BASEBOARD_FAB2(SCH_1):PAGE207

VR_PVCCIN_CPU1_PH2_BOOT_R @BASEBOARD_FAB2_LIB.BASEBOARD_FAB2(SCH_1):VR_PVCCIN_CPU1_PH2_BOOT_R
  RT17    2      B RES_0603-0,5.0%,1/10W,CHIP,G22A   I100 @BASEBOARD_FAB2_LIB.BASEBOARD_FAB2(SCH_1):PAGE207
 EU1D4   33  BOOST IR354XX_SM-IR35411,IC,H73688-0A   I113 @BASEBOARD_FAB2_LIB.BASEBOARD_FAB2(SCH_1):PAGE207

VR_PVCCIN_CPU1_PH2_OCSET @BASEBOARD_FAB2_LIB.BASEBOARD_FAB2(SCH_1):VR_PVCCIN_CPU1_PH2_OCSET
 R1E13    1      A RES_0402-68.1K,1%,1/16W,EMPTY,A    I67 @BASEBOARD_FAB2_LIB.BASEBOARD_FAB2(SCH_1):PAGE207
 EU1D4   37  OCSET IR354XX_SM-IR35411,IC,H73688-0A   I113 @BASEBOARD_FAB2_LIB.BASEBOARD_FAB2(SCH_1):PAGE207

VR_PVCCIN_CPU1_PH2_PHASE @BASEBOARD_FAB2_LIB.BASEBOARD_FAB2(SCH_1):VR_PVCCIN_CPU1_PH2_PHASE
 C1D36    2      B CAP_0402-0.220UF,16V,10%,X7R,AA    I38 @BASEBOARD_FAB2_LIB.BASEBOARD_FAB2(SCH_1):PAGE207
 EU1D4   32  PHASE IR354XX_SM-IR35411,IC,H73688-0A   I113 @BASEBOARD_FAB2_LIB.BASEBOARD_FAB2(SCH_1):PAGE207

VR_PVCCIN_CPU1_PH2_VCIN @BASEBOARD_FAB2_LIB.BASEBOARD_FAB2(SCH_1):VR_PVCCIN_CPU1_PH2_VCIN
 C1E24    1      A CAP_0402-1.0UF,16V,10%,X6S,D97A    I40 @BASEBOARD_FAB2_LIB.BASEBOARD_FAB2(SCH_1):PAGE207
 R9R11    1      A RES_0402-0.0,5%,1/16W,CHIP,G21A   I105 @BASEBOARD_FAB2_LIB.BASEBOARD_FAB2(SCH_1):PAGE207
 EU1D4    3    VCC IR354XX_SM-IR35411,IC,H73688-0A   I113 @BASEBOARD_FAB2_LIB.BASEBOARD_FAB2(SCH_1):PAGE207

VR_PVCCIN_CPU1_PH3_BOOT @BASEBOARD_FAB2_LIB.BASEBOARD_FAB2(SCH_1):VR_PVCCIN_CPU1_PH3_BOOT
 C1D20    1      A CAP_0402-0.220UF,16V,10%,X7R,AA    I40 @BASEBOARD_FAB2_LIB.BASEBOARD_FAB2(SCH_1):PAGE208
  RT11    1      A RES_0603-0,5.0%,1/10W,CHIP,G22A   I108 @BASEBOARD_FAB2_LIB.BASEBOARD_FAB2(SCH_1):PAGE208

VR_PVCCIN_CPU1_PH3_BOOT_R @BASEBOARD_FAB2_LIB.BASEBOARD_FAB2(SCH_1):VR_PVCCIN_CPU1_PH3_BOOT_R
 EU1D3   33  BOOST IR354XX_SM-IR35411,IC,H73688-0A    I27 @BASEBOARD_FAB2_LIB.BASEBOARD_FAB2(SCH_1):PAGE208
  RT11    2      B RES_0603-0,5.0%,1/10W,CHIP,G22A   I108 @BASEBOARD_FAB2_LIB.BASEBOARD_FAB2(SCH_1):PAGE208

VR_PVCCIN_CPU1_PH3_OCSET @BASEBOARD_FAB2_LIB.BASEBOARD_FAB2(SCH_1):VR_PVCCIN_CPU1_PH3_OCSET
 EU1D3   37  OCSET IR354XX_SM-IR35411,IC,H73688-0A    I27 @BASEBOARD_FAB2_LIB.BASEBOARD_FAB2(SCH_1):PAGE208
 R1D55    1      A RES_0402-68.1K,1%,1/16W,EMPTY,A    I76 @BASEBOARD_FAB2_LIB.BASEBOARD_FAB2(SCH_1):PAGE208

VR_PVCCIN_CPU1_PH3_PHASE @BASEBOARD_FAB2_LIB.BASEBOARD_FAB2(SCH_1):VR_PVCCIN_CPU1_PH3_PHASE
 EU1D3   32  PHASE IR354XX_SM-IR35411,IC,H73688-0A    I27 @BASEBOARD_FAB2_LIB.BASEBOARD_FAB2(SCH_1):PAGE208
 C1D20    2      B CAP_0402-0.220UF,16V,10%,X7R,AA    I40 @BASEBOARD_FAB2_LIB.BASEBOARD_FAB2(SCH_1):PAGE208

VR_PVCCIN_CPU1_PH3_VCIN @BASEBOARD_FAB2_LIB.BASEBOARD_FAB2(SCH_1):VR_PVCCIN_CPU1_PH3_VCIN
 EU1D3    3    VCC IR354XX_SM-IR35411,IC,H73688-0A    I27 @BASEBOARD_FAB2_LIB.BASEBOARD_FAB2(SCH_1):PAGE208
 C1D17    1      A CAP_0402-1.0UF,16V,10%,X6S,D97A    I43 @BASEBOARD_FAB2_LIB.BASEBOARD_FAB2(SCH_1):PAGE208
 R9P22    1      A RES_0402-0.0,5%,1/16W,CHIP,G21A   I114 @BASEBOARD_FAB2_LIB.BASEBOARD_FAB2(SCH_1):PAGE208

VR_PVCCIN_CPU1_PH4_BOOT @BASEBOARD_FAB2_LIB.BASEBOARD_FAB2(SCH_1):VR_PVCCIN_CPU1_PH4_BOOT
 C1D10    1      A CAP_0402-0.220UF,16V,10%,X7R,AA    I48 @BASEBOARD_FAB2_LIB.BASEBOARD_FAB2(SCH_1):PAGE208
  RT14    1      A RES_0603-0,5.0%,1/10W,CHIP,G22A   I109 @BASEBOARD_FAB2_LIB.BASEBOARD_FAB2(SCH_1):PAGE208

VR_PVCCIN_CPU1_PH4_BOOT_R @BASEBOARD_FAB2_LIB.BASEBOARD_FAB2(SCH_1):VR_PVCCIN_CPU1_PH4_BOOT_R
 EU1D1   33  BOOST IR354XX_SM-IR35411,IC,H73688-0A    I71 @BASEBOARD_FAB2_LIB.BASEBOARD_FAB2(SCH_1):PAGE208
  RT14    2      B RES_0603-0,5.0%,1/10W,CHIP,G22A   I109 @BASEBOARD_FAB2_LIB.BASEBOARD_FAB2(SCH_1):PAGE208

VR_PVCCIN_CPU1_PH4_OCSET @BASEBOARD_FAB2_LIB.BASEBOARD_FAB2(SCH_1):VR_PVCCIN_CPU1_PH4_OCSET
 EU1D1   37  OCSET IR354XX_SM-IR35411,IC,H73688-0A    I71 @BASEBOARD_FAB2_LIB.BASEBOARD_FAB2(SCH_1):PAGE208
 R1D54    1      A RES_0402-68.1K,1%,1/16W,EMPTY,A    I75 @BASEBOARD_FAB2_LIB.BASEBOARD_FAB2(SCH_1):PAGE208

VR_PVCCIN_CPU1_PH4_PHASE @BASEBOARD_FAB2_LIB.BASEBOARD_FAB2(SCH_1):VR_PVCCIN_CPU1_PH4_PHASE
 C1D10    2      B CAP_0402-0.220UF,16V,10%,X7R,AA    I48 @BASEBOARD_FAB2_LIB.BASEBOARD_FAB2(SCH_1):PAGE208
 EU1D1   32  PHASE IR354XX_SM-IR35411,IC,H73688-0A    I71 @BASEBOARD_FAB2_LIB.BASEBOARD_FAB2(SCH_1):PAGE208

VR_PVCCIN_CPU1_PH4_VCIN @BASEBOARD_FAB2_LIB.BASEBOARD_FAB2(SCH_1):VR_PVCCIN_CPU1_PH4_VCIN
  C1D7    1      A CAP_0402-1.0UF,16V,10%,X6S,D97A    I50 @BASEBOARD_FAB2_LIB.BASEBOARD_FAB2(SCH_1):PAGE208
 EU1D1    3    VCC IR354XX_SM-IR35411,IC,H73688-0A    I71 @BASEBOARD_FAB2_LIB.BASEBOARD_FAB2(SCH_1):PAGE208
  R9P8    1      A RES_0402-0.0,5%,1/16W,CHIP,G21A   I115 @BASEBOARD_FAB2_LIB.BASEBOARD_FAB2(SCH_1):PAGE208

VR_PVCCIN_CPU1_PH5_BOOT @BASEBOARD_FAB2_LIB.BASEBOARD_FAB2(SCH_1):VR_PVCCIN_CPU1_PH5_BOOT
 C1C24    1      A CAP_0402-0.220UF,16V,10%,X7R,AA    I20 @BASEBOARD_FAB2_LIB.BASEBOARD_FAB2(SCH_1):PAGE209
   RT9    1      A RES_0603-0,5.0%,1/10W,CHIP,G22A    I75 @BASEBOARD_FAB2_LIB.BASEBOARD_FAB2(SCH_1):PAGE209

VR_PVCCIN_CPU1_PH5_BOOT_R @BASEBOARD_FAB2_LIB.BASEBOARD_FAB2(SCH_1):VR_PVCCIN_CPU1_PH5_BOOT_R
 EU1C3   33  BOOST IR354XX_SM-IR35411,IC,H73688-0A    I56 @BASEBOARD_FAB2_LIB.BASEBOARD_FAB2(SCH_1):PAGE209
   RT9    2      B RES_0603-0,5.0%,1/10W,CHIP,G22A    I75 @BASEBOARD_FAB2_LIB.BASEBOARD_FAB2(SCH_1):PAGE209

VR_PVCCIN_CPU1_PH5_OCSET @BASEBOARD_FAB2_LIB.BASEBOARD_FAB2(SCH_1):VR_PVCCIN_CPU1_PH5_OCSET
 EU1C3   37  OCSET IR354XX_SM-IR35411,IC,H73688-0A    I56 @BASEBOARD_FAB2_LIB.BASEBOARD_FAB2(SCH_1):PAGE209
 R1D52    1      A RES_0402-68.1K,1%,1/16W,EMPTY,A    I59 @BASEBOARD_FAB2_LIB.BASEBOARD_FAB2(SCH_1):PAGE209

VR_PVCCIN_CPU1_PH5_PHASE @BASEBOARD_FAB2_LIB.BASEBOARD_FAB2(SCH_1):VR_PVCCIN_CPU1_PH5_PHASE
 C1C24    2      B CAP_0402-0.220UF,16V,10%,X7R,AA    I20 @BASEBOARD_FAB2_LIB.BASEBOARD_FAB2(SCH_1):PAGE209
 EU1C3   32  PHASE IR354XX_SM-IR35411,IC,H73688-0A    I56 @BASEBOARD_FAB2_LIB.BASEBOARD_FAB2(SCH_1):PAGE209

VR_PVCCIN_CPU1_PH5_VCIN @BASEBOARD_FAB2_LIB.BASEBOARD_FAB2(SCH_1):VR_PVCCIN_CPU1_PH5_VCIN
 C1D32    1      A CAP_0402-1.0UF,16V,10%,X6S,D97A    I18 @BASEBOARD_FAB2_LIB.BASEBOARD_FAB2(SCH_1):PAGE209
 EU1C3    3    VCC IR354XX_SM-IR35411,IC,H73688-0A    I56 @BASEBOARD_FAB2_LIB.BASEBOARD_FAB2(SCH_1):PAGE209
 R9P32    1      A RES_0402-0.0,5%,1/16W,CHIP,G21A    I79 @BASEBOARD_FAB2_LIB.BASEBOARD_FAB2(SCH_1):PAGE209

VR_PVCCIN_CPU1_PHASE1 @BASEBOARD_FAB2_LIB.BASEBOARD_FAB2(SCH_1):VR_PVCCIN_CPU1_PHASE1
 EU1E2   10     SW IR354XX_SM-IR35411,IC,H73688-0A    I20 @BASEBOARD_FAB2_LIB.BASEBOARD_FAB2(SCH_1):PAGE207
  CT23    1      A CAP_0402LF-1000PF,50V,10%,X7R,A    I95 @BASEBOARD_FAB2_LIB.BASEBOARD_FAB2(SCH_1):PAGE207
  L1E1    1      S IND-120NH-30-GP_DISCRET-GB2-INA   I107 @BASEBOARD_FAB2_LIB.BASEBOARD_FAB2(SCH_1):PAGE207

VR_PVCCIN_CPU1_PHASE1_RC @BASEBOARD_FAB2_LIB.BASEBOARD_FAB2(SCH_1):VR_PVCCIN_CPU1_PHASE1_RC
  CT23    2      B CAP_0402LF-1000PF,50V,10%,X7R,A    I95 @BASEBOARD_FAB2_LIB.BASEBOARD_FAB2(SCH_1):PAGE207
  RT16    1      1 1R3F-GP_RCL_GP-1R3F-GP,64.1R00A   I111 @BASEBOARD_FAB2_LIB.BASEBOARD_FAB2(SCH_1):PAGE207

VR_PVCCIN_CPU1_PHASE2 @BASEBOARD_FAB2_LIB.BASEBOARD_FAB2(SCH_1):VR_PVCCIN_CPU1_PHASE2
  CT27    1      A CAP_0402LF-1000PF,50V,10%,X7R,A    I96 @BASEBOARD_FAB2_LIB.BASEBOARD_FAB2(SCH_1):PAGE207
  L1D3    1      S IND-120NH-30-GP_DISCRET-GB2-INA   I108 @BASEBOARD_FAB2_LIB.BASEBOARD_FAB2(SCH_1):PAGE207
 EU1D4   10     SW IR354XX_SM-IR35411,IC,H73688-0A   I113 @BASEBOARD_FAB2_LIB.BASEBOARD_FAB2(SCH_1):PAGE207

VR_PVCCIN_CPU1_PHASE2_RC @BASEBOARD_FAB2_LIB.BASEBOARD_FAB2(SCH_1):VR_PVCCIN_CPU1_PHASE2_RC
  CT27    2      B CAP_0402LF-1000PF,50V,10%,X7R,A    I96 @BASEBOARD_FAB2_LIB.BASEBOARD_FAB2(SCH_1):PAGE207
  RT18    1      1 1R3F-GP_RCL_GP-1R3F-GP,64.1R00A   I112 @BASEBOARD_FAB2_LIB.BASEBOARD_FAB2(SCH_1):PAGE207

VR_PVCCIN_CPU1_PHASE3 @BASEBOARD_FAB2_LIB.BASEBOARD_FAB2(SCH_1):VR_PVCCIN_CPU1_PHASE3
 EU1D3   10     SW IR354XX_SM-IR35411,IC,H73688-0A    I27 @BASEBOARD_FAB2_LIB.BASEBOARD_FAB2(SCH_1):PAGE208
  CT18    1      A CAP_0402LF-1000PF,50V,10%,X7R,A   I104 @BASEBOARD_FAB2_LIB.BASEBOARD_FAB2(SCH_1):PAGE208
  L1D2    1      S IND-120NH-30-GP_DISCRET-GB2-INA   I116 @BASEBOARD_FAB2_LIB.BASEBOARD_FAB2(SCH_1):PAGE208

VR_PVCCIN_CPU1_PHASE3_RC @BASEBOARD_FAB2_LIB.BASEBOARD_FAB2(SCH_1):VR_PVCCIN_CPU1_PHASE3_RC
  CT18    2      B CAP_0402LF-1000PF,50V,10%,X7R,A   I104 @BASEBOARD_FAB2_LIB.BASEBOARD_FAB2(SCH_1):PAGE208
  RT12    1      1 1R3F-GP_RCL_GP-1R3F-GP,64.1R00A   I120 @BASEBOARD_FAB2_LIB.BASEBOARD_FAB2(SCH_1):PAGE208

VR_PVCCIN_CPU1_PHASE4 @BASEBOARD_FAB2_LIB.BASEBOARD_FAB2(SCH_1):VR_PVCCIN_CPU1_PHASE4
 EU1D1   10     SW IR354XX_SM-IR35411,IC,H73688-0A    I71 @BASEBOARD_FAB2_LIB.BASEBOARD_FAB2(SCH_1):PAGE208
  CT20    1      A CAP_0402LF-1000PF,50V,10%,X7R,A   I105 @BASEBOARD_FAB2_LIB.BASEBOARD_FAB2(SCH_1):PAGE208
  L1D1    1      S IND-120NH-30-GP_DISCRET-GB2-INA   I117 @BASEBOARD_FAB2_LIB.BASEBOARD_FAB2(SCH_1):PAGE208

VR_PVCCIN_CPU1_PHASE4_RC @BASEBOARD_FAB2_LIB.BASEBOARD_FAB2(SCH_1):VR_PVCCIN_CPU1_PHASE4_RC
  CT20    2      B CAP_0402LF-1000PF,50V,10%,X7R,A   I105 @BASEBOARD_FAB2_LIB.BASEBOARD_FAB2(SCH_1):PAGE208
  RT13    1      1 1R3F-GP_RCL_GP-1R3F-GP,64.1R00A   I121 @BASEBOARD_FAB2_LIB.BASEBOARD_FAB2(SCH_1):PAGE208

VR_PVCCIN_CPU1_PHASE5 @BASEBOARD_FAB2_LIB.BASEBOARD_FAB2(SCH_1):VR_PVCCIN_CPU1_PHASE5
 EU1C3   10     SW IR354XX_SM-IR35411,IC,H73688-0A    I56 @BASEBOARD_FAB2_LIB.BASEBOARD_FAB2(SCH_1):PAGE209
  CT14    1      A CAP_0402LF-1000PF,50V,10%,X7R,A    I73 @BASEBOARD_FAB2_LIB.BASEBOARD_FAB2(SCH_1):PAGE209
  L1C2    1      S IND-120NH-30-GP_DISCRET-GB2-INA    I80 @BASEBOARD_FAB2_LIB.BASEBOARD_FAB2(SCH_1):PAGE209

VR_PVCCIN_CPU1_PHASE5_RC @BASEBOARD_FAB2_LIB.BASEBOARD_FAB2(SCH_1):VR_PVCCIN_CPU1_PHASE5_RC
  CT14    2      B CAP_0402LF-1000PF,50V,10%,X7R,A    I73 @BASEBOARD_FAB2_LIB.BASEBOARD_FAB2(SCH_1):PAGE209
  RT10    1      1 1R3F-GP_RCL_GP-1R3F-GP,64.1R00A    I90 @BASEBOARD_FAB2_LIB.BASEBOARD_FAB2(SCH_1):PAGE209

VR_PVCCIN_CPU1_PWM1 @BASEBOARD_FAB2_LIB.BASEBOARD_FAB2(SCH_1):VR_PVCCIN_CPU1_PWM1
 EU1C2    7  APWM1 PXE1610B_QFN-IC,H79206-001   I130 @BASEBOARD_FAB2_LIB.BASEBOARD_FAB2(SCH_1):PAGE206
 EU1E2   34    PWM IR354XX_SM-IR35411,IC,H73688-0A    I20 @BASEBOARD_FAB2_LIB.BASEBOARD_FAB2(SCH_1):PAGE207

VR_PVCCIN_CPU1_PWM2 @BASEBOARD_FAB2_LIB.BASEBOARD_FAB2(SCH_1):VR_PVCCIN_CPU1_PWM2
 EU1C2    6  APWM2 PXE1610B_QFN-IC,H79206-001   I130 @BASEBOARD_FAB2_LIB.BASEBOARD_FAB2(SCH_1):PAGE206
 EU1D4   34    PWM IR354XX_SM-IR35411,IC,H73688-0A   I113 @BASEBOARD_FAB2_LIB.BASEBOARD_FAB2(SCH_1):PAGE207

VR_PVCCIN_CPU1_PWM3 @BASEBOARD_FAB2_LIB.BASEBOARD_FAB2(SCH_1):VR_PVCCIN_CPU1_PWM3
 EU1C2    5  APWM3 PXE1610B_QFN-IC,H79206-001   I130 @BASEBOARD_FAB2_LIB.BASEBOARD_FAB2(SCH_1):PAGE206
 EU1D3   34    PWM IR354XX_SM-IR35411,IC,H73688-0A    I27 @BASEBOARD_FAB2_LIB.BASEBOARD_FAB2(SCH_1):PAGE208

VR_PVCCIN_CPU1_PWM4 @BASEBOARD_FAB2_LIB.BASEBOARD_FAB2(SCH_1):VR_PVCCIN_CPU1_PWM4
 EU1C2    4  APWM4 PXE1610B_QFN-IC,H79206-001   I130 @BASEBOARD_FAB2_LIB.BASEBOARD_FAB2(SCH_1):PAGE206
 EU1D1   34    PWM IR354XX_SM-IR35411,IC,H73688-0A    I71 @BASEBOARD_FAB2_LIB.BASEBOARD_FAB2(SCH_1):PAGE208

VR_PVCCIN_CPU1_PWM5 @BASEBOARD_FAB2_LIB.BASEBOARD_FAB2(SCH_1):VR_PVCCIN_CPU1_PWM5
 EU1C2    3  APWM5 PXE1610B_QFN-IC,H79206-001   I130 @BASEBOARD_FAB2_LIB.BASEBOARD_FAB2(SCH_1):PAGE206
 EU1C3   34    PWM IR354XX_SM-IR35411,IC,H73688-0A    I56 @BASEBOARD_FAB2_LIB.BASEBOARD_FAB2(SCH_1):PAGE209

VR_PVCCIN_CPU1_VD12 @BASEBOARD_FAB2_LIB.BASEBOARD_FAB2(SCH_1):VR_PVCCIN_CPU1_VD12
 C1C13    1      A CAP_A_0402V-1.0UF,6.3V,10%,X6SA    I29 @BASEBOARD_FAB2_LIB.BASEBOARD_FAB2(SCH_1):PAGE206
 C1C14    1      A CAP_A_0402V-0.1UF,16V,10%,X7R,A    I31 @BASEBOARD_FAB2_LIB.BASEBOARD_FAB2(SCH_1):PAGE206
 EU1C2   48   VD12 PXE1610B_QFN-IC,H79206-001   I130 @BASEBOARD_FAB2_LIB.BASEBOARD_FAB2(SCH_1):PAGE206

VR_PVCCIN_CPU1_VDD @BASEBOARD_FAB2_LIB.BASEBOARD_FAB2(SCH_1):VR_PVCCIN_CPU1_VDD
  C1C7    1      A CAP_A_0402V-1.0UF,6.3V,10%,X6SA    I41 @BASEBOARD_FAB2_LIB.BASEBOARD_FAB2(SCH_1):PAGE206
  C1C9    1      A CAP_A_0402V-0.1UF,16V,10%,X7R,A    I42 @BASEBOARD_FAB2_LIB.BASEBOARD_FAB2(SCH_1):PAGE206
 R1C14    2      B RES_0402-0.0,5%,1/16W,CHIP,G21A    I46 @BASEBOARD_FAB2_LIB.BASEBOARD_FAB2(SCH_1):PAGE206
 EU1C2   47    VDD PXE1610B_QFN-IC,H79206-001   I130 @BASEBOARD_FAB2_LIB.BASEBOARD_FAB2(SCH_1):PAGE206

VR_PVCCIN_CPU1_VREN @BASEBOARD_FAB2_LIB.BASEBOARD_FAB2(SCH_1):VR_PVCCIN_CPU1_VREN
 R9N16    2      B RES_0402-0.0,5%,1/16W,CHIP,G21A   I119 @BASEBOARD_FAB2_LIB.BASEBOARD_FAB2(SCH_1):PAGE206
 R9N14    2      B RES_0402-1.00K,1%,1/16W,CHIP,GA   I120 @BASEBOARD_FAB2_LIB.BASEBOARD_FAB2(SCH_1):PAGE206
 EU1C2   12  AVREN PXE1610B_QFN-IC,H79206-001   I130 @BASEBOARD_FAB2_LIB.BASEBOARD_FAB2(SCH_1):PAGE206

VR_PVCCIN_CPU1_XADDR1 @BASEBOARD_FAB2_LIB.BASEBOARD_FAB2(SCH_1):VR_PVCCIN_CPU1_XADDR1
  R9N8    1      A RES_0402-4.02K,1%,1/16W,CHIP,GA   I112 @BASEBOARD_FAB2_LIB.BASEBOARD_FAB2(SCH_1):PAGE206
 EU1C2   44 XADDR1 PXE1610B_QFN-IC,H79206-001   I130 @BASEBOARD_FAB2_LIB.BASEBOARD_FAB2(SCH_1):PAGE206

VR_PVCCIN_CPU1_XADDR2 @BASEBOARD_FAB2_LIB.BASEBOARD_FAB2(SCH_1):VR_PVCCIN_CPU1_XADDR2
  R9N7    1      A RES_0402-3.16K,1%,1/16W,CHIP,GA   I111 @BASEBOARD_FAB2_LIB.BASEBOARD_FAB2(SCH_1):PAGE206
 EU1C2   41 XADDR2 PXE1610B_QFN-IC,H79206-001   I130 @BASEBOARD_FAB2_LIB.BASEBOARD_FAB2(SCH_1):PAGE206

VR_PVCCIOMCP_CPU0_XADDR1 @BASEBOARD_FAB2_LIB.BASEBOARD_FAB2(SCH_1):VR_PVCCIOMCP_CPU0_XADDR1
  J6B1  E10  IOE10 SCONN120_H61426002_SM-CONN,H61A    I56 @BASEBOARD_FAB2_LIB.BASEBOARD_FAB2(SCH_1):PAGE194
 R3N29    1      A RES_0402-16K,1.0%,1/16W,CHIP,GA   I156 @BASEBOARD_FAB2_LIB.BASEBOARD_FAB2(SCH_1):PAGE194

VR_PVCCIOMCP_CPU1_XADDR1 @BASEBOARD_FAB2_LIB.BASEBOARD_FAB2(SCH_1):VR_PVCCIOMCP_CPU1_XADDR1
  J4B2  E10  IOE10 SCONN120_H61426002_SM-CONN,H61A    I46 @BASEBOARD_FAB2_LIB.BASEBOARD_FAB2(SCH_1):PAGE193
 R4C12    1      A RES_0402-8.06K,1%,1/16W,CHIP,GA   I169 @BASEBOARD_FAB2_LIB.BASEBOARD_FAB2(SCH_1):PAGE193

VR_PVCCIO_CPU0_AIREF1 @BASEBOARD_FAB2_LIB.BASEBOARD_FAB2(SCH_1):VR_PVCCIO_CPU0_AIREF1
 EU3P1   21 AIREF1 PXE1110B_QFN-IC,H89187-001    I93 @BASEBOARD_FAB2_LIB.BASEBOARD_FAB2(SCH_1):PAGE211
 EU7C1   39  REFIN IR354XX_SM-IR35412,IC,H73684-0A   I101 @BASEBOARD_FAB2_LIB.BASEBOARD_FAB2(SCH_1):PAGE212
  CT70    1      A CAP_A_0402V-0.1UF,16V,10%,X7R,A   I106 @BASEBOARD_FAB2_LIB.BASEBOARD_FAB2(SCH_1):PAGE212
  CF13    1      1 SC22P50V2JN-4GP_SMD-BCG-SC22P5A    I95 @BASEBOARD_FAB2_LIB.BASEBOARD_FAB2(SCH_1):PAGE211
  RF13    1      A RES_0402-1.0K,0.1%,1/16W,CHIP,A    I96 @BASEBOARD_FAB2_LIB.BASEBOARD_FAB2(SCH_1):PAGE211

VR_PVCCIO_CPU0_AVSP @BASEBOARD_FAB2_LIB.BASEBOARD_FAB2(SCH_1):VR_PVCCIO_CPU0_AVSP
 R3N19    2      B RES_0402-10.0,1%,1/16W,CHIP,G2A    I81 @BASEBOARD_FAB2_LIB.BASEBOARD_FAB2(SCH_1):PAGE211
 C3N39    1      A CAP_0402LF-220PF,50V,10%,X7R,AA    I83 @BASEBOARD_FAB2_LIB.BASEBOARD_FAB2(SCH_1):PAGE211
 EU3P1   19  AVSEN PXE1110B_QFN-IC,H89187-001    I93 @BASEBOARD_FAB2_LIB.BASEBOARD_FAB2(SCH_1):PAGE211

VR_PVCCIO_CPU0_EN @BASEBOARD_FAB2_LIB.BASEBOARD_FAB2(SCH_1):VR_PVCCIO_CPU0_EN
 R3P26    2      B RES_0402-0.0,5%,1/16W,CHIP,G21A    I87 @BASEBOARD_FAB2_LIB.BASEBOARD_FAB2(SCH_1):PAGE211
 R3P21    2      B RES_0402-100.0K,1%,1/16W,EMPTYA    I88 @BASEBOARD_FAB2_LIB.BASEBOARD_FAB2(SCH_1):PAGE211
 EU3P1   10  AVREN PXE1110B_QFN-IC,H89187-001    I93 @BASEBOARD_FAB2_LIB.BASEBOARD_FAB2(SCH_1):PAGE211

VR_PVCCIO_CPU0_OCSET @BASEBOARD_FAB2_LIB.BASEBOARD_FAB2(SCH_1):VR_PVCCIO_CPU0_OCSET
 EU7C1   37  OCSET IR354XX_SM-IR35412,IC,H73684-0A   I101 @BASEBOARD_FAB2_LIB.BASEBOARD_FAB2(SCH_1):PAGE212
 R7C25    1      A RES_0402-68.1K,1%,1/16W,EMPTY,A   I103 @BASEBOARD_FAB2_LIB.BASEBOARD_FAB2(SCH_1):PAGE212

VR_PVCCIO_CPU0_PH1_BOOT @BASEBOARD_FAB2_LIB.BASEBOARD_FAB2(SCH_1):VR_PVCCIO_CPU0_PH1_BOOT
 C7C14    1      A CAP_0402-0.220UF,16V,10%,X7R,AA    I37 @BASEBOARD_FAB2_LIB.BASEBOARD_FAB2(SCH_1):PAGE212
  RT47    1      A RES_0603-0,5.0%,1/10W,CHIP,G22A   I120 @BASEBOARD_FAB2_LIB.BASEBOARD_FAB2(SCH_1):PAGE212

VR_PVCCIO_CPU0_PH1_BOOT_R @BASEBOARD_FAB2_LIB.BASEBOARD_FAB2(SCH_1):VR_PVCCIO_CPU0_PH1_BOOT_R
 EU7C1   33  BOOST IR354XX_SM-IR35412,IC,H73684-0A   I101 @BASEBOARD_FAB2_LIB.BASEBOARD_FAB2(SCH_1):PAGE212
  RT47    2      B RES_0603-0,5.0%,1/10W,CHIP,G22A   I120 @BASEBOARD_FAB2_LIB.BASEBOARD_FAB2(SCH_1):PAGE212

VR_PVCCIO_CPU0_PH1_PHASE @BASEBOARD_FAB2_LIB.BASEBOARD_FAB2(SCH_1):VR_PVCCIO_CPU0_PH1_PHASE
 C7C14    2      B CAP_0402-0.220UF,16V,10%,X7R,AA    I37 @BASEBOARD_FAB2_LIB.BASEBOARD_FAB2(SCH_1):PAGE212
 EU7C1   32  PHASE IR354XX_SM-IR35412,IC,H73684-0A   I101 @BASEBOARD_FAB2_LIB.BASEBOARD_FAB2(SCH_1):PAGE212

VR_PVCCIO_CPU0_PH1_SW @BASEBOARD_FAB2_LIB.BASEBOARD_FAB2(SCH_1):VR_PVCCIO_CPU0_PH1_SW
 EU7C1   10     SW IR354XX_SM-IR35412,IC,H73684-0A   I101 @BASEBOARD_FAB2_LIB.BASEBOARD_FAB2(SCH_1):PAGE212
  CT72    1      A CAP_0402LF-1000PF,50V,10%,X7R,A   I118 @BASEBOARD_FAB2_LIB.BASEBOARD_FAB2(SCH_1):PAGE212
  L7C2    1      S IND-150NH-56-GP_DISCRET-GA1-INA   I141 @BASEBOARD_FAB2_LIB.BASEBOARD_FAB2(SCH_1):PAGE212

VR_PVCCIO_CPU0_PH1_SW_RC @BASEBOARD_FAB2_LIB.BASEBOARD_FAB2(SCH_1):VR_PVCCIO_CPU0_PH1_SW_RC
  CT72    2      B CAP_0402LF-1000PF,50V,10%,X7R,A   I118 @BASEBOARD_FAB2_LIB.BASEBOARD_FAB2(SCH_1):PAGE212
  RT48    1      1 1R3F-GP_RCL_GP-1R3F-GP,64.1R00A   I144 @BASEBOARD_FAB2_LIB.BASEBOARD_FAB2(SCH_1):PAGE212

VR_PVCCIO_CPU0_PH1_VCIN @BASEBOARD_FAB2_LIB.BASEBOARD_FAB2(SCH_1):VR_PVCCIO_CPU0_PH1_VCIN
 C7C17    1      A CAP_0402-1.0UF,16V,10%,X6S,D97A    I36 @BASEBOARD_FAB2_LIB.BASEBOARD_FAB2(SCH_1):PAGE212
 EU7C1    3    VCC IR354XX_SM-IR35412,IC,H73684-0A   I101 @BASEBOARD_FAB2_LIB.BASEBOARD_FAB2(SCH_1):PAGE212
  R3N7    1      A RES_0402-0.0,5%,1/16W,CHIP,G21A   I140 @BASEBOARD_FAB2_LIB.BASEBOARD_FAB2(SCH_1):PAGE212

VR_PVCCIO_CPU0_PWM1 @BASEBOARD_FAB2_LIB.BASEBOARD_FAB2(SCH_1):VR_PVCCIO_CPU0_PWM1
 EU3P1    5  APWM1 PXE1110B_QFN-IC,H89187-001    I93 @BASEBOARD_FAB2_LIB.BASEBOARD_FAB2(SCH_1):PAGE211
 EU7C1   34    PWM IR354XX_SM-IR35412,IC,H73684-0A   I101 @BASEBOARD_FAB2_LIB.BASEBOARD_FAB2(SCH_1):PAGE212

VR_PVCCIO_CPU0_VD12 @BASEBOARD_FAB2_LIB.BASEBOARD_FAB2(SCH_1):VR_PVCCIO_CPU0_VD12
  C3P4    1      A CAP_A_0402V-1.0UF,6.3V,10%,X6SA    I11 @BASEBOARD_FAB2_LIB.BASEBOARD_FAB2(SCH_1):PAGE211
  C3P5    1      A CAP_A_0402V-0.1UF,16V,10%,X7R,A    I13 @BASEBOARD_FAB2_LIB.BASEBOARD_FAB2(SCH_1):PAGE211
 EU3P1   40   VD12 PXE1110B_QFN-IC,H89187-001    I93 @BASEBOARD_FAB2_LIB.BASEBOARD_FAB2(SCH_1):PAGE211

VR_PVCCIO_CPU0_VDD @BASEBOARD_FAB2_LIB.BASEBOARD_FAB2(SCH_1):VR_PVCCIO_CPU0_VDD
  C3P3    1      A CAP_A_0402V-1.0UF,6.3V,10%,X6SA    I20 @BASEBOARD_FAB2_LIB.BASEBOARD_FAB2(SCH_1):PAGE211
  C3P7    1      A CAP_A_0402V-0.1UF,16V,10%,X7R,A    I22 @BASEBOARD_FAB2_LIB.BASEBOARD_FAB2(SCH_1):PAGE211
 R3P22    2      B RES_0402-0.0,5%,1/16W,CHIP,G21A    I24 @BASEBOARD_FAB2_LIB.BASEBOARD_FAB2(SCH_1):PAGE211
 EU3P1   39    VDD PXE1110B_QFN-IC,H89187-001    I93 @BASEBOARD_FAB2_LIB.BASEBOARD_FAB2(SCH_1):PAGE211

VR_PVCCIO_CPU0_VINSEN @BASEBOARD_FAB2_LIB.BASEBOARD_FAB2(SCH_1):VR_PVCCIO_CPU0_VINSEN
 R3P12    2      B RES_0402-100.0K,1%,1/16W,CHIP,B    I31 @BASEBOARD_FAB2_LIB.BASEBOARD_FAB2(SCH_1):PAGE211
 R3P16    1      A RES_0402-1.5K,1%,1/16W,CHIP,G2A    I32 @BASEBOARD_FAB2_LIB.BASEBOARD_FAB2(SCH_1):PAGE211
 EU3P1   37 VINSEN PXE1110B_QFN-IC,H89187-001    I93 @BASEBOARD_FAB2_LIB.BASEBOARD_FAB2(SCH_1):PAGE211
  C3P2    1      A CAP_A_0402V-0.1UF,16V,10%,X7R,A   I103 @BASEBOARD_FAB2_LIB.BASEBOARD_FAB2(SCH_1):PAGE211

VR_PVCCIO_CPU0_XADDR1 @BASEBOARD_FAB2_LIB.BASEBOARD_FAB2(SCH_1):VR_PVCCIO_CPU0_XADDR1
 R3N31    1      A RES_0402-3.16K,1%,1/16W,CHIP,GA    I52 @BASEBOARD_FAB2_LIB.BASEBOARD_FAB2(SCH_1):PAGE211
 EU3P1   36 XADDR1 PXE1110B_QFN-IC,H89187-001    I93 @BASEBOARD_FAB2_LIB.BASEBOARD_FAB2(SCH_1):PAGE211

VR_PVCCIO_CPU0_XADDR2 @BASEBOARD_FAB2_LIB.BASEBOARD_FAB2(SCH_1):VR_PVCCIO_CPU0_XADDR2
 EU3P1   33 XADDR2 PXE1110B_QFN-IC,H89187-001    I93 @BASEBOARD_FAB2_LIB.BASEBOARD_FAB2(SCH_1):PAGE211
 R3N22    1      A RES_0402-4.02K,1%,1/16W,CHIP,GA   I102 @BASEBOARD_FAB2_LIB.BASEBOARD_FAB2(SCH_1):PAGE211

VR_PVCCIO_CPU1_AIREF1 @BASEBOARD_FAB2_LIB.BASEBOARD_FAB2(SCH_1):VR_PVCCIO_CPU1_AIREF1
 EU4D5   21 AIREF1 PXE1110B_QFN-IC,H89187-001    I96 @BASEBOARD_FAB2_LIB.BASEBOARD_FAB2(SCH_1):PAGE213
 EU4E2   39  REFIN IR354XX_SM-IR35412,IC,H73684-0A   I126 @BASEBOARD_FAB2_LIB.BASEBOARD_FAB2(SCH_1):PAGE214
  CT63    1      A CAP_A_0402V-0.1UF,16V,10%,X7R,A   I137 @BASEBOARD_FAB2_LIB.BASEBOARD_FAB2(SCH_1):PAGE214
  CF14    1      1 SC22P50V2JN-4GP_SMD-BCG-SC22P5A    I98 @BASEBOARD_FAB2_LIB.BASEBOARD_FAB2(SCH_1):PAGE213
  RF14    1      A RES_0402-1.0K,0.1%,1/16W,CHIP,A    I99 @BASEBOARD_FAB2_LIB.BASEBOARD_FAB2(SCH_1):PAGE213

VR_PVCCIO_CPU1_AVSP @BASEBOARD_FAB2_LIB.BASEBOARD_FAB2(SCH_1):VR_PVCCIO_CPU1_AVSP
 C4D44    1      A CAP_0402LF-220PF,50V,10%,X7R,AA    I83 @BASEBOARD_FAB2_LIB.BASEBOARD_FAB2(SCH_1):PAGE213
  R4E7    2      B RES_0402-10.0,1%,1/16W,CHIP,G2A    I84 @BASEBOARD_FAB2_LIB.BASEBOARD_FAB2(SCH_1):PAGE213
 EU4D5   19  AVSEN PXE1110B_QFN-IC,H89187-001    I96 @BASEBOARD_FAB2_LIB.BASEBOARD_FAB2(SCH_1):PAGE213

VR_PVCCIO_CPU1_EN @BASEBOARD_FAB2_LIB.BASEBOARD_FAB2(SCH_1):VR_PVCCIO_CPU1_EN
 R6P41    2      B RES_0402-0.0,5%,1/16W,CHIP,G21A    I90 @BASEBOARD_FAB2_LIB.BASEBOARD_FAB2(SCH_1):PAGE213
 R6P40    2      B RES_0402-100.0K,1%,1/16W,EMPTYA    I91 @BASEBOARD_FAB2_LIB.BASEBOARD_FAB2(SCH_1):PAGE213
 EU4D5   10  AVREN PXE1110B_QFN-IC,H89187-001    I96 @BASEBOARD_FAB2_LIB.BASEBOARD_FAB2(SCH_1):PAGE213

VR_PVCCIO_CPU1_OCSET @BASEBOARD_FAB2_LIB.BASEBOARD_FAB2(SCH_1):VR_PVCCIO_CPU1_OCSET
 EU4E2   37  OCSET IR354XX_SM-IR35412,IC,H73684-0A   I126 @BASEBOARD_FAB2_LIB.BASEBOARD_FAB2(SCH_1):PAGE214
 R4E21    1      A RES_0402-68.1K,1%,1/16W,EMPTY,A   I127 @BASEBOARD_FAB2_LIB.BASEBOARD_FAB2(SCH_1):PAGE214

VR_PVCCIO_CPU1_PH1_BOOT @BASEBOARD_FAB2_LIB.BASEBOARD_FAB2(SCH_1):VR_PVCCIO_CPU1_PH1_BOOT
 C4E18    1      A CAP_0402-0.220UF,16V,10%,X7R,AA    I78 @BASEBOARD_FAB2_LIB.BASEBOARD_FAB2(SCH_1):PAGE214
  RT41    1      A RES_0603-0,5.0%,1/10W,CHIP,G22A   I145 @BASEBOARD_FAB2_LIB.BASEBOARD_FAB2(SCH_1):PAGE214

VR_PVCCIO_CPU1_PH1_BOOT_R @BASEBOARD_FAB2_LIB.BASEBOARD_FAB2(SCH_1):VR_PVCCIO_CPU1_PH1_BOOT_R
 EU4E2   33  BOOST IR354XX_SM-IR35412,IC,H73684-0A   I126 @BASEBOARD_FAB2_LIB.BASEBOARD_FAB2(SCH_1):PAGE214
  RT41    2      B RES_0603-0,5.0%,1/10W,CHIP,G22A   I145 @BASEBOARD_FAB2_LIB.BASEBOARD_FAB2(SCH_1):PAGE214

VR_PVCCIO_CPU1_PH1_PHASE @BASEBOARD_FAB2_LIB.BASEBOARD_FAB2(SCH_1):VR_PVCCIO_CPU1_PH1_PHASE
 C4E18    2      B CAP_0402-0.220UF,16V,10%,X7R,AA    I78 @BASEBOARD_FAB2_LIB.BASEBOARD_FAB2(SCH_1):PAGE214
 EU4E2   32  PHASE IR354XX_SM-IR35412,IC,H73684-0A   I126 @BASEBOARD_FAB2_LIB.BASEBOARD_FAB2(SCH_1):PAGE214

VR_PVCCIO_CPU1_PH1_SW @BASEBOARD_FAB2_LIB.BASEBOARD_FAB2(SCH_1):VR_PVCCIO_CPU1_PH1_SW
 EU4E2   10     SW IR354XX_SM-IR35412,IC,H73684-0A   I126 @BASEBOARD_FAB2_LIB.BASEBOARD_FAB2(SCH_1):PAGE214
  CT62    1      A CAP_0402LF-1000PF,50V,10%,X7R,A   I143 @BASEBOARD_FAB2_LIB.BASEBOARD_FAB2(SCH_1):PAGE214
  L4E2    1      S IND-150NH-56-GP_DISCRET-GA1-INA   I174 @BASEBOARD_FAB2_LIB.BASEBOARD_FAB2(SCH_1):PAGE214

VR_PVCCIO_CPU1_PH1_SW_RC @BASEBOARD_FAB2_LIB.BASEBOARD_FAB2(SCH_1):VR_PVCCIO_CPU1_PH1_SW_RC
  CT62    2      B CAP_0402LF-1000PF,50V,10%,X7R,A   I143 @BASEBOARD_FAB2_LIB.BASEBOARD_FAB2(SCH_1):PAGE214
  RT42    1      1 1R3F-GP_RCL_GP-1R3F-GP,64.1R00A   I176 @BASEBOARD_FAB2_LIB.BASEBOARD_FAB2(SCH_1):PAGE214

VR_PVCCIO_CPU1_PH1_VCIN @BASEBOARD_FAB2_LIB.BASEBOARD_FAB2(SCH_1):VR_PVCCIO_CPU1_PH1_VCIN
 C4E22    1      A CAP_0402-1.0UF,16V,10%,X6S,D97A    I76 @BASEBOARD_FAB2_LIB.BASEBOARD_FAB2(SCH_1):PAGE214
 EU4E2    3    VCC IR354XX_SM-IR35412,IC,H73684-0A   I126 @BASEBOARD_FAB2_LIB.BASEBOARD_FAB2(SCH_1):PAGE214
  R6R5    1      A RES_0402-0.0,5%,1/16W,CHIP,G21A   I173 @BASEBOARD_FAB2_LIB.BASEBOARD_FAB2(SCH_1):PAGE214

VR_PVCCIO_CPU1_PWM1 @BASEBOARD_FAB2_LIB.BASEBOARD_FAB2(SCH_1):VR_PVCCIO_CPU1_PWM1
 EU4D5    5  APWM1 PXE1110B_QFN-IC,H89187-001    I96 @BASEBOARD_FAB2_LIB.BASEBOARD_FAB2(SCH_1):PAGE213
 EU4E2   34    PWM IR354XX_SM-IR35412,IC,H73684-0A   I126 @BASEBOARD_FAB2_LIB.BASEBOARD_FAB2(SCH_1):PAGE214

VR_PVCCIO_CPU1_VD12 @BASEBOARD_FAB2_LIB.BASEBOARD_FAB2(SCH_1):VR_PVCCIO_CPU1_VD12
 C4D31    1      A CAP_A_0402V-1.0UF,6.3V,10%,X6SA     I9 @BASEBOARD_FAB2_LIB.BASEBOARD_FAB2(SCH_1):PAGE213
 C4D32    1      A CAP_A_0402V-0.1UF,16V,10%,X7R,A    I11 @BASEBOARD_FAB2_LIB.BASEBOARD_FAB2(SCH_1):PAGE213
 EU4D5   40   VD12 PXE1110B_QFN-IC,H89187-001    I96 @BASEBOARD_FAB2_LIB.BASEBOARD_FAB2(SCH_1):PAGE213

VR_PVCCIO_CPU1_VDD @BASEBOARD_FAB2_LIB.BASEBOARD_FAB2(SCH_1):VR_PVCCIO_CPU1_VDD
 C4D36    1      A CAP_A_0402V-1.0UF,6.3V,10%,X6SA    I17 @BASEBOARD_FAB2_LIB.BASEBOARD_FAB2(SCH_1):PAGE213
 R4D47    2      B RES_0402-0.0,5%,1/16W,CHIP,G21A    I25 @BASEBOARD_FAB2_LIB.BASEBOARD_FAB2(SCH_1):PAGE213
 C4D38    1      A CAP_A_0402V-0.1UF,16V,10%,X7R,A    I35 @BASEBOARD_FAB2_LIB.BASEBOARD_FAB2(SCH_1):PAGE213
 EU4D5   39    VDD PXE1110B_QFN-IC,H89187-001    I96 @BASEBOARD_FAB2_LIB.BASEBOARD_FAB2(SCH_1):PAGE213

VR_PVCCIO_CPU1_VINSEN @BASEBOARD_FAB2_LIB.BASEBOARD_FAB2(SCH_1):VR_PVCCIO_CPU1_VINSEN
 R4D60    2      B RES_0402-100.0K,1%,1/16W,CHIP,B    I31 @BASEBOARD_FAB2_LIB.BASEBOARD_FAB2(SCH_1):PAGE213
 R4D57    1      A RES_0402-1.5K,1%,1/16W,CHIP,G2A    I32 @BASEBOARD_FAB2_LIB.BASEBOARD_FAB2(SCH_1):PAGE213
 EU4D5   37 VINSEN PXE1110B_QFN-IC,H89187-001    I96 @BASEBOARD_FAB2_LIB.BASEBOARD_FAB2(SCH_1):PAGE213
 C4D40    1      A CAP_A_0402V-0.1UF,16V,10%,X7R,A   I105 @BASEBOARD_FAB2_LIB.BASEBOARD_FAB2(SCH_1):PAGE213

VR_PVCCIO_CPU1_XADDR1 @BASEBOARD_FAB2_LIB.BASEBOARD_FAB2(SCH_1):VR_PVCCIO_CPU1_XADDR1
 EU4D5   36 XADDR1 PXE1110B_QFN-IC,H89187-001    I96 @BASEBOARD_FAB2_LIB.BASEBOARD_FAB2(SCH_1):PAGE213
 R4D64    1      A RES_0402-3.16K,1%,1/16W,CHIP,GA   I104 @BASEBOARD_FAB2_LIB.BASEBOARD_FAB2(SCH_1):PAGE213

VR_PVCCIO_CPU1_XADDR2 @BASEBOARD_FAB2_LIB.BASEBOARD_FAB2(SCH_1):VR_PVCCIO_CPU1_XADDR2
 EU4D5   33 XADDR2 PXE1110B_QFN-IC,H89187-001    I96 @BASEBOARD_FAB2_LIB.BASEBOARD_FAB2(SCH_1):PAGE213
  R4E2    1      A RES_0402-3.16K,1%,1/16W,CHIP,GA   I103 @BASEBOARD_FAB2_LIB.BASEBOARD_FAB2(SCH_1):PAGE213

VR_PVCCMCP_CPU0_XADDR2 @BASEBOARD_FAB2_LIB.BASEBOARD_FAB2(SCH_1):VR_PVCCMCP_CPU0_XADDR2
  J6B1  F10  IOF10 SCONN120_H61426002_SM-CONN,H61A    I56 @BASEBOARD_FAB2_LIB.BASEBOARD_FAB2(SCH_1):PAGE194
 R7C24    1      A RES_0402-4.02K,1%,1/16W,CHIP,GA   I155 @BASEBOARD_FAB2_LIB.BASEBOARD_FAB2(SCH_1):PAGE194

VR_PVCCMCP_CPU1_XADDR2 @BASEBOARD_FAB2_LIB.BASEBOARD_FAB2(SCH_1):VR_PVCCMCP_CPU1_XADDR2
  J4B2  F10  IOF10 SCONN120_H61426002_SM-CONN,H61A    I46 @BASEBOARD_FAB2_LIB.BASEBOARD_FAB2(SCH_1):PAGE193
 R4C11    1      A RES_0402-3.16K,1%,1/16W,CHIP,GA   I170 @BASEBOARD_FAB2_LIB.BASEBOARD_FAB2(SCH_1):PAGE193

VR_PVDDQ_ABC_AIINSEN @BASEBOARD_FAB2_LIB.BASEBOARD_FAB2(SCH_1):VR_PVDDQ_ABC_AIINSEN
 EU7G1   38 IINSEN PXM1310B_QFN-IC,H89186-001    I69 @BASEBOARD_FAB2_LIB.BASEBOARD_FAB2(SCH_1):PAGE215
 C12W1    1      A CAP_0402LF-47.0PF,50V,5%,COG,AA     I8 @BASEBOARD_FAB2_LIB.BASEBOARD_FAB2(SCH_1):PAGE197
 R12W1    2      2 665KR5B-1-GP_SMD-RG3-665KR5B-1A   I101 @BASEBOARD_FAB2_LIB.BASEBOARD_FAB2(SCH_1):PAGE197
 R12W5    1      1 665KR2B-GP_SMD-RG2-665KR2B-GP,A   I111 @BASEBOARD_FAB2_LIB.BASEBOARD_FAB2(SCH_1):PAGE197

VR_PVDDQ_ABC_AIREF1 @BASEBOARD_FAB2_LIB.BASEBOARD_FAB2(SCH_1):VR_PVDDQ_ABC_AIREF1
 EU7G2   39  REFIN IR354XX_SM-IR35411,IC,H73688-0A   I102 @BASEBOARD_FAB2_LIB.BASEBOARD_FAB2(SCH_1):PAGE216
  CT51    1      A CAP_A_0402V-0.1UF,16V,10%,X7R,A   I108 @BASEBOARD_FAB2_LIB.BASEBOARD_FAB2(SCH_1):PAGE216
  RF15    1      A RES_0402-1.0K,0.1%,1/16W,CHIP,A    I15 @BASEBOARD_FAB2_LIB.BASEBOARD_FAB2(SCH_1):PAGE215
  CF15    1      1 SC22P50V2JN-4GP_SMD-BCG-SC22P5A    I16 @BASEBOARD_FAB2_LIB.BASEBOARD_FAB2(SCH_1):PAGE215
 EU7G1   21 AIREF1 PXM1310B_QFN-IC,H89186-001    I69 @BASEBOARD_FAB2_LIB.BASEBOARD_FAB2(SCH_1):PAGE215

VR_PVDDQ_ABC_AIREF2 @BASEBOARD_FAB2_LIB.BASEBOARD_FAB2(SCH_1):VR_PVDDQ_ABC_AIREF2
 EU7G3   39  REFIN IR354XX_SM-IR35411,IC,H73688-0A   I103 @BASEBOARD_FAB2_LIB.BASEBOARD_FAB2(SCH_1):PAGE216
  CT52    1      A CAP_A_0402V-0.1UF,16V,10%,X7R,A   I111 @BASEBOARD_FAB2_LIB.BASEBOARD_FAB2(SCH_1):PAGE216
  CF16    1      1 SC22P50V2JN-4GP_SMD-BCG-SC22P5A    I26 @BASEBOARD_FAB2_LIB.BASEBOARD_FAB2(SCH_1):PAGE215
  RF16    1      A RES_0402-1.0K,0.1%,1/16W,CHIP,A    I27 @BASEBOARD_FAB2_LIB.BASEBOARD_FAB2(SCH_1):PAGE215
 EU7G1   23 AIREF2 PXM1310B_QFN-IC,H89186-001    I69 @BASEBOARD_FAB2_LIB.BASEBOARD_FAB2(SCH_1):PAGE215

VR_PVDDQ_ABC_AVSP @BASEBOARD_FAB2_LIB.BASEBOARD_FAB2(SCH_1):VR_PVDDQ_ABC_AVSP
  R7G9    2      B RES_0402-10.0,1%,1/16W,CHIP,G2A    I12 @BASEBOARD_FAB2_LIB.BASEBOARD_FAB2(SCH_1):PAGE215
  C7G4    1      A CAP_0402LF-220PF,50V,10%,X7R,AA    I14 @BASEBOARD_FAB2_LIB.BASEBOARD_FAB2(SCH_1):PAGE215
 EU7G1   19  AVSEN PXM1310B_QFN-IC,H89186-001    I69 @BASEBOARD_FAB2_LIB.BASEBOARD_FAB2(SCH_1):PAGE215

VR_PVDDQ_ABC_PH1_BOOT @BASEBOARD_FAB2_LIB.BASEBOARD_FAB2(SCH_1):VR_PVDDQ_ABC_PH1_BOOT
 C7G31    1      A CAP_0402-0.220UF,16V,10%,X7R,AA    I44 @BASEBOARD_FAB2_LIB.BASEBOARD_FAB2(SCH_1):PAGE216
  RT33    1      A RES_0603-0,5.0%,1/10W,CHIP,G22A   I139 @BASEBOARD_FAB2_LIB.BASEBOARD_FAB2(SCH_1):PAGE216

VR_PVDDQ_ABC_PH1_BOOT_R @BASEBOARD_FAB2_LIB.BASEBOARD_FAB2(SCH_1):VR_PVDDQ_ABC_PH1_BOOT_R
 EU7G2   33  BOOST IR354XX_SM-IR35411,IC,H73688-0A   I102 @BASEBOARD_FAB2_LIB.BASEBOARD_FAB2(SCH_1):PAGE216
  RT33    2      B RES_0603-0,5.0%,1/10W,CHIP,G22A   I139 @BASEBOARD_FAB2_LIB.BASEBOARD_FAB2(SCH_1):PAGE216

VR_PVDDQ_ABC_PH1_OCSET @BASEBOARD_FAB2_LIB.BASEBOARD_FAB2(SCH_1):VR_PVDDQ_ABC_PH1_OCSET
 EU7G2   37  OCSET IR354XX_SM-IR35411,IC,H73688-0A   I102 @BASEBOARD_FAB2_LIB.BASEBOARD_FAB2(SCH_1):PAGE216
 R7G25    1      A RES_0402-68.1K,1%,1/16W,EMPTY,A   I104 @BASEBOARD_FAB2_LIB.BASEBOARD_FAB2(SCH_1):PAGE216

VR_PVDDQ_ABC_PH1_PHASE @BASEBOARD_FAB2_LIB.BASEBOARD_FAB2(SCH_1):VR_PVDDQ_ABC_PH1_PHASE
 C7G31    2      B CAP_0402-0.220UF,16V,10%,X7R,AA    I44 @BASEBOARD_FAB2_LIB.BASEBOARD_FAB2(SCH_1):PAGE216
 EU7G2   32  PHASE IR354XX_SM-IR35411,IC,H73688-0A   I102 @BASEBOARD_FAB2_LIB.BASEBOARD_FAB2(SCH_1):PAGE216

VR_PVDDQ_ABC_PH1_SW @BASEBOARD_FAB2_LIB.BASEBOARD_FAB2(SCH_1):VR_PVDDQ_ABC_PH1_SW
 EU7G2   10     SW IR354XX_SM-IR35411,IC,H73688-0A   I102 @BASEBOARD_FAB2_LIB.BASEBOARD_FAB2(SCH_1):PAGE216
  CT50    1      A CAP_0402LF-1000PF,50V,10%,X7R,A   I135 @BASEBOARD_FAB2_LIB.BASEBOARD_FAB2(SCH_1):PAGE216
  L7G1    1      S IND-120NH-30-GP_DISCRET-GB2-INA   I153 @BASEBOARD_FAB2_LIB.BASEBOARD_FAB2(SCH_1):PAGE216

VR_PVDDQ_ABC_PH1_SW_RC @BASEBOARD_FAB2_LIB.BASEBOARD_FAB2(SCH_1):VR_PVDDQ_ABC_PH1_SW_RC
  CT50    2      B CAP_0402LF-1000PF,50V,10%,X7R,A   I135 @BASEBOARD_FAB2_LIB.BASEBOARD_FAB2(SCH_1):PAGE216
  RT34    1      1 1R3F-GP_RCL_GP-1R3F-GP,64.1R00A   I151 @BASEBOARD_FAB2_LIB.BASEBOARD_FAB2(SCH_1):PAGE216

VR_PVDDQ_ABC_PH1_VCIN @BASEBOARD_FAB2_LIB.BASEBOARD_FAB2(SCH_1):VR_PVDDQ_ABC_PH1_VCIN
 C7G33    1      A CAP_0402-1.0UF,16V,10%,X6S,D97A    I50 @BASEBOARD_FAB2_LIB.BASEBOARD_FAB2(SCH_1):PAGE216
 EU7G2    3    VCC IR354XX_SM-IR35411,IC,H73688-0A   I102 @BASEBOARD_FAB2_LIB.BASEBOARD_FAB2(SCH_1):PAGE216
  R3U6    1      A RES_0402-0.0,5%,1/16W,CHIP,G21A   I145 @BASEBOARD_FAB2_LIB.BASEBOARD_FAB2(SCH_1):PAGE216

VR_PVDDQ_ABC_PH2_BOOT @BASEBOARD_FAB2_LIB.BASEBOARD_FAB2(SCH_1):VR_PVDDQ_ABC_PH2_BOOT
 C7G38    1      A CAP_0402-0.220UF,16V,10%,X7R,AA   I128 @BASEBOARD_FAB2_LIB.BASEBOARD_FAB2(SCH_1):PAGE216
  RT36    1      A RES_0603-0,5.0%,1/10W,CHIP,G22A   I140 @BASEBOARD_FAB2_LIB.BASEBOARD_FAB2(SCH_1):PAGE216

VR_PVDDQ_ABC_PH2_BOOT_R @BASEBOARD_FAB2_LIB.BASEBOARD_FAB2(SCH_1):VR_PVDDQ_ABC_PH2_BOOT_R
 EU7G3   33  BOOST IR354XX_SM-IR35411,IC,H73688-0A   I103 @BASEBOARD_FAB2_LIB.BASEBOARD_FAB2(SCH_1):PAGE216
  RT36    2      B RES_0603-0,5.0%,1/10W,CHIP,G22A   I140 @BASEBOARD_FAB2_LIB.BASEBOARD_FAB2(SCH_1):PAGE216

VR_PVDDQ_ABC_PH2_OCSET @BASEBOARD_FAB2_LIB.BASEBOARD_FAB2(SCH_1):VR_PVDDQ_ABC_PH2_OCSET
 EU7G3   37  OCSET IR354XX_SM-IR35411,IC,H73688-0A   I103 @BASEBOARD_FAB2_LIB.BASEBOARD_FAB2(SCH_1):PAGE216
 R7G30    1      A RES_0402-68.1K,1%,1/16W,EMPTY,A   I106 @BASEBOARD_FAB2_LIB.BASEBOARD_FAB2(SCH_1):PAGE216

VR_PVDDQ_ABC_PH2_PHASE @BASEBOARD_FAB2_LIB.BASEBOARD_FAB2(SCH_1):VR_PVDDQ_ABC_PH2_PHASE
 EU7G3   32  PHASE IR354XX_SM-IR35411,IC,H73688-0A   I103 @BASEBOARD_FAB2_LIB.BASEBOARD_FAB2(SCH_1):PAGE216
 C7G38    2      B CAP_0402-0.220UF,16V,10%,X7R,AA   I128 @BASEBOARD_FAB2_LIB.BASEBOARD_FAB2(SCH_1):PAGE216

VR_PVDDQ_ABC_PH2_SW @BASEBOARD_FAB2_LIB.BASEBOARD_FAB2(SCH_1):VR_PVDDQ_ABC_PH2_SW
 EU7G3   10     SW IR354XX_SM-IR35411,IC,H73688-0A   I103 @BASEBOARD_FAB2_LIB.BASEBOARD_FAB2(SCH_1):PAGE216
  CT53    1      A CAP_0402LF-1000PF,50V,10%,X7R,A   I136 @BASEBOARD_FAB2_LIB.BASEBOARD_FAB2(SCH_1):PAGE216
  L7G2    1      S IND-120NH-30-GP_DISCRET-GB2-INA   I155 @BASEBOARD_FAB2_LIB.BASEBOARD_FAB2(SCH_1):PAGE216

VR_PVDDQ_ABC_PH2_SW_RC @BASEBOARD_FAB2_LIB.BASEBOARD_FAB2(SCH_1):VR_PVDDQ_ABC_PH2_SW_RC
  CT53    2      B CAP_0402LF-1000PF,50V,10%,X7R,A   I136 @BASEBOARD_FAB2_LIB.BASEBOARD_FAB2(SCH_1):PAGE216
  RT35    1      1 1R3F-GP_RCL_GP-1R3F-GP,64.1R00A   I152 @BASEBOARD_FAB2_LIB.BASEBOARD_FAB2(SCH_1):PAGE216

VR_PVDDQ_ABC_PH2_VCIN @BASEBOARD_FAB2_LIB.BASEBOARD_FAB2(SCH_1):VR_PVDDQ_ABC_PH2_VCIN
 C7G40    1      A CAP_0402-1.0UF,16V,10%,X6S,D97A    I77 @BASEBOARD_FAB2_LIB.BASEBOARD_FAB2(SCH_1):PAGE216
 EU7G3    3    VCC IR354XX_SM-IR35411,IC,H73688-0A   I103 @BASEBOARD_FAB2_LIB.BASEBOARD_FAB2(SCH_1):PAGE216
  R3U9    1      A RES_0402-0.0,5%,1/16W,CHIP,G21A   I146 @BASEBOARD_FAB2_LIB.BASEBOARD_FAB2(SCH_1):PAGE216

VR_PVDDQ_ABC_PWM1 @BASEBOARD_FAB2_LIB.BASEBOARD_FAB2(SCH_1):VR_PVDDQ_ABC_PWM1
 EU7G2   34    PWM IR354XX_SM-IR35411,IC,H73688-0A   I102 @BASEBOARD_FAB2_LIB.BASEBOARD_FAB2(SCH_1):PAGE216
 EU7G1    5  APWM1 PXM1310B_QFN-IC,H89186-001    I69 @BASEBOARD_FAB2_LIB.BASEBOARD_FAB2(SCH_1):PAGE215

VR_PVDDQ_ABC_PWM2 @BASEBOARD_FAB2_LIB.BASEBOARD_FAB2(SCH_1):VR_PVDDQ_ABC_PWM2
 EU7G3   34    PWM IR354XX_SM-IR35411,IC,H73688-0A   I103 @BASEBOARD_FAB2_LIB.BASEBOARD_FAB2(SCH_1):PAGE216
 EU7G1    4  APWM2 PXM1310B_QFN-IC,H89186-001    I69 @BASEBOARD_FAB2_LIB.BASEBOARD_FAB2(SCH_1):PAGE215

VR_PVDDQ_ABC_VD12 @BASEBOARD_FAB2_LIB.BASEBOARD_FAB2(SCH_1):VR_PVDDQ_ABC_VD12
 C7F15    1      A CAP_A_0402V-0.1UF,16V,10%,X7R,A    I38 @BASEBOARD_FAB2_LIB.BASEBOARD_FAB2(SCH_1):PAGE215
 C7F16    1      A CAP_A_0402V-1.0UF,6.3V,10%,X6SA    I40 @BASEBOARD_FAB2_LIB.BASEBOARD_FAB2(SCH_1):PAGE215
 EU7G1   40   VD12 PXM1310B_QFN-IC,H89186-001    I69 @BASEBOARD_FAB2_LIB.BASEBOARD_FAB2(SCH_1):PAGE215

VR_PVDDQ_ABC_VDD @BASEBOARD_FAB2_LIB.BASEBOARD_FAB2(SCH_1):VR_PVDDQ_ABC_VDD
 R3T13    2      B RES_0402-0.0,5%,1/16W,CHIP,G21A    I33 @BASEBOARD_FAB2_LIB.BASEBOARD_FAB2(SCH_1):PAGE215
 C7F17    1      A CAP_A_0402V-0.1UF,16V,10%,X7R,A    I34 @BASEBOARD_FAB2_LIB.BASEBOARD_FAB2(SCH_1):PAGE215
 C7F18    1      A CAP_A_0402V-1.0UF,6.3V,10%,X6SA    I35 @BASEBOARD_FAB2_LIB.BASEBOARD_FAB2(SCH_1):PAGE215
 EU7G1   39    VDD PXM1310B_QFN-IC,H89186-001    I69 @BASEBOARD_FAB2_LIB.BASEBOARD_FAB2(SCH_1):PAGE215

VR_PVDDQ_ABC_VINSEN @BASEBOARD_FAB2_LIB.BASEBOARD_FAB2(SCH_1):VR_PVDDQ_ABC_VINSEN
 EU7G1   37 VINSEN PXM1310B_QFN-IC,H89186-001    I69 @BASEBOARD_FAB2_LIB.BASEBOARD_FAB2(SCH_1):PAGE215
 C12W1    2      B CAP_0402LF-47.0PF,50V,5%,COG,AA     I8 @BASEBOARD_FAB2_LIB.BASEBOARD_FAB2(SCH_1):PAGE197
 R12W5    2      2 665KR2B-GP_SMD-RG2-665KR2B-GP,A   I111 @BASEBOARD_FAB2_LIB.BASEBOARD_FAB2(SCH_1):PAGE197
 R12W2    2      2 665KR5B-1-GP_SMD-RG3-665KR5B-1A   I117 @BASEBOARD_FAB2_LIB.BASEBOARD_FAB2(SCH_1):PAGE197

VR_PVDDQ_ABC_VREN @BASEBOARD_FAB2_LIB.BASEBOARD_FAB2(SCH_1):VR_PVDDQ_ABC_VREN
 R7F21    2      B RES_0402-0.0,5%,1/16W,CHIP,G21A    I13 @BASEBOARD_FAB2_LIB.BASEBOARD_FAB2(SCH_1):PAGE215
 R7F20    2      B RES_0402-100.0K,1%,1/16W,EMPTYA    I29 @BASEBOARD_FAB2_LIB.BASEBOARD_FAB2(SCH_1):PAGE215
 EU7G1   10  AVREN PXM1310B_QFN-IC,H89186-001    I69 @BASEBOARD_FAB2_LIB.BASEBOARD_FAB2(SCH_1):PAGE215

VR_PVDDQ_ABC_XADDR1 @BASEBOARD_FAB2_LIB.BASEBOARD_FAB2(SCH_1):VR_PVDDQ_ABC_XADDR1
 EU7G1   36 XADDR1 PXM1310B_QFN-IC,H89186-001    I69 @BASEBOARD_FAB2_LIB.BASEBOARD_FAB2(SCH_1):PAGE215
  R7G8    1      A RES_0402-2.26K,1.0%,1/16W,CHIPA    I72 @BASEBOARD_FAB2_LIB.BASEBOARD_FAB2(SCH_1):PAGE215

VR_PVDDQ_ABC_XADDR2 @BASEBOARD_FAB2_LIB.BASEBOARD_FAB2(SCH_1):VR_PVDDQ_ABC_XADDR2
 EU7G1   33 XADDR2 PXM1310B_QFN-IC,H89186-001    I69 @BASEBOARD_FAB2_LIB.BASEBOARD_FAB2(SCH_1):PAGE215
 R7G10    1      A RES_0402-2.26K,1.0%,1/16W,CHIPA    I73 @BASEBOARD_FAB2_LIB.BASEBOARD_FAB2(SCH_1):PAGE215

VR_PVDDQ_DEF_AIINSEN @BASEBOARD_FAB2_LIB.BASEBOARD_FAB2(SCH_1):VR_PVDDQ_DEF_AIINSEN
 EU7A5   38 IINSEN PXM1310B_QFN-IC,H89186-001    I69 @BASEBOARD_FAB2_LIB.BASEBOARD_FAB2(SCH_1):PAGE218
 C12W2    1      A CAP_0402LF-47.0PF,50V,5%,COG,AA     I1 @BASEBOARD_FAB2_LIB.BASEBOARD_FAB2(SCH_1):PAGE197
R12W10    1      1 665KR2B-GP_SMD-RG2-665KR2B-GP,A   I109 @BASEBOARD_FAB2_LIB.BASEBOARD_FAB2(SCH_1):PAGE197
 R12W6    2      2 665KR5B-1-GP_SMD-RG3-665KR5B-1A   I120 @BASEBOARD_FAB2_LIB.BASEBOARD_FAB2(SCH_1):PAGE197

VR_PVDDQ_DEF_AIREF1 @BASEBOARD_FAB2_LIB.BASEBOARD_FAB2(SCH_1):VR_PVDDQ_DEF_AIREF1
 EU7A1   39  REFIN IR354XX_SM-IR35411,IC,H73688-0A   I106 @BASEBOARD_FAB2_LIB.BASEBOARD_FAB2(SCH_1):PAGE219
  CT45    1      A CAP_A_0402V-0.1UF,16V,10%,X7R,A   I116 @BASEBOARD_FAB2_LIB.BASEBOARD_FAB2(SCH_1):PAGE219
  RF17    1      A RES_0402-1.0K,0.1%,1/16W,CHIP,A    I18 @BASEBOARD_FAB2_LIB.BASEBOARD_FAB2(SCH_1):PAGE218
 EU7A5   21 AIREF1 PXM1310B_QFN-IC,H89186-001    I69 @BASEBOARD_FAB2_LIB.BASEBOARD_FAB2(SCH_1):PAGE218
  CF17    1      1 SC22P50V2JN-4GP_SMD-BCG-SC22P5A    I17 @BASEBOARD_FAB2_LIB.BASEBOARD_FAB2(SCH_1):PAGE218

VR_PVDDQ_DEF_AIREF2 @BASEBOARD_FAB2_LIB.BASEBOARD_FAB2(SCH_1):VR_PVDDQ_DEF_AIREF2
 EU7A4   39  REFIN IR354XX_SM-IR35411,IC,H73688-0A   I107 @BASEBOARD_FAB2_LIB.BASEBOARD_FAB2(SCH_1):PAGE219
  CT46    1      A CAP_A_0402V-0.1UF,16V,10%,X7R,A   I113 @BASEBOARD_FAB2_LIB.BASEBOARD_FAB2(SCH_1):PAGE219
  RF18    1      A RES_0402-1.0K,0.1%,1/16W,CHIP,A    I19 @BASEBOARD_FAB2_LIB.BASEBOARD_FAB2(SCH_1):PAGE218
  CF18    1      1 SC22P50V2JN-4GP_SMD-BCG-SC22P5A    I20 @BASEBOARD_FAB2_LIB.BASEBOARD_FAB2(SCH_1):PAGE218
 EU7A5   23 AIREF2 PXM1310B_QFN-IC,H89186-001    I69 @BASEBOARD_FAB2_LIB.BASEBOARD_FAB2(SCH_1):PAGE218

VR_PVDDQ_DEF_AVSP @BASEBOARD_FAB2_LIB.BASEBOARD_FAB2(SCH_1):VR_PVDDQ_DEF_AVSP
  R7A7    2      B RES_0402-10.0,1%,1/16W,CHIP,G2A    I13 @BASEBOARD_FAB2_LIB.BASEBOARD_FAB2(SCH_1):PAGE218
 EU7A5   19  AVSEN PXM1310B_QFN-IC,H89186-001    I69 @BASEBOARD_FAB2_LIB.BASEBOARD_FAB2(SCH_1):PAGE218
 C7A28    1      A CAP_0402LF-220PF,50V,10%,X7R,AA    I14 @BASEBOARD_FAB2_LIB.BASEBOARD_FAB2(SCH_1):PAGE218

VR_PVDDQ_DEF_PH1_BOOT @BASEBOARD_FAB2_LIB.BASEBOARD_FAB2(SCH_1):VR_PVDDQ_DEF_PH1_BOOT
 C7A12    1      A CAP_0402-0.220UF,16V,10%,X7R,AA    I44 @BASEBOARD_FAB2_LIB.BASEBOARD_FAB2(SCH_1):PAGE219
  RT30    1      A RES_0603-0,5.0%,1/10W,CHIP,G22A   I141 @BASEBOARD_FAB2_LIB.BASEBOARD_FAB2(SCH_1):PAGE219

VR_PVDDQ_DEF_PH1_BOOT_R @BASEBOARD_FAB2_LIB.BASEBOARD_FAB2(SCH_1):VR_PVDDQ_DEF_PH1_BOOT_R
 EU7A1   33  BOOST IR354XX_SM-IR35411,IC,H73688-0A   I106 @BASEBOARD_FAB2_LIB.BASEBOARD_FAB2(SCH_1):PAGE219
  RT30    2      B RES_0603-0,5.0%,1/10W,CHIP,G22A   I141 @BASEBOARD_FAB2_LIB.BASEBOARD_FAB2(SCH_1):PAGE219

VR_PVDDQ_DEF_PH1_OCSET @BASEBOARD_FAB2_LIB.BASEBOARD_FAB2(SCH_1):VR_PVDDQ_DEF_PH1_OCSET
 EU7A1   37  OCSET IR354XX_SM-IR35411,IC,H73688-0A   I106 @BASEBOARD_FAB2_LIB.BASEBOARD_FAB2(SCH_1):PAGE219
 R7A20    1      A RES_0402-68.1K,1%,1/16W,EMPTY,A   I108 @BASEBOARD_FAB2_LIB.BASEBOARD_FAB2(SCH_1):PAGE219

VR_PVDDQ_DEF_PH1_PHASE @BASEBOARD_FAB2_LIB.BASEBOARD_FAB2(SCH_1):VR_PVDDQ_DEF_PH1_PHASE
 C7A12    2      B CAP_0402-0.220UF,16V,10%,X7R,AA    I44 @BASEBOARD_FAB2_LIB.BASEBOARD_FAB2(SCH_1):PAGE219
 EU7A1   32  PHASE IR354XX_SM-IR35411,IC,H73688-0A   I106 @BASEBOARD_FAB2_LIB.BASEBOARD_FAB2(SCH_1):PAGE219

VR_PVDDQ_DEF_PH1_SW @BASEBOARD_FAB2_LIB.BASEBOARD_FAB2(SCH_1):VR_PVDDQ_DEF_PH1_SW
 EU7A1   10     SW IR354XX_SM-IR35411,IC,H73688-0A   I106 @BASEBOARD_FAB2_LIB.BASEBOARD_FAB2(SCH_1):PAGE219
  CT44    1      A CAP_0402LF-1000PF,50V,10%,X7R,A   I137 @BASEBOARD_FAB2_LIB.BASEBOARD_FAB2(SCH_1):PAGE219
  L7A1    1      S IND-120NH-30-GP_DISCRET-GB2-INA   I157 @BASEBOARD_FAB2_LIB.BASEBOARD_FAB2(SCH_1):PAGE219

VR_PVDDQ_DEF_PH1_SW_RC @BASEBOARD_FAB2_LIB.BASEBOARD_FAB2(SCH_1):VR_PVDDQ_DEF_PH1_SW_RC
  CT44    2      B CAP_0402LF-1000PF,50V,10%,X7R,A   I137 @BASEBOARD_FAB2_LIB.BASEBOARD_FAB2(SCH_1):PAGE219
  RT29    1      1 1R3F-GP_RCL_GP-1R3F-GP,64.1R00A   I153 @BASEBOARD_FAB2_LIB.BASEBOARD_FAB2(SCH_1):PAGE219

VR_PVDDQ_DEF_PH1_VCIN @BASEBOARD_FAB2_LIB.BASEBOARD_FAB2(SCH_1):VR_PVDDQ_DEF_PH1_VCIN
 C7A16    1      A CAP_0402-1.0UF,16V,10%,X6S,D97A    I50 @BASEBOARD_FAB2_LIB.BASEBOARD_FAB2(SCH_1):PAGE219
 EU7A1    3    VCC IR354XX_SM-IR35411,IC,H73688-0A   I106 @BASEBOARD_FAB2_LIB.BASEBOARD_FAB2(SCH_1):PAGE219
  R3L6    1      A RES_0402-0.0,5%,1/16W,CHIP,G21A   I147 @BASEBOARD_FAB2_LIB.BASEBOARD_FAB2(SCH_1):PAGE219

VR_PVDDQ_DEF_PH2_BOOT @BASEBOARD_FAB2_LIB.BASEBOARD_FAB2(SCH_1):VR_PVDDQ_DEF_PH2_BOOT
 C7A22    1      A CAP_0402-0.220UF,16V,10%,X7R,AA    I75 @BASEBOARD_FAB2_LIB.BASEBOARD_FAB2(SCH_1):PAGE219
  RT31    1      A RES_0603-0,5.0%,1/10W,CHIP,G22A   I142 @BASEBOARD_FAB2_LIB.BASEBOARD_FAB2(SCH_1):PAGE219

VR_PVDDQ_DEF_PH2_BOOT_R @BASEBOARD_FAB2_LIB.BASEBOARD_FAB2(SCH_1):VR_PVDDQ_DEF_PH2_BOOT_R
 EU7A4   33  BOOST IR354XX_SM-IR35411,IC,H73688-0A   I107 @BASEBOARD_FAB2_LIB.BASEBOARD_FAB2(SCH_1):PAGE219
  RT31    2      B RES_0603-0,5.0%,1/10W,CHIP,G22A   I142 @BASEBOARD_FAB2_LIB.BASEBOARD_FAB2(SCH_1):PAGE219

VR_PVDDQ_DEF_PH2_OCSET @BASEBOARD_FAB2_LIB.BASEBOARD_FAB2(SCH_1):VR_PVDDQ_DEF_PH2_OCSET
 EU7A4   37  OCSET IR354XX_SM-IR35411,IC,H73688-0A   I107 @BASEBOARD_FAB2_LIB.BASEBOARD_FAB2(SCH_1):PAGE219
 R7A21    1      A RES_0402-68.1K,1%,1/16W,EMPTY,A   I110 @BASEBOARD_FAB2_LIB.BASEBOARD_FAB2(SCH_1):PAGE219

VR_PVDDQ_DEF_PH2_PHASE @BASEBOARD_FAB2_LIB.BASEBOARD_FAB2(SCH_1):VR_PVDDQ_DEF_PH2_PHASE
 C7A22    2      B CAP_0402-0.220UF,16V,10%,X7R,AA    I75 @BASEBOARD_FAB2_LIB.BASEBOARD_FAB2(SCH_1):PAGE219
 EU7A4   32  PHASE IR354XX_SM-IR35411,IC,H73688-0A   I107 @BASEBOARD_FAB2_LIB.BASEBOARD_FAB2(SCH_1):PAGE219

VR_PVDDQ_DEF_PH2_SW @BASEBOARD_FAB2_LIB.BASEBOARD_FAB2(SCH_1):VR_PVDDQ_DEF_PH2_SW
 EU7A4   10     SW IR354XX_SM-IR35411,IC,H73688-0A   I107 @BASEBOARD_FAB2_LIB.BASEBOARD_FAB2(SCH_1):PAGE219
  CT47    1      A CAP_0402LF-1000PF,50V,10%,X7R,A   I138 @BASEBOARD_FAB2_LIB.BASEBOARD_FAB2(SCH_1):PAGE219
  L7A3    1      S IND-120NH-30-GP_DISCRET-GB2-INA   I158 @BASEBOARD_FAB2_LIB.BASEBOARD_FAB2(SCH_1):PAGE219

VR_PVDDQ_DEF_PH2_SW_RC @BASEBOARD_FAB2_LIB.BASEBOARD_FAB2(SCH_1):VR_PVDDQ_DEF_PH2_SW_RC
  CT47    2      B CAP_0402LF-1000PF,50V,10%,X7R,A   I138 @BASEBOARD_FAB2_LIB.BASEBOARD_FAB2(SCH_1):PAGE219
  RT32    1      1 1R3F-GP_RCL_GP-1R3F-GP,64.1R00A   I154 @BASEBOARD_FAB2_LIB.BASEBOARD_FAB2(SCH_1):PAGE219

VR_PVDDQ_DEF_PH2_VCIN @BASEBOARD_FAB2_LIB.BASEBOARD_FAB2(SCH_1):VR_PVDDQ_DEF_PH2_VCIN
 C7A24    1      A CAP_0402-1.0UF,16V,10%,X6S,D97A    I77 @BASEBOARD_FAB2_LIB.BASEBOARD_FAB2(SCH_1):PAGE219
 EU7A4    3    VCC IR354XX_SM-IR35411,IC,H73688-0A   I107 @BASEBOARD_FAB2_LIB.BASEBOARD_FAB2(SCH_1):PAGE219
  R3L8    1      A RES_0402-0.0,5%,1/16W,CHIP,G21A   I148 @BASEBOARD_FAB2_LIB.BASEBOARD_FAB2(SCH_1):PAGE219

VR_PVDDQ_DEF_PWM1 @BASEBOARD_FAB2_LIB.BASEBOARD_FAB2(SCH_1):VR_PVDDQ_DEF_PWM1
 EU7A1   34    PWM IR354XX_SM-IR35411,IC,H73688-0A   I106 @BASEBOARD_FAB2_LIB.BASEBOARD_FAB2(SCH_1):PAGE219
 EU7A5    5  APWM1 PXM1310B_QFN-IC,H89186-001    I69 @BASEBOARD_FAB2_LIB.BASEBOARD_FAB2(SCH_1):PAGE218

VR_PVDDQ_DEF_PWM2 @BASEBOARD_FAB2_LIB.BASEBOARD_FAB2(SCH_1):VR_PVDDQ_DEF_PWM2
 EU7A4   34    PWM IR354XX_SM-IR35411,IC,H73688-0A   I107 @BASEBOARD_FAB2_LIB.BASEBOARD_FAB2(SCH_1):PAGE219
 EU7A5    4  APWM2 PXM1310B_QFN-IC,H89186-001    I69 @BASEBOARD_FAB2_LIB.BASEBOARD_FAB2(SCH_1):PAGE218

VR_PVDDQ_DEF_VD12 @BASEBOARD_FAB2_LIB.BASEBOARD_FAB2(SCH_1):VR_PVDDQ_DEF_VD12
  C7B2    1      A CAP_A_0402V-0.1UF,16V,10%,X7R,A    I28 @BASEBOARD_FAB2_LIB.BASEBOARD_FAB2(SCH_1):PAGE218
  C7B1    1      A CAP_A_0402V-1.0UF,6.3V,10%,X6SA    I30 @BASEBOARD_FAB2_LIB.BASEBOARD_FAB2(SCH_1):PAGE218
 EU7A5   40   VD12 PXM1310B_QFN-IC,H89186-001    I69 @BASEBOARD_FAB2_LIB.BASEBOARD_FAB2(SCH_1):PAGE218

VR_PVDDQ_DEF_VDD @BASEBOARD_FAB2_LIB.BASEBOARD_FAB2(SCH_1):VR_PVDDQ_DEF_VDD
  R3M1    2      B RES_0402-0.0,5%,1/16W,CHIP,G21A    I35 @BASEBOARD_FAB2_LIB.BASEBOARD_FAB2(SCH_1):PAGE218
 C7A38    1      A CAP_A_0402V-0.1UF,16V,10%,X7R,A    I38 @BASEBOARD_FAB2_LIB.BASEBOARD_FAB2(SCH_1):PAGE218
 EU7A5   39    VDD PXM1310B_QFN-IC,H89186-001    I69 @BASEBOARD_FAB2_LIB.BASEBOARD_FAB2(SCH_1):PAGE218
 C7A37    1      A CAP_A_0402V-1.0UF,6.3V,10%,X6SA    I40 @BASEBOARD_FAB2_LIB.BASEBOARD_FAB2(SCH_1):PAGE218

VR_PVDDQ_DEF_VINSEN @BASEBOARD_FAB2_LIB.BASEBOARD_FAB2(SCH_1):VR_PVDDQ_DEF_VINSEN
 EU7A5   37 VINSEN PXM1310B_QFN-IC,H89186-001    I69 @BASEBOARD_FAB2_LIB.BASEBOARD_FAB2(SCH_1):PAGE218
 C12W2    2      B CAP_0402LF-47.0PF,50V,5%,COG,AA     I1 @BASEBOARD_FAB2_LIB.BASEBOARD_FAB2(SCH_1):PAGE197
R12W10    2      2 665KR2B-GP_SMD-RG2-665KR2B-GP,A   I109 @BASEBOARD_FAB2_LIB.BASEBOARD_FAB2(SCH_1):PAGE197
 R12W7    2      2 665KR5B-1-GP_SMD-RG3-665KR5B-1A   I121 @BASEBOARD_FAB2_LIB.BASEBOARD_FAB2(SCH_1):PAGE197

VR_PVDDQ_DEF_VREN @BASEBOARD_FAB2_LIB.BASEBOARD_FAB2(SCH_1):VR_PVDDQ_DEF_VREN
  R3M6    2      B RES_0402-0.0,5%,1/16W,CHIP,G21A    I15 @BASEBOARD_FAB2_LIB.BASEBOARD_FAB2(SCH_1):PAGE218
  R3M5    2      B RES_0402-100.0K,1%,1/16W,EMPTYA    I34 @BASEBOARD_FAB2_LIB.BASEBOARD_FAB2(SCH_1):PAGE218
 EU7A5   10  AVREN PXM1310B_QFN-IC,H89186-001    I69 @BASEBOARD_FAB2_LIB.BASEBOARD_FAB2(SCH_1):PAGE218

VR_PVDDQ_DEF_XADDR1 @BASEBOARD_FAB2_LIB.BASEBOARD_FAB2(SCH_1):VR_PVDDQ_DEF_XADDR1
 EU7A5   36 XADDR1 PXM1310B_QFN-IC,H89186-001    I69 @BASEBOARD_FAB2_LIB.BASEBOARD_FAB2(SCH_1):PAGE218
 R7A10    1      A RES_0402-16K,1.0%,1/16W,CHIP,GA    I73 @BASEBOARD_FAB2_LIB.BASEBOARD_FAB2(SCH_1):PAGE218

VR_PVDDQ_DEF_XADDR2 @BASEBOARD_FAB2_LIB.BASEBOARD_FAB2(SCH_1):VR_PVDDQ_DEF_XADDR2
 EU7A5   33 XADDR2 PXM1310B_QFN-IC,H89186-001    I69 @BASEBOARD_FAB2_LIB.BASEBOARD_FAB2(SCH_1):PAGE218
  R7A8    1      A RES_0402-2.26K,1.0%,1/16W,CHIPA    I74 @BASEBOARD_FAB2_LIB.BASEBOARD_FAB2(SCH_1):PAGE218

VR_PVDDQ_GHJ_AIINSEN @BASEBOARD_FAB2_LIB.BASEBOARD_FAB2(SCH_1):VR_PVDDQ_GHJ_AIINSEN
 EU1G2   38 IINSEN PXM1310B_QFN-IC,H89186-001    I69 @BASEBOARD_FAB2_LIB.BASEBOARD_FAB2(SCH_1):PAGE223
 C12W3    1      A CAP_0402LF-47.0PF,50V,5%,COG,AA    I42 @BASEBOARD_FAB2_LIB.BASEBOARD_FAB2(SCH_1):PAGE197
R12W15    1      1 665KR2B-GP_SMD-RG2-665KR2B-GP,A   I112 @BASEBOARD_FAB2_LIB.BASEBOARD_FAB2(SCH_1):PAGE197
R12W11    2      2 665KR5B-1-GP_SMD-RG3-665KR5B-1A   I118 @BASEBOARD_FAB2_LIB.BASEBOARD_FAB2(SCH_1):PAGE197

VR_PVDDQ_GHJ_AIREF1 @BASEBOARD_FAB2_LIB.BASEBOARD_FAB2(SCH_1):VR_PVDDQ_GHJ_AIREF1
  RF19    1      A RES_0402-1.0K,0.1%,1/16W,CHIP,A    I16 @BASEBOARD_FAB2_LIB.BASEBOARD_FAB2(SCH_1):PAGE223
 EU1G1   39  REFIN IR354XX_SM-IR35411,IC,H73688-0A   I110 @BASEBOARD_FAB2_LIB.BASEBOARD_FAB2(SCH_1):PAGE224
  CT30    1      A CAP_A_0402V-0.1UF,16V,10%,X7R,A   I117 @BASEBOARD_FAB2_LIB.BASEBOARD_FAB2(SCH_1):PAGE224
  CF19    1      1 SC22P50V2JN-4GP_SMD-BCG-SC22P5A    I15 @BASEBOARD_FAB2_LIB.BASEBOARD_FAB2(SCH_1):PAGE223
 EU1G2   21 AIREF1 PXM1310B_QFN-IC,H89186-001    I69 @BASEBOARD_FAB2_LIB.BASEBOARD_FAB2(SCH_1):PAGE223

VR_PVDDQ_GHJ_AIREF2 @BASEBOARD_FAB2_LIB.BASEBOARD_FAB2(SCH_1):VR_PVDDQ_GHJ_AIREF2
 EU1F1   39  REFIN IR354XX_SM-IR35411,IC,H73688-0A   I111 @BASEBOARD_FAB2_LIB.BASEBOARD_FAB2(SCH_1):PAGE224
  CT31    1      A CAP_A_0402V-0.1UF,16V,10%,X7R,A   I124 @BASEBOARD_FAB2_LIB.BASEBOARD_FAB2(SCH_1):PAGE224
  RF20    1      A RES_0402-1.0K,0.1%,1/16W,CHIP,A    I19 @BASEBOARD_FAB2_LIB.BASEBOARD_FAB2(SCH_1):PAGE223
 EU1G2   23 AIREF2 PXM1310B_QFN-IC,H89186-001    I69 @BASEBOARD_FAB2_LIB.BASEBOARD_FAB2(SCH_1):PAGE223
  CF20    1      1 SC22P50V2JN-4GP_SMD-BCG-SC22P5A    I17 @BASEBOARD_FAB2_LIB.BASEBOARD_FAB2(SCH_1):PAGE223

VR_PVDDQ_GHJ_AVSP @BASEBOARD_FAB2_LIB.BASEBOARD_FAB2(SCH_1):VR_PVDDQ_GHJ_AVSP
 C1G16    1      A CAP_0402LF-220PF,50V,10%,X7R,AA    I12 @BASEBOARD_FAB2_LIB.BASEBOARD_FAB2(SCH_1):PAGE223
 EU1G2   19  AVSEN PXM1310B_QFN-IC,H89186-001    I69 @BASEBOARD_FAB2_LIB.BASEBOARD_FAB2(SCH_1):PAGE223
  R1G5    2      B RES_0402-10.0,1%,1/16W,CHIP,G2A    I13 @BASEBOARD_FAB2_LIB.BASEBOARD_FAB2(SCH_1):PAGE223

VR_PVDDQ_GHJ_PH1_BOOT @BASEBOARD_FAB2_LIB.BASEBOARD_FAB2(SCH_1):VR_PVDDQ_GHJ_PH1_BOOT
 C1G11    1      A CAP_0402-0.220UF,16V,10%,X7R,AA    I44 @BASEBOARD_FAB2_LIB.BASEBOARD_FAB2(SCH_1):PAGE224
  RT19    1      A RES_0603-0,5.0%,1/10W,CHIP,G22A   I144 @BASEBOARD_FAB2_LIB.BASEBOARD_FAB2(SCH_1):PAGE224

VR_PVDDQ_GHJ_PH1_BOOT_R @BASEBOARD_FAB2_LIB.BASEBOARD_FAB2(SCH_1):VR_PVDDQ_GHJ_PH1_BOOT_R
 EU1G1   33  BOOST IR354XX_SM-IR35411,IC,H73688-0A   I110 @BASEBOARD_FAB2_LIB.BASEBOARD_FAB2(SCH_1):PAGE224
  RT19    2      B RES_0603-0,5.0%,1/10W,CHIP,G22A   I144 @BASEBOARD_FAB2_LIB.BASEBOARD_FAB2(SCH_1):PAGE224

VR_PVDDQ_GHJ_PH1_OCSET @BASEBOARD_FAB2_LIB.BASEBOARD_FAB2(SCH_1):VR_PVDDQ_GHJ_PH1_OCSET
 EU1G1   37  OCSET IR354XX_SM-IR35411,IC,H73688-0A   I110 @BASEBOARD_FAB2_LIB.BASEBOARD_FAB2(SCH_1):PAGE224
 R1G26    1      A RES_0402-68.1K,1%,1/16W,EMPTY,A   I112 @BASEBOARD_FAB2_LIB.BASEBOARD_FAB2(SCH_1):PAGE224

VR_PVDDQ_GHJ_PH1_PHASE @BASEBOARD_FAB2_LIB.BASEBOARD_FAB2(SCH_1):VR_PVDDQ_GHJ_PH1_PHASE
 C1G11    2      B CAP_0402-0.220UF,16V,10%,X7R,AA    I44 @BASEBOARD_FAB2_LIB.BASEBOARD_FAB2(SCH_1):PAGE224
 EU1G1   32  PHASE IR354XX_SM-IR35411,IC,H73688-0A   I110 @BASEBOARD_FAB2_LIB.BASEBOARD_FAB2(SCH_1):PAGE224

VR_PVDDQ_GHJ_PH1_SW @BASEBOARD_FAB2_LIB.BASEBOARD_FAB2(SCH_1):VR_PVDDQ_GHJ_PH1_SW
 EU1G1   10     SW IR354XX_SM-IR35411,IC,H73688-0A   I110 @BASEBOARD_FAB2_LIB.BASEBOARD_FAB2(SCH_1):PAGE224
  CT29    1      A CAP_0402LF-1000PF,50V,10%,X7R,A   I140 @BASEBOARD_FAB2_LIB.BASEBOARD_FAB2(SCH_1):PAGE224
  L1G1    1      S IND-120NH-30-GP_DISCRET-GB2-INA   I160 @BASEBOARD_FAB2_LIB.BASEBOARD_FAB2(SCH_1):PAGE224

VR_PVDDQ_GHJ_PH1_SW_RC @BASEBOARD_FAB2_LIB.BASEBOARD_FAB2(SCH_1):VR_PVDDQ_GHJ_PH1_SW_RC
  CT29    2      B CAP_0402LF-1000PF,50V,10%,X7R,A   I140 @BASEBOARD_FAB2_LIB.BASEBOARD_FAB2(SCH_1):PAGE224
  RT20    1      1 1R3F-GP_RCL_GP-1R3F-GP,64.1R00A   I156 @BASEBOARD_FAB2_LIB.BASEBOARD_FAB2(SCH_1):PAGE224

VR_PVDDQ_GHJ_PH1_VCIN @BASEBOARD_FAB2_LIB.BASEBOARD_FAB2(SCH_1):VR_PVDDQ_GHJ_PH1_VCIN
  C1G6    1      A CAP_0402-1.0UF,16V,10%,X6S,D97A    I50 @BASEBOARD_FAB2_LIB.BASEBOARD_FAB2(SCH_1):PAGE224
 EU1G1    3    VCC IR354XX_SM-IR35411,IC,H73688-0A   I110 @BASEBOARD_FAB2_LIB.BASEBOARD_FAB2(SCH_1):PAGE224
  R9U1    1      A RES_0402-0.0,5%,1/16W,CHIP,G21A   I150 @BASEBOARD_FAB2_LIB.BASEBOARD_FAB2(SCH_1):PAGE224

VR_PVDDQ_GHJ_PH2_BOOT @BASEBOARD_FAB2_LIB.BASEBOARD_FAB2(SCH_1):VR_PVDDQ_GHJ_PH2_BOOT
 C1F26    1      A CAP_0402-0.220UF,16V,10%,X7R,AA    I75 @BASEBOARD_FAB2_LIB.BASEBOARD_FAB2(SCH_1):PAGE224
  RT21    1      A RES_0603-0,5.0%,1/10W,CHIP,G22A   I145 @BASEBOARD_FAB2_LIB.BASEBOARD_FAB2(SCH_1):PAGE224

VR_PVDDQ_GHJ_PH2_BOOT_R @BASEBOARD_FAB2_LIB.BASEBOARD_FAB2(SCH_1):VR_PVDDQ_GHJ_PH2_BOOT_R
 EU1F1   33  BOOST IR354XX_SM-IR35411,IC,H73688-0A   I111 @BASEBOARD_FAB2_LIB.BASEBOARD_FAB2(SCH_1):PAGE224
  RT21    2      B RES_0603-0,5.0%,1/10W,CHIP,G22A   I145 @BASEBOARD_FAB2_LIB.BASEBOARD_FAB2(SCH_1):PAGE224

VR_PVDDQ_GHJ_PH2_OCSET @BASEBOARD_FAB2_LIB.BASEBOARD_FAB2(SCH_1):VR_PVDDQ_GHJ_PH2_OCSET
 EU1F1   37  OCSET IR354XX_SM-IR35411,IC,H73688-0A   I111 @BASEBOARD_FAB2_LIB.BASEBOARD_FAB2(SCH_1):PAGE224
 R1G25    1      A RES_0402-68.1K,1%,1/16W,EMPTY,A   I114 @BASEBOARD_FAB2_LIB.BASEBOARD_FAB2(SCH_1):PAGE224

VR_PVDDQ_GHJ_PH2_PHASE @BASEBOARD_FAB2_LIB.BASEBOARD_FAB2(SCH_1):VR_PVDDQ_GHJ_PH2_PHASE
 C1F26    2      B CAP_0402-0.220UF,16V,10%,X7R,AA    I75 @BASEBOARD_FAB2_LIB.BASEBOARD_FAB2(SCH_1):PAGE224
 EU1F1   32  PHASE IR354XX_SM-IR35411,IC,H73688-0A   I111 @BASEBOARD_FAB2_LIB.BASEBOARD_FAB2(SCH_1):PAGE224

VR_PVDDQ_GHJ_PH2_SW @BASEBOARD_FAB2_LIB.BASEBOARD_FAB2(SCH_1):VR_PVDDQ_GHJ_PH2_SW
 EU1F1   10     SW IR354XX_SM-IR35411,IC,H73688-0A   I111 @BASEBOARD_FAB2_LIB.BASEBOARD_FAB2(SCH_1):PAGE224
  CT33    1      A CAP_0402LF-1000PF,50V,10%,X7R,A   I141 @BASEBOARD_FAB2_LIB.BASEBOARD_FAB2(SCH_1):PAGE224
  L1F2    1      S IND-120NH-30-GP_DISCRET-GB2-INA   I161 @BASEBOARD_FAB2_LIB.BASEBOARD_FAB2(SCH_1):PAGE224

VR_PVDDQ_GHJ_PH2_SW_RC @BASEBOARD_FAB2_LIB.BASEBOARD_FAB2(SCH_1):VR_PVDDQ_GHJ_PH2_SW_RC
  CT33    2      B CAP_0402LF-1000PF,50V,10%,X7R,A   I141 @BASEBOARD_FAB2_LIB.BASEBOARD_FAB2(SCH_1):PAGE224
  RT22    1      1 1R3F-GP_RCL_GP-1R3F-GP,64.1R00A   I157 @BASEBOARD_FAB2_LIB.BASEBOARD_FAB2(SCH_1):PAGE224

VR_PVDDQ_GHJ_PH2_VCIN @BASEBOARD_FAB2_LIB.BASEBOARD_FAB2(SCH_1):VR_PVDDQ_GHJ_PH2_VCIN
 C1G28    1      A CAP_0402-1.0UF,16V,10%,X6S,D97A    I77 @BASEBOARD_FAB2_LIB.BASEBOARD_FAB2(SCH_1):PAGE224
 EU1F1    3    VCC IR354XX_SM-IR35411,IC,H73688-0A   I111 @BASEBOARD_FAB2_LIB.BASEBOARD_FAB2(SCH_1):PAGE224
 R9U12    1      A RES_0402-0.0,5%,1/16W,CHIP,G21A   I151 @BASEBOARD_FAB2_LIB.BASEBOARD_FAB2(SCH_1):PAGE224

VR_PVDDQ_GHJ_PWM1 @BASEBOARD_FAB2_LIB.BASEBOARD_FAB2(SCH_1):VR_PVDDQ_GHJ_PWM1
 EU1G1   34    PWM IR354XX_SM-IR35411,IC,H73688-0A   I110 @BASEBOARD_FAB2_LIB.BASEBOARD_FAB2(SCH_1):PAGE224
 EU1G2    5  APWM1 PXM1310B_QFN-IC,H89186-001    I69 @BASEBOARD_FAB2_LIB.BASEBOARD_FAB2(SCH_1):PAGE223

VR_PVDDQ_GHJ_PWM2 @BASEBOARD_FAB2_LIB.BASEBOARD_FAB2(SCH_1):VR_PVDDQ_GHJ_PWM2
 EU1F1   34    PWM IR354XX_SM-IR35411,IC,H73688-0A   I111 @BASEBOARD_FAB2_LIB.BASEBOARD_FAB2(SCH_1):PAGE224
 EU1G2    4  APWM2 PXM1310B_QFN-IC,H89186-001    I69 @BASEBOARD_FAB2_LIB.BASEBOARD_FAB2(SCH_1):PAGE223

VR_PVDDQ_GHJ_VD12 @BASEBOARD_FAB2_LIB.BASEBOARD_FAB2(SCH_1):VR_PVDDQ_GHJ_VD12
 C1G23    1      A CAP_A_0402V-1.0UF,6.3V,10%,X6SA    I44 @BASEBOARD_FAB2_LIB.BASEBOARD_FAB2(SCH_1):PAGE223
 C1G22    1      A CAP_A_0402V-0.1UF,16V,10%,X7R,A    I43 @BASEBOARD_FAB2_LIB.BASEBOARD_FAB2(SCH_1):PAGE223
 EU1G2   40   VD12 PXM1310B_QFN-IC,H89186-001    I69 @BASEBOARD_FAB2_LIB.BASEBOARD_FAB2(SCH_1):PAGE223

VR_PVDDQ_GHJ_VDD @BASEBOARD_FAB2_LIB.BASEBOARD_FAB2(SCH_1):VR_PVDDQ_GHJ_VDD
 C1G25    1      A CAP_A_0402V-0.1UF,16V,10%,X7R,A    I35 @BASEBOARD_FAB2_LIB.BASEBOARD_FAB2(SCH_1):PAGE223
 EU1G2   39    VDD PXM1310B_QFN-IC,H89186-001    I69 @BASEBOARD_FAB2_LIB.BASEBOARD_FAB2(SCH_1):PAGE223
 R9U10    2      B RES_0402-0.0,5%,1/16W,CHIP,G21A    I32 @BASEBOARD_FAB2_LIB.BASEBOARD_FAB2(SCH_1):PAGE223
 C1G27    1      A CAP_A_0402V-1.0UF,6.3V,10%,X6SA    I36 @BASEBOARD_FAB2_LIB.BASEBOARD_FAB2(SCH_1):PAGE223

VR_PVDDQ_GHJ_VINSEN @BASEBOARD_FAB2_LIB.BASEBOARD_FAB2(SCH_1):VR_PVDDQ_GHJ_VINSEN
 EU1G2   37 VINSEN PXM1310B_QFN-IC,H89186-001    I69 @BASEBOARD_FAB2_LIB.BASEBOARD_FAB2(SCH_1):PAGE223
 C12W3    2      B CAP_0402LF-47.0PF,50V,5%,COG,AA    I42 @BASEBOARD_FAB2_LIB.BASEBOARD_FAB2(SCH_1):PAGE197
R12W15    2      2 665KR2B-GP_SMD-RG2-665KR2B-GP,A   I112 @BASEBOARD_FAB2_LIB.BASEBOARD_FAB2(SCH_1):PAGE197
R12W12    2      2 665KR5B-1-GP_SMD-RG3-665KR5B-1A   I119 @BASEBOARD_FAB2_LIB.BASEBOARD_FAB2(SCH_1):PAGE197

VR_PVDDQ_GHJ_VREN @BASEBOARD_FAB2_LIB.BASEBOARD_FAB2(SCH_1):VR_PVDDQ_GHJ_VREN
  R9U7    2      B RES_0402-0.0,5%,1/16W,CHIP,G21A    I14 @BASEBOARD_FAB2_LIB.BASEBOARD_FAB2(SCH_1):PAGE223
  R9U8    2      B RES_0402-100.0K,1%,1/16W,EMPTYA    I31 @BASEBOARD_FAB2_LIB.BASEBOARD_FAB2(SCH_1):PAGE223
 EU1G2   10  AVREN PXM1310B_QFN-IC,H89186-001    I69 @BASEBOARD_FAB2_LIB.BASEBOARD_FAB2(SCH_1):PAGE223

VR_PVDDQ_GHJ_XADDR1 @BASEBOARD_FAB2_LIB.BASEBOARD_FAB2(SCH_1):VR_PVDDQ_GHJ_XADDR1
 EU1G2   36 XADDR1 PXM1310B_QFN-IC,H89186-001    I69 @BASEBOARD_FAB2_LIB.BASEBOARD_FAB2(SCH_1):PAGE223
 R1G23    1      A RES_0402-5.36K,1.0%,1/16W,CHIPA    I73 @BASEBOARD_FAB2_LIB.BASEBOARD_FAB2(SCH_1):PAGE223

VR_PVDDQ_GHJ_XADDR2 @BASEBOARD_FAB2_LIB.BASEBOARD_FAB2(SCH_1):VR_PVDDQ_GHJ_XADDR2
 EU1G2   33 XADDR2 PXM1310B_QFN-IC,H89186-001    I69 @BASEBOARD_FAB2_LIB.BASEBOARD_FAB2(SCH_1):PAGE223
 R1G22    1      A RES_0402-3.16K,1%,1/16W,CHIP,GA    I74 @BASEBOARD_FAB2_LIB.BASEBOARD_FAB2(SCH_1):PAGE223

VR_PVDDQ_KLM_AIINSEN @BASEBOARD_FAB2_LIB.BASEBOARD_FAB2(SCH_1):VR_PVDDQ_KLM_AIINSEN
 EU1B1   38 IINSEN PXM1310B_QFN-IC,H89186-001    I69 @BASEBOARD_FAB2_LIB.BASEBOARD_FAB2(SCH_1):PAGE226
 C12W4    1      A CAP_0402LF-47.0PF,50V,5%,COG,AA    I18 @BASEBOARD_FAB2_LIB.BASEBOARD_FAB2(SCH_1):PAGE197
R12W20    1      1 665KR2B-GP_SMD-RG2-665KR2B-GP,A   I110 @BASEBOARD_FAB2_LIB.BASEBOARD_FAB2(SCH_1):PAGE197
R12W16    2      2 665KR5B-1-GP_SMD-RG3-665KR5B-1A   I122 @BASEBOARD_FAB2_LIB.BASEBOARD_FAB2(SCH_1):PAGE197

VR_PVDDQ_KLM_AIREF1 @BASEBOARD_FAB2_LIB.BASEBOARD_FAB2(SCH_1):VR_PVDDQ_KLM_AIREF1
  RF21    1      A RES_0402-1.0K,0.1%,1/16W,CHIP,A    I16 @BASEBOARD_FAB2_LIB.BASEBOARD_FAB2(SCH_1):PAGE226
 EU1A2   39  REFIN IR354XX_SM-IR35411,IC,H73688-0A   I101 @BASEBOARD_FAB2_LIB.BASEBOARD_FAB2(SCH_1):PAGE227
   CT7    1      A CAP_A_0402V-0.1UF,16V,10%,X7R,A   I109 @BASEBOARD_FAB2_LIB.BASEBOARD_FAB2(SCH_1):PAGE227
  CF21    1      1 SC22P50V2JN-4GP_SMD-BCG-SC22P5A    I15 @BASEBOARD_FAB2_LIB.BASEBOARD_FAB2(SCH_1):PAGE226
 EU1B1   21 AIREF1 PXM1310B_QFN-IC,H89186-001    I69 @BASEBOARD_FAB2_LIB.BASEBOARD_FAB2(SCH_1):PAGE226

VR_PVDDQ_KLM_AIREF2 @BASEBOARD_FAB2_LIB.BASEBOARD_FAB2(SCH_1):VR_PVDDQ_KLM_AIREF2
 EU1A1   39  REFIN IR354XX_SM-IR35411,IC,H73688-0A   I102 @BASEBOARD_FAB2_LIB.BASEBOARD_FAB2(SCH_1):PAGE227
  CT12    1      A CAP_A_0402V-0.1UF,16V,10%,X7R,A   I122 @BASEBOARD_FAB2_LIB.BASEBOARD_FAB2(SCH_1):PAGE227
  RF22    1      A RES_0402-1.0K,0.1%,1/16W,CHIP,A    I18 @BASEBOARD_FAB2_LIB.BASEBOARD_FAB2(SCH_1):PAGE226
 EU1B1   23 AIREF2 PXM1310B_QFN-IC,H89186-001    I69 @BASEBOARD_FAB2_LIB.BASEBOARD_FAB2(SCH_1):PAGE226
  CF22    1      1 SC22P50V2JN-4GP_SMD-BCG-SC22P5A    I17 @BASEBOARD_FAB2_LIB.BASEBOARD_FAB2(SCH_1):PAGE226

VR_PVDDQ_KLM_AVSP @BASEBOARD_FAB2_LIB.BASEBOARD_FAB2(SCH_1):VR_PVDDQ_KLM_AVSP
 C1B12    1      A CAP_0402LF-220PF,50V,10%,X7R,AA    I12 @BASEBOARD_FAB2_LIB.BASEBOARD_FAB2(SCH_1):PAGE226
 EU1B1   19  AVSEN PXM1310B_QFN-IC,H89186-001    I69 @BASEBOARD_FAB2_LIB.BASEBOARD_FAB2(SCH_1):PAGE226
 R1B16    2      B RES_0402-10.0,1%,1/16W,CHIP,G2A    I13 @BASEBOARD_FAB2_LIB.BASEBOARD_FAB2(SCH_1):PAGE226

VR_PVDDQ_KLM_PH1_BOOT @BASEBOARD_FAB2_LIB.BASEBOARD_FAB2(SCH_1):VR_PVDDQ_KLM_PH1_BOOT
 C1A18    1      A CAP_0402-0.220UF,16V,10%,X7R,AA    I44 @BASEBOARD_FAB2_LIB.BASEBOARD_FAB2(SCH_1):PAGE227
   RT5    1      A RES_0603-0,5.0%,1/10W,CHIP,G22A   I138 @BASEBOARD_FAB2_LIB.BASEBOARD_FAB2(SCH_1):PAGE227

VR_PVDDQ_KLM_PH1_BOOT_R @BASEBOARD_FAB2_LIB.BASEBOARD_FAB2(SCH_1):VR_PVDDQ_KLM_PH1_BOOT_R
 EU1A2   33  BOOST IR354XX_SM-IR35411,IC,H73688-0A   I101 @BASEBOARD_FAB2_LIB.BASEBOARD_FAB2(SCH_1):PAGE227
   RT5    2      B RES_0603-0,5.0%,1/10W,CHIP,G22A   I138 @BASEBOARD_FAB2_LIB.BASEBOARD_FAB2(SCH_1):PAGE227

VR_PVDDQ_KLM_PH1_OCSET @BASEBOARD_FAB2_LIB.BASEBOARD_FAB2(SCH_1):VR_PVDDQ_KLM_PH1_OCSET
 EU1A2   37  OCSET IR354XX_SM-IR35411,IC,H73688-0A   I101 @BASEBOARD_FAB2_LIB.BASEBOARD_FAB2(SCH_1):PAGE227
  R1A3    1      A RES_0402-68.1K,1%,1/16W,EMPTY,A   I103 @BASEBOARD_FAB2_LIB.BASEBOARD_FAB2(SCH_1):PAGE227

VR_PVDDQ_KLM_PH1_PHASE @BASEBOARD_FAB2_LIB.BASEBOARD_FAB2(SCH_1):VR_PVDDQ_KLM_PH1_PHASE
 C1A18    2      B CAP_0402-0.220UF,16V,10%,X7R,AA    I44 @BASEBOARD_FAB2_LIB.BASEBOARD_FAB2(SCH_1):PAGE227
 EU1A2   32  PHASE IR354XX_SM-IR35411,IC,H73688-0A   I101 @BASEBOARD_FAB2_LIB.BASEBOARD_FAB2(SCH_1):PAGE227

VR_PVDDQ_KLM_PH1_RC @BASEBOARD_FAB2_LIB.BASEBOARD_FAB2(SCH_1):VR_PVDDQ_KLM_PH1_RC
   CT9    2      B CAP_0402LF-1000PF,50V,10%,X7R,A   I134 @BASEBOARD_FAB2_LIB.BASEBOARD_FAB2(SCH_1):PAGE227
   RT6    1      1 1R3F-GP_RCL_GP-1R3F-GP,64.1R00A   I149 @BASEBOARD_FAB2_LIB.BASEBOARD_FAB2(SCH_1):PAGE227

VR_PVDDQ_KLM_PH1_SW @BASEBOARD_FAB2_LIB.BASEBOARD_FAB2(SCH_1):VR_PVDDQ_KLM_PH1_SW
 EU1A2   10     SW IR354XX_SM-IR35411,IC,H73688-0A   I101 @BASEBOARD_FAB2_LIB.BASEBOARD_FAB2(SCH_1):PAGE227
   CT9    1      A CAP_0402LF-1000PF,50V,10%,X7R,A   I134 @BASEBOARD_FAB2_LIB.BASEBOARD_FAB2(SCH_1):PAGE227
  L1A2    1      S IND-120NH-30-GP_DISCRET-GB2-INA   I152 @BASEBOARD_FAB2_LIB.BASEBOARD_FAB2(SCH_1):PAGE227

VR_PVDDQ_KLM_PH1_VCIN @BASEBOARD_FAB2_LIB.BASEBOARD_FAB2(SCH_1):VR_PVDDQ_KLM_PH1_VCIN
 C1B20    1      A CAP_0402-1.0UF,16V,10%,X6S,D97A    I50 @BASEBOARD_FAB2_LIB.BASEBOARD_FAB2(SCH_1):PAGE227
 EU1A2    3    VCC IR354XX_SM-IR35411,IC,H73688-0A   I101 @BASEBOARD_FAB2_LIB.BASEBOARD_FAB2(SCH_1):PAGE227
  R9L9    1      A RES_0402-0.0,5%,1/16W,CHIP,G21A   I154 @BASEBOARD_FAB2_LIB.BASEBOARD_FAB2(SCH_1):PAGE227

VR_PVDDQ_KLM_PH2_BOOT @BASEBOARD_FAB2_LIB.BASEBOARD_FAB2(SCH_1):VR_PVDDQ_KLM_PH2_BOOT
  C1A8    1      A CAP_0402-0.220UF,16V,10%,X7R,AA    I75 @BASEBOARD_FAB2_LIB.BASEBOARD_FAB2(SCH_1):PAGE227
   RT8    1      A RES_0603-0,5.0%,1/10W,CHIP,G22A   I139 @BASEBOARD_FAB2_LIB.BASEBOARD_FAB2(SCH_1):PAGE227

VR_PVDDQ_KLM_PH2_BOOT_R @BASEBOARD_FAB2_LIB.BASEBOARD_FAB2(SCH_1):VR_PVDDQ_KLM_PH2_BOOT_R
 EU1A1   33  BOOST IR354XX_SM-IR35411,IC,H73688-0A   I102 @BASEBOARD_FAB2_LIB.BASEBOARD_FAB2(SCH_1):PAGE227
   RT8    2      B RES_0603-0,5.0%,1/10W,CHIP,G22A   I139 @BASEBOARD_FAB2_LIB.BASEBOARD_FAB2(SCH_1):PAGE227

VR_PVDDQ_KLM_PH2_OCSET @BASEBOARD_FAB2_LIB.BASEBOARD_FAB2(SCH_1):VR_PVDDQ_KLM_PH2_OCSET
 EU1A1   37  OCSET IR354XX_SM-IR35411,IC,H73688-0A   I102 @BASEBOARD_FAB2_LIB.BASEBOARD_FAB2(SCH_1):PAGE227
  R1A2    1      A RES_0402-68.1K,1%,1/16W,EMPTY,A   I105 @BASEBOARD_FAB2_LIB.BASEBOARD_FAB2(SCH_1):PAGE227

VR_PVDDQ_KLM_PH2_PHASE @BASEBOARD_FAB2_LIB.BASEBOARD_FAB2(SCH_1):VR_PVDDQ_KLM_PH2_PHASE
  C1A8    2      B CAP_0402-0.220UF,16V,10%,X7R,AA    I75 @BASEBOARD_FAB2_LIB.BASEBOARD_FAB2(SCH_1):PAGE227
 EU1A1   32  PHASE IR354XX_SM-IR35411,IC,H73688-0A   I102 @BASEBOARD_FAB2_LIB.BASEBOARD_FAB2(SCH_1):PAGE227

VR_PVDDQ_KLM_PH2_RC @BASEBOARD_FAB2_LIB.BASEBOARD_FAB2(SCH_1):VR_PVDDQ_KLM_PH2_RC
  CT11    2      B CAP_0402LF-1000PF,50V,10%,X7R,A   I135 @BASEBOARD_FAB2_LIB.BASEBOARD_FAB2(SCH_1):PAGE227
   RT7    1      1 1R3F-GP_RCL_GP-1R3F-GP,64.1R00A   I150 @BASEBOARD_FAB2_LIB.BASEBOARD_FAB2(SCH_1):PAGE227

VR_PVDDQ_KLM_PH2_SW @BASEBOARD_FAB2_LIB.BASEBOARD_FAB2(SCH_1):VR_PVDDQ_KLM_PH2_SW
 EU1A1   10     SW IR354XX_SM-IR35411,IC,H73688-0A   I102 @BASEBOARD_FAB2_LIB.BASEBOARD_FAB2(SCH_1):PAGE227
  CT11    1      A CAP_0402LF-1000PF,50V,10%,X7R,A   I135 @BASEBOARD_FAB2_LIB.BASEBOARD_FAB2(SCH_1):PAGE227
  L1A1    1      S IND-120NH-30-GP_DISCRET-GB2-INA   I153 @BASEBOARD_FAB2_LIB.BASEBOARD_FAB2(SCH_1):PAGE227

VR_PVDDQ_KLM_PH2_VCIN @BASEBOARD_FAB2_LIB.BASEBOARD_FAB2(SCH_1):VR_PVDDQ_KLM_PH2_VCIN
  C1A6    1      A CAP_0402-1.0UF,16V,10%,X6S,D97A    I77 @BASEBOARD_FAB2_LIB.BASEBOARD_FAB2(SCH_1):PAGE227
 EU1A1    3    VCC IR354XX_SM-IR35411,IC,H73688-0A   I102 @BASEBOARD_FAB2_LIB.BASEBOARD_FAB2(SCH_1):PAGE227
  R9L4    1      A RES_0402-0.0,5%,1/16W,CHIP,G21A   I155 @BASEBOARD_FAB2_LIB.BASEBOARD_FAB2(SCH_1):PAGE227

VR_PVDDQ_KLM_PWM1 @BASEBOARD_FAB2_LIB.BASEBOARD_FAB2(SCH_1):VR_PVDDQ_KLM_PWM1
 EU1A2   34    PWM IR354XX_SM-IR35411,IC,H73688-0A   I101 @BASEBOARD_FAB2_LIB.BASEBOARD_FAB2(SCH_1):PAGE227
 EU1B1    5  APWM1 PXM1310B_QFN-IC,H89186-001    I69 @BASEBOARD_FAB2_LIB.BASEBOARD_FAB2(SCH_1):PAGE226

VR_PVDDQ_KLM_PWM2 @BASEBOARD_FAB2_LIB.BASEBOARD_FAB2(SCH_1):VR_PVDDQ_KLM_PWM2
 EU1A1   34    PWM IR354XX_SM-IR35411,IC,H73688-0A   I102 @BASEBOARD_FAB2_LIB.BASEBOARD_FAB2(SCH_1):PAGE227
 EU1B1    4  APWM2 PXM1310B_QFN-IC,H89186-001    I69 @BASEBOARD_FAB2_LIB.BASEBOARD_FAB2(SCH_1):PAGE226

VR_PVDDQ_KLM_VD12 @BASEBOARD_FAB2_LIB.BASEBOARD_FAB2(SCH_1):VR_PVDDQ_KLM_VD12
  C1B2    1      A CAP_A_0402V-0.1UF,16V,10%,X7R,A    I44 @BASEBOARD_FAB2_LIB.BASEBOARD_FAB2(SCH_1):PAGE226
  C1B3    1      A CAP_A_0402V-1.0UF,6.3V,10%,X6SA    I45 @BASEBOARD_FAB2_LIB.BASEBOARD_FAB2(SCH_1):PAGE226
 EU1B1   40   VD12 PXM1310B_QFN-IC,H89186-001    I69 @BASEBOARD_FAB2_LIB.BASEBOARD_FAB2(SCH_1):PAGE226

VR_PVDDQ_KLM_VDD @BASEBOARD_FAB2_LIB.BASEBOARD_FAB2(SCH_1):VR_PVDDQ_KLM_VDD
  C1B6    1      A CAP_A_0402V-1.0UF,6.3V,10%,X6SA    I38 @BASEBOARD_FAB2_LIB.BASEBOARD_FAB2(SCH_1):PAGE226
 EU1B1   39    VDD PXM1310B_QFN-IC,H89186-001    I69 @BASEBOARD_FAB2_LIB.BASEBOARD_FAB2(SCH_1):PAGE226
  C1B5    1      A CAP_A_0402V-0.1UF,16V,10%,X7R,A    I32 @BASEBOARD_FAB2_LIB.BASEBOARD_FAB2(SCH_1):PAGE226
  R9M3    2      B RES_0402-0.0,5%,1/16W,CHIP,G21A    I36 @BASEBOARD_FAB2_LIB.BASEBOARD_FAB2(SCH_1):PAGE226

VR_PVDDQ_KLM_VINSEN @BASEBOARD_FAB2_LIB.BASEBOARD_FAB2(SCH_1):VR_PVDDQ_KLM_VINSEN
 EU1B1   37 VINSEN PXM1310B_QFN-IC,H89186-001    I69 @BASEBOARD_FAB2_LIB.BASEBOARD_FAB2(SCH_1):PAGE226
 C12W4    2      B CAP_0402LF-47.0PF,50V,5%,COG,AA    I18 @BASEBOARD_FAB2_LIB.BASEBOARD_FAB2(SCH_1):PAGE197
R12W20    2      2 665KR2B-GP_SMD-RG2-665KR2B-GP,A   I110 @BASEBOARD_FAB2_LIB.BASEBOARD_FAB2(SCH_1):PAGE197
R12W17    2      2 665KR5B-1-GP_SMD-RG3-665KR5B-1A   I123 @BASEBOARD_FAB2_LIB.BASEBOARD_FAB2(SCH_1):PAGE197

VR_PVDDQ_KLM_VREN @BASEBOARD_FAB2_LIB.BASEBOARD_FAB2(SCH_1):VR_PVDDQ_KLM_VREN
  R9M9    2      B RES_0402-0.0,5%,1/16W,CHIP,G21A    I14 @BASEBOARD_FAB2_LIB.BASEBOARD_FAB2(SCH_1):PAGE226
  R9M5    2      B RES_0402-100.0K,1%,1/16W,EMPTYA    I34 @BASEBOARD_FAB2_LIB.BASEBOARD_FAB2(SCH_1):PAGE226
 EU1B1   10  AVREN PXM1310B_QFN-IC,H89186-001    I69 @BASEBOARD_FAB2_LIB.BASEBOARD_FAB2(SCH_1):PAGE226

VR_PVDDQ_KLM_XADDR1 @BASEBOARD_FAB2_LIB.BASEBOARD_FAB2(SCH_1):VR_PVDDQ_KLM_XADDR1
 EU1B1   36 XADDR1 PXM1310B_QFN-IC,H89186-001    I69 @BASEBOARD_FAB2_LIB.BASEBOARD_FAB2(SCH_1):PAGE226
 R1B12    1      A RES_0402-16K,1.0%,1/16W,CHIP,GA    I72 @BASEBOARD_FAB2_LIB.BASEBOARD_FAB2(SCH_1):PAGE226

VR_PVDDQ_KLM_XADDR2 @BASEBOARD_FAB2_LIB.BASEBOARD_FAB2(SCH_1):VR_PVDDQ_KLM_XADDR2
 EU1B1   33 XADDR2 PXM1310B_QFN-IC,H89186-001    I69 @BASEBOARD_FAB2_LIB.BASEBOARD_FAB2(SCH_1):PAGE226
 R1B15    1      A RES_0402-3.16K,1%,1/16W,CHIP,GA    I73 @BASEBOARD_FAB2_LIB.BASEBOARD_FAB2(SCH_1):PAGE226

VR_PVNN_P1V05_PCH_VD12 @BASEBOARD_FAB2_LIB.BASEBOARD_FAB2(SCH_1):VR_PVNN_P1V05_PCH_VD12
  C8A7    1      A CAP_A_0402V-1.0UF,6.3V,10%,X6SA   I143 @BASEBOARD_FAB2_LIB.BASEBOARD_FAB2(SCH_1):PAGE235
  C8A8    1      A CAP_A_0402V-0.1UF,16V,10%,X7R,A   I145 @BASEBOARD_FAB2_LIB.BASEBOARD_FAB2(SCH_1):PAGE235
 EU8A1   40   VD12 PXE1110B_QFN-IC,H89187-001   I229 @BASEBOARD_FAB2_LIB.BASEBOARD_FAB2(SCH_1):PAGE235
  R8W2    2      B RES_0402-1.00K,1%,1/16W,CHIP,GA   I247 @BASEBOARD_FAB2_LIB.BASEBOARD_FAB2(SCH_1):PAGE235
  R8W3    1      A RES_0402-1.00K,1%,1/16W,CHIP,GA   I248 @BASEBOARD_FAB2_LIB.BASEBOARD_FAB2(SCH_1):PAGE235

VR_PVNN_PCH_AIREF1 @BASEBOARD_FAB2_LIB.BASEBOARD_FAB2(SCH_1):VR_PVNN_PCH_AIREF1
 EU8A1   21 AIREF1 PXE1110B_QFN-IC,H89187-001   I229 @BASEBOARD_FAB2_LIB.BASEBOARD_FAB2(SCH_1):PAGE235
 EU7A3   39  REFIN IR354XX_SM-IR35412,IC,H73684-0A   I116 @BASEBOARD_FAB2_LIB.BASEBOARD_FAB2(SCH_1):PAGE236
  CT66    1      A CAP_A_0402V-0.1UF,16V,10%,X7R,A   I127 @BASEBOARD_FAB2_LIB.BASEBOARD_FAB2(SCH_1):PAGE236
  CF23    1      1 SC22P50V2JN-4GP_SMD-BCG-SC22P5A   I239 @BASEBOARD_FAB2_LIB.BASEBOARD_FAB2(SCH_1):PAGE235
  RF23    1      A RES_0402-1.0K,0.1%,1/16W,CHIP,A   I241 @BASEBOARD_FAB2_LIB.BASEBOARD_FAB2(SCH_1):PAGE235

VR_PVNN_PCH_AVSP @BASEBOARD_FAB2_LIB.BASEBOARD_FAB2(SCH_1):VR_PVNN_PCH_AVSP
  C8A2    1      A CAP_0402LF-220PF,50V,10%,X7R,AA   I209 @BASEBOARD_FAB2_LIB.BASEBOARD_FAB2(SCH_1):PAGE235
  R8A1    2      B RES_0402-10.0,1%,1/16W,CHIP,G2A   I210 @BASEBOARD_FAB2_LIB.BASEBOARD_FAB2(SCH_1):PAGE235
 EU8A1   19  AVSEN PXE1110B_QFN-IC,H89187-001   I229 @BASEBOARD_FAB2_LIB.BASEBOARD_FAB2(SCH_1):PAGE235

VR_PVNN_PCH_PH1_BOOT @BASEBOARD_FAB2_LIB.BASEBOARD_FAB2(SCH_1):VR_PVNN_PCH_PH1_BOOT
 C7A43    1      A CAP_0402-0.220UF,16V,10%,X7R,AA    I21 @BASEBOARD_FAB2_LIB.BASEBOARD_FAB2(SCH_1):PAGE236
  RT44    1      A RES_0603-0,5.0%,1/10W,CHIP,G22A   I153 @BASEBOARD_FAB2_LIB.BASEBOARD_FAB2(SCH_1):PAGE236

VR_PVNN_PCH_PH1_BOOT_R @BASEBOARD_FAB2_LIB.BASEBOARD_FAB2(SCH_1):VR_PVNN_PCH_PH1_BOOT_R
 EU7A3   33  BOOST IR354XX_SM-IR35412,IC,H73684-0A   I116 @BASEBOARD_FAB2_LIB.BASEBOARD_FAB2(SCH_1):PAGE236
  RT44    2      B RES_0603-0,5.0%,1/10W,CHIP,G22A   I153 @BASEBOARD_FAB2_LIB.BASEBOARD_FAB2(SCH_1):PAGE236

VR_PVNN_PCH_PH1_PHASE @BASEBOARD_FAB2_LIB.BASEBOARD_FAB2(SCH_1):VR_PVNN_PCH_PH1_PHASE
 C7A43    2      B CAP_0402-0.220UF,16V,10%,X7R,AA    I21 @BASEBOARD_FAB2_LIB.BASEBOARD_FAB2(SCH_1):PAGE236
 EU7A3   32  PHASE IR354XX_SM-IR35412,IC,H73684-0A   I116 @BASEBOARD_FAB2_LIB.BASEBOARD_FAB2(SCH_1):PAGE236

VR_PVNN_PCH_PH1_PHASE_SW @BASEBOARD_FAB2_LIB.BASEBOARD_FAB2(SCH_1):VR_PVNN_PCH_PH1_PHASE_SW
 EU7A3   10     SW IR354XX_SM-IR35412,IC,H73684-0A   I116 @BASEBOARD_FAB2_LIB.BASEBOARD_FAB2(SCH_1):PAGE236
  CT65    1      A CAP_0402LF-1000PF,50V,10%,X7R,A   I149 @BASEBOARD_FAB2_LIB.BASEBOARD_FAB2(SCH_1):PAGE236
  L7A2    1      S IND-300NH-20-GP_DISCRET-GB1-INA   I178 @BASEBOARD_FAB2_LIB.BASEBOARD_FAB2(SCH_1):PAGE236

VR_PVNN_PCH_PH1_PHASE_SW_RC @BASEBOARD_FAB2_LIB.BASEBOARD_FAB2(SCH_1):VR_PVNN_PCH_PH1_PHASE_SW_RC
  CT65    2      B CAP_0402LF-1000PF,50V,10%,X7R,A   I149 @BASEBOARD_FAB2_LIB.BASEBOARD_FAB2(SCH_1):PAGE236
  RT43    1      1 1R3F-GP_RCL_GP-1R3F-GP,64.1R00A   I182 @BASEBOARD_FAB2_LIB.BASEBOARD_FAB2(SCH_1):PAGE236

VR_PVNN_PCH_PH1_VCIN @BASEBOARD_FAB2_LIB.BASEBOARD_FAB2(SCH_1):VR_PVNN_PCH_PH1_VCIN
  C7A6    1      A CAP_0402-1.0UF,16V,10%,X6S,D97A    I19 @BASEBOARD_FAB2_LIB.BASEBOARD_FAB2(SCH_1):PAGE236
 EU7A3    3    VCC IR354XX_SM-IR35412,IC,H73684-0A   I116 @BASEBOARD_FAB2_LIB.BASEBOARD_FAB2(SCH_1):PAGE236
  R3L1    1      A RES_0402-0.0,5%,1/16W,CHIP,G21A   I175 @BASEBOARD_FAB2_LIB.BASEBOARD_FAB2(SCH_1):PAGE236

VR_PVNN_PCH_PWM1 @BASEBOARD_FAB2_LIB.BASEBOARD_FAB2(SCH_1):VR_PVNN_PCH_PWM1
 EU8A1    5  APWM1 PXE1110B_QFN-IC,H89187-001   I229 @BASEBOARD_FAB2_LIB.BASEBOARD_FAB2(SCH_1):PAGE235
 EU7A3   34    PWM IR354XX_SM-IR35412,IC,H73684-0A   I116 @BASEBOARD_FAB2_LIB.BASEBOARD_FAB2(SCH_1):PAGE236

VR_PVNN_PCH_STBY_OCSET @BASEBOARD_FAB2_LIB.BASEBOARD_FAB2(SCH_1):VR_PVNN_PCH_STBY_OCSET
 EU7A3   37  OCSET IR354XX_SM-IR35412,IC,H73684-0A   I116 @BASEBOARD_FAB2_LIB.BASEBOARD_FAB2(SCH_1):PAGE236
 R3L15    1      A RES_0402-68.1K,1%,1/16W,EMPTY,A   I118 @BASEBOARD_FAB2_LIB.BASEBOARD_FAB2(SCH_1):PAGE236

VR_PVNN_PCH_VDD @BASEBOARD_FAB2_LIB.BASEBOARD_FAB2(SCH_1):VR_PVNN_PCH_VDD
  C2L8    1      A CAP_A_0402V-1.0UF,6.3V,10%,X6SA   I151 @BASEBOARD_FAB2_LIB.BASEBOARD_FAB2(SCH_1):PAGE235
 R2L14    2      B RES_0402-0.0,5%,1/16W,CHIP,G21A   I159 @BASEBOARD_FAB2_LIB.BASEBOARD_FAB2(SCH_1):PAGE235
 C2L11    1      A CAP_A_0402V-0.1UF,16V,10%,X7R,A   I169 @BASEBOARD_FAB2_LIB.BASEBOARD_FAB2(SCH_1):PAGE235
 EU8A1   39    VDD PXE1110B_QFN-IC,H89187-001   I229 @BASEBOARD_FAB2_LIB.BASEBOARD_FAB2(SCH_1):PAGE235

VR_PVNN_PCH_VINSEN @BASEBOARD_FAB2_LIB.BASEBOARD_FAB2(SCH_1):VR_PVNN_PCH_VINSEN
  R8A4    2      B RES_0402-100.0K,1%,1/16W,CHIP,B   I165 @BASEBOARD_FAB2_LIB.BASEBOARD_FAB2(SCH_1):PAGE235
 R2L10    1      A RES_0402-1.5K,1%,1/16W,CHIP,G2A   I166 @BASEBOARD_FAB2_LIB.BASEBOARD_FAB2(SCH_1):PAGE235
 EU8A1   37 VINSEN PXE1110B_QFN-IC,H89187-001   I229 @BASEBOARD_FAB2_LIB.BASEBOARD_FAB2(SCH_1):PAGE235
  C8A3    1      A CAP_A_0402V-0.1UF,16V,10%,X7R,A   I255 @BASEBOARD_FAB2_LIB.BASEBOARD_FAB2(SCH_1):PAGE235

VR_PVNN_PCH_VREN @BASEBOARD_FAB2_LIB.BASEBOARD_FAB2(SCH_1):VR_PVNN_PCH_VREN
 R2L17    2      B RES_0402-0.0,5%,1/16W,CHIP,G21A   I221 @BASEBOARD_FAB2_LIB.BASEBOARD_FAB2(SCH_1):PAGE235
  R8A7    2      B RES_0402-100.0K,1%,1/16W,EMPTYA   I222 @BASEBOARD_FAB2_LIB.BASEBOARD_FAB2(SCH_1):PAGE235
 EU8A1   10  AVREN PXE1110B_QFN-IC,H89187-001   I229 @BASEBOARD_FAB2_LIB.BASEBOARD_FAB2(SCH_1):PAGE235

VR_PVNN_PCH_XADDR1 @BASEBOARD_FAB2_LIB.BASEBOARD_FAB2(SCH_1):VR_PVNN_PCH_XADDR1
 EU8A1   36 XADDR1 PXE1110B_QFN-IC,H89187-001   I229 @BASEBOARD_FAB2_LIB.BASEBOARD_FAB2(SCH_1):PAGE235
  R2L9    1      A RES_0402-4.02K,1%,1/16W,CHIP,GA   I254 @BASEBOARD_FAB2_LIB.BASEBOARD_FAB2(SCH_1):PAGE235

VR_PVNN_PCH_XADDR2 @BASEBOARD_FAB2_LIB.BASEBOARD_FAB2(SCH_1):VR_PVNN_PCH_XADDR2
  R8A2    1      A RES_0402-2.67K,1%,1/16W,CHIP,GA   I217 @BASEBOARD_FAB2_LIB.BASEBOARD_FAB2(SCH_1):PAGE235
 EU8A1   33 XADDR2 PXE1110B_QFN-IC,H89187-001   I229 @BASEBOARD_FAB2_LIB.BASEBOARD_FAB2(SCH_1):PAGE235

VR_PVPP_ABC_BOOT @BASEBOARD_FAB2_LIB.BASEBOARD_FAB2(SCH_1):VR_PVPP_ABC_BOOT
 EU7F1   36    BST NCP3232L_SM-IC,H86355-001   I193 @BASEBOARD_FAB2_LIB.BASEBOARD_FAB2(SCH_1):PAGE231
  R7F8    1      A RES_0603-0,5.0%,1/10W,CHIP,G22A   I229 @BASEBOARD_FAB2_LIB.BASEBOARD_FAB2(SCH_1):PAGE231

VR_PVPP_ABC_BOOT_R @BASEBOARD_FAB2_LIB.BASEBOARD_FAB2(SCH_1):VR_PVPP_ABC_BOOT_R
  C7F4    2      B CAP_0603LF-0.1UF,25V,10%,X7R,6A   I159 @BASEBOARD_FAB2_LIB.BASEBOARD_FAB2(SCH_1):PAGE231
  R7F8    2      B RES_0603-0,5.0%,1/10W,CHIP,G22A   I229 @BASEBOARD_FAB2_LIB.BASEBOARD_FAB2(SCH_1):PAGE231

VR_PVPP_ABC_ISET @BASEBOARD_FAB2_LIB.BASEBOARD_FAB2(SCH_1):VR_PVPP_ABC_ISET
 R7F15    1      A RES_0402-7.87K,1.0%,1/16W,CHIPA   I134 @BASEBOARD_FAB2_LIB.BASEBOARD_FAB2(SCH_1):PAGE231
 EU7F1    4   ISET NCP3232L_SM-IC,H86355-001   I193 @BASEBOARD_FAB2_LIB.BASEBOARD_FAB2(SCH_1):PAGE231

VR_PVPP_ABC_PHASE @BASEBOARD_FAB2_LIB.BASEBOARD_FAB2(SCH_1):VR_PVPP_ABC_PHASE
  C7F4    1      A CAP_0603LF-0.1UF,25V,10%,X7R,6A   I159 @BASEBOARD_FAB2_LIB.BASEBOARD_FAB2(SCH_1):PAGE231
  C7F3    1      A CAP_0402LF-3300PF,50V,10%,EMPTA   I175 @BASEBOARD_FAB2_LIB.BASEBOARD_FAB2(SCH_1):PAGE231
  L7F1    1    INA INDUCTOR_SM-0.47UH,IND,E13358-A   I178 @BASEBOARD_FAB2_LIB.BASEBOARD_FAB2(SCH_1):PAGE231
 EU7F1   35    VSW NCP3232L_SM-IC,H86355-001   I193 @BASEBOARD_FAB2_LIB.BASEBOARD_FAB2(SCH_1):PAGE231
 EU7F1   15 VSWH<0> NCP3232L_SM-IC,H86355-001   I193 @BASEBOARD_FAB2_LIB.BASEBOARD_FAB2(SCH_1):PAGE231
 EU7F1   29 VSWH<1> NCP3232L_SM-IC,H86355-001   I193 @BASEBOARD_FAB2_LIB.BASEBOARD_FAB2(SCH_1):PAGE231
 EU7F1   30 VSWH<2> NCP3232L_SM-IC,H86355-001   I193 @BASEBOARD_FAB2_LIB.BASEBOARD_FAB2(SCH_1):PAGE231
 EU7F1   31 VSWH<3> NCP3232L_SM-IC,H86355-001   I193 @BASEBOARD_FAB2_LIB.BASEBOARD_FAB2(SCH_1):PAGE231
 EU7F1   32 VSWH<4> NCP3232L_SM-IC,H86355-001   I193 @BASEBOARD_FAB2_LIB.BASEBOARD_FAB2(SCH_1):PAGE231
 EU7F1   33 VSWH<5> NCP3232L_SM-IC,H86355-001   I193 @BASEBOARD_FAB2_LIB.BASEBOARD_FAB2(SCH_1):PAGE231
 EU7F1   34 VSWH<6> NCP3232L_SM-IC,H86355-001   I193 @BASEBOARD_FAB2_LIB.BASEBOARD_FAB2(SCH_1):PAGE231
 EU7F1   43 VSWH<7> NCP3232L_SM-IC,H86355-001   I193 @BASEBOARD_FAB2_LIB.BASEBOARD_FAB2(SCH_1):PAGE231

VR_PVPP_ABC_SNUB @BASEBOARD_FAB2_LIB.BASEBOARD_FAB2(SCH_1):VR_PVPP_ABC_SNUB
  R7F7    1      A RES_0402-2.2,5%,1/16W,EMPTY,G2A   I174 @BASEBOARD_FAB2_LIB.BASEBOARD_FAB2(SCH_1):PAGE231
  C7F3    2      B CAP_0402LF-3300PF,50V,10%,EMPTA   I175 @BASEBOARD_FAB2_LIB.BASEBOARD_FAB2(SCH_1):PAGE231

VR_PVPP_ABC_SS @BASEBOARD_FAB2_LIB.BASEBOARD_FAB2(SCH_1):VR_PVPP_ABC_SS
 EU7F1    1     SS NCP3232L_SM-IC,H86355-001   I193 @BASEBOARD_FAB2_LIB.BASEBOARD_FAB2(SCH_1):PAGE231
 C7F10    1      A CAP_0402-0.027UF,16V,10%,X7R,AA   I194 @BASEBOARD_FAB2_LIB.BASEBOARD_FAB2(SCH_1):PAGE231

VR_PVPP_DEF_BOOT @BASEBOARD_FAB2_LIB.BASEBOARD_FAB2(SCH_1):VR_PVPP_DEF_BOOT
 EU7B1   36    BST NCP3232L_SM-IC,H86355-001   I214 @BASEBOARD_FAB2_LIB.BASEBOARD_FAB2(SCH_1):PAGE232
 R7B19    1      A RES_0603-0,5.0%,1/10W,CHIP,G22A   I313 @BASEBOARD_FAB2_LIB.BASEBOARD_FAB2(SCH_1):PAGE232

VR_PVPP_DEF_BOOT_R @BASEBOARD_FAB2_LIB.BASEBOARD_FAB2(SCH_1):VR_PVPP_DEF_BOOT_R
 C7B30    2      B CAP_0603LF-0.1UF,25V,10%,X7R,6A   I241 @BASEBOARD_FAB2_LIB.BASEBOARD_FAB2(SCH_1):PAGE232
 R7B19    2      B RES_0603-0,5.0%,1/10W,CHIP,G22A   I313 @BASEBOARD_FAB2_LIB.BASEBOARD_FAB2(SCH_1):PAGE232

VR_PVPP_DEF_ISET @BASEBOARD_FAB2_LIB.BASEBOARD_FAB2(SCH_1):VR_PVPP_DEF_ISET
 EU7B1    4   ISET NCP3232L_SM-IC,H86355-001   I214 @BASEBOARD_FAB2_LIB.BASEBOARD_FAB2(SCH_1):PAGE232
 R7B14    1      A RES_0402-7.87K,1.0%,1/16W,CHIPA   I315 @BASEBOARD_FAB2_LIB.BASEBOARD_FAB2(SCH_1):PAGE232

VR_PVPP_DEF_PHASE @BASEBOARD_FAB2_LIB.BASEBOARD_FAB2(SCH_1):VR_PVPP_DEF_PHASE
 EU7B1   35    VSW NCP3232L_SM-IC,H86355-001   I214 @BASEBOARD_FAB2_LIB.BASEBOARD_FAB2(SCH_1):PAGE232
 EU7B1   15 VSWH<0> NCP3232L_SM-IC,H86355-001   I214 @BASEBOARD_FAB2_LIB.BASEBOARD_FAB2(SCH_1):PAGE232
 EU7B1   29 VSWH<1> NCP3232L_SM-IC,H86355-001   I214 @BASEBOARD_FAB2_LIB.BASEBOARD_FAB2(SCH_1):PAGE232
 EU7B1   30 VSWH<2> NCP3232L_SM-IC,H86355-001   I214 @BASEBOARD_FAB2_LIB.BASEBOARD_FAB2(SCH_1):PAGE232
 EU7B1   31 VSWH<3> NCP3232L_SM-IC,H86355-001   I214 @BASEBOARD_FAB2_LIB.BASEBOARD_FAB2(SCH_1):PAGE232
 EU7B1   32 VSWH<4> NCP3232L_SM-IC,H86355-001   I214 @BASEBOARD_FAB2_LIB.BASEBOARD_FAB2(SCH_1):PAGE232
 EU7B1   33 VSWH<5> NCP3232L_SM-IC,H86355-001   I214 @BASEBOARD_FAB2_LIB.BASEBOARD_FAB2(SCH_1):PAGE232
 EU7B1   34 VSWH<6> NCP3232L_SM-IC,H86355-001   I214 @BASEBOARD_FAB2_LIB.BASEBOARD_FAB2(SCH_1):PAGE232
 EU7B1   43 VSWH<7> NCP3232L_SM-IC,H86355-001   I214 @BASEBOARD_FAB2_LIB.BASEBOARD_FAB2(SCH_1):PAGE232
 C7A34    1      A CAP_0402LF-3300PF,50V,10%,EMPTA   I220 @BASEBOARD_FAB2_LIB.BASEBOARD_FAB2(SCH_1):PAGE232
  L7B1    1    INA INDUCTOR_SM-0.47UH,IND,E13358-A   I239 @BASEBOARD_FAB2_LIB.BASEBOARD_FAB2(SCH_1):PAGE232
 C7B30    1      A CAP_0603LF-0.1UF,25V,10%,X7R,6A   I241 @BASEBOARD_FAB2_LIB.BASEBOARD_FAB2(SCH_1):PAGE232

VR_PVPP_DEF_SNUB @BASEBOARD_FAB2_LIB.BASEBOARD_FAB2(SCH_1):VR_PVPP_DEF_SNUB
 R7A15    1      A RES_0402-2.2,5%,1/16W,EMPTY,G2A   I218 @BASEBOARD_FAB2_LIB.BASEBOARD_FAB2(SCH_1):PAGE232
 C7A34    2      B CAP_0402LF-3300PF,50V,10%,EMPTA   I220 @BASEBOARD_FAB2_LIB.BASEBOARD_FAB2(SCH_1):PAGE232

VR_PVPP_DEF_SS @BASEBOARD_FAB2_LIB.BASEBOARD_FAB2(SCH_1):VR_PVPP_DEF_SS
 C7B11    1      A CAP_0402-0.027UF,16V,10%,X7R,AA   I197 @BASEBOARD_FAB2_LIB.BASEBOARD_FAB2(SCH_1):PAGE232
 EU7B1    1     SS NCP3232L_SM-IC,H86355-001   I214 @BASEBOARD_FAB2_LIB.BASEBOARD_FAB2(SCH_1):PAGE232

VR_PVPP_GHJ_BOOT @BASEBOARD_FAB2_LIB.BASEBOARD_FAB2(SCH_1):VR_PVPP_GHJ_BOOT
 EU4G1   36    BST NCP3232L_SM-IC,H86355-001   I225 @BASEBOARD_FAB2_LIB.BASEBOARD_FAB2(SCH_1):PAGE233
 R4G24    1      A RES_0603-0,5.0%,1/10W,CHIP,G22A   I282 @BASEBOARD_FAB2_LIB.BASEBOARD_FAB2(SCH_1):PAGE233

VR_PVPP_GHJ_BOOT_R @BASEBOARD_FAB2_LIB.BASEBOARD_FAB2(SCH_1):VR_PVPP_GHJ_BOOT_R
 C4G26    2      B CAP_0603LF-0.1UF,25V,10%,X7R,6A   I224 @BASEBOARD_FAB2_LIB.BASEBOARD_FAB2(SCH_1):PAGE233
 R4G24    2      B RES_0603-0,5.0%,1/10W,CHIP,G22A   I282 @BASEBOARD_FAB2_LIB.BASEBOARD_FAB2(SCH_1):PAGE233

VR_PVPP_GHJ_ISET @BASEBOARD_FAB2_LIB.BASEBOARD_FAB2(SCH_1):VR_PVPP_GHJ_ISET
 EU4G1    4   ISET NCP3232L_SM-IC,H86355-001   I225 @BASEBOARD_FAB2_LIB.BASEBOARD_FAB2(SCH_1):PAGE233
 R4G11    1      A RES_0402-7.87K,1.0%,1/16W,CHIPA   I284 @BASEBOARD_FAB2_LIB.BASEBOARD_FAB2(SCH_1):PAGE233

VR_PVPP_GHJ_PHASE @BASEBOARD_FAB2_LIB.BASEBOARD_FAB2(SCH_1):VR_PVPP_GHJ_PHASE
 C4F12    1      A CAP_0402LF-3300PF,50V,10%,EMPTA   I209 @BASEBOARD_FAB2_LIB.BASEBOARD_FAB2(SCH_1):PAGE233
 C4G26    1      A CAP_0603LF-0.1UF,25V,10%,X7R,6A   I224 @BASEBOARD_FAB2_LIB.BASEBOARD_FAB2(SCH_1):PAGE233
 EU4G1   35    VSW NCP3232L_SM-IC,H86355-001   I225 @BASEBOARD_FAB2_LIB.BASEBOARD_FAB2(SCH_1):PAGE233
 EU4G1   15 VSWH<0> NCP3232L_SM-IC,H86355-001   I225 @BASEBOARD_FAB2_LIB.BASEBOARD_FAB2(SCH_1):PAGE233
 EU4G1   29 VSWH<1> NCP3232L_SM-IC,H86355-001   I225 @BASEBOARD_FAB2_LIB.BASEBOARD_FAB2(SCH_1):PAGE233
 EU4G1   30 VSWH<2> NCP3232L_SM-IC,H86355-001   I225 @BASEBOARD_FAB2_LIB.BASEBOARD_FAB2(SCH_1):PAGE233
 EU4G1   31 VSWH<3> NCP3232L_SM-IC,H86355-001   I225 @BASEBOARD_FAB2_LIB.BASEBOARD_FAB2(SCH_1):PAGE233
 EU4G1   32 VSWH<4> NCP3232L_SM-IC,H86355-001   I225 @BASEBOARD_FAB2_LIB.BASEBOARD_FAB2(SCH_1):PAGE233
 EU4G1   33 VSWH<5> NCP3232L_SM-IC,H86355-001   I225 @BASEBOARD_FAB2_LIB.BASEBOARD_FAB2(SCH_1):PAGE233
 EU4G1   34 VSWH<6> NCP3232L_SM-IC,H86355-001   I225 @BASEBOARD_FAB2_LIB.BASEBOARD_FAB2(SCH_1):PAGE233
 EU4G1   43 VSWH<7> NCP3232L_SM-IC,H86355-001   I225 @BASEBOARD_FAB2_LIB.BASEBOARD_FAB2(SCH_1):PAGE233
  L4G1    1    INA INDUCTOR_SM-0.47UH,IND,E13358-A   I277 @BASEBOARD_FAB2_LIB.BASEBOARD_FAB2(SCH_1):PAGE233

VR_PVPP_GHJ_SNUB @BASEBOARD_FAB2_LIB.BASEBOARD_FAB2(SCH_1):VR_PVPP_GHJ_SNUB
  R4F6    1      A RES_0402-2.2,5%,1/16W,EMPTY,G2A   I208 @BASEBOARD_FAB2_LIB.BASEBOARD_FAB2(SCH_1):PAGE233
 C4F12    2      B CAP_0402LF-3300PF,50V,10%,EMPTA   I209 @BASEBOARD_FAB2_LIB.BASEBOARD_FAB2(SCH_1):PAGE233

VR_PVPP_GHJ_SS @BASEBOARD_FAB2_LIB.BASEBOARD_FAB2(SCH_1):VR_PVPP_GHJ_SS
  C4G8    1      A CAP_0402-0.027UF,16V,10%,X7R,AA   I194 @BASEBOARD_FAB2_LIB.BASEBOARD_FAB2(SCH_1):PAGE233
 EU4G1    1     SS NCP3232L_SM-IC,H86355-001   I225 @BASEBOARD_FAB2_LIB.BASEBOARD_FAB2(SCH_1):PAGE233

VR_PVPP_KLM_BOOT @BASEBOARD_FAB2_LIB.BASEBOARD_FAB2(SCH_1):VR_PVPP_KLM_BOOT
 EU4A3   36    BST NCP3232L_SM-IC,H86355-001   I184 @BASEBOARD_FAB2_LIB.BASEBOARD_FAB2(SCH_1):PAGE234
 R4B13    1      A RES_0603-0,5.0%,1/10W,CHIP,G22A   I226 @BASEBOARD_FAB2_LIB.BASEBOARD_FAB2(SCH_1):PAGE234

VR_PVPP_KLM_BOOT_R @BASEBOARD_FAB2_LIB.BASEBOARD_FAB2(SCH_1):VR_PVPP_KLM_BOOT_R
 C4B15    2      B CAP_0603LF-0.1UF,25V,10%,X7R,6A   I182 @BASEBOARD_FAB2_LIB.BASEBOARD_FAB2(SCH_1):PAGE234
 R4B13    2      B RES_0603-0,5.0%,1/10W,CHIP,G22A   I226 @BASEBOARD_FAB2_LIB.BASEBOARD_FAB2(SCH_1):PAGE234

VR_PVPP_KLM_ISET @BASEBOARD_FAB2_LIB.BASEBOARD_FAB2(SCH_1):VR_PVPP_KLM_ISET
 EU4A3    4   ISET NCP3232L_SM-IC,H86355-001   I184 @BASEBOARD_FAB2_LIB.BASEBOARD_FAB2(SCH_1):PAGE234
  R4B6    1      A RES_0402-7.87K,1.0%,1/16W,CHIPA   I228 @BASEBOARD_FAB2_LIB.BASEBOARD_FAB2(SCH_1):PAGE234

VR_PVPP_KLM_PHASE @BASEBOARD_FAB2_LIB.BASEBOARD_FAB2(SCH_1):VR_PVPP_KLM_PHASE
 C4A16    1      A CAP_0402LF-3300PF,50V,10%,EMPTA   I163 @BASEBOARD_FAB2_LIB.BASEBOARD_FAB2(SCH_1):PAGE234
  L4A1    1    INA INDUCTOR_SM-0.47UH,IND,E13358-A   I164 @BASEBOARD_FAB2_LIB.BASEBOARD_FAB2(SCH_1):PAGE234
 C4B15    1      A CAP_0603LF-0.1UF,25V,10%,X7R,6A   I182 @BASEBOARD_FAB2_LIB.BASEBOARD_FAB2(SCH_1):PAGE234
 EU4A3   35    VSW NCP3232L_SM-IC,H86355-001   I184 @BASEBOARD_FAB2_LIB.BASEBOARD_FAB2(SCH_1):PAGE234
 EU4A3   15 VSWH<0> NCP3232L_SM-IC,H86355-001   I184 @BASEBOARD_FAB2_LIB.BASEBOARD_FAB2(SCH_1):PAGE234
 EU4A3   29 VSWH<1> NCP3232L_SM-IC,H86355-001   I184 @BASEBOARD_FAB2_LIB.BASEBOARD_FAB2(SCH_1):PAGE234
 EU4A3   30 VSWH<2> NCP3232L_SM-IC,H86355-001   I184 @BASEBOARD_FAB2_LIB.BASEBOARD_FAB2(SCH_1):PAGE234
 EU4A3   31 VSWH<3> NCP3232L_SM-IC,H86355-001   I184 @BASEBOARD_FAB2_LIB.BASEBOARD_FAB2(SCH_1):PAGE234
 EU4A3   32 VSWH<4> NCP3232L_SM-IC,H86355-001   I184 @BASEBOARD_FAB2_LIB.BASEBOARD_FAB2(SCH_1):PAGE234
 EU4A3   33 VSWH<5> NCP3232L_SM-IC,H86355-001   I184 @BASEBOARD_FAB2_LIB.BASEBOARD_FAB2(SCH_1):PAGE234
 EU4A3   34 VSWH<6> NCP3232L_SM-IC,H86355-001   I184 @BASEBOARD_FAB2_LIB.BASEBOARD_FAB2(SCH_1):PAGE234
 EU4A3   43 VSWH<7> NCP3232L_SM-IC,H86355-001   I184 @BASEBOARD_FAB2_LIB.BASEBOARD_FAB2(SCH_1):PAGE234

VR_PVPP_KLM_SNUB @BASEBOARD_FAB2_LIB.BASEBOARD_FAB2(SCH_1):VR_PVPP_KLM_SNUB
  R4A7    1      A RES_0402-2.2,5%,1/16W,EMPTY,G2A   I162 @BASEBOARD_FAB2_LIB.BASEBOARD_FAB2(SCH_1):PAGE234
 C4A16    2      B CAP_0402LF-3300PF,50V,10%,EMPTA   I163 @BASEBOARD_FAB2_LIB.BASEBOARD_FAB2(SCH_1):PAGE234

VR_PVPP_KLM_SS @BASEBOARD_FAB2_LIB.BASEBOARD_FAB2(SCH_1):VR_PVPP_KLM_SS
  C4B6    1      A CAP_0402-0.027UF,16V,10%,X7R,AA   I146 @BASEBOARD_FAB2_LIB.BASEBOARD_FAB2(SCH_1):PAGE234
 EU4A3    1     SS NCP3232L_SM-IC,H86355-001   I184 @BASEBOARD_FAB2_LIB.BASEBOARD_FAB2(SCH_1):PAGE234

VR_PVSA_CPU0_BIREF1 @BASEBOARD_FAB2_LIB.BASEBOARD_FAB2(SCH_1):VR_PVSA_CPU0_BIREF1
 EU4D4   37 BIREF1 PXE1610B_QFN-IC,H79206-001   I155 @BASEBOARD_FAB2_LIB.BASEBOARD_FAB2(SCH_1):PAGE201
 EU4C1   39  REFIN IR354XX_SM-IR35412,IC,H73684-0A    I46 @BASEBOARD_FAB2_LIB.BASEBOARD_FAB2(SCH_1):PAGE205
  CT60    1      A CAP_A_0402V-0.1UF,16V,10%,X7R,A    I69 @BASEBOARD_FAB2_LIB.BASEBOARD_FAB2(SCH_1):PAGE205
   CF6    1      1 SC22P50V2JN-4GP_SMD-BCG-SC22P5A   I173 @BASEBOARD_FAB2_LIB.BASEBOARD_FAB2(SCH_1):PAGE201
   RF6    1      A RES_0402-1.0K,0.1%,1/16W,CHIP,A   I180 @BASEBOARD_FAB2_LIB.BASEBOARD_FAB2(SCH_1):PAGE201

VR_PVSA_CPU0_BOOT @BASEBOARD_FAB2_LIB.BASEBOARD_FAB2(SCH_1):VR_PVSA_CPU0_BOOT
  C4C8    1      A CAP_0402-0.220UF,16V,10%,X7R,AA    I25 @BASEBOARD_FAB2_LIB.BASEBOARD_FAB2(SCH_1):PAGE205
  RT40    1      A RES_0603-0,5.0%,1/10W,CHIP,G22A    I78 @BASEBOARD_FAB2_LIB.BASEBOARD_FAB2(SCH_1):PAGE205

VR_PVSA_CPU0_BOOT_R @BASEBOARD_FAB2_LIB.BASEBOARD_FAB2(SCH_1):VR_PVSA_CPU0_BOOT_R
 EU4C1   33  BOOST IR354XX_SM-IR35412,IC,H73684-0A    I46 @BASEBOARD_FAB2_LIB.BASEBOARD_FAB2(SCH_1):PAGE205
  RT40    2      B RES_0603-0,5.0%,1/10W,CHIP,G22A    I78 @BASEBOARD_FAB2_LIB.BASEBOARD_FAB2(SCH_1):PAGE205

VR_PVSA_CPU0_OCSET @BASEBOARD_FAB2_LIB.BASEBOARD_FAB2(SCH_1):VR_PVSA_CPU0_OCSET
 EU4C1   37  OCSET IR354XX_SM-IR35412,IC,H73684-0A    I46 @BASEBOARD_FAB2_LIB.BASEBOARD_FAB2(SCH_1):PAGE205
 R4C13    1      A RES_0402-68.1K,1%,1/16W,EMPTY,A    I62 @BASEBOARD_FAB2_LIB.BASEBOARD_FAB2(SCH_1):PAGE205

VR_PVSA_CPU0_PHASE @BASEBOARD_FAB2_LIB.BASEBOARD_FAB2(SCH_1):VR_PVSA_CPU0_PHASE
  C4C8    2      B CAP_0402-0.220UF,16V,10%,X7R,AA    I25 @BASEBOARD_FAB2_LIB.BASEBOARD_FAB2(SCH_1):PAGE205
 EU4C1   32  PHASE IR354XX_SM-IR35412,IC,H73684-0A    I46 @BASEBOARD_FAB2_LIB.BASEBOARD_FAB2(SCH_1):PAGE205

VR_PVSA_CPU0_PHASE_SW @BASEBOARD_FAB2_LIB.BASEBOARD_FAB2(SCH_1):VR_PVSA_CPU0_PHASE_SW
 EU4C1   10     SW IR354XX_SM-IR35412,IC,H73684-0A    I46 @BASEBOARD_FAB2_LIB.BASEBOARD_FAB2(SCH_1):PAGE205
  CT59    1      A CAP_0402LF-1000PF,50V,10%,X7R,A    I76 @BASEBOARD_FAB2_LIB.BASEBOARD_FAB2(SCH_1):PAGE205
  L4C2    1      S IND-300NH-20-GP_DISCRET-GB1-INA    I82 @BASEBOARD_FAB2_LIB.BASEBOARD_FAB2(SCH_1):PAGE205

VR_PVSA_CPU0_PHASE_SW_RC @BASEBOARD_FAB2_LIB.BASEBOARD_FAB2(SCH_1):VR_PVSA_CPU0_PHASE_SW_RC
  CT59    2      B CAP_0402LF-1000PF,50V,10%,X7R,A    I76 @BASEBOARD_FAB2_LIB.BASEBOARD_FAB2(SCH_1):PAGE205
  RT39    1      1 1R3F-GP_RCL_GP-1R3F-GP,64.1R00A    I84 @BASEBOARD_FAB2_LIB.BASEBOARD_FAB2(SCH_1):PAGE205

VR_PVSA_CPU0_PWM @BASEBOARD_FAB2_LIB.BASEBOARD_FAB2(SCH_1):VR_PVSA_CPU0_PWM
 EU4D4    1  BPWM1 PXE1610B_QFN-IC,H79206-001   I155 @BASEBOARD_FAB2_LIB.BASEBOARD_FAB2(SCH_1):PAGE201
 EU4C1   34    PWM IR354XX_SM-IR35412,IC,H73684-0A    I46 @BASEBOARD_FAB2_LIB.BASEBOARD_FAB2(SCH_1):PAGE205

VR_PVSA_CPU0_VCIN @BASEBOARD_FAB2_LIB.BASEBOARD_FAB2(SCH_1):VR_PVSA_CPU0_VCIN
  C4C6    1      A CAP_0402-1.0UF,16V,10%,X6S,D97A    I20 @BASEBOARD_FAB2_LIB.BASEBOARD_FAB2(SCH_1):PAGE205
 EU4C1    3    VCC IR354XX_SM-IR35412,IC,H73684-0A    I46 @BASEBOARD_FAB2_LIB.BASEBOARD_FAB2(SCH_1):PAGE205
  R6N3    1      A RES_0402-0.0,5%,1/16W,CHIP,G21A    I81 @BASEBOARD_FAB2_LIB.BASEBOARD_FAB2(SCH_1):PAGE205

VR_PVSA_CPU1_BIREF1 @BASEBOARD_FAB2_LIB.BASEBOARD_FAB2(SCH_1):VR_PVSA_CPU1_BIREF1
 EU1C2   37 BIREF1 PXE1610B_QFN-IC,H79206-001   I130 @BASEBOARD_FAB2_LIB.BASEBOARD_FAB2(SCH_1):PAGE206
 EU1C1   39  REFIN IR354XX_SM-IR35412,IC,H73684-0A    I51 @BASEBOARD_FAB2_LIB.BASEBOARD_FAB2(SCH_1):PAGE210
  CT57    1      A CAP_A_0402V-0.1UF,16V,10%,X7R,A    I55 @BASEBOARD_FAB2_LIB.BASEBOARD_FAB2(SCH_1):PAGE210
  CF12    1      1 SC22P50V2JN-4GP_SMD-BCG-SC22P5A   I142 @BASEBOARD_FAB2_LIB.BASEBOARD_FAB2(SCH_1):PAGE206
  RF12    1      A RES_0402-1.0K,0.1%,1/16W,CHIP,A   I149 @BASEBOARD_FAB2_LIB.BASEBOARD_FAB2(SCH_1):PAGE206

VR_PVSA_CPU1_BOOT @BASEBOARD_FAB2_LIB.BASEBOARD_FAB2(SCH_1):VR_PVSA_CPU1_BOOT
 C1C12    1      A CAP_0402-0.220UF,16V,10%,X7R,AA    I24 @BASEBOARD_FAB2_LIB.BASEBOARD_FAB2(SCH_1):PAGE210
  RT37    1      A RES_0603-0,5.0%,1/10W,CHIP,G22A    I68 @BASEBOARD_FAB2_LIB.BASEBOARD_FAB2(SCH_1):PAGE210

VR_PVSA_CPU1_BOOT_R @BASEBOARD_FAB2_LIB.BASEBOARD_FAB2(SCH_1):VR_PVSA_CPU1_BOOT_R
 EU1C1   33  BOOST IR354XX_SM-IR35412,IC,H73684-0A    I51 @BASEBOARD_FAB2_LIB.BASEBOARD_FAB2(SCH_1):PAGE210
  RT37    2      B RES_0603-0,5.0%,1/10W,CHIP,G22A    I68 @BASEBOARD_FAB2_LIB.BASEBOARD_FAB2(SCH_1):PAGE210

VR_PVSA_CPU1_OCSET @BASEBOARD_FAB2_LIB.BASEBOARD_FAB2(SCH_1):VR_PVSA_CPU1_OCSET
 EU1C1   37  OCSET IR354XX_SM-IR35412,IC,H73684-0A    I51 @BASEBOARD_FAB2_LIB.BASEBOARD_FAB2(SCH_1):PAGE210
 R1C37    1      A RES_0402-68.1K,1%,1/16W,EMPTY,A    I52 @BASEBOARD_FAB2_LIB.BASEBOARD_FAB2(SCH_1):PAGE210

VR_PVSA_CPU1_PHASE @BASEBOARD_FAB2_LIB.BASEBOARD_FAB2(SCH_1):VR_PVSA_CPU1_PHASE
 C1C12    2      B CAP_0402-0.220UF,16V,10%,X7R,AA    I24 @BASEBOARD_FAB2_LIB.BASEBOARD_FAB2(SCH_1):PAGE210
 EU1C1   32  PHASE IR354XX_SM-IR35412,IC,H73684-0A    I51 @BASEBOARD_FAB2_LIB.BASEBOARD_FAB2(SCH_1):PAGE210

VR_PVSA_CPU1_PHASE_SW @BASEBOARD_FAB2_LIB.BASEBOARD_FAB2(SCH_1):VR_PVSA_CPU1_PHASE_SW
 EU1C1   10     SW IR354XX_SM-IR35412,IC,H73684-0A    I51 @BASEBOARD_FAB2_LIB.BASEBOARD_FAB2(SCH_1):PAGE210
  CT56    1      A CAP_0402LF-1000PF,50V,10%,X7R,A    I66 @BASEBOARD_FAB2_LIB.BASEBOARD_FAB2(SCH_1):PAGE210
  L1C1    1      S IND-300NH-20-GP_DISCRET-GB1-INA    I72 @BASEBOARD_FAB2_LIB.BASEBOARD_FAB2(SCH_1):PAGE210

VR_PVSA_CPU1_PHASE_SW_RC @BASEBOARD_FAB2_LIB.BASEBOARD_FAB2(SCH_1):VR_PVSA_CPU1_PHASE_SW_RC
  CT56    2      B CAP_0402LF-1000PF,50V,10%,X7R,A    I66 @BASEBOARD_FAB2_LIB.BASEBOARD_FAB2(SCH_1):PAGE210
  RT38    1      1 1R3F-GP_RCL_GP-1R3F-GP,64.1R00A    I74 @BASEBOARD_FAB2_LIB.BASEBOARD_FAB2(SCH_1):PAGE210

VR_PVSA_CPU1_PWM @BASEBOARD_FAB2_LIB.BASEBOARD_FAB2(SCH_1):VR_PVSA_CPU1_PWM
 EU1C2    1  BPWM1 PXE1610B_QFN-IC,H79206-001   I130 @BASEBOARD_FAB2_LIB.BASEBOARD_FAB2(SCH_1):PAGE206
 EU1C1   34    PWM IR354XX_SM-IR35412,IC,H73684-0A    I51 @BASEBOARD_FAB2_LIB.BASEBOARD_FAB2(SCH_1):PAGE210

VR_PVSA_CPU1_VCIN @BASEBOARD_FAB2_LIB.BASEBOARD_FAB2(SCH_1):VR_PVSA_CPU1_VCIN
  C1C5    1      A CAP_0402-1.0UF,16V,10%,X6S,D97A    I26 @BASEBOARD_FAB2_LIB.BASEBOARD_FAB2(SCH_1):PAGE210
 EU1C1    3    VCC IR354XX_SM-IR35412,IC,H73684-0A    I51 @BASEBOARD_FAB2_LIB.BASEBOARD_FAB2(SCH_1):PAGE210
  R9N3    1      A RES_0402-0.0,5%,1/16W,CHIP,G21A    I71 @BASEBOARD_FAB2_LIB.BASEBOARD_FAB2(SCH_1):PAGE210

VR_PVTT_ABC_BIAS @BASEBOARD_FAB2_LIB.BASEBOARD_FAB2(SCH_1):VR_PVTT_ABC_BIAS
 C4G15    1      A CAP_0402-1.0UF,16V,10%,X6S,D97A    I13 @BASEBOARD_FAB2_LIB.BASEBOARD_FAB2(SCH_1):PAGE221
  R6U4    2      B RES_0402-0.0,5%,1/16W,CHIP,G21A    I14 @BASEBOARD_FAB2_LIB.BASEBOARD_FAB2(SCH_1):PAGE221
 EU4G3    2   BIAS MIC5166_DFN-IC,H55101-001    I15 @BASEBOARD_FAB2_LIB.BASEBOARD_FAB2(SCH_1):PAGE221

VR_PVTT_ABC_SNS @BASEBOARD_FAB2_LIB.BASEBOARD_FAB2(SCH_1):VR_PVTT_ABC_SNS
 SH5U1    1      A SHUNT_SH0201-EMPTY,N_A     I9 @BASEBOARD_FAB2_LIB.BASEBOARD_FAB2(SCH_1):PAGE221
 EU4G3    6    SNS MIC5166_DFN-IC,H55101-001    I15 @BASEBOARD_FAB2_LIB.BASEBOARD_FAB2(SCH_1):PAGE221

VR_PVTT_ABC_VREF @BASEBOARD_FAB2_LIB.BASEBOARD_FAB2(SCH_1):VR_PVTT_ABC_VREF
 C4G16    1      A CAP_0402-1.0UF,16V,10%,X6S,D97A    I22 @BASEBOARD_FAB2_LIB.BASEBOARD_FAB2(SCH_1):PAGE221
 EU4G3    1   VREF MIC5166_DFN-IC,H55101-001    I15 @BASEBOARD_FAB2_LIB.BASEBOARD_FAB2(SCH_1):PAGE221

VR_PVTT_DEF_BIAS @BASEBOARD_FAB2_LIB.BASEBOARD_FAB2(SCH_1):VR_PVTT_DEF_BIAS
 C4A10    1      A CAP_0402-1.0UF,16V,10%,X6S,D97A    I12 @BASEBOARD_FAB2_LIB.BASEBOARD_FAB2(SCH_1):PAGE222
 R6L11    2      B RES_0402-0.0,5%,1/16W,CHIP,G21A    I10 @BASEBOARD_FAB2_LIB.BASEBOARD_FAB2(SCH_1):PAGE222
 EU4A1    2   BIAS MIC5166_DFN-IC,H55101-001    I13 @BASEBOARD_FAB2_LIB.BASEBOARD_FAB2(SCH_1):PAGE222

VR_PVTT_DEF_SNS @BASEBOARD_FAB2_LIB.BASEBOARD_FAB2(SCH_1):VR_PVTT_DEF_SNS
 EU4A1    6    SNS MIC5166_DFN-IC,H55101-001    I13 @BASEBOARD_FAB2_LIB.BASEBOARD_FAB2(SCH_1):PAGE222
 SH5L1    1      A SHUNT_SH0201-EMPTY,N_A    I30 @BASEBOARD_FAB2_LIB.BASEBOARD_FAB2(SCH_1):PAGE222

VR_PVTT_DEF_VREF @BASEBOARD_FAB2_LIB.BASEBOARD_FAB2(SCH_1):VR_PVTT_DEF_VREF
 EU4A1    1   VREF MIC5166_DFN-IC,H55101-001    I13 @BASEBOARD_FAB2_LIB.BASEBOARD_FAB2(SCH_1):PAGE222
  C4A9    1      A CAP_0402-1.0UF,16V,10%,X6S,D97A    I20 @BASEBOARD_FAB2_LIB.BASEBOARD_FAB2(SCH_1):PAGE222

VR_PVTT_GHJ_BIAS @BASEBOARD_FAB2_LIB.BASEBOARD_FAB2(SCH_1):VR_PVTT_GHJ_BIAS
  R6U7    2      B RES_0402-0.0,5%,1/16W,CHIP,G21A     I9 @BASEBOARD_FAB2_LIB.BASEBOARD_FAB2(SCH_1):PAGE229
 C4G18    1      A CAP_0402-1.0UF,16V,10%,X6S,D97A    I16 @BASEBOARD_FAB2_LIB.BASEBOARD_FAB2(SCH_1):PAGE229
 EU4G2    2   BIAS MIC5166_DFN-IC,H55101-001    I37 @BASEBOARD_FAB2_LIB.BASEBOARD_FAB2(SCH_1):PAGE229

VR_PVTT_GHJ_SNS @BASEBOARD_FAB2_LIB.BASEBOARD_FAB2(SCH_1):VR_PVTT_GHJ_SNS
 SH8U1    1      A SHUNT_SH0201-EMPTY,N_A    I12 @BASEBOARD_FAB2_LIB.BASEBOARD_FAB2(SCH_1):PAGE229
 EU4G2    6    SNS MIC5166_DFN-IC,H55101-001    I37 @BASEBOARD_FAB2_LIB.BASEBOARD_FAB2(SCH_1):PAGE229

VR_PVTT_GHJ_VREF @BASEBOARD_FAB2_LIB.BASEBOARD_FAB2(SCH_1):VR_PVTT_GHJ_VREF
 C4G21    1      A CAP_0402-1.0UF,16V,10%,X6S,D97A    I21 @BASEBOARD_FAB2_LIB.BASEBOARD_FAB2(SCH_1):PAGE229
 EU4G2    1   VREF MIC5166_DFN-IC,H55101-001    I37 @BASEBOARD_FAB2_LIB.BASEBOARD_FAB2(SCH_1):PAGE229

VR_PVTT_KLM_BIAS @BASEBOARD_FAB2_LIB.BASEBOARD_FAB2(SCH_1):VR_PVTT_KLM_BIAS
  C4A8    1      A CAP_0402-1.0UF,16V,10%,X6S,D97A    I12 @BASEBOARD_FAB2_LIB.BASEBOARD_FAB2(SCH_1):PAGE230
  R6L8    2      B RES_0402-0.0,5%,1/16W,CHIP,G21A    I13 @BASEBOARD_FAB2_LIB.BASEBOARD_FAB2(SCH_1):PAGE230
 EU4A2    2   BIAS MIC5166_DFN-IC,H55101-001    I37 @BASEBOARD_FAB2_LIB.BASEBOARD_FAB2(SCH_1):PAGE230

VR_PVTT_KLM_SNS @BASEBOARD_FAB2_LIB.BASEBOARD_FAB2(SCH_1):VR_PVTT_KLM_SNS
 SH8L1    1      A SHUNT_SH0201-EMPTY,N_A    I30 @BASEBOARD_FAB2_LIB.BASEBOARD_FAB2(SCH_1):PAGE230
 EU4A2    6    SNS MIC5166_DFN-IC,H55101-001    I37 @BASEBOARD_FAB2_LIB.BASEBOARD_FAB2(SCH_1):PAGE230

VR_PVTT_KLM_VREF @BASEBOARD_FAB2_LIB.BASEBOARD_FAB2(SCH_1):VR_PVTT_KLM_VREF
 C4A14    1      A CAP_0402-1.0UF,16V,10%,X6S,D97A    I36 @BASEBOARD_FAB2_LIB.BASEBOARD_FAB2(SCH_1):PAGE230
 EU4A2    1   VREF MIC5166_DFN-IC,H55101-001    I37 @BASEBOARD_FAB2_LIB.BASEBOARD_FAB2(SCH_1):PAGE230

VR_VB_PVPP_ABC @BASEBOARD_FAB2_LIB.BASEBOARD_FAB2(SCH_1):VR_VB_PVPP_ABC
 EU7F1   38     VB NCP3232L_SM-IC,H86355-001   I193 @BASEBOARD_FAB2_LIB.BASEBOARD_FAB2(SCH_1):PAGE231
 C3T11    1      A CAP_0603-4.7UF,6.3V,10%,X6S,E1A   I202 @BASEBOARD_FAB2_LIB.BASEBOARD_FAB2(SCH_1):PAGE231

VR_VB_PVPP_DEF @BASEBOARD_FAB2_LIB.BASEBOARD_FAB2(SCH_1):VR_VB_PVPP_DEF
 EU7B1   38     VB NCP3232L_SM-IC,H86355-001   I214 @BASEBOARD_FAB2_LIB.BASEBOARD_FAB2(SCH_1):PAGE232
 C3M10    1      A CAP_0603-4.7UF,6.3V,10%,X6S,E1A   I253 @BASEBOARD_FAB2_LIB.BASEBOARD_FAB2(SCH_1):PAGE232

VR_VB_PVPP_GHJ @BASEBOARD_FAB2_LIB.BASEBOARD_FAB2(SCH_1):VR_VB_PVPP_GHJ
  C6U6    1      A CAP_0603-4.7UF,6.3V,10%,X6S,E1A   I187 @BASEBOARD_FAB2_LIB.BASEBOARD_FAB2(SCH_1):PAGE233
 EU4G1   38     VB NCP3232L_SM-IC,H86355-001   I225 @BASEBOARD_FAB2_LIB.BASEBOARD_FAB2(SCH_1):PAGE233

VR_VB_PVPP_KLM @BASEBOARD_FAB2_LIB.BASEBOARD_FAB2(SCH_1):VR_VB_PVPP_KLM
 C6L12    1      A CAP_0603-4.7UF,6.3V,10%,X6S,E1A   I144 @BASEBOARD_FAB2_LIB.BASEBOARD_FAB2(SCH_1):PAGE234
 EU4A3   38     VB NCP3232L_SM-IC,H86355-001   I184 @BASEBOARD_FAB2_LIB.BASEBOARD_FAB2(SCH_1):PAGE234

VR_VRRDY_PVCCIN_CPU0 @BASEBOARD_FAB2_LIB.BASEBOARD_FAB2(SCH_1):VR_VRRDY_PVCCIN_CPU0
 R4D58    2      B RES_0402-1.00K,1%,1/16W,CHIP,GA    I25 @BASEBOARD_FAB2_LIB.BASEBOARD_FAB2(SCH_1):PAGE201
 R4D63    1      A RES_0402-22.1,1.0%,1/16W,CHIP,A   I124 @BASEBOARD_FAB2_LIB.BASEBOARD_FAB2(SCH_1):PAGE201
 C4D42    1      A CAP_0402LF-1000PF,50V,10%,X7R,A   I125 @BASEBOARD_FAB2_LIB.BASEBOARD_FAB2(SCH_1):PAGE201
 EU4D4   11 AVRRDY PXE1610B_QFN-IC,H79206-001   I155 @BASEBOARD_FAB2_LIB.BASEBOARD_FAB2(SCH_1):PAGE201

VR_VRRDY_PVCCIN_CPU1 @BASEBOARD_FAB2_LIB.BASEBOARD_FAB2(SCH_1):VR_VRRDY_PVCCIN_CPU1
 R1C28    2      B RES_0402-1.00K,1%,1/16W,CHIP,GA    I35 @BASEBOARD_FAB2_LIB.BASEBOARD_FAB2(SCH_1):PAGE206
 R1C30    1      A RES_0402-22.1,1.0%,1/16W,CHIP,A   I113 @BASEBOARD_FAB2_LIB.BASEBOARD_FAB2(SCH_1):PAGE206
 C1C23    1      A CAP_0402LF-1000PF,50V,10%,X7R,A   I114 @BASEBOARD_FAB2_LIB.BASEBOARD_FAB2(SCH_1):PAGE206
 EU1C2   11 AVRRDY PXE1610B_QFN-IC,H79206-001   I130 @BASEBOARD_FAB2_LIB.BASEBOARD_FAB2(SCH_1):PAGE206

VSENSE_P12V_ADM1085 @BASEBOARD_FAB2_LIB.BASEBOARD_FAB2(SCH_1):VSENSE_P12V_ADM1085
  U7D3    3    VIN ADM1085_SMT-IC,H46130-001    I70 @BASEBOARD_FAB2_LIB.BASEBOARD_FAB2(SCH_1):PAGE196
 R3P48    2      B RES_0402-90.9K,1%,1/16W,CHIP,GA    I74 @BASEBOARD_FAB2_LIB.BASEBOARD_FAB2(SCH_1):PAGE196
 R3P51    1      A RES_0402-6.34K,1%,1/16W,CHIP,GA    I75 @BASEBOARD_FAB2_LIB.BASEBOARD_FAB2(SCH_1):PAGE196

VSENSE_P1V05_PCH_STBY_AVSN @BASEBOARD_FAB2_LIB.BASEBOARD_FAB2(SCH_1):VSENSE_P1V05_PCH_STBY_AVSN
  C2L2    2      B CAP_0402LF-220PF,50V,10%,X7R,AA   I153 @BASEBOARD_FAB2_LIB.BASEBOARD_FAB2(SCH_1):PAGE235
 EU8A1   30  BVREF PXE1110B_QFN-IC,H89187-001   I229 @BASEBOARD_FAB2_LIB.BASEBOARD_FAB2(SCH_1):PAGE235
 R8B15    2      B RES_0402-100.0,1%,1/16W,EMPTY,A    I57 @BASEBOARD_FAB2_LIB.BASEBOARD_FAB2(SCH_1):PAGE236
 R8B12    1      A RES_0402-0.0,5%,1/16W,CHIP,G21A    I59 @BASEBOARD_FAB2_LIB.BASEBOARD_FAB2(SCH_1):PAGE236

VSENSE_P1V05_PCH_STBY_AVSP @BASEBOARD_FAB2_LIB.BASEBOARD_FAB2(SCH_1):VSENSE_P1V05_PCH_STBY_AVSP
  R2L8    1      A RES_0603-10.0,1%,1/10W,CHIP,G2A   I154 @BASEBOARD_FAB2_LIB.BASEBOARD_FAB2(SCH_1):PAGE235
 R8B14    1      A RES_0402-0.0,5%,1/16W,CHIP,G21A    I56 @BASEBOARD_FAB2_LIB.BASEBOARD_FAB2(SCH_1):PAGE236
 R8B15    1      A RES_0402-100.0,1%,1/16W,EMPTY,A    I57 @BASEBOARD_FAB2_LIB.BASEBOARD_FAB2(SCH_1):PAGE236

VSENSE_P1V8MCP_CPU0_SKT_VRTN @BASEBOARD_FAB2_LIB.BASEBOARD_FAB2(SCH_1):VSENSE_P1V8MCP_CPU0_SKT_VRTN
  U5D1 AL20 RSVD<215> SKX_EXT_B_BGA1-IC,TBD   I204 @BASEBOARD_FAB2_LIB.BASEBOARD_FAB2(SCH_1):PAGE22
  J6E1   D2   IOD2 SCONN120_H61426002_SM-CONN,H61A    I55 @BASEBOARD_FAB2_LIB.BASEBOARD_FAB2(SCH_1):PAGE194

VSENSE_P1V8MCP_CPU0_SKT_VSEN @BASEBOARD_FAB2_LIB.BASEBOARD_FAB2(SCH_1):VSENSE_P1V8MCP_CPU0_SKT_VSEN
  U5D1 AK21 RSVD<221> SKX_EXT_B_BGA1-IC,TBD   I204 @BASEBOARD_FAB2_LIB.BASEBOARD_FAB2(SCH_1):PAGE22
  J6E1   D1   IOD1 SCONN120_H61426002_SM-CONN,H61A    I55 @BASEBOARD_FAB2_LIB.BASEBOARD_FAB2(SCH_1):PAGE194

VSENSE_P1V8MCP_CPU1_SKT_VRTN @BASEBOARD_FAB2_LIB.BASEBOARD_FAB2(SCH_1):VSENSE_P1V8MCP_CPU1_SKT_VRTN
  U2D1 AL20 RSVD<215> SKX_EXT_B_BGA1-IC,TBD   I169 @BASEBOARD_FAB2_LIB.BASEBOARD_FAB2(SCH_1):PAGE56
  J4E1   D2   IOD2 SCONN120_H61426002_SM-CONN,H61A    I45 @BASEBOARD_FAB2_LIB.BASEBOARD_FAB2(SCH_1):PAGE193

VSENSE_P1V8MCP_CPU1_SKT_VSEN @BASEBOARD_FAB2_LIB.BASEBOARD_FAB2(SCH_1):VSENSE_P1V8MCP_CPU1_SKT_VSEN
  U2D1 AK21 RSVD<221> SKX_EXT_B_BGA1-IC,TBD   I169 @BASEBOARD_FAB2_LIB.BASEBOARD_FAB2(SCH_1):PAGE56
  J4E1   D1   IOD1 SCONN120_H61426002_SM-CONN,H61A    I45 @BASEBOARD_FAB2_LIB.BASEBOARD_FAB2(SCH_1):PAGE193

VSENSE_P3V3_STBY @BASEBOARD_FAB2_LIB.BASEBOARD_FAB2(SCH_1):VSENSE_P3V3_STBY
 R8E31    1      A RES_0402-23.2K,1%,1/16W,CHIP,GA   I143 @BASEBOARD_FAB2_LIB.BASEBOARD_FAB2(SCH_1):PAGE240
 R8E25    2      B RES_0402-0.0,5%,1/16W,CHIP,G21A   I144 @BASEBOARD_FAB2_LIB.BASEBOARD_FAB2(SCH_1):PAGE240

VSENSE_PMAX_CPU0 @BASEBOARD_FAB2_LIB.BASEBOARD_FAB2(SCH_1):VSENSE_PMAX_CPU0
  R5D5    1      A RES_0402-249,0.1%,1/16W,CHIP,GA   I303 @BASEBOARD_FAB2_LIB.BASEBOARD_FAB2(SCH_1):PAGE37
  U5D1 AD41 VSENSEPMAX SKX_EXT_B_BGA1-IC,TBD   I311 @BASEBOARD_FAB2_LIB.BASEBOARD_FAB2(SCH_1):PAGE37
  R5D6    2      B RES_0402-10.0,1%,1/16W,EMPTY,GA   I312 @BASEBOARD_FAB2_LIB.BASEBOARD_FAB2(SCH_1):PAGE37

VSENSE_PMAX_CPU1 @BASEBOARD_FAB2_LIB.BASEBOARD_FAB2(SCH_1):VSENSE_PMAX_CPU1
 R3D27    1      A RES_0402-249,0.1%,1/16W,CHIP,GA    I43 @BASEBOARD_FAB2_LIB.BASEBOARD_FAB2(SCH_1):PAGE71
  U2D1 AD41 VSENSEPMAX SKX_EXT_B_BGA1-IC,TBD    I51 @BASEBOARD_FAB2_LIB.BASEBOARD_FAB2(SCH_1):PAGE71
 R3D32    2      B RES_0402-10.0,1%,1/16W,EMPTY,GA    I53 @BASEBOARD_FAB2_LIB.BASEBOARD_FAB2(SCH_1):PAGE71

VSENSE_PVCCIN_CPU0_AVSP @BASEBOARD_FAB2_LIB.BASEBOARD_FAB2(SCH_1):VSENSE_PVCCIN_CPU0_AVSP
 C4D45    1      A CAP_0402LF-220PF,50V,10%,X7R,AA    I70 @BASEBOARD_FAB2_LIB.BASEBOARD_FAB2(SCH_1):PAGE201
  R4E8    2      B RES_0402-10.0,1%,1/16W,CHIP,G2A   I109 @BASEBOARD_FAB2_LIB.BASEBOARD_FAB2(SCH_1):PAGE201
 EU4D4   21  AVSEN PXE1610B_QFN-IC,H79206-001   I155 @BASEBOARD_FAB2_LIB.BASEBOARD_FAB2(SCH_1):PAGE201

VSENSE_PVCCIN_CPU0_N @BASEBOARD_FAB2_LIB.BASEBOARD_FAB2(SCH_1):VSENSE_PVCCIN_CPU0_N
 C4D45    2      B CAP_0402LF-220PF,50V,10%,X7R,AA    I70 @BASEBOARD_FAB2_LIB.BASEBOARD_FAB2(SCH_1):PAGE201
 EU4D4   22  AVREF PXE1610B_QFN-IC,H79206-001   I155 @BASEBOARD_FAB2_LIB.BASEBOARD_FAB2(SCH_1):PAGE201
 R4E17    1      A RES_0402-0.0,5%,1/16W,CHIP,G21A    I62 @BASEBOARD_FAB2_LIB.BASEBOARD_FAB2(SCH_1):PAGE204
 R4E15    2      B RES_0402-1.00K,1%,1/16W,EMPTY,A    I63 @BASEBOARD_FAB2_LIB.BASEBOARD_FAB2(SCH_1):PAGE204
 R4E18    1      A RES_0402-100.0,1%,1/16W,CHIP,GA    I64 @BASEBOARD_FAB2_LIB.BASEBOARD_FAB2(SCH_1):PAGE204

VSENSE_PVCCIN_CPU0_P @BASEBOARD_FAB2_LIB.BASEBOARD_FAB2(SCH_1):VSENSE_PVCCIN_CPU0_P
  R4E8    1      A RES_0402-10.0,1%,1/16W,CHIP,G2A   I109 @BASEBOARD_FAB2_LIB.BASEBOARD_FAB2(SCH_1):PAGE201
 R4E14    1      A RES_0402-100.0,1%,1/16W,CHIP,GA    I60 @BASEBOARD_FAB2_LIB.BASEBOARD_FAB2(SCH_1):PAGE204
 R4E16    1      A RES_0402-0.0,5%,1/16W,CHIP,G21A    I61 @BASEBOARD_FAB2_LIB.BASEBOARD_FAB2(SCH_1):PAGE204
 R4E15    1      A RES_0402-1.00K,1%,1/16W,EMPTY,A    I63 @BASEBOARD_FAB2_LIB.BASEBOARD_FAB2(SCH_1):PAGE204

VSENSE_PVCCIN_CPU0_SKT_VRTN @BASEBOARD_FAB2_LIB.BASEBOARD_FAB2(SCH_1):VSENSE_PVCCIN_CPU0_SKT_VRTN
  U5D1 AY85 VSS_VCCIN_SENSE SKX_EXT_B_BGA1-IC,TBD   I311 @BASEBOARD_FAB2_LIB.BASEBOARD_FAB2(SCH_1):PAGE37
 R4E17    2      B RES_0402-0.0,5%,1/16W,CHIP,G21A    I62 @BASEBOARD_FAB2_LIB.BASEBOARD_FAB2(SCH_1):PAGE204

VSENSE_PVCCIN_CPU0_SKT_VSEN @BASEBOARD_FAB2_LIB.BASEBOARD_FAB2(SCH_1):VSENSE_PVCCIN_CPU0_SKT_VSEN
  U5D1 BA86 VCCIN_SENSE SKX_EXT_B_BGA1-IC,TBD   I311 @BASEBOARD_FAB2_LIB.BASEBOARD_FAB2(SCH_1):PAGE37
 R4E16    2      B RES_0402-0.0,5%,1/16W,CHIP,G21A    I61 @BASEBOARD_FAB2_LIB.BASEBOARD_FAB2(SCH_1):PAGE204

VSENSE_PVCCIN_CPU1_AVSP @BASEBOARD_FAB2_LIB.BASEBOARD_FAB2(SCH_1):VSENSE_PVCCIN_CPU1_AVSP
  C1D1    1      A CAP_0402LF-220PF,50V,10%,X7R,AA    I78 @BASEBOARD_FAB2_LIB.BASEBOARD_FAB2(SCH_1):PAGE206
  R1D4    2      B RES_0402-10.0,1%,1/16W,CHIP,G2A    I79 @BASEBOARD_FAB2_LIB.BASEBOARD_FAB2(SCH_1):PAGE206
 EU1C2   21  AVSEN PXE1610B_QFN-IC,H79206-001   I130 @BASEBOARD_FAB2_LIB.BASEBOARD_FAB2(SCH_1):PAGE206

VSENSE_PVCCIN_CPU1_N @BASEBOARD_FAB2_LIB.BASEBOARD_FAB2(SCH_1):VSENSE_PVCCIN_CPU1_N
  C1D1    2      B CAP_0402LF-220PF,50V,10%,X7R,AA    I78 @BASEBOARD_FAB2_LIB.BASEBOARD_FAB2(SCH_1):PAGE206
 EU1C2   22  AVREF PXE1610B_QFN-IC,H79206-001   I130 @BASEBOARD_FAB2_LIB.BASEBOARD_FAB2(SCH_1):PAGE206
  R1E5    2      B RES_0402-1.00K,1%,1/16W,EMPTY,A     I3 @BASEBOARD_FAB2_LIB.BASEBOARD_FAB2(SCH_1):PAGE209
  R1E8    1      A RES_0402-100.0,1%,1/16W,CHIP,GA     I9 @BASEBOARD_FAB2_LIB.BASEBOARD_FAB2(SCH_1):PAGE209
  R1E7    1      A RES_0402-0.0,5%,1/16W,CHIP,G21A    I10 @BASEBOARD_FAB2_LIB.BASEBOARD_FAB2(SCH_1):PAGE209

VSENSE_PVCCIN_CPU1_P @BASEBOARD_FAB2_LIB.BASEBOARD_FAB2(SCH_1):VSENSE_PVCCIN_CPU1_P
  R1D4    1      A RES_0402-10.0,1%,1/16W,CHIP,G2A    I79 @BASEBOARD_FAB2_LIB.BASEBOARD_FAB2(SCH_1):PAGE206
  R1E5    1      A RES_0402-1.00K,1%,1/16W,EMPTY,A     I3 @BASEBOARD_FAB2_LIB.BASEBOARD_FAB2(SCH_1):PAGE209
  R1E6    1      A RES_0402-0.0,5%,1/16W,CHIP,G21A    I11 @BASEBOARD_FAB2_LIB.BASEBOARD_FAB2(SCH_1):PAGE209
  R1E4    1      A RES_0402-100.0,1%,1/16W,CHIP,GA    I15 @BASEBOARD_FAB2_LIB.BASEBOARD_FAB2(SCH_1):PAGE209

VSENSE_PVCCIN_CPU1_SKT_VRTN @BASEBOARD_FAB2_LIB.BASEBOARD_FAB2(SCH_1):VSENSE_PVCCIN_CPU1_SKT_VRTN
  U2D1 AY85 VSS_VCCIN_SENSE SKX_EXT_B_BGA1-IC,TBD    I51 @BASEBOARD_FAB2_LIB.BASEBOARD_FAB2(SCH_1):PAGE71
  R1E7    2      B RES_0402-0.0,5%,1/16W,CHIP,G21A    I10 @BASEBOARD_FAB2_LIB.BASEBOARD_FAB2(SCH_1):PAGE209

VSENSE_PVCCIN_CPU1_SKT_VSEN @BASEBOARD_FAB2_LIB.BASEBOARD_FAB2(SCH_1):VSENSE_PVCCIN_CPU1_SKT_VSEN
  U2D1 BA86 VCCIN_SENSE SKX_EXT_B_BGA1-IC,TBD    I51 @BASEBOARD_FAB2_LIB.BASEBOARD_FAB2(SCH_1):PAGE71
  R1E6    2      B RES_0402-0.0,5%,1/16W,CHIP,G21A    I11 @BASEBOARD_FAB2_LIB.BASEBOARD_FAB2(SCH_1):PAGE209

VSENSE_PVCCIOMCP_CPU0_SKT_VRTN @BASEBOARD_FAB2_LIB.BASEBOARD_FAB2(SCH_1):VSENSE_PVCCIOMCP_CPU0_SKT_VRTN
  U5D1 BU16 CD_VCCP_SENSE<0> SKX_EXT_B_BGA1-IC,TBD   I127 @BASEBOARD_FAB2_LIB.BASEBOARD_FAB2(SCH_1):PAGE39
  J6B1   F8   IOF8 SCONN120_H61426002_SM-CONN,H61A    I56 @BASEBOARD_FAB2_LIB.BASEBOARD_FAB2(SCH_1):PAGE194

VSENSE_PVCCIOMCP_CPU0_SKT_VSEN @BASEBOARD_FAB2_LIB.BASEBOARD_FAB2(SCH_1):VSENSE_PVCCIOMCP_CPU0_SKT_VSEN
  U5D1 BT17 CD_VCCP_SENSE<1> SKX_EXT_B_BGA1-IC,TBD   I127 @BASEBOARD_FAB2_LIB.BASEBOARD_FAB2(SCH_1):PAGE39
  J6B1   E8   IOE8 SCONN120_H61426002_SM-CONN,H61A    I56 @BASEBOARD_FAB2_LIB.BASEBOARD_FAB2(SCH_1):PAGE194

VSENSE_PVCCIOMCP_CPU1_SKT_VRTN @BASEBOARD_FAB2_LIB.BASEBOARD_FAB2(SCH_1):VSENSE_PVCCIOMCP_CPU1_SKT_VRTN
  U2D1 BU16 CD_VCCP_SENSE<0> SKX_EXT_B_BGA1-IC,TBD   I107 @BASEBOARD_FAB2_LIB.BASEBOARD_FAB2(SCH_1):PAGE73
  J4B2   F8   IOF8 SCONN120_H61426002_SM-CONN,H61A    I46 @BASEBOARD_FAB2_LIB.BASEBOARD_FAB2(SCH_1):PAGE193

VSENSE_PVCCIOMCP_CPU1_SKT_VSEN @BASEBOARD_FAB2_LIB.BASEBOARD_FAB2(SCH_1):VSENSE_PVCCIOMCP_CPU1_SKT_VSEN
  U2D1 BT17 CD_VCCP_SENSE<1> SKX_EXT_B_BGA1-IC,TBD   I107 @BASEBOARD_FAB2_LIB.BASEBOARD_FAB2(SCH_1):PAGE73
  J4B2   E8   IOE8 SCONN120_H61426002_SM-CONN,H61A    I46 @BASEBOARD_FAB2_LIB.BASEBOARD_FAB2(SCH_1):PAGE193

VSENSE_PVCCIO_CPU0_AVSN @BASEBOARD_FAB2_LIB.BASEBOARD_FAB2(SCH_1):VSENSE_PVCCIO_CPU0_AVSN
 C3N39    2      B CAP_0402LF-220PF,50V,10%,X7R,AA    I83 @BASEBOARD_FAB2_LIB.BASEBOARD_FAB2(SCH_1):PAGE211
 EU3P1   20  AVREF PXE1110B_QFN-IC,H89187-001    I93 @BASEBOARD_FAB2_LIB.BASEBOARD_FAB2(SCH_1):PAGE211
 R3N20    1      A RES_0402-100.0,1%,1/16W,CHIP,GA    I68 @BASEBOARD_FAB2_LIB.BASEBOARD_FAB2(SCH_1):PAGE212
 SH3P2    2      B SHUNT_SH0201-EMPTY,N_A   I105 @BASEBOARD_FAB2_LIB.BASEBOARD_FAB2(SCH_1):PAGE212

VSENSE_PVCCIO_CPU0_AVSP @BASEBOARD_FAB2_LIB.BASEBOARD_FAB2(SCH_1):VSENSE_PVCCIO_CPU0_AVSP
 R3N19    1      A RES_0402-10.0,1%,1/16W,CHIP,G2A    I81 @BASEBOARD_FAB2_LIB.BASEBOARD_FAB2(SCH_1):PAGE211
 R3N21    1      A RES_0402-100.0,1%,1/16W,CHIP,GA    I74 @BASEBOARD_FAB2_LIB.BASEBOARD_FAB2(SCH_1):PAGE212
 SH3P1    2      B SHUNT_SH0201-EMPTY,N_A   I104 @BASEBOARD_FAB2_LIB.BASEBOARD_FAB2(SCH_1):PAGE212

VSENSE_PVCCIO_CPU0_SKT_VRTN @BASEBOARD_FAB2_LIB.BASEBOARD_FAB2(SCH_1):VSENSE_PVCCIO_CPU0_SKT_VRTN
  U5D1  BF5 VSS_VCCIO_SENSE SKX_EXT_B_BGA1-IC,TBD   I127 @BASEBOARD_FAB2_LIB.BASEBOARD_FAB2(SCH_1):PAGE39
  C3P1    2      B CAP_A_0402V-0.1UF,16V,10%,EMPTA    I60 @BASEBOARD_FAB2_LIB.BASEBOARD_FAB2(SCH_1):PAGE212
 SH3P2    1      A SHUNT_SH0201-EMPTY,N_A   I105 @BASEBOARD_FAB2_LIB.BASEBOARD_FAB2(SCH_1):PAGE212

VSENSE_PVCCIO_CPU0_SKT_VSEN @BASEBOARD_FAB2_LIB.BASEBOARD_FAB2(SCH_1):VSENSE_PVCCIO_CPU0_SKT_VSEN
  U5D1  BH5 VCCIO_SENSE SKX_EXT_B_BGA1-IC,TBD   I127 @BASEBOARD_FAB2_LIB.BASEBOARD_FAB2(SCH_1):PAGE39
  C3P1    1      A CAP_A_0402V-0.1UF,16V,10%,EMPTA    I60 @BASEBOARD_FAB2_LIB.BASEBOARD_FAB2(SCH_1):PAGE212
 SH3P1    1      A SHUNT_SH0201-EMPTY,N_A   I104 @BASEBOARD_FAB2_LIB.BASEBOARD_FAB2(SCH_1):PAGE212

VSENSE_PVCCIO_CPU1_AVSN @BASEBOARD_FAB2_LIB.BASEBOARD_FAB2(SCH_1):VSENSE_PVCCIO_CPU1_AVSN
 C4D44    2      B CAP_0402LF-220PF,50V,10%,X7R,AA    I83 @BASEBOARD_FAB2_LIB.BASEBOARD_FAB2(SCH_1):PAGE213
 EU4D5   20  AVREF PXE1110B_QFN-IC,H89187-001    I96 @BASEBOARD_FAB2_LIB.BASEBOARD_FAB2(SCH_1):PAGE213
 R3D28    1      A RES_0402-100.0,1%,1/16W,CHIP,GA   I101 @BASEBOARD_FAB2_LIB.BASEBOARD_FAB2(SCH_1):PAGE214
 SH3D1    2      B SHUNT_SH0201-EMPTY,N_A   I130 @BASEBOARD_FAB2_LIB.BASEBOARD_FAB2(SCH_1):PAGE214

VSENSE_PVCCIO_CPU1_AVSP @BASEBOARD_FAB2_LIB.BASEBOARD_FAB2(SCH_1):VSENSE_PVCCIO_CPU1_AVSP
  R4E7    1      A RES_0402-10.0,1%,1/16W,CHIP,G2A    I84 @BASEBOARD_FAB2_LIB.BASEBOARD_FAB2(SCH_1):PAGE213
  R3E1    1      A RES_0402-100.0,1%,1/16W,CHIP,GA   I105 @BASEBOARD_FAB2_LIB.BASEBOARD_FAB2(SCH_1):PAGE214
 SH3D2    2      B SHUNT_SH0201-EMPTY,N_A   I129 @BASEBOARD_FAB2_LIB.BASEBOARD_FAB2(SCH_1):PAGE214

VSENSE_PVCCIO_CPU1_SKT_VRTN @BASEBOARD_FAB2_LIB.BASEBOARD_FAB2(SCH_1):VSENSE_PVCCIO_CPU1_SKT_VRTN
  U2D1  BF5 VSS_VCCIO_SENSE SKX_EXT_B_BGA1-IC,TBD   I107 @BASEBOARD_FAB2_LIB.BASEBOARD_FAB2(SCH_1):PAGE73
 C3D27    2      B CAP_A_0402V-0.1UF,16V,10%,EMPTA    I96 @BASEBOARD_FAB2_LIB.BASEBOARD_FAB2(SCH_1):PAGE214
 SH3D1    1      A SHUNT_SH0201-EMPTY,N_A   I130 @BASEBOARD_FAB2_LIB.BASEBOARD_FAB2(SCH_1):PAGE214

VSENSE_PVCCIO_CPU1_SKT_VSEN @BASEBOARD_FAB2_LIB.BASEBOARD_FAB2(SCH_1):VSENSE_PVCCIO_CPU1_SKT_VSEN
  U2D1  BH5 VCCIO_SENSE SKX_EXT_B_BGA1-IC,TBD   I107 @BASEBOARD_FAB2_LIB.BASEBOARD_FAB2(SCH_1):PAGE73
 C3D27    1      A CAP_A_0402V-0.1UF,16V,10%,EMPTA    I96 @BASEBOARD_FAB2_LIB.BASEBOARD_FAB2(SCH_1):PAGE214
 SH3D2    1      A SHUNT_SH0201-EMPTY,N_A   I129 @BASEBOARD_FAB2_LIB.BASEBOARD_FAB2(SCH_1):PAGE214

VSENSE_PVCCMCP_CPU0_SKT_VRTN @BASEBOARD_FAB2_LIB.BASEBOARD_FAB2(SCH_1):VSENSE_PVCCMCP_CPU0_SKT_VRTN
  U5D1 BL16 CD_VSS_VCC_CORE_SENSE SKX_EXT_B_BGA1-IC,TBD   I127 @BASEBOARD_FAB2_LIB.BASEBOARD_FAB2(SCH_1):PAGE39
  J6E1   B4   IOB4 SCONN120_H61426002_SM-CONN,H61A    I55 @BASEBOARD_FAB2_LIB.BASEBOARD_FAB2(SCH_1):PAGE194

VSENSE_PVCCMCP_CPU0_SKT_VSEN @BASEBOARD_FAB2_LIB.BASEBOARD_FAB2(SCH_1):VSENSE_PVCCMCP_CPU0_SKT_VSEN
  U5D1 BN16 CD_VCC_CORE_SENSE SKX_EXT_B_BGA1-IC,TBD   I127 @BASEBOARD_FAB2_LIB.BASEBOARD_FAB2(SCH_1):PAGE39
  J6E1   A4   IOA4 SCONN120_H61426002_SM-CONN,H61A    I55 @BASEBOARD_FAB2_LIB.BASEBOARD_FAB2(SCH_1):PAGE194

VSENSE_PVCCMCP_CPU1_SKT_VRTN @BASEBOARD_FAB2_LIB.BASEBOARD_FAB2(SCH_1):VSENSE_PVCCMCP_CPU1_SKT_VRTN
  U2D1 BL16 CD_VSS_VCC_CORE_SENSE SKX_EXT_B_BGA1-IC,TBD   I107 @BASEBOARD_FAB2_LIB.BASEBOARD_FAB2(SCH_1):PAGE73
  J4E1   B4   IOB4 SCONN120_H61426002_SM-CONN,H61A    I45 @BASEBOARD_FAB2_LIB.BASEBOARD_FAB2(SCH_1):PAGE193

VSENSE_PVCCMCP_CPU1_SKT_VSEN @BASEBOARD_FAB2_LIB.BASEBOARD_FAB2(SCH_1):VSENSE_PVCCMCP_CPU1_SKT_VSEN
  U2D1 BN16 CD_VCC_CORE_SENSE SKX_EXT_B_BGA1-IC,TBD   I107 @BASEBOARD_FAB2_LIB.BASEBOARD_FAB2(SCH_1):PAGE73
  J4E1   A4   IOA4 SCONN120_H61426002_SM-CONN,H61A    I45 @BASEBOARD_FAB2_LIB.BASEBOARD_FAB2(SCH_1):PAGE193

VSENSE_PVDDQ_ABC_N @BASEBOARD_FAB2_LIB.BASEBOARD_FAB2(SCH_1):VSENSE_PVDDQ_ABC_N
  R4U6    2      B RES_0402-100.0,1%,1/16W,EMPTY,A    I74 @BASEBOARD_FAB2_LIB.BASEBOARD_FAB2(SCH_1):PAGE217
 SH4U1    1      A SHUNT_SH0201-EMPTY,N_A   I259 @BASEBOARD_FAB2_LIB.BASEBOARD_FAB2(SCH_1):PAGE217
  C7G4    2      B CAP_0402LF-220PF,50V,10%,X7R,AA    I14 @BASEBOARD_FAB2_LIB.BASEBOARD_FAB2(SCH_1):PAGE215
 EU7G1   20  AVREF PXM1310B_QFN-IC,H89186-001    I69 @BASEBOARD_FAB2_LIB.BASEBOARD_FAB2(SCH_1):PAGE215

VSENSE_PVDDQ_ABC_P @BASEBOARD_FAB2_LIB.BASEBOARD_FAB2(SCH_1):VSENSE_PVDDQ_ABC_P
  R4U6    1      A RES_0402-100.0,1%,1/16W,EMPTY,A    I74 @BASEBOARD_FAB2_LIB.BASEBOARD_FAB2(SCH_1):PAGE217
 SH4U2    1      A SHUNT_SH0201-EMPTY,N_A   I260 @BASEBOARD_FAB2_LIB.BASEBOARD_FAB2(SCH_1):PAGE217
  R7G9    1      A RES_0402-10.0,1%,1/16W,CHIP,G2A    I12 @BASEBOARD_FAB2_LIB.BASEBOARD_FAB2(SCH_1):PAGE215

VSENSE_PVDDQ_ABC_VTT @BASEBOARD_FAB2_LIB.BASEBOARD_FAB2(SCH_1):VSENSE_PVDDQ_ABC_VTT
  R6U5    2      B RES_0402-0.0,5%,1/16W,CHIP,G21A     I6 @BASEBOARD_FAB2_LIB.BASEBOARD_FAB2(SCH_1):PAGE221
 C6U12    1      A CAP_0603-4.7UF,6.3V,10%,X6S,E1A    I11 @BASEBOARD_FAB2_LIB.BASEBOARD_FAB2(SCH_1):PAGE221
 EU4G3    4   VDDQ MIC5166_DFN-IC,H55101-001    I15 @BASEBOARD_FAB2_LIB.BASEBOARD_FAB2(SCH_1):PAGE221

VSENSE_PVDDQ_DEF_N @BASEBOARD_FAB2_LIB.BASEBOARD_FAB2(SCH_1):VSENSE_PVDDQ_DEF_N
  R4L2    2      B RES_0402-100.0,1%,1/16W,EMPTY,A    I74 @BASEBOARD_FAB2_LIB.BASEBOARD_FAB2(SCH_1):PAGE220
 SH4L1    1      A SHUNT_SH0201-EMPTY,N_A   I240 @BASEBOARD_FAB2_LIB.BASEBOARD_FAB2(SCH_1):PAGE220
 EU7A5   20  AVREF PXM1310B_QFN-IC,H89186-001    I69 @BASEBOARD_FAB2_LIB.BASEBOARD_FAB2(SCH_1):PAGE218
 C7A28    2      B CAP_0402LF-220PF,50V,10%,X7R,AA    I14 @BASEBOARD_FAB2_LIB.BASEBOARD_FAB2(SCH_1):PAGE218

VSENSE_PVDDQ_DEF_P @BASEBOARD_FAB2_LIB.BASEBOARD_FAB2(SCH_1):VSENSE_PVDDQ_DEF_P
  R4L2    1      A RES_0402-100.0,1%,1/16W,EMPTY,A    I74 @BASEBOARD_FAB2_LIB.BASEBOARD_FAB2(SCH_1):PAGE220
 SH4L2    1      A SHUNT_SH0201-EMPTY,N_A   I239 @BASEBOARD_FAB2_LIB.BASEBOARD_FAB2(SCH_1):PAGE220
  R7A7    1      A RES_0402-10.0,1%,1/16W,CHIP,G2A    I13 @BASEBOARD_FAB2_LIB.BASEBOARD_FAB2(SCH_1):PAGE218

VSENSE_PVDDQ_DEF_VTT @BASEBOARD_FAB2_LIB.BASEBOARD_FAB2(SCH_1):VSENSE_PVDDQ_DEF_VTT
 R6L10    2      B RES_0402-0.0,5%,1/16W,CHIP,G21A     I6 @BASEBOARD_FAB2_LIB.BASEBOARD_FAB2(SCH_1):PAGE222
 C4A11    1      A CAP_0603-4.7UF,6.3V,10%,X6S,E1A     I9 @BASEBOARD_FAB2_LIB.BASEBOARD_FAB2(SCH_1):PAGE222
 EU4A1    4   VDDQ MIC5166_DFN-IC,H55101-001    I13 @BASEBOARD_FAB2_LIB.BASEBOARD_FAB2(SCH_1):PAGE222

VSENSE_PVDDQ_GHJ_N @BASEBOARD_FAB2_LIB.BASEBOARD_FAB2(SCH_1):VSENSE_PVDDQ_GHJ_N
  R7U2    2      B RES_0402-100.0,1%,1/16W,EMPTY,A    I74 @BASEBOARD_FAB2_LIB.BASEBOARD_FAB2(SCH_1):PAGE225
 SH7U2    1      A SHUNT_SH0201-EMPTY,N_A   I244 @BASEBOARD_FAB2_LIB.BASEBOARD_FAB2(SCH_1):PAGE225
 C1G16    2      B CAP_0402LF-220PF,50V,10%,X7R,AA    I12 @BASEBOARD_FAB2_LIB.BASEBOARD_FAB2(SCH_1):PAGE223
 EU1G2   20  AVREF PXM1310B_QFN-IC,H89186-001    I69 @BASEBOARD_FAB2_LIB.BASEBOARD_FAB2(SCH_1):PAGE223

VSENSE_PVDDQ_GHJ_P @BASEBOARD_FAB2_LIB.BASEBOARD_FAB2(SCH_1):VSENSE_PVDDQ_GHJ_P
  R7U2    1      A RES_0402-100.0,1%,1/16W,EMPTY,A    I74 @BASEBOARD_FAB2_LIB.BASEBOARD_FAB2(SCH_1):PAGE225
 SH7U1    1      A SHUNT_SH0201-EMPTY,N_A   I243 @BASEBOARD_FAB2_LIB.BASEBOARD_FAB2(SCH_1):PAGE225
  R1G5    1      A RES_0402-10.0,1%,1/16W,CHIP,G2A    I13 @BASEBOARD_FAB2_LIB.BASEBOARD_FAB2(SCH_1):PAGE223

VSENSE_PVDDQ_GHJ_VTT @BASEBOARD_FAB2_LIB.BASEBOARD_FAB2(SCH_1):VSENSE_PVDDQ_GHJ_VTT
  R6U6    2      B RES_0402-0.0,5%,1/16W,CHIP,G21A     I6 @BASEBOARD_FAB2_LIB.BASEBOARD_FAB2(SCH_1):PAGE229
 EU4G2    4   VDDQ MIC5166_DFN-IC,H55101-001    I37 @BASEBOARD_FAB2_LIB.BASEBOARD_FAB2(SCH_1):PAGE229
 C6U11    1      A CAP_0603-4.7UF,6.3V,10%,X6S,E1A    I14 @BASEBOARD_FAB2_LIB.BASEBOARD_FAB2(SCH_1):PAGE229

VSENSE_PVDDQ_KLM_N @BASEBOARD_FAB2_LIB.BASEBOARD_FAB2(SCH_1):VSENSE_PVDDQ_KLM_N
  R7L2    2      B RES_0402-100.0,1%,1/16W,EMPTY,A    I74 @BASEBOARD_FAB2_LIB.BASEBOARD_FAB2(SCH_1):PAGE228
 SH7L1    1      A SHUNT_SH0201-EMPTY,N_A   I246 @BASEBOARD_FAB2_LIB.BASEBOARD_FAB2(SCH_1):PAGE228
 C1B12    2      B CAP_0402LF-220PF,50V,10%,X7R,AA    I12 @BASEBOARD_FAB2_LIB.BASEBOARD_FAB2(SCH_1):PAGE226
 EU1B1   20  AVREF PXM1310B_QFN-IC,H89186-001    I69 @BASEBOARD_FAB2_LIB.BASEBOARD_FAB2(SCH_1):PAGE226

VSENSE_PVDDQ_KLM_P @BASEBOARD_FAB2_LIB.BASEBOARD_FAB2(SCH_1):VSENSE_PVDDQ_KLM_P
  R7L2    1      A RES_0402-100.0,1%,1/16W,EMPTY,A    I74 @BASEBOARD_FAB2_LIB.BASEBOARD_FAB2(SCH_1):PAGE228
 SH7L2    1      A SHUNT_SH0201-EMPTY,N_A   I245 @BASEBOARD_FAB2_LIB.BASEBOARD_FAB2(SCH_1):PAGE228
 R1B16    1      A RES_0402-10.0,1%,1/16W,CHIP,G2A    I13 @BASEBOARD_FAB2_LIB.BASEBOARD_FAB2(SCH_1):PAGE226

VSENSE_PVDDQ_KLM_VTT @BASEBOARD_FAB2_LIB.BASEBOARD_FAB2(SCH_1):VSENSE_PVDDQ_KLM_VTT
  R6L6    2      B RES_0402-0.0,5%,1/16W,CHIP,G21A     I6 @BASEBOARD_FAB2_LIB.BASEBOARD_FAB2(SCH_1):PAGE230
  C4A7    1      A CAP_0603-4.7UF,6.3V,10%,X6S,E1A    I10 @BASEBOARD_FAB2_LIB.BASEBOARD_FAB2(SCH_1):PAGE230
 EU4A2    4   VDDQ MIC5166_DFN-IC,H55101-001    I37 @BASEBOARD_FAB2_LIB.BASEBOARD_FAB2(SCH_1):PAGE230

VSENSE_PVNN_PCH_STBY_AVSN @BASEBOARD_FAB2_LIB.BASEBOARD_FAB2(SCH_1):VSENSE_PVNN_PCH_STBY_AVSN
  C8A2    2      B CAP_0402LF-220PF,50V,10%,X7R,AA   I209 @BASEBOARD_FAB2_LIB.BASEBOARD_FAB2(SCH_1):PAGE235
 EU8A1   20  AVREF PXE1110B_QFN-IC,H89187-001   I229 @BASEBOARD_FAB2_LIB.BASEBOARD_FAB2(SCH_1):PAGE235
 R7A18    2      B RES_0402-0.0,5%,1/16W,CHIP,G21A    I92 @BASEBOARD_FAB2_LIB.BASEBOARD_FAB2(SCH_1):PAGE236

VSENSE_PVNN_PCH_STBY_AVSP @BASEBOARD_FAB2_LIB.BASEBOARD_FAB2(SCH_1):VSENSE_PVNN_PCH_STBY_AVSP
  R8A1    1      A RES_0402-10.0,1%,1/16W,CHIP,G2A   I210 @BASEBOARD_FAB2_LIB.BASEBOARD_FAB2(SCH_1):PAGE235
 R7A13    1      A RES_0402-100.0,1%,1/16W,CHIP,GA    I90 @BASEBOARD_FAB2_LIB.BASEBOARD_FAB2(SCH_1):PAGE236
 R7A19    2      B RES_0402-10.0,1%,1/16W,CHIP,G2A    I93 @BASEBOARD_FAB2_LIB.BASEBOARD_FAB2(SCH_1):PAGE236
 R7A14    2      B RES_0402-10.0,1%,1/16W,CHIP,G2A    I94 @BASEBOARD_FAB2_LIB.BASEBOARD_FAB2(SCH_1):PAGE236

VSENSE_PVNN_PCH_STBY_FPK @BASEBOARD_FAB2_LIB.BASEBOARD_FAB2(SCH_1):VSENSE_PVNN_PCH_STBY_FPK
  U7C1 AK36 VCCPRIM_AVID_SENSE LBG_CORE_QAT_EXT_D_BGA1-IC,H91A    I21 @BASEBOARD_FAB2_LIB.BASEBOARD_FAB2(SCH_1):PAGE123
 R7A14    1      A RES_0402-10.0,1%,1/16W,CHIP,G2A    I94 @BASEBOARD_FAB2_LIB.BASEBOARD_FAB2(SCH_1):PAGE236

VSENSE_PVNN_PCH_STBY_QAT @BASEBOARD_FAB2_LIB.BASEBOARD_FAB2(SCH_1):VSENSE_PVNN_PCH_STBY_QAT
  U7C1  V37 VCCPRIM_AVID_QAT_SENSE LBG_CORE_QAT_EXT_D_BGA1-IC,H91A    I21 @BASEBOARD_FAB2_LIB.BASEBOARD_FAB2(SCH_1):PAGE123
 R7A19    1      A RES_0402-10.0,1%,1/16W,CHIP,G2A    I93 @BASEBOARD_FAB2_LIB.BASEBOARD_FAB2(SCH_1):PAGE236

VSENSE_PVPP_ABC @BASEBOARD_FAB2_LIB.BASEBOARD_FAB2(SCH_1):VSENSE_PVPP_ABC
 R7F13    1      A RES_0402-20.0K,1%,1/16W,CHIP,GA   I167 @BASEBOARD_FAB2_LIB.BASEBOARD_FAB2(SCH_1):PAGE231
 R7F12    2      B RES_0402-0.0,5%,1/16W,CHIP,G21A   I168 @BASEBOARD_FAB2_LIB.BASEBOARD_FAB2(SCH_1):PAGE231
 R7F17    1      A RES_0402-1.0K,0.1%,1/16W,CHIP,A   I218 @BASEBOARD_FAB2_LIB.BASEBOARD_FAB2(SCH_1):PAGE231

VSENSE_PVPP_DEF @BASEBOARD_FAB2_LIB.BASEBOARD_FAB2(SCH_1):VSENSE_PVPP_DEF
 R7B18    1      A RES_0402-1.0K,0.1%,1/16W,CHIP,A   I298 @BASEBOARD_FAB2_LIB.BASEBOARD_FAB2(SCH_1):PAGE232
 R7B11    2      B RES_0402-0.0,5%,1/16W,CHIP,G21A   I299 @BASEBOARD_FAB2_LIB.BASEBOARD_FAB2(SCH_1):PAGE232
 R7B15    1      A RES_0402-20.0K,1%,1/16W,CHIP,GA   I303 @BASEBOARD_FAB2_LIB.BASEBOARD_FAB2(SCH_1):PAGE232

VSENSE_PVPP_GHJ @BASEBOARD_FAB2_LIB.BASEBOARD_FAB2(SCH_1):VSENSE_PVPP_GHJ
 R4G10    1      A RES_0402-1.0K,0.1%,1/16W,CHIP,A   I266 @BASEBOARD_FAB2_LIB.BASEBOARD_FAB2(SCH_1):PAGE233
  R4G7    1      A RES_0402-20.0K,1%,1/16W,CHIP,GA   I270 @BASEBOARD_FAB2_LIB.BASEBOARD_FAB2(SCH_1):PAGE233
  R4G8    2      B RES_0402-0.0,5%,1/16W,CHIP,G21A   I271 @BASEBOARD_FAB2_LIB.BASEBOARD_FAB2(SCH_1):PAGE233

VSENSE_PVPP_KLM @BASEBOARD_FAB2_LIB.BASEBOARD_FAB2(SCH_1):VSENSE_PVPP_KLM
  R4B3    2      B RES_0402-0.0,5%,1/16W,CHIP,G21A   I214 @BASEBOARD_FAB2_LIB.BASEBOARD_FAB2(SCH_1):PAGE234
  R4B5    1      A RES_0402-20.0K,1%,1/16W,CHIP,GA   I215 @BASEBOARD_FAB2_LIB.BASEBOARD_FAB2(SCH_1):PAGE234
  R4B9    1      A RES_0402-1.0K,0.1%,1/16W,CHIP,A   I219 @BASEBOARD_FAB2_LIB.BASEBOARD_FAB2(SCH_1):PAGE234

VSENSE_PVSA_CPU0_BVSP @BASEBOARD_FAB2_LIB.BASEBOARD_FAB2(SCH_1):VSENSE_PVSA_CPU0_BVSP
 C4D29    1      A CAP_0402LF-220PF,50V,10%,X7R,AA    I64 @BASEBOARD_FAB2_LIB.BASEBOARD_FAB2(SCH_1):PAGE201
 R4D39    2      B RES_0402-10.0,1%,1/16W,CHIP,G2A   I110 @BASEBOARD_FAB2_LIB.BASEBOARD_FAB2(SCH_1):PAGE201
 EU4D4   35  BVSEN PXE1610B_QFN-IC,H79206-001   I155 @BASEBOARD_FAB2_LIB.BASEBOARD_FAB2(SCH_1):PAGE201

VSENSE_PVSA_CPU0_N @BASEBOARD_FAB2_LIB.BASEBOARD_FAB2(SCH_1):VSENSE_PVSA_CPU0_N
 C4D29    2      B CAP_0402LF-220PF,50V,10%,X7R,AA    I64 @BASEBOARD_FAB2_LIB.BASEBOARD_FAB2(SCH_1):PAGE201
 EU4D4   36  BVREF PXE1610B_QFN-IC,H79206-001   I155 @BASEBOARD_FAB2_LIB.BASEBOARD_FAB2(SCH_1):PAGE201
  R4C1    1      A RES_0402-100.0,1%,1/16W,CHIP,GA    I29 @BASEBOARD_FAB2_LIB.BASEBOARD_FAB2(SCH_1):PAGE205
  R4C2    1      A RES_0402-0.0,5%,1/16W,CHIP,G21A    I30 @BASEBOARD_FAB2_LIB.BASEBOARD_FAB2(SCH_1):PAGE205
  R4C3    2      B RES_0402-1.00K,1%,1/16W,EMPTY,A    I37 @BASEBOARD_FAB2_LIB.BASEBOARD_FAB2(SCH_1):PAGE205

VSENSE_PVSA_CPU0_P @BASEBOARD_FAB2_LIB.BASEBOARD_FAB2(SCH_1):VSENSE_PVSA_CPU0_P
 R4D39    1      A RES_0402-10.0,1%,1/16W,CHIP,G2A   I110 @BASEBOARD_FAB2_LIB.BASEBOARD_FAB2(SCH_1):PAGE201
  R4C5    1      A RES_0402-100.0,1%,1/16W,CHIP,GA    I24 @BASEBOARD_FAB2_LIB.BASEBOARD_FAB2(SCH_1):PAGE205
  R4C4    1      A RES_0402-0.0,5%,1/16W,CHIP,G21A    I26 @BASEBOARD_FAB2_LIB.BASEBOARD_FAB2(SCH_1):PAGE205
  R4C3    1      A RES_0402-1.00K,1%,1/16W,EMPTY,A    I37 @BASEBOARD_FAB2_LIB.BASEBOARD_FAB2(SCH_1):PAGE205

VSENSE_PVSA_CPU0_SKT_VRTN @BASEBOARD_FAB2_LIB.BASEBOARD_FAB2(SCH_1):VSENSE_PVSA_CPU0_SKT_VRTN
  U5D1 CG76 VSS_VCCSA_SENSE SKX_EXT_B_BGA1-IC,TBD   I127 @BASEBOARD_FAB2_LIB.BASEBOARD_FAB2(SCH_1):PAGE39
  R4C2    2      B RES_0402-0.0,5%,1/16W,CHIP,G21A    I30 @BASEBOARD_FAB2_LIB.BASEBOARD_FAB2(SCH_1):PAGE205

VSENSE_PVSA_CPU0_SKT_VSEN @BASEBOARD_FAB2_LIB.BASEBOARD_FAB2(SCH_1):VSENSE_PVSA_CPU0_SKT_VSEN
  U5D1 CE76 VCCSA_SENSE SKX_EXT_B_BGA1-IC,TBD   I127 @BASEBOARD_FAB2_LIB.BASEBOARD_FAB2(SCH_1):PAGE39
  R4C4    2      B RES_0402-0.0,5%,1/16W,CHIP,G21A    I26 @BASEBOARD_FAB2_LIB.BASEBOARD_FAB2(SCH_1):PAGE205

VSENSE_PVSA_CPU1_BVSP @BASEBOARD_FAB2_LIB.BASEBOARD_FAB2(SCH_1):VSENSE_PVSA_CPU1_BVSP
 C1C16    1      A CAP_0402LF-220PF,50V,10%,X7R,AA    I68 @BASEBOARD_FAB2_LIB.BASEBOARD_FAB2(SCH_1):PAGE206
 R1C21    2      B RES_0402-10.0,1%,1/16W,CHIP,G2A    I77 @BASEBOARD_FAB2_LIB.BASEBOARD_FAB2(SCH_1):PAGE206
 EU1C2   35  BVSEN PXE1610B_QFN-IC,H79206-001   I130 @BASEBOARD_FAB2_LIB.BASEBOARD_FAB2(SCH_1):PAGE206

VSENSE_PVSA_CPU1_N @BASEBOARD_FAB2_LIB.BASEBOARD_FAB2(SCH_1):VSENSE_PVSA_CPU1_N
 C1C16    2      B CAP_0402LF-220PF,50V,10%,X7R,AA    I68 @BASEBOARD_FAB2_LIB.BASEBOARD_FAB2(SCH_1):PAGE206
 EU1C2   36  BVREF PXE1610B_QFN-IC,H79206-001   I130 @BASEBOARD_FAB2_LIB.BASEBOARD_FAB2(SCH_1):PAGE206
  R1C5    1      A RES_0402-0.0,5%,1/16W,CHIP,G21A    I32 @BASEBOARD_FAB2_LIB.BASEBOARD_FAB2(SCH_1):PAGE210
  R1C4    1      A RES_0402-100.0,1%,1/16W,CHIP,GA    I33 @BASEBOARD_FAB2_LIB.BASEBOARD_FAB2(SCH_1):PAGE210
  R1C6    2      B RES_0402-1.00K,1%,1/16W,EMPTY,A    I34 @BASEBOARD_FAB2_LIB.BASEBOARD_FAB2(SCH_1):PAGE210

VSENSE_PVSA_CPU1_P @BASEBOARD_FAB2_LIB.BASEBOARD_FAB2(SCH_1):VSENSE_PVSA_CPU1_P
 R1C21    1      A RES_0402-10.0,1%,1/16W,CHIP,G2A    I77 @BASEBOARD_FAB2_LIB.BASEBOARD_FAB2(SCH_1):PAGE206
 R1C12    1      A RES_0402-100.0,1%,1/16W,CHIP,GA    I29 @BASEBOARD_FAB2_LIB.BASEBOARD_FAB2(SCH_1):PAGE210
  R1C7    1      A RES_0402-0.0,5%,1/16W,CHIP,G21A    I31 @BASEBOARD_FAB2_LIB.BASEBOARD_FAB2(SCH_1):PAGE210
  R1C6    1      A RES_0402-1.00K,1%,1/16W,EMPTY,A    I34 @BASEBOARD_FAB2_LIB.BASEBOARD_FAB2(SCH_1):PAGE210

VSENSE_PVSA_CPU1_SKT_VRTN @BASEBOARD_FAB2_LIB.BASEBOARD_FAB2(SCH_1):VSENSE_PVSA_CPU1_SKT_VRTN
  U2D1 CG76 VSS_VCCSA_SENSE SKX_EXT_B_BGA1-IC,TBD   I107 @BASEBOARD_FAB2_LIB.BASEBOARD_FAB2(SCH_1):PAGE73
  R1C5    2      B RES_0402-0.0,5%,1/16W,CHIP,G21A    I32 @BASEBOARD_FAB2_LIB.BASEBOARD_FAB2(SCH_1):PAGE210

VSENSE_PVSA_CPU1_SKT_VSEN @BASEBOARD_FAB2_LIB.BASEBOARD_FAB2(SCH_1):VSENSE_PVSA_CPU1_SKT_VSEN
  U2D1 CE76 VCCSA_SENSE SKX_EXT_B_BGA1-IC,TBD   I107 @BASEBOARD_FAB2_LIB.BASEBOARD_FAB2(SCH_1):PAGE73
  R1C7    2      B RES_0402-0.0,5%,1/16W,CHIP,G21A    I31 @BASEBOARD_FAB2_LIB.BASEBOARD_FAB2(SCH_1):PAGE210

VSENSE_RGND_P3V3_STBY @BASEBOARD_FAB2_LIB.BASEBOARD_FAB2(SCH_1):VSENSE_RGND_P3V3_STBY
 EU8F1    7   RGND RT8240_QFN-IC,H66262-001   I125 @BASEBOARD_FAB2_LIB.BASEBOARD_FAB2(SCH_1):PAGE240
 R8E38    1      A RES_0402-0.0,5%,1/16W,CHIP,G21A   I140 @BASEBOARD_FAB2_LIB.BASEBOARD_FAB2(SCH_1):PAGE240

VSENSE_VCCINR2PMAX_CPU0 @BASEBOARD_FAB2_LIB.BASEBOARD_FAB2(SCH_1):VSENSE_VCCINR2PMAX_CPU0
  R5P1    2      B RES_0603-100.0K,1%,1/10W,CHIP,A   I309 @BASEBOARD_FAB2_LIB.BASEBOARD_FAB2(SCH_1):PAGE37
  U5D1 AW86 VCCINPMAX<0> SKX_EXT_B_BGA1-IC,TBD   I311 @BASEBOARD_FAB2_LIB.BASEBOARD_FAB2(SCH_1):PAGE37
  U5D1 AV85 VCCINPMAX<1> SKX_EXT_B_BGA1-IC,TBD   I311 @BASEBOARD_FAB2_LIB.BASEBOARD_FAB2(SCH_1):PAGE37

VSENSE_VCCINR2PMAX_CPU1 @BASEBOARD_FAB2_LIB.BASEBOARD_FAB2(SCH_1):VSENSE_VCCINR2PMAX_CPU1
 RT8P1    2      B RES_0603-100.0K,1%,1/10W,CHIP,A    I49 @BASEBOARD_FAB2_LIB.BASEBOARD_FAB2(SCH_1):PAGE71
  U2D1 AW86 VCCINPMAX<0> SKX_EXT_B_BGA1-IC,TBD    I51 @BASEBOARD_FAB2_LIB.BASEBOARD_FAB2(SCH_1):PAGE71
  U2D1 AV85 VCCINPMAX<1> SKX_EXT_B_BGA1-IC,TBD    I51 @BASEBOARD_FAB2_LIB.BASEBOARD_FAB2(SCH_1):PAGE71

VSENSE_VOUT_P3V3_STBY @BASEBOARD_FAB2_LIB.BASEBOARD_FAB2(SCH_1):VSENSE_VOUT_P3V3_STBY
 EU8F1    6   VOUT RT8240_QFN-IC,H66262-001   I125 @BASEBOARD_FAB2_LIB.BASEBOARD_FAB2(SCH_1):PAGE240
 R8E34    1      A RES_0402-10.0K,1%,1/16W,CHIP,GA   I142 @BASEBOARD_FAB2_LIB.BASEBOARD_FAB2(SCH_1):PAGE240
 R8E31    2      B RES_0402-23.2K,1%,1/16W,CHIP,GA   I143 @BASEBOARD_FAB2_LIB.BASEBOARD_FAB2(SCH_1):PAGE240

V_IBMC_5V_DDC_SCL_J @BASEBOARD_FAB2_LIB.BASEBOARD_FAB2(SCH_1):V_IBMC_5V_DDC_SCL_J
R25W133    2      B RES_0402-33.2,1%,1/16W,CHIP,G2A    I34 @BASEBOARD_FAB2_LIB.BASEBOARD_FAB2(SCH_1):PAGE255
C25W78    1      A CAP_0402LF-100.0PF,50V,5%,COG,A    I35 @BASEBOARD_FAB2_LIB.BASEBOARD_FAB2(SCH_1):PAGE255
CR25W2    2    AC1 DIODEAC_DUAL_ARRAY_SM9-ESD3V3UA   I131 @BASEBOARD_FAB2_LIB.BASEBOARD_FAB2(SCH_1):PAGE255
CR25W2    8   OUT1 DIODEAC_DUAL_ARRAY_SM9-ESD3V3UA   I131 @BASEBOARD_FAB2_LIB.BASEBOARD_FAB2(SCH_1):PAGE255
 J25W1   12     12 SMC-CON13-GP_CONN-GC2-SMC-CON1A   I136 @BASEBOARD_FAB2_LIB.BASEBOARD_FAB2(SCH_1):PAGE255

V_IBMC_5V_DDC_SDA_J @BASEBOARD_FAB2_LIB.BASEBOARD_FAB2(SCH_1):V_IBMC_5V_DDC_SDA_J
R25W136    2      B RES_0402-33.2,1%,1/16W,CHIP,G2A    I38 @BASEBOARD_FAB2_LIB.BASEBOARD_FAB2(SCH_1):PAGE255
C25W79    1      A CAP_0402LF-100.0PF,50V,5%,COG,A    I39 @BASEBOARD_FAB2_LIB.BASEBOARD_FAB2(SCH_1):PAGE255
CR25W2    1    AC0 DIODEAC_DUAL_ARRAY_SM9-ESD3V3UA   I131 @BASEBOARD_FAB2_LIB.BASEBOARD_FAB2(SCH_1):PAGE255
CR25W2    9   OUT0 DIODEAC_DUAL_ARRAY_SM9-ESD3V3UA   I131 @BASEBOARD_FAB2_LIB.BASEBOARD_FAB2(SCH_1):PAGE255
 J25W1   11     11 SMC-CON13-GP_CONN-GC2-SMC-CON1A   I136 @BASEBOARD_FAB2_LIB.BASEBOARD_FAB2(SCH_1):PAGE255

V_IO_B_J @BASEBOARD_FAB2_LIB.BASEBOARD_FAB2(SCH_1):V_IO_B_J
C25W75    1      A CAP_0402LF-12.0PF,50V,5%,COG,AA    I21 @BASEBOARD_FAB2_LIB.BASEBOARD_FAB2(SCH_1):PAGE255
R25W126    1      A RES_0402-150.0,1%,1/16W,CHIP,GA    I26 @BASEBOARD_FAB2_LIB.BASEBOARD_FAB2(SCH_1):PAGE255
 L25W1    2      2 IND-68NH-15-GP_DISCRET-GC1-INDA    I76 @BASEBOARD_FAB2_LIB.BASEBOARD_FAB2(SCH_1):PAGE255
CR25W1    1    AC0 DIODEAC_DUAL_ARRAY_SM9-ESD3V3UA   I129 @BASEBOARD_FAB2_LIB.BASEBOARD_FAB2(SCH_1):PAGE255
CR25W1    9   OUT0 DIODEAC_DUAL_ARRAY_SM9-ESD3V3UA   I129 @BASEBOARD_FAB2_LIB.BASEBOARD_FAB2(SCH_1):PAGE255
 J25W1    5      5 SMC-CON13-GP_CONN-GC2-SMC-CON1A   I136 @BASEBOARD_FAB2_LIB.BASEBOARD_FAB2(SCH_1):PAGE255

V_IO_G_J @BASEBOARD_FAB2_LIB.BASEBOARD_FAB2(SCH_1):V_IO_G_J
C25W76    1      A CAP_0402LF-12.0PF,50V,5%,COG,AA    I18 @BASEBOARD_FAB2_LIB.BASEBOARD_FAB2(SCH_1):PAGE255
R25W127    1      A RES_0402-150.0,1%,1/16W,CHIP,GA    I24 @BASEBOARD_FAB2_LIB.BASEBOARD_FAB2(SCH_1):PAGE255
 L25W2    2      2 IND-68NH-15-GP_DISCRET-GC1-INDA    I77 @BASEBOARD_FAB2_LIB.BASEBOARD_FAB2(SCH_1):PAGE255
CR25W1    2    AC1 DIODEAC_DUAL_ARRAY_SM9-ESD3V3UA   I129 @BASEBOARD_FAB2_LIB.BASEBOARD_FAB2(SCH_1):PAGE255
CR25W1    8   OUT1 DIODEAC_DUAL_ARRAY_SM9-ESD3V3UA   I129 @BASEBOARD_FAB2_LIB.BASEBOARD_FAB2(SCH_1):PAGE255
 J25W1    3      3 SMC-CON13-GP_CONN-GC2-SMC-CON1A   I136 @BASEBOARD_FAB2_LIB.BASEBOARD_FAB2(SCH_1):PAGE255

V_IO_HSYNC_J @BASEBOARD_FAB2_LIB.BASEBOARD_FAB2(SCH_1):V_IO_HSYNC_J
R25W138    2      B RES_0402-33.2,1%,1/16W,CHIP,G2A    I49 @BASEBOARD_FAB2_LIB.BASEBOARD_FAB2(SCH_1):PAGE255
C25W81    1      A CAP_0402LF-10.0PF,50V,5%,COG,AA    I60 @BASEBOARD_FAB2_LIB.BASEBOARD_FAB2(SCH_1):PAGE255
CR25W2    5    AC3 DIODEAC_DUAL_ARRAY_SM9-ESD3V3UA   I131 @BASEBOARD_FAB2_LIB.BASEBOARD_FAB2(SCH_1):PAGE255
CR25W2    6   OUT3 DIODEAC_DUAL_ARRAY_SM9-ESD3V3UA   I131 @BASEBOARD_FAB2_LIB.BASEBOARD_FAB2(SCH_1):PAGE255
 J25W1    9      9 SMC-CON13-GP_CONN-GC2-SMC-CON1A   I136 @BASEBOARD_FAB2_LIB.BASEBOARD_FAB2(SCH_1):PAGE255

V_IO_R_J @BASEBOARD_FAB2_LIB.BASEBOARD_FAB2(SCH_1):V_IO_R_J
C25W77    1      A CAP_0402LF-12.0PF,50V,5%,COG,AA    I16 @BASEBOARD_FAB2_LIB.BASEBOARD_FAB2(SCH_1):PAGE255
R25W128    1      A RES_0402-150.0,1%,1/16W,CHIP,GA    I22 @BASEBOARD_FAB2_LIB.BASEBOARD_FAB2(SCH_1):PAGE255
 L25W3    2      2 IND-68NH-15-GP_DISCRET-GC1-INDA    I78 @BASEBOARD_FAB2_LIB.BASEBOARD_FAB2(SCH_1):PAGE255
CR25W1    4    AC2 DIODEAC_DUAL_ARRAY_SM9-ESD3V3UA   I129 @BASEBOARD_FAB2_LIB.BASEBOARD_FAB2(SCH_1):PAGE255
CR25W1    7   OUT2 DIODEAC_DUAL_ARRAY_SM9-ESD3V3UA   I129 @BASEBOARD_FAB2_LIB.BASEBOARD_FAB2(SCH_1):PAGE255
 J25W1    1      1 SMC-CON13-GP_CONN-GC2-SMC-CON1A   I136 @BASEBOARD_FAB2_LIB.BASEBOARD_FAB2(SCH_1):PAGE255

V_IO_VSYNC_J @BASEBOARD_FAB2_LIB.BASEBOARD_FAB2(SCH_1):V_IO_VSYNC_J
R25W139    2      B RES_0402-33.2,1%,1/16W,CHIP,G2A    I59 @BASEBOARD_FAB2_LIB.BASEBOARD_FAB2(SCH_1):PAGE255
C25W82    1      A CAP_0402LF-10.0PF,50V,5%,COG,AA    I62 @BASEBOARD_FAB2_LIB.BASEBOARD_FAB2(SCH_1):PAGE255
CR25W2    4    AC2 DIODEAC_DUAL_ARRAY_SM9-ESD3V3UA   I131 @BASEBOARD_FAB2_LIB.BASEBOARD_FAB2(SCH_1):PAGE255
CR25W2    7   OUT2 DIODEAC_DUAL_ARRAY_SM9-ESD3V3UA   I131 @BASEBOARD_FAB2_LIB.BASEBOARD_FAB2(SCH_1):PAGE255
 J25W1    7      7 SMC-CON13-GP_CONN-GC2-SMC-CON1A   I136 @BASEBOARD_FAB2_LIB.BASEBOARD_FAB2(SCH_1):PAGE255

XDP_CPU0_TDO @BASEBOARD_FAB2_LIB.BASEBOARD_FAB2(SCH_1):XDP_CPU0_TDO
  U5D1 AE14    TDO SKX_EXT_B_BGA1-IC,TBD   I259 @BASEBOARD_FAB2_LIB.BASEBOARD_FAB2(SCH_1):PAGE21
  U1M7    1     B1 NC7SB3157_SMLF-IC,C99406-001    I40 @BASEBOARD_FAB2_LIB.BASEBOARD_FAB2(SCH_1):PAGE112
 R4P23    2      B RES_0402-150.0,1%,1/16W,CHIP,GA    I58 @BASEBOARD_FAB2_LIB.BASEBOARD_FAB2(SCH_1):PAGE112
  U1M4    2      A 74CBTLV1G125_SMLF-IC,C88177-00A   I127 @BASEBOARD_FAB2_LIB.BASEBOARD_FAB2(SCH_1):PAGE112

XDP_CPU1_TDI @BASEBOARD_FAB2_LIB.BASEBOARD_FAB2(SCH_1):XDP_CPU1_TDI
  U2D1 AC14    TDI SKX_EXT_B_BGA1-IC,TBD   I172 @BASEBOARD_FAB2_LIB.BASEBOARD_FAB2(SCH_1):PAGE55
  R6T6    2      B RES_0402-150.0,1%,1/16W,CHIP,GA    I56 @BASEBOARD_FAB2_LIB.BASEBOARD_FAB2(SCH_1):PAGE112
  U1M4    4      B 74CBTLV1G125_SMLF-IC,C88177-00A   I127 @BASEBOARD_FAB2_LIB.BASEBOARD_FAB2(SCH_1):PAGE112

XDP_CPU1_TDO @BASEBOARD_FAB2_LIB.BASEBOARD_FAB2(SCH_1):XDP_CPU1_TDO
  U2D1 AE14    TDO SKX_EXT_B_BGA1-IC,TBD   I172 @BASEBOARD_FAB2_LIB.BASEBOARD_FAB2(SCH_1):PAGE55
  U1M7    3     B0 NC7SB3157_SMLF-IC,C99406-001    I40 @BASEBOARD_FAB2_LIB.BASEBOARD_FAB2(SCH_1):PAGE112
  R6T7    2      B RES_0402-150.0,1%,1/16W,CHIP,GA    I55 @BASEBOARD_FAB2_LIB.BASEBOARD_FAB2(SCH_1):PAGE112

XDP_CPU_GTL_TCK_R2 @BASEBOARD_FAB2_LIB.BASEBOARD_FAB2(SCH_1):XDP_CPU_GTL_TCK_R2
  R9A2    2      B RES_0402-33.2,1%,1/16W,EMPTY,GA    I83 @BASEBOARD_FAB2_LIB.BASEBOARD_FAB2(SCH_1):PAGE111
  Q9A1    1   E<0> NPN_DUAL_SSOPLF-MBT3904,EMPTY,A    I93 @BASEBOARD_FAB2_LIB.BASEBOARD_FAB2(SCH_1):PAGE111

XDP_CPU_MBP0_N @BASEBOARD_FAB2_LIB.BASEBOARD_FAB2(SCH_1):XDP_CPU_MBP0_N
  U5D1 AJ10 BPM_N<0> SKX_EXT_B_BGA1-IC,TBD   I259 @BASEBOARD_FAB2_LIB.BASEBOARD_FAB2(SCH_1):PAGE21
  U2D1 AJ10 BPM_N<0> SKX_EXT_B_BGA1-IC,TBD   I172 @BASEBOARD_FAB2_LIB.BASEBOARD_FAB2(SCH_1):PAGE55
 R7P30    2      B RES_0402-100.0,1%,1/16W,CHIP,GA    I50 @BASEBOARD_FAB2_LIB.BASEBOARD_FAB2(SCH_1):PAGE112
 R4P12    2      B RES_0402-100.0,1%,1/16W,CHIP,GA    I57 @BASEBOARD_FAB2_LIB.BASEBOARD_FAB2(SCH_1):PAGE112

XDP_CPU_MBP1_N @BASEBOARD_FAB2_LIB.BASEBOARD_FAB2(SCH_1):XDP_CPU_MBP1_N
  U5D1 AH11 BPM_N<1> SKX_EXT_B_BGA1-IC,TBD   I259 @BASEBOARD_FAB2_LIB.BASEBOARD_FAB2(SCH_1):PAGE21
  U2D1 AH11 BPM_N<1> SKX_EXT_B_BGA1-IC,TBD   I172 @BASEBOARD_FAB2_LIB.BASEBOARD_FAB2(SCH_1):PAGE55
 R6P46    2      B RES_0402-100.0,1%,1/16W,CHIP,GA    I49 @BASEBOARD_FAB2_LIB.BASEBOARD_FAB2(SCH_1):PAGE112
 R4P15    2      B RES_0402-100.0,1%,1/16W,CHIP,GA    I53 @BASEBOARD_FAB2_LIB.BASEBOARD_FAB2(SCH_1):PAGE112

XDP_CPU_OBSFN_B0_MBP6_N @BASEBOARD_FAB2_LIB.BASEBOARD_FAB2(SCH_1):XDP_CPU_OBSFN_B0_MBP6_N
  U5D1 AE12 BPM_N<6> SKX_EXT_B_BGA1-IC,TBD   I259 @BASEBOARD_FAB2_LIB.BASEBOARD_FAB2(SCH_1):PAGE21
  U2D1 AE12 BPM_N<6> SKX_EXT_B_BGA1-IC,TBD   I172 @BASEBOARD_FAB2_LIB.BASEBOARD_FAB2(SCH_1):PAGE55
  U1L5    6   B<2> TTL3126_QFNLF-74CBTLV3126,IC,DB   I109 @BASEBOARD_FAB2_LIB.BASEBOARD_FAB2(SCH_1):PAGE112
  R6T8    2      B RES_0402-100.0,1%,1/16W,CHIP,GA   I121 @BASEBOARD_FAB2_LIB.BASEBOARD_FAB2(SCH_1):PAGE112

XDP_CPU_OBSFN_B1_MBP7_N @BASEBOARD_FAB2_LIB.BASEBOARD_FAB2(SCH_1):XDP_CPU_OBSFN_B1_MBP7_N
  U5D1 AC12 BPM_N<7> SKX_EXT_B_BGA1-IC,TBD   I259 @BASEBOARD_FAB2_LIB.BASEBOARD_FAB2(SCH_1):PAGE21
  U2D1 AC12 BPM_N<7> SKX_EXT_B_BGA1-IC,TBD   I172 @BASEBOARD_FAB2_LIB.BASEBOARD_FAB2(SCH_1):PAGE55
  U1L5    3   B<3> TTL3126_QFNLF-74CBTLV3126,IC,DB   I109 @BASEBOARD_FAB2_LIB.BASEBOARD_FAB2(SCH_1):PAGE112
  R6T9    2      B RES_0402-100.0,1%,1/16W,CHIP,GA   I120 @BASEBOARD_FAB2_LIB.BASEBOARD_FAB2(SCH_1):PAGE112

XDP_CPU_PRDY_N @BASEBOARD_FAB2_LIB.BASEBOARD_FAB2(SCH_1):XDP_CPU_PRDY_N
  U5D1 AG16 PRDY_N SKX_EXT_B_BGA1-IC,TBD   I259 @BASEBOARD_FAB2_LIB.BASEBOARD_FAB2(SCH_1):PAGE21
  U2D1 AG16 PRDY_N SKX_EXT_B_BGA1-IC,TBD   I172 @BASEBOARD_FAB2_LIB.BASEBOARD_FAB2(SCH_1):PAGE55
  R1M3    2      B RES_0402-100.0,1%,1/16W,CHIP,GA    I51 @BASEBOARD_FAB2_LIB.BASEBOARD_FAB2(SCH_1):PAGE112
  U1L5    8   B<1> TTL3126_QFNLF-74CBTLV3126,IC,DB   I109 @BASEBOARD_FAB2_LIB.BASEBOARD_FAB2(SCH_1):PAGE112

XDP_CPU_PREQ_N @BASEBOARD_FAB2_LIB.BASEBOARD_FAB2(SCH_1):XDP_CPU_PREQ_N
  U5D1 AR12 PREQ_N SKX_EXT_B_BGA1-IC,TBD   I259 @BASEBOARD_FAB2_LIB.BASEBOARD_FAB2(SCH_1):PAGE21
  U2D1 AR12 PREQ_N SKX_EXT_B_BGA1-IC,TBD   I172 @BASEBOARD_FAB2_LIB.BASEBOARD_FAB2(SCH_1):PAGE55
  R1M4    2      B RES_0402-100.0,1%,1/16W,CHIP,GA    I54 @BASEBOARD_FAB2_LIB.BASEBOARD_FAB2(SCH_1):PAGE112
  U1L5   11   B<0> TTL3126_QFNLF-74CBTLV3126,IC,DB   I109 @BASEBOARD_FAB2_LIB.BASEBOARD_FAB2(SCH_1):PAGE112

XDP_CPU_PWR_DEBUG_N @BASEBOARD_FAB2_LIB.BASEBOARD_FAB2(SCH_1):XDP_CPU_PWR_DEBUG_N
  U5D1 AP17 PWR_DEBUG_N SKX_EXT_B_BGA1-IC,TBD   I204 @BASEBOARD_FAB2_LIB.BASEBOARD_FAB2(SCH_1):PAGE22
  U2D1 AP17 PWR_DEBUG_N SKX_EXT_B_BGA1-IC,TBD   I169 @BASEBOARD_FAB2_LIB.BASEBOARD_FAB2(SCH_1):PAGE56
  J9A3   45   IO45 SCONN60_C21100002_SMLF-CONN,C2A    I26 @BASEBOARD_FAB2_LIB.BASEBOARD_FAB2(SCH_1):PAGE111
 R1L17    1      A RES_0402-150.0,1%,1/16W,CHIP,GA    I56 @BASEBOARD_FAB2_LIB.BASEBOARD_FAB2(SCH_1):PAGE111
  C9A4    1      A CAP_A_0402V-0.1UF,16V,10%,X7R,A    I59 @BASEBOARD_FAB2_LIB.BASEBOARD_FAB2(SCH_1):PAGE111
  U7D1    4      B 74CBTLV1G125_SMLF-IC,C88177-00A   I142 @BASEBOARD_FAB2_LIB.BASEBOARD_FAB2(SCH_1):PAGE118
U25W10    3     B1 GTL2014_SM-IC,D66151-001    I49 @BASEBOARD_FAB2_LIB.BASEBOARD_FAB2(SCH_1):PAGE269

XDP_CPU_TCK0 @BASEBOARD_FAB2_LIB.BASEBOARD_FAB2(SCH_1):XDP_CPU_TCK0
  U5D1 AA14    TCK SKX_EXT_B_BGA1-IC,TBD   I259 @BASEBOARD_FAB2_LIB.BASEBOARD_FAB2(SCH_1):PAGE21
  U2D1 AA14    TCK SKX_EXT_B_BGA1-IC,TBD   I172 @BASEBOARD_FAB2_LIB.BASEBOARD_FAB2(SCH_1):PAGE55
  J9A3   57   IO57 SCONN60_C21100002_SMLF-CONN,C2A    I26 @BASEBOARD_FAB2_LIB.BASEBOARD_FAB2(SCH_1):PAGE111
  R9A3    2      B RES_0402-0.0,5%,1/16W,CHIP,G21A    I74 @BASEBOARD_FAB2_LIB.BASEBOARD_FAB2(SCH_1):PAGE111
  Q9A1    4   E<0> NPN_DUAL_SSOPLF-MBT3904,EMPTY,A    I94 @BASEBOARD_FAB2_LIB.BASEBOARD_FAB2(SCH_1):PAGE111
 R7P29    1      A RES_0402-51.1,1.0%,1/16W,CHIP,A    I61 @BASEBOARD_FAB2_LIB.BASEBOARD_FAB2(SCH_1):PAGE112
FB25W1    2      2 BLM15AG121SN-1GP_DISCRET-G-BLMA    I71 @BASEBOARD_FAB2_LIB.BASEBOARD_FAB2(SCH_1):PAGE269

XDP_CPU_TCK0_R @BASEBOARD_FAB2_LIB.BASEBOARD_FAB2(SCH_1):XDP_CPU_TCK0_R
U25W12    6   B<2> TTL3126_QFNLF-74CBTLV3126,IC,DB    I33 @BASEBOARD_FAB2_LIB.BASEBOARD_FAB2(SCH_1):PAGE269
FB25W1    1      1 BLM15AG121SN-1GP_DISCRET-G-BLMA    I71 @BASEBOARD_FAB2_LIB.BASEBOARD_FAB2(SCH_1):PAGE269

XDP_CPU_TCK_BUF @BASEBOARD_FAB2_LIB.BASEBOARD_FAB2(SCH_1):XDP_CPU_TCK_BUF
  Q9A1    2   B<0> NPN_DUAL_SSOPLF-MBT3904,EMPTY,A    I93 @BASEBOARD_FAB2_LIB.BASEBOARD_FAB2(SCH_1):PAGE111
  Q9A1    6   C<0> NPN_DUAL_SSOPLF-MBT3904,EMPTY,A    I93 @BASEBOARD_FAB2_LIB.BASEBOARD_FAB2(SCH_1):PAGE111
  Q9A1    5   B<0> NPN_DUAL_SSOPLF-MBT3904,EMPTY,A    I94 @BASEBOARD_FAB2_LIB.BASEBOARD_FAB2(SCH_1):PAGE111
  R9A1    2      B RES_0402-1.00K,1%,1/16W,EMPTY,A    I95 @BASEBOARD_FAB2_LIB.BASEBOARD_FAB2(SCH_1):PAGE111

XDP_CPU_TDI @BASEBOARD_FAB2_LIB.BASEBOARD_FAB2(SCH_1):XDP_CPU_TDI
  U5D1 AC14    TDI SKX_EXT_B_BGA1-IC,TBD   I259 @BASEBOARD_FAB2_LIB.BASEBOARD_FAB2(SCH_1):PAGE21
 R4P24    2      B RES_0402-150.0,1%,1/16W,CHIP,GA    I59 @BASEBOARD_FAB2_LIB.BASEBOARD_FAB2(SCH_1):PAGE112
  U1L1   11   B<0> TTL3126_QFNLF-74CBTLV3126,IC,DB   I108 @BASEBOARD_FAB2_LIB.BASEBOARD_FAB2(SCH_1):PAGE112

XDP_CPU_TDO @BASEBOARD_FAB2_LIB.BASEBOARD_FAB2(SCH_1):XDP_CPU_TDO
  U1M7    4      A NC7SB3157_SMLF-IC,C99406-001    I40 @BASEBOARD_FAB2_LIB.BASEBOARD_FAB2(SCH_1):PAGE112
  U1L1    8   B<1> TTL3126_QFNLF-74CBTLV3126,IC,DB   I108 @BASEBOARD_FAB2_LIB.BASEBOARD_FAB2(SCH_1):PAGE112

XDP_CPU_TMS @BASEBOARD_FAB2_LIB.BASEBOARD_FAB2(SCH_1):XDP_CPU_TMS
  U5D1  W14    TMS SKX_EXT_B_BGA1-IC,TBD   I259 @BASEBOARD_FAB2_LIB.BASEBOARD_FAB2(SCH_1):PAGE21
  U2D1  W14    TMS SKX_EXT_B_BGA1-IC,TBD   I172 @BASEBOARD_FAB2_LIB.BASEBOARD_FAB2(SCH_1):PAGE55
 R1L15    2      B RES_0402-150.0,1%,1/16W,CHIP,GA    I60 @BASEBOARD_FAB2_LIB.BASEBOARD_FAB2(SCH_1):PAGE112
  U1L1    6   B<2> TTL3126_QFNLF-74CBTLV3126,IC,DB   I108 @BASEBOARD_FAB2_LIB.BASEBOARD_FAB2(SCH_1):PAGE112

XDP_CPU_TRST_N @BASEBOARD_FAB2_LIB.BASEBOARD_FAB2(SCH_1):XDP_CPU_TRST_N
  U5D1  Y13 TRST_N SKX_EXT_B_BGA1-IC,TBD   I259 @BASEBOARD_FAB2_LIB.BASEBOARD_FAB2(SCH_1):PAGE21
  U2D1  Y13 TRST_N SKX_EXT_B_BGA1-IC,TBD   I172 @BASEBOARD_FAB2_LIB.BASEBOARD_FAB2(SCH_1):PAGE55
  R6T5    1      A RES_0402-1.00K,1%,1/16W,CHIP,GA    I62 @BASEBOARD_FAB2_LIB.BASEBOARD_FAB2(SCH_1):PAGE112
  U1L1    3   B<3> TTL3126_QFNLF-74CBTLV3126,IC,DB   I108 @BASEBOARD_FAB2_LIB.BASEBOARD_FAB2(SCH_1):PAGE112

XDP_DEBUG_CONSENT_N @BASEBOARD_FAB2_LIB.BASEBOARD_FAB2(SCH_1):XDP_DEBUG_CONSENT_N
  J9A3    1    IO1 SCONN60_C21100002_SMLF-CONN,C2A    I26 @BASEBOARD_FAB2_LIB.BASEBOARD_FAB2(SCH_1):PAGE111
  R2P2    2      B RES_0402-1.00K,1%,1/16W,CHIP,GA    I37 @BASEBOARD_FAB2_LIB.BASEBOARD_FAB2(SCH_1):PAGE111

XDP_ITP_PMODE @BASEBOARD_FAB2_LIB.BASEBOARD_FAB2(SCH_1):XDP_ITP_PMODE
  J9A3   46   IO46 SCONN60_C21100002_SMLF-CONN,C2A    I26 @BASEBOARD_FAB2_LIB.BASEBOARD_FAB2(SCH_1):PAGE111
 R9A17    1      A RES_0402-1.00K,1%,1/16W,CHIP,GA    I57 @BASEBOARD_FAB2_LIB.BASEBOARD_FAB2(SCH_1):PAGE111
  U7C1 AR54 ITP_PMODE LBG_CORE_QAT_EXT_D_BGA1-IC,H91A    I73 @BASEBOARD_FAB2_LIB.BASEBOARD_FAB2(SCH_1):PAGE118

XDP_OBSFN_B0_MBP6_N @BASEBOARD_FAB2_LIB.BASEBOARD_FAB2(SCH_1):XDP_OBSFN_B0_MBP6_N
  J9A3   22   IO22 SCONN60_C21100002_SMLF-CONN,C2A    I26 @BASEBOARD_FAB2_LIB.BASEBOARD_FAB2(SCH_1):PAGE111
  U1L5    5   A<2> TTL3126_QFNLF-74CBTLV3126,IC,DB   I109 @BASEBOARD_FAB2_LIB.BASEBOARD_FAB2(SCH_1):PAGE112

XDP_OBSFN_B1_MBP7_N @BASEBOARD_FAB2_LIB.BASEBOARD_FAB2(SCH_1):XDP_OBSFN_B1_MBP7_N
  J9A3   24   IO24 SCONN60_C21100002_SMLF-CONN,C2A    I26 @BASEBOARD_FAB2_LIB.BASEBOARD_FAB2(SCH_1):PAGE111
  U1L5    2   A<3> TTL3126_QFNLF-74CBTLV3126,IC,DB   I109 @BASEBOARD_FAB2_LIB.BASEBOARD_FAB2(SCH_1):PAGE112

XDP_PCH_CPU_TCK0 @BASEBOARD_FAB2_LIB.BASEBOARD_FAB2(SCH_1):XDP_PCH_CPU_TCK0
  R9A3    1      A RES_0402-0.0,5%,1/16W,CHIP,G21A    I74 @BASEBOARD_FAB2_LIB.BASEBOARD_FAB2(SCH_1):PAGE111
  R9A2    1      A RES_0402-33.2,1%,1/16W,EMPTY,GA    I83 @BASEBOARD_FAB2_LIB.BASEBOARD_FAB2(SCH_1):PAGE111
 R3M10    1      A RES_0402-1.00K,1%,1/16W,CHIP,GA    I85 @BASEBOARD_FAB2_LIB.BASEBOARD_FAB2(SCH_1):PAGE112
  U7C1 AF54  JTAGX LBG_CORE_QAT_EXT_D_BGA1-IC,H91A    I73 @BASEBOARD_FAB2_LIB.BASEBOARD_FAB2(SCH_1):PAGE118

XDP_PCH_PWR_DEBUG_N @BASEBOARD_FAB2_LIB.BASEBOARD_FAB2(SCH_1):XDP_PCH_PWR_DEBUG_N
  U7C1  G15   GPD0 LBG_CORE_QAT_EXT_D_BGA1-IC,H91A    I73 @BASEBOARD_FAB2_LIB.BASEBOARD_FAB2(SCH_1):PAGE118
  U7D1    2      A 74CBTLV1G125_SMLF-IC,C88177-00A   I142 @BASEBOARD_FAB2_LIB.BASEBOARD_FAB2(SCH_1):PAGE118
 R7C23    2      B RES_0402-10.0K,1%,1/16W,CHIP,GA   I144 @BASEBOARD_FAB2_LIB.BASEBOARD_FAB2(SCH_1):PAGE118

XDP_PCH_TCK1 @BASEBOARD_FAB2_LIB.BASEBOARD_FAB2(SCH_1):XDP_PCH_TCK1
  J9A3   55   IO55 SCONN60_C21100002_SMLF-CONN,C2A    I26 @BASEBOARD_FAB2_LIB.BASEBOARD_FAB2(SCH_1):PAGE111
  R8B1    1      A RES_0402-51.1,1.0%,1/16W,CHIP,A    I95 @BASEBOARD_FAB2_LIB.BASEBOARD_FAB2(SCH_1):PAGE112
  U7C1 AL56 JTAG_TCK LBG_CORE_QAT_EXT_D_BGA1-IC,H91A    I73 @BASEBOARD_FAB2_LIB.BASEBOARD_FAB2(SCH_1):PAGE118
FB25W2    2      2 BLM15AG121SN-1GP_DISCRET-G-BLMA    I72 @BASEBOARD_FAB2_LIB.BASEBOARD_FAB2(SCH_1):PAGE269

XDP_PCH_TCK1_R @BASEBOARD_FAB2_LIB.BASEBOARD_FAB2(SCH_1):XDP_PCH_TCK1_R
U25W12    8   B<1> TTL3126_QFNLF-74CBTLV3126,IC,DB    I33 @BASEBOARD_FAB2_LIB.BASEBOARD_FAB2(SCH_1):PAGE269
FB25W2    1      1 BLM15AG121SN-1GP_DISCRET-G-BLMA    I72 @BASEBOARD_FAB2_LIB.BASEBOARD_FAB2(SCH_1):PAGE269

XDP_PRDY_N @BASEBOARD_FAB2_LIB.BASEBOARD_FAB2(SCH_1):XDP_PRDY_N
  J9A3    5    IO5 SCONN60_C21100002_SMLF-CONN,C2A    I26 @BASEBOARD_FAB2_LIB.BASEBOARD_FAB2(SCH_1):PAGE111
 R1L39    2      B RES_0402-100.0,1%,1/16W,CHIP,GA    I76 @BASEBOARD_FAB2_LIB.BASEBOARD_FAB2(SCH_1):PAGE112
  U1L5    9   A<1> TTL3126_QFNLF-74CBTLV3126,IC,DB   I109 @BASEBOARD_FAB2_LIB.BASEBOARD_FAB2(SCH_1):PAGE112
  U7C1 AD54 PRDY_N LBG_CORE_QAT_EXT_D_BGA1-IC,H91A    I73 @BASEBOARD_FAB2_LIB.BASEBOARD_FAB2(SCH_1):PAGE118
U25W11    3     B1 GTL2014_SM-IC,D66151-001    I33 @BASEBOARD_FAB2_LIB.BASEBOARD_FAB2(SCH_1):PAGE268

XDP_PREQ_N @BASEBOARD_FAB2_LIB.BASEBOARD_FAB2(SCH_1):XDP_PREQ_N
  J9A3    3    IO3 SCONN60_C21100002_SMLF-CONN,C2A    I26 @BASEBOARD_FAB2_LIB.BASEBOARD_FAB2(SCH_1):PAGE111
 R1L41    2      B RES_0402-100.0,1%,1/16W,CHIP,GA    I77 @BASEBOARD_FAB2_LIB.BASEBOARD_FAB2(SCH_1):PAGE112
  U1L5   12   A<0> TTL3126_QFNLF-74CBTLV3126,IC,DB   I109 @BASEBOARD_FAB2_LIB.BASEBOARD_FAB2(SCH_1):PAGE112
  U7C1  U54 PREQ_N LBG_CORE_QAT_EXT_D_BGA1-IC,H91A    I73 @BASEBOARD_FAB2_LIB.BASEBOARD_FAB2(SCH_1):PAGE118
U25W10    2     B0 GTL2014_SM-IC,D66151-001    I49 @BASEBOARD_FAB2_LIB.BASEBOARD_FAB2(SCH_1):PAGE269

XDP_PRESENT_N @BASEBOARD_FAB2_LIB.BASEBOARD_FAB2(SCH_1):XDP_PRESENT_N
  J9A3   60   IO60 SCONN60_C21100002_SMLF-CONN,C2A    I26 @BASEBOARD_FAB2_LIB.BASEBOARD_FAB2(SCH_1):PAGE111
 U25W4  W19 GPIOR4_SPI2MOSI AST2520A1-GP-GP_ASIC2-GB1-AST2A   I105 @BASEBOARD_FAB2_LIB.BASEBOARD_FAB2(SCH_1):PAGE146
R25W179    2      B RES_0402-1.00K,1%,1/16W,CHIP,GA     I7 @BASEBOARD_FAB2_LIB.BASEBOARD_FAB2(SCH_1):PAGE268
U25W14    2      A TTL1G07_A_SOP-74LVC1G07,IC,C88B    I13 @BASEBOARD_FAB2_LIB.BASEBOARD_FAB2(SCH_1):PAGE268
U25W18    1   A<0> TTL1G08_SOTLF-NC7SZ08,IC,D1032B    I57 @BASEBOARD_FAB2_LIB.BASEBOARD_FAB2(SCH_1):PAGE268

XDP_PWRGD_RST_N @BASEBOARD_FAB2_LIB.BASEBOARD_FAB2(SCH_1):XDP_PWRGD_RST_N
 R1L23    1      A RES_0402-1.00K,1%,1/16W,CHIP,GA    I13 @BASEBOARD_FAB2_LIB.BASEBOARD_FAB2(SCH_1):PAGE111
  C1L8    1      A CAP_A_0402V-0.1UF,16V,10%,X7R,A    I14 @BASEBOARD_FAB2_LIB.BASEBOARD_FAB2(SCH_1):PAGE111
  J9A3   41   IO41 SCONN60_C21100002_SMLF-CONN,C2A    I26 @BASEBOARD_FAB2_LIB.BASEBOARD_FAB2(SCH_1):PAGE111
  U8D7  M11  PB19D LCMXO2_A_256BGA-IC,H63395-001   I179 @BASEBOARD_FAB2_LIB.BASEBOARD_FAB2(SCH_1):PAGE190

XDP_RSMRST_N @BASEBOARD_FAB2_LIB.BASEBOARD_FAB2(SCH_1):XDP_RSMRST_N
  J9A3   39   IO39 SCONN60_C21100002_SMLF-CONN,C2A    I26 @BASEBOARD_FAB2_LIB.BASEBOARD_FAB2(SCH_1):PAGE111
 R9A15    2      B RES_0402-1.00K,1%,1/16W,CHIP,GA    I60 @BASEBOARD_FAB2_LIB.BASEBOARD_FAB2(SCH_1):PAGE111

XDP_RST_CO_N @BASEBOARD_FAB2_LIB.BASEBOARD_FAB2(SCH_1):XDP_RST_CO_N
 R9A14    1      A RES_0402-1.00K,1%,1/16W,CHIP,GA    I11 @BASEBOARD_FAB2_LIB.BASEBOARD_FAB2(SCH_1):PAGE111
  C9A5    1      A CAP_A_0402V-0.1UF,16V,10%,X7R,A    I12 @BASEBOARD_FAB2_LIB.BASEBOARD_FAB2(SCH_1):PAGE111
  J9A3   48   IO48 SCONN60_C21100002_SMLF-CONN,C2A    I26 @BASEBOARD_FAB2_LIB.BASEBOARD_FAB2(SCH_1):PAGE111
  U1L4    2      A TTL1G07_A_SOP-74LVC1G07,IC,C88B    I85 @BASEBOARD_FAB2_LIB.BASEBOARD_FAB2(SCH_1):PAGE111

XDP_SPI_PCH_MOSI_BOOT_HALT_N @BASEBOARD_FAB2_LIB.BASEBOARD_FAB2(SCH_1):XDP_SPI_PCH_MOSI_BOOT_HALT_N
  J9A3    6    IO6 SCONN60_C21100002_SMLF-CONN,C2A    I26 @BASEBOARD_FAB2_LIB.BASEBOARD_FAB2(SCH_1):PAGE111
  R8E2    1      A RES_0402-1.00K,1%,1/16W,CHIP,GA    I89 @BASEBOARD_FAB2_LIB.BASEBOARD_FAB2(SCH_1):PAGE111

XDP_SYSPWROK @BASEBOARD_FAB2_LIB.BASEBOARD_FAB2(SCH_1):XDP_SYSPWROK
 R1L13    1      A RES_0402-1.00K,1%,1/16W,CHIP,GA     I6 @BASEBOARD_FAB2_LIB.BASEBOARD_FAB2(SCH_1):PAGE111
  C9A2    1      A CAP_A_0402V-0.1UF,16V,10%,X7R,A    I10 @BASEBOARD_FAB2_LIB.BASEBOARD_FAB2(SCH_1):PAGE111
  J9A3   47   IO47 SCONN60_C21100002_SMLF-CONN,C2A    I26 @BASEBOARD_FAB2_LIB.BASEBOARD_FAB2(SCH_1):PAGE111
  U8D7  N11  PB21D LCMXO2_A_256BGA-IC,H63395-001   I179 @BASEBOARD_FAB2_LIB.BASEBOARD_FAB2(SCH_1):PAGE190
R25W182    1      A RES_0402-0.0,5%,1/16W,CHIP,G21A   I151 @BASEBOARD_FAB2_LIB.BASEBOARD_FAB2(SCH_1):PAGE144

XDP_TDI @BASEBOARD_FAB2_LIB.BASEBOARD_FAB2(SCH_1):XDP_TDI
  J9A3   56   IO56 SCONN60_C21100002_SMLF-CONN,C2A    I26 @BASEBOARD_FAB2_LIB.BASEBOARD_FAB2(SCH_1):PAGE111
 R8A13    2      B RES_0402-150.0,1%,1/16W,CHIP,GA    I79 @BASEBOARD_FAB2_LIB.BASEBOARD_FAB2(SCH_1):PAGE112
  U1L1   12   A<0> TTL3126_QFNLF-74CBTLV3126,IC,DB   I108 @BASEBOARD_FAB2_LIB.BASEBOARD_FAB2(SCH_1):PAGE112
  U7C1 AN54 JTAG_TDI LBG_CORE_QAT_EXT_D_BGA1-IC,H91A    I73 @BASEBOARD_FAB2_LIB.BASEBOARD_FAB2(SCH_1):PAGE118
FB25W4    2      2 BLM15AG121SN-1GP_DISCRET-G-BLMA    I75 @BASEBOARD_FAB2_LIB.BASEBOARD_FAB2(SCH_1):PAGE269

XDP_TDI_R @BASEBOARD_FAB2_LIB.BASEBOARD_FAB2(SCH_1):XDP_TDI_R
U25W10    5     B2 GTL2014_SM-IC,D66151-001    I49 @BASEBOARD_FAB2_LIB.BASEBOARD_FAB2(SCH_1):PAGE269
FB25W4    1      1 BLM15AG121SN-1GP_DISCRET-G-BLMA    I75 @BASEBOARD_FAB2_LIB.BASEBOARD_FAB2(SCH_1):PAGE269

XDP_TDO @BASEBOARD_FAB2_LIB.BASEBOARD_FAB2(SCH_1):XDP_TDO
  J9A3   52   IO52 SCONN60_C21100002_SMLF-CONN,C2A    I26 @BASEBOARD_FAB2_LIB.BASEBOARD_FAB2(SCH_1):PAGE111
 R9A11    2      B RES_0402-150.0,1%,1/16W,CHIP,GA    I78 @BASEBOARD_FAB2_LIB.BASEBOARD_FAB2(SCH_1):PAGE112
  U1L1    9   A<1> TTL3126_QFNLF-74CBTLV3126,IC,DB   I108 @BASEBOARD_FAB2_LIB.BASEBOARD_FAB2(SCH_1):PAGE112
  U7C1 AP56 JTAG_TDO LBG_CORE_QAT_EXT_D_BGA1-IC,H91A    I73 @BASEBOARD_FAB2_LIB.BASEBOARD_FAB2(SCH_1):PAGE118
U25W11    6     B3 GTL2014_SM-IC,D66151-001    I33 @BASEBOARD_FAB2_LIB.BASEBOARD_FAB2(SCH_1):PAGE268

XDP_TMS @BASEBOARD_FAB2_LIB.BASEBOARD_FAB2(SCH_1):XDP_TMS
  J9A3   58   IO58 SCONN60_C21100002_SMLF-CONN,C2A    I26 @BASEBOARD_FAB2_LIB.BASEBOARD_FAB2(SCH_1):PAGE111
 R8A14    2      B RES_0402-150.0,1%,1/16W,CHIP,GA    I80 @BASEBOARD_FAB2_LIB.BASEBOARD_FAB2(SCH_1):PAGE112
  U1L1    5   A<2> TTL3126_QFNLF-74CBTLV3126,IC,DB   I108 @BASEBOARD_FAB2_LIB.BASEBOARD_FAB2(SCH_1):PAGE112
  U7C1 AH54 JTAG_TMS LBG_CORE_QAT_EXT_D_BGA1-IC,H91A    I73 @BASEBOARD_FAB2_LIB.BASEBOARD_FAB2(SCH_1):PAGE118
FB25W5    2      2 BLM15AG121SN-1GP_DISCRET-G-BLMA    I74 @BASEBOARD_FAB2_LIB.BASEBOARD_FAB2(SCH_1):PAGE269

XDP_TMS_R @BASEBOARD_FAB2_LIB.BASEBOARD_FAB2(SCH_1):XDP_TMS_R
U25W10    6     B3 GTL2014_SM-IC,D66151-001    I49 @BASEBOARD_FAB2_LIB.BASEBOARD_FAB2(SCH_1):PAGE269
FB25W5    1      1 BLM15AG121SN-1GP_DISCRET-G-BLMA    I74 @BASEBOARD_FAB2_LIB.BASEBOARD_FAB2(SCH_1):PAGE269

XDP_TRST_N @BASEBOARD_FAB2_LIB.BASEBOARD_FAB2(SCH_1):XDP_TRST_N
  J9A3   54   IO54 SCONN60_C21100002_SMLF-CONN,C2A    I26 @BASEBOARD_FAB2_LIB.BASEBOARD_FAB2(SCH_1):PAGE111
  R8B2    1      A RES_0402-1.00K,1%,1/16W,CHIP,GA    I94 @BASEBOARD_FAB2_LIB.BASEBOARD_FAB2(SCH_1):PAGE112
  U1L1    2   A<3> TTL3126_QFNLF-74CBTLV3126,IC,DB   I108 @BASEBOARD_FAB2_LIB.BASEBOARD_FAB2(SCH_1):PAGE112
  U7C1 AT56 CPU_TRST_N LBG_CORE_QAT_EXT_D_BGA1-IC,H91A    I73 @BASEBOARD_FAB2_LIB.BASEBOARD_FAB2(SCH_1):PAGE118
FB25W3    2      2 BLM15AG121SN-1GP_DISCRET-G-BLMA    I73 @BASEBOARD_FAB2_LIB.BASEBOARD_FAB2(SCH_1):PAGE269

XDP_TRST_R_N @BASEBOARD_FAB2_LIB.BASEBOARD_FAB2(SCH_1):XDP_TRST_R_N
U25W12   11   B<0> TTL3126_QFNLF-74CBTLV3126,IC,DB    I33 @BASEBOARD_FAB2_LIB.BASEBOARD_FAB2(SCH_1):PAGE269
FB25W3    1      1 BLM15AG121SN-1GP_DISCRET-G-BLMA    I73 @BASEBOARD_FAB2_LIB.BASEBOARD_FAB2(SCH_1):PAGE269

XTAL_25MHZ_IN @BASEBOARD_FAB2_LIB.BASEBOARD_FAB2(SCH_1):XTAL_25MHZ_IN
  Y9E1    1      A CRYSTAL_2013-25.000MHZ,IC,D717A   I109 @BASEBOARD_FAB2_LIB.BASEBOARD_FAB2(SCH_1):PAGE139
 R9E20    1      A RES_0402-0.0,5%,1/16W,CHIP,G21A   I110 @BASEBOARD_FAB2_LIB.BASEBOARD_FAB2(SCH_1):PAGE139
  C9E9    1      A CAP_0402LF-15.0PF,50V,5%,COG,AA   I249 @BASEBOARD_FAB2_LIB.BASEBOARD_FAB2(SCH_1):PAGE139

XTAL_25MHZ_IN_R @BASEBOARD_FAB2_LIB.BASEBOARD_FAB2(SCH_1):XTAL_25MHZ_IN_R
 EU9E1   46  XTAL1 SPRINGVILLE_SM1-IC,G47144-004    I72 @BASEBOARD_FAB2_LIB.BASEBOARD_FAB2(SCH_1):PAGE139
 R9E20    2      B RES_0402-0.0,5%,1/16W,CHIP,G21A   I110 @BASEBOARD_FAB2_LIB.BASEBOARD_FAB2(SCH_1):PAGE139

XTAL_25MHZ_OUT @BASEBOARD_FAB2_LIB.BASEBOARD_FAB2(SCH_1):XTAL_25MHZ_OUT
 EU9E1   45  XTAL2 SPRINGVILLE_SM1-IC,G47144-004    I72 @BASEBOARD_FAB2_LIB.BASEBOARD_FAB2(SCH_1):PAGE139
 R9E18    2      B RES_0402-0.0,5%,1/16W,CHIP,G21A   I201 @BASEBOARD_FAB2_LIB.BASEBOARD_FAB2(SCH_1):PAGE139

XTAL_25MHZ_OUT_R @BASEBOARD_FAB2_LIB.BASEBOARD_FAB2(SCH_1):XTAL_25MHZ_OUT_R
  Y9E1    3      B CRYSTAL_2013-25.000MHZ,IC,D717A   I109 @BASEBOARD_FAB2_LIB.BASEBOARD_FAB2(SCH_1):PAGE139
 R9E18    1      A RES_0402-0.0,5%,1/16W,CHIP,G21A   I201 @BASEBOARD_FAB2_LIB.BASEBOARD_FAB2(SCH_1):PAGE139
  C9E8    1      A CAP_0402LF-15.0PF,50V,5%,COG,AA   I250 @BASEBOARD_FAB2_LIB.BASEBOARD_FAB2(SCH_1):PAGE139

XTAL_33K_RTC1 @BASEBOARD_FAB2_LIB.BASEBOARD_FAB2(SCH_1):XTAL_33K_RTC1
  U7C1  K17  RTCX1 LBG_CORE_QAT_EXT_D_BGA1-IC,H91A    I40 @BASEBOARD_FAB2_LIB.BASEBOARD_FAB2(SCH_1):PAGE114
  R7C6    1      A RES_0603-10M,1.0%,1/10W,CHIP,GA    I54 @BASEBOARD_FAB2_LIB.BASEBOARD_FAB2(SCH_1):PAGE114
  Y7C2    1      A CRYSTAL_SM-32.768KHZ,IC,C13544A    I55 @BASEBOARD_FAB2_LIB.BASEBOARD_FAB2(SCH_1):PAGE114
 C7C13    1      A CAP_0402LF-15.0PF,50V,5%,COG,AA   I195 @BASEBOARD_FAB2_LIB.BASEBOARD_FAB2(SCH_1):PAGE114

XTAL_33K_RTC2 @BASEBOARD_FAB2_LIB.BASEBOARD_FAB2(SCH_1):XTAL_33K_RTC2
  U7C1  H17  RTCX2 LBG_CORE_QAT_EXT_D_BGA1-IC,H91A    I40 @BASEBOARD_FAB2_LIB.BASEBOARD_FAB2(SCH_1):PAGE114
  R7C6    2      B RES_0603-10M,1.0%,1/10W,CHIP,GA    I54 @BASEBOARD_FAB2_LIB.BASEBOARD_FAB2(SCH_1):PAGE114
  Y7C2    2      B CRYSTAL_SM-32.768KHZ,IC,C13544A    I55 @BASEBOARD_FAB2_LIB.BASEBOARD_FAB2(SCH_1):PAGE114
 C7C15    1      A CAP_0402LF-15.0PF,50V,5%,COG,AA   I196 @BASEBOARD_FAB2_LIB.BASEBOARD_FAB2(SCH_1):PAGE114

XTAL_CK_MNG_IN @BASEBOARD_FAB2_LIB.BASEBOARD_FAB2(SCH_1):XTAL_CK_MNG_IN
 EU8F2   19  X1_25 ICS9FGP204_MLFP-IC,E95226-001    I34 @BASEBOARD_FAB2_LIB.BASEBOARD_FAB2(SCH_1):PAGE101
  Y8F1    1      A CRYSTAL_2013LF-25.000MHZ,IC,D7B    I52 @BASEBOARD_FAB2_LIB.BASEBOARD_FAB2(SCH_1):PAGE101
 C8F18    1      A CAP_0402LF-15.0PF,50V,5%,COG,AA   I147 @BASEBOARD_FAB2_LIB.BASEBOARD_FAB2(SCH_1):PAGE101

XTAL_CK_MNG_OUT @BASEBOARD_FAB2_LIB.BASEBOARD_FAB2(SCH_1):XTAL_CK_MNG_OUT
  Y8F1    3      B CRYSTAL_2013LF-25.000MHZ,IC,D7B    I52 @BASEBOARD_FAB2_LIB.BASEBOARD_FAB2(SCH_1):PAGE101
 R1W24    1      A RES_0402-0.0,5%,1/16W,CHIP,G21A   I138 @BASEBOARD_FAB2_LIB.BASEBOARD_FAB2(SCH_1):PAGE101
 C8F19    1      A CAP_0402LF-15.0PF,50V,5%,COG,AA   I146 @BASEBOARD_FAB2_LIB.BASEBOARD_FAB2(SCH_1):PAGE101

XTAL_CK_MNG_OUT_R @BASEBOARD_FAB2_LIB.BASEBOARD_FAB2(SCH_1):XTAL_CK_MNG_OUT_R
 EU8F2   20  X2_25 ICS9FGP204_MLFP-IC,E95226-001    I34 @BASEBOARD_FAB2_LIB.BASEBOARD_FAB2(SCH_1):PAGE101
 R1W24    2      B RES_0402-0.0,5%,1/16W,CHIP,G21A   I138 @BASEBOARD_FAB2_LIB.BASEBOARD_FAB2(SCH_1):PAGE101

XTAL_KR_25M_IN @BASEBOARD_FAB2_LIB.BASEBOARD_FAB2(SCH_1):XTAL_KR_25M_IN
  U7C1 BV16 LAN_XTAL_IN LBG_CORE_QAT_EXT_D_BGA1-IC,H91A    I73 @BASEBOARD_FAB2_LIB.BASEBOARD_FAB2(SCH_1):PAGE118
  Y8C1    1      A CRYSTAL_2013-25.000MHZ,IC,H196A    I76 @BASEBOARD_FAB2_LIB.BASEBOARD_FAB2(SCH_1):PAGE118
  C8C1    1      A CAP_0402LF-33.0PF,50V,5%,COG,AA   I178 @BASEBOARD_FAB2_LIB.BASEBOARD_FAB2(SCH_1):PAGE118

XTAL_KR_25M_OUT @BASEBOARD_FAB2_LIB.BASEBOARD_FAB2(SCH_1):XTAL_KR_25M_OUT
  U7C1 BY16 LAN_XTAL_OUT LBG_CORE_QAT_EXT_D_BGA1-IC,H91A    I73 @BASEBOARD_FAB2_LIB.BASEBOARD_FAB2(SCH_1):PAGE118
  Y8C1    3      B CRYSTAL_2013-25.000MHZ,IC,H196A    I76 @BASEBOARD_FAB2_LIB.BASEBOARD_FAB2(SCH_1):PAGE118
  C8C2    1      A CAP_0402LF-33.0PF,50V,5%,COG,AA   I179 @BASEBOARD_FAB2_LIB.BASEBOARD_FAB2(SCH_1):PAGE118

XTAL_PCH_48M_IN @BASEBOARD_FAB2_LIB.BASEBOARD_FAB2(SCH_1):XTAL_PCH_48M_IN
  U7C1  B35 XTAL_IN LBG_CORE_QAT_EXT_D_BGA1-IC,H91A    I40 @BASEBOARD_FAB2_LIB.BASEBOARD_FAB2(SCH_1):PAGE114
  R7C1    1      A RES_0603-200K,0.1%,1/10W,CHIP,A    I48 @BASEBOARD_FAB2_LIB.BASEBOARD_FAB2(SCH_1):PAGE114
  Y7C1    1      A CRYSTAL_2013-48.000MHZ,IC,D717A    I49 @BASEBOARD_FAB2_LIB.BASEBOARD_FAB2(SCH_1):PAGE114
  C7C4    1      A CAP_0402LF-15.0PF,50V,5%,COG,AA    I50 @BASEBOARD_FAB2_LIB.BASEBOARD_FAB2(SCH_1):PAGE114

XTAL_PCH_48M_OUT @BASEBOARD_FAB2_LIB.BASEBOARD_FAB2(SCH_1):XTAL_PCH_48M_OUT
  U7C1  D35 XTAL_OUT LBG_CORE_QAT_EXT_D_BGA1-IC,H91A    I40 @BASEBOARD_FAB2_LIB.BASEBOARD_FAB2(SCH_1):PAGE114
  C7C5    1      A CAP_0402LF-15.0PF,50V,5%,COG,AA    I47 @BASEBOARD_FAB2_LIB.BASEBOARD_FAB2(SCH_1):PAGE114
  R7C1    2      B RES_0603-200K,0.1%,1/10W,CHIP,A    I48 @BASEBOARD_FAB2_LIB.BASEBOARD_FAB2(SCH_1):PAGE114
  Y7C1    3      B CRYSTAL_2013-48.000MHZ,IC,D717A    I49 @BASEBOARD_FAB2_LIB.BASEBOARD_FAB2(SCH_1):PAGE114

END GLOBAL SIGNAL CROSS REFERENCE
GLOBAL PART CROSS REFERENCE - 16-Jun-2017 AT 17:50:48

BT8G1 BATTERY_PLCLF-202168-001

C1A1 CAP_0805LF-22UF,4V,20%,X6S,C95A
     1 PVDDQ_KLM @BASEBOARD_FAB2_LIB.BASEBOARD_FAB2(SCH_1):PVDDQ_KLM    I68 @BASEBOARD_FAB2_LIB.BASEBOARD_FAB2(SCH_1):PAGE227
     2    GND @BASEBOARD_FAB2_LIB.BASEBOARD_FAB2(SCH_1):GND    I68 @BASEBOARD_FAB2_LIB.BASEBOARD_FAB2(SCH_1):PAGE227

C1A2 SC1U10V2KX-4-GP_SMD-BCG6-SC1U1A
     1 P5V_STBY @BASEBOARD_FAB2_LIB.BASEBOARD_FAB2(SCH_1):P5V_STBY   I148 @BASEBOARD_FAB2_LIB.BASEBOARD_FAB2(SCH_1):PAGE227
     2    GND @BASEBOARD_FAB2_LIB.BASEBOARD_FAB2(SCH_1):GND   I148 @BASEBOARD_FAB2_LIB.BASEBOARD_FAB2(SCH_1):PAGE227

C1A4 CAP_0805-10UF,16V,10%,X7R,G106A
     1 P12V_NVDIMM_KLM @BASEBOARD_FAB2_LIB.BASEBOARD_FAB2(SCH_1):P12V_NVDIMM_KLM    I60 @BASEBOARD_FAB2_LIB.BASEBOARD_FAB2(SCH_1):PAGE197
     2    GND @BASEBOARD_FAB2_LIB.BASEBOARD_FAB2(SCH_1):GND    I60 @BASEBOARD_FAB2_LIB.BASEBOARD_FAB2(SCH_1):PAGE197

C1A5 CAP_A_0402V-0.01UF,25V,10%,X7RA
     1 M_M_VREF @BASEBOARD_FAB2_LIB.BASEBOARD_FAB2(SCH_1):M_M_VREF   I178 @BASEBOARD_FAB2_LIB.BASEBOARD_FAB2(SCH_1):PAGE87
     2    GND @BASEBOARD_FAB2_LIB.BASEBOARD_FAB2(SCH_1):GND   I178 @BASEBOARD_FAB2_LIB.BASEBOARD_FAB2(SCH_1):PAGE87

C1A6 CAP_0402-1.0UF,16V,10%,X6S,D97A
     1 VR_PVDDQ_KLM_PH2_VCIN @BASEBOARD_FAB2_LIB.BASEBOARD_FAB2(SCH_1):VR_PVDDQ_KLM_PH2_VCIN    I77 @BASEBOARD_FAB2_LIB.BASEBOARD_FAB2(SCH_1):PAGE227
     2    GND @BASEBOARD_FAB2_LIB.BASEBOARD_FAB2(SCH_1):GND    I77 @BASEBOARD_FAB2_LIB.BASEBOARD_FAB2(SCH_1):PAGE227

C1A8 CAP_0402-0.220UF,16V,10%,X7R,AA
     1 VR_PVDDQ_KLM_PH2_BOOT @BASEBOARD_FAB2_LIB.BASEBOARD_FAB2(SCH_1):VR_PVDDQ_KLM_PH2_BOOT    I75 @BASEBOARD_FAB2_LIB.BASEBOARD_FAB2(SCH_1):PAGE227
     2 VR_PVDDQ_KLM_PH2_PHASE @BASEBOARD_FAB2_LIB.BASEBOARD_FAB2(SCH_1):VR_PVDDQ_KLM_PH2_PHASE    I75 @BASEBOARD_FAB2_LIB.BASEBOARD_FAB2(SCH_1):PAGE227

C1A9 CAP_0402-1.0UF,16V,10%,X6S,D97A
     1 VR_FET_SW_P12V_STBY_PVDDQ_KLM @BASEBOARD_FAB2_LIB.BASEBOARD_FAB2(SCH_1):VR_FET_SW_P12V_STBY_PVDDQ_KLM    I79 @BASEBOARD_FAB2_LIB.BASEBOARD_FAB2(SCH_1):PAGE227
     2    GND @BASEBOARD_FAB2_LIB.BASEBOARD_FAB2(SCH_1):GND    I79 @BASEBOARD_FAB2_LIB.BASEBOARD_FAB2(SCH_1):PAGE227

C1A10 CAP_A_0402V-0.1UF,16V,10%,X7R,A
     1 VR_FET_SW_P12V_STBY_PVDDQ_KLM @BASEBOARD_FAB2_LIB.BASEBOARD_FAB2(SCH_1):VR_FET_SW_P12V_STBY_PVDDQ_KLM    I51 @BASEBOARD_FAB2_LIB.BASEBOARD_FAB2(SCH_1):PAGE227
     2    GND @BASEBOARD_FAB2_LIB.BASEBOARD_FAB2(SCH_1):GND    I51 @BASEBOARD_FAB2_LIB.BASEBOARD_FAB2(SCH_1):PAGE227

C1A11 SC1U10V2KX-4-GP_SMD-BCG6-SC1U1A
     1 P5V_STBY @BASEBOARD_FAB2_LIB.BASEBOARD_FAB2(SCH_1):P5V_STBY   I147 @BASEBOARD_FAB2_LIB.BASEBOARD_FAB2(SCH_1):PAGE227
     2    GND @BASEBOARD_FAB2_LIB.BASEBOARD_FAB2(SCH_1):GND   I147 @BASEBOARD_FAB2_LIB.BASEBOARD_FAB2(SCH_1):PAGE227

C1A12 CAP_0805LF-22UF,4V,20%,X6S,C95A
     1 PVDDQ_KLM @BASEBOARD_FAB2_LIB.BASEBOARD_FAB2(SCH_1):PVDDQ_KLM     I6 @BASEBOARD_FAB2_LIB.BASEBOARD_FAB2(SCH_1):PAGE227
     2    GND @BASEBOARD_FAB2_LIB.BASEBOARD_FAB2(SCH_1):GND     I6 @BASEBOARD_FAB2_LIB.BASEBOARD_FAB2(SCH_1):PAGE227

C1A13 CAP_0402-0.22UF,16V,10%,X7R,A3A
     1 P5V_STBY @BASEBOARD_FAB2_LIB.BASEBOARD_FAB2(SCH_1):P5V_STBY    I72 @BASEBOARD_FAB2_LIB.BASEBOARD_FAB2(SCH_1):PAGE227
     2    GND @BASEBOARD_FAB2_LIB.BASEBOARD_FAB2(SCH_1):GND    I72 @BASEBOARD_FAB2_LIB.BASEBOARD_FAB2(SCH_1):PAGE227

C1A16 CAP_0805-10UF,16V,10%,X7R,G106A
     1 P12V_NVDIMM_KLM @BASEBOARD_FAB2_LIB.BASEBOARD_FAB2(SCH_1):P12V_NVDIMM_KLM    I75 @BASEBOARD_FAB2_LIB.BASEBOARD_FAB2(SCH_1):PAGE197
     2    GND @BASEBOARD_FAB2_LIB.BASEBOARD_FAB2(SCH_1):GND    I75 @BASEBOARD_FAB2_LIB.BASEBOARD_FAB2(SCH_1):PAGE197

C1A17 CAP_A_0402V-0.01UF,25V,10%,X7RA
     1 M_L_VREF @BASEBOARD_FAB2_LIB.BASEBOARD_FAB2(SCH_1):M_L_VREF   I182 @BASEBOARD_FAB2_LIB.BASEBOARD_FAB2(SCH_1):PAGE86
     2    GND @BASEBOARD_FAB2_LIB.BASEBOARD_FAB2(SCH_1):GND   I182 @BASEBOARD_FAB2_LIB.BASEBOARD_FAB2(SCH_1):PAGE86

C1A18 CAP_0402-0.220UF,16V,10%,X7R,AA
     1 VR_PVDDQ_KLM_PH1_BOOT @BASEBOARD_FAB2_LIB.BASEBOARD_FAB2(SCH_1):VR_PVDDQ_KLM_PH1_BOOT    I44 @BASEBOARD_FAB2_LIB.BASEBOARD_FAB2(SCH_1):PAGE227
     2 VR_PVDDQ_KLM_PH1_PHASE @BASEBOARD_FAB2_LIB.BASEBOARD_FAB2(SCH_1):VR_PVDDQ_KLM_PH1_PHASE    I44 @BASEBOARD_FAB2_LIB.BASEBOARD_FAB2(SCH_1):PAGE227

C1A19 CAP_0402-1.0UF,16V,10%,X6S,D97A
     1 VR_FET_SW_P12V_STBY_PVDDQ_KLM @BASEBOARD_FAB2_LIB.BASEBOARD_FAB2(SCH_1):VR_FET_SW_P12V_STBY_PVDDQ_KLM    I48 @BASEBOARD_FAB2_LIB.BASEBOARD_FAB2(SCH_1):PAGE227
     2    GND @BASEBOARD_FAB2_LIB.BASEBOARD_FAB2(SCH_1):GND    I48 @BASEBOARD_FAB2_LIB.BASEBOARD_FAB2(SCH_1):PAGE227

C1A20 CAP_A_0402V-0.1UF,16V,10%,X7R,A
     1 VR_FET_SW_P12V_STBY_PVDDQ_KLM @BASEBOARD_FAB2_LIB.BASEBOARD_FAB2(SCH_1):VR_FET_SW_P12V_STBY_PVDDQ_KLM    I78 @BASEBOARD_FAB2_LIB.BASEBOARD_FAB2(SCH_1):PAGE227
     2    GND @BASEBOARD_FAB2_LIB.BASEBOARD_FAB2(SCH_1):GND    I78 @BASEBOARD_FAB2_LIB.BASEBOARD_FAB2(SCH_1):PAGE227

C1B2 CAP_A_0402V-0.1UF,16V,10%,X7R,A
     1 VR_PVDDQ_KLM_VD12 @BASEBOARD_FAB2_LIB.BASEBOARD_FAB2(SCH_1):VR_PVDDQ_KLM_VD12    I44 @BASEBOARD_FAB2_LIB.BASEBOARD_FAB2(SCH_1):PAGE226
     2    GND @BASEBOARD_FAB2_LIB.BASEBOARD_FAB2(SCH_1):GND    I44 @BASEBOARD_FAB2_LIB.BASEBOARD_FAB2(SCH_1):PAGE226

C1B3 CAP_A_0402V-1.0UF,6.3V,10%,X6SA
     1 VR_PVDDQ_KLM_VD12 @BASEBOARD_FAB2_LIB.BASEBOARD_FAB2(SCH_1):VR_PVDDQ_KLM_VD12    I45 @BASEBOARD_FAB2_LIB.BASEBOARD_FAB2(SCH_1):PAGE226
     2    GND @BASEBOARD_FAB2_LIB.BASEBOARD_FAB2(SCH_1):GND    I45 @BASEBOARD_FAB2_LIB.BASEBOARD_FAB2(SCH_1):PAGE226

C1B4 CAP_0402LF-1000PF,50V,10%,X7R,A
     1 PWRGD_PVDDQ_KLM_R @BASEBOARD_FAB2_LIB.BASEBOARD_FAB2(SCH_1):PWRGD_PVDDQ_KLM_R    I40 @BASEBOARD_FAB2_LIB.BASEBOARD_FAB2(SCH_1):PAGE226
     2    GND @BASEBOARD_FAB2_LIB.BASEBOARD_FAB2(SCH_1):GND    I40 @BASEBOARD_FAB2_LIB.BASEBOARD_FAB2(SCH_1):PAGE226

C1B5 CAP_A_0402V-0.1UF,16V,10%,X7R,A
     1 VR_PVDDQ_KLM_VDD @BASEBOARD_FAB2_LIB.BASEBOARD_FAB2(SCH_1):VR_PVDDQ_KLM_VDD    I32 @BASEBOARD_FAB2_LIB.BASEBOARD_FAB2(SCH_1):PAGE226
     2    GND @BASEBOARD_FAB2_LIB.BASEBOARD_FAB2(SCH_1):GND    I32 @BASEBOARD_FAB2_LIB.BASEBOARD_FAB2(SCH_1):PAGE226

C1B6 CAP_A_0402V-1.0UF,6.3V,10%,X6SA
     1 VR_PVDDQ_KLM_VDD @BASEBOARD_FAB2_LIB.BASEBOARD_FAB2(SCH_1):VR_PVDDQ_KLM_VDD    I38 @BASEBOARD_FAB2_LIB.BASEBOARD_FAB2(SCH_1):PAGE226
     2    GND @BASEBOARD_FAB2_LIB.BASEBOARD_FAB2(SCH_1):GND    I38 @BASEBOARD_FAB2_LIB.BASEBOARD_FAB2(SCH_1):PAGE226

C1B7 CAP_0805-10UF,16V,10%,X7R,G106A
     1 P12V_NVDIMM_KLM @BASEBOARD_FAB2_LIB.BASEBOARD_FAB2(SCH_1):P12V_NVDIMM_KLM    I72 @BASEBOARD_FAB2_LIB.BASEBOARD_FAB2(SCH_1):PAGE197
     2    GND @BASEBOARD_FAB2_LIB.BASEBOARD_FAB2(SCH_1):GND    I72 @BASEBOARD_FAB2_LIB.BASEBOARD_FAB2(SCH_1):PAGE197

C1B9 CAP_A_0402V-0.01UF,25V,10%,X7RA
     1 M_K_VREF @BASEBOARD_FAB2_LIB.BASEBOARD_FAB2(SCH_1):M_K_VREF   I176 @BASEBOARD_FAB2_LIB.BASEBOARD_FAB2(SCH_1):PAGE83
     2    GND @BASEBOARD_FAB2_LIB.BASEBOARD_FAB2(SCH_1):GND   I176 @BASEBOARD_FAB2_LIB.BASEBOARD_FAB2(SCH_1):PAGE83

C1B10 CAPP_2626-270UF,16V,20%,OSCON,A
     1 VR_FET_SW_P12V_STBY_PVDDQ_KLM @BASEBOARD_FAB2_LIB.BASEBOARD_FAB2(SCH_1):VR_FET_SW_P12V_STBY_PVDDQ_KLM   I175 @BASEBOARD_FAB2_LIB.BASEBOARD_FAB2(SCH_1):PAGE228
     2    GND @BASEBOARD_FAB2_LIB.BASEBOARD_FAB2(SCH_1):GND   I175 @BASEBOARD_FAB2_LIB.BASEBOARD_FAB2(SCH_1):PAGE228

C1B11 CAP_0402LF-220PF,50V,10%,X7R,AA
     1 A_TSENSE_PVDDQ_KLM @BASEBOARD_FAB2_LIB.BASEBOARD_FAB2(SCH_1):A_TSENSE_PVDDQ_KLM    I23 @BASEBOARD_FAB2_LIB.BASEBOARD_FAB2(SCH_1):PAGE226
     2    GND @BASEBOARD_FAB2_LIB.BASEBOARD_FAB2(SCH_1):GND    I23 @BASEBOARD_FAB2_LIB.BASEBOARD_FAB2(SCH_1):PAGE226

C1B12 CAP_0402LF-220PF,50V,10%,X7R,AA
     1 VR_PVDDQ_KLM_AVSP @BASEBOARD_FAB2_LIB.BASEBOARD_FAB2(SCH_1):VR_PVDDQ_KLM_AVSP    I12 @BASEBOARD_FAB2_LIB.BASEBOARD_FAB2(SCH_1):PAGE226
     2 VSENSE_PVDDQ_KLM_N @BASEBOARD_FAB2_LIB.BASEBOARD_FAB2(SCH_1):VSENSE_PVDDQ_KLM_N    I12 @BASEBOARD_FAB2_LIB.BASEBOARD_FAB2(SCH_1):PAGE226

C1B14 CAPP_4040LF-470UF,16V,20%,ALUMA
     1 P12V_STBY @BASEBOARD_FAB2_LIB.BASEBOARD_FAB2(SCH_1):P12V_STBY    I84 @BASEBOARD_FAB2_LIB.BASEBOARD_FAB2(SCH_1):PAGE195
     2    GND @BASEBOARD_FAB2_LIB.BASEBOARD_FAB2(SCH_1):GND    I84 @BASEBOARD_FAB2_LIB.BASEBOARD_FAB2(SCH_1):PAGE195

C1B15 CAP_A_0402V-0.01UF,25V,10%,X7RA
     1 FAN_TACH2 @BASEBOARD_FAB2_LIB.BASEBOARD_FAB2(SCH_1):FAN_TACH2    I68 @BASEBOARD_FAB2_LIB.BASEBOARD_FAB2(SCH_1):PAGE161
     2    GND @BASEBOARD_FAB2_LIB.BASEBOARD_FAB2(SCH_1):GND    I68 @BASEBOARD_FAB2_LIB.BASEBOARD_FAB2(SCH_1):PAGE161

C1B18 CAP_0805-10UF,16V,10%,X6S,C953A
     1 P12V_FAN @BASEBOARD_FAB2_LIB.BASEBOARD_FAB2(SCH_1):P12V_FAN    I61 @BASEBOARD_FAB2_LIB.BASEBOARD_FAB2(SCH_1):PAGE198
     2    GND @BASEBOARD_FAB2_LIB.BASEBOARD_FAB2(SCH_1):GND    I61 @BASEBOARD_FAB2_LIB.BASEBOARD_FAB2(SCH_1):PAGE198

C1B19 CAP_A_0402V-0.1UF,16V,10%,X7R,A
     1 P12V_FAN @BASEBOARD_FAB2_LIB.BASEBOARD_FAB2(SCH_1):P12V_FAN    I64 @BASEBOARD_FAB2_LIB.BASEBOARD_FAB2(SCH_1):PAGE198
     2    GND @BASEBOARD_FAB2_LIB.BASEBOARD_FAB2(SCH_1):GND    I64 @BASEBOARD_FAB2_LIB.BASEBOARD_FAB2(SCH_1):PAGE198

C1B20 CAP_0402-1.0UF,16V,10%,X6S,D97A
     1 VR_PVDDQ_KLM_PH1_VCIN @BASEBOARD_FAB2_LIB.BASEBOARD_FAB2(SCH_1):VR_PVDDQ_KLM_PH1_VCIN    I50 @BASEBOARD_FAB2_LIB.BASEBOARD_FAB2(SCH_1):PAGE227
     2    GND @BASEBOARD_FAB2_LIB.BASEBOARD_FAB2(SCH_1):GND    I50 @BASEBOARD_FAB2_LIB.BASEBOARD_FAB2(SCH_1):PAGE227

C1B21 CAP_0402-0.22UF,16V,10%,X7R,A3A
     1 P5V_STBY @BASEBOARD_FAB2_LIB.BASEBOARD_FAB2(SCH_1):P5V_STBY    I54 @BASEBOARD_FAB2_LIB.BASEBOARD_FAB2(SCH_1):PAGE227
     2    GND @BASEBOARD_FAB2_LIB.BASEBOARD_FAB2(SCH_1):GND    I54 @BASEBOARD_FAB2_LIB.BASEBOARD_FAB2(SCH_1):PAGE227

C1C1 CAPP_2626-270UF,16V,20%,OSCON,A
     1 VR_FET_SW_P12V_STBY_PVCCIN_CPU1 @BASEBOARD_FAB2_LIB.BASEBOARD_FAB2(SCH_1):VR_FET_SW_P12V_STBY_PVCCIN_CPU1    I35 @BASEBOARD_FAB2_LIB.BASEBOARD_FAB2(SCH_1):PAGE209
     2    GND @BASEBOARD_FAB2_LIB.BASEBOARD_FAB2(SCH_1):GND    I35 @BASEBOARD_FAB2_LIB.BASEBOARD_FAB2(SCH_1):PAGE209

C1C2 CAPP_2626-270UF,16V,20%,OSCON,A
     1 VR_FET_SW_P12V_STBY_PVCCIN_CPU1 @BASEBOARD_FAB2_LIB.BASEBOARD_FAB2(SCH_1):VR_FET_SW_P12V_STBY_PVCCIN_CPU1    I38 @BASEBOARD_FAB2_LIB.BASEBOARD_FAB2(SCH_1):PAGE209
     2    GND @BASEBOARD_FAB2_LIB.BASEBOARD_FAB2(SCH_1):GND    I38 @BASEBOARD_FAB2_LIB.BASEBOARD_FAB2(SCH_1):PAGE209

C1C3 SC1U10V2KX-4-GP_SMD-BCG6-SC1U1A
     1 P5V_STBY @BASEBOARD_FAB2_LIB.BASEBOARD_FAB2(SCH_1):P5V_STBY    I73 @BASEBOARD_FAB2_LIB.BASEBOARD_FAB2(SCH_1):PAGE210
     2    GND @BASEBOARD_FAB2_LIB.BASEBOARD_FAB2(SCH_1):GND    I73 @BASEBOARD_FAB2_LIB.BASEBOARD_FAB2(SCH_1):PAGE210

C1C4 CAP_0402-0.22UF,16V,10%,X7R,A3A
     1 P5V_STBY @BASEBOARD_FAB2_LIB.BASEBOARD_FAB2(SCH_1):P5V_STBY    I22 @BASEBOARD_FAB2_LIB.BASEBOARD_FAB2(SCH_1):PAGE210
     2    GND @BASEBOARD_FAB2_LIB.BASEBOARD_FAB2(SCH_1):GND    I22 @BASEBOARD_FAB2_LIB.BASEBOARD_FAB2(SCH_1):PAGE210

C1C5 CAP_0402-1.0UF,16V,10%,X6S,D97A
     1 VR_PVSA_CPU1_VCIN @BASEBOARD_FAB2_LIB.BASEBOARD_FAB2(SCH_1):VR_PVSA_CPU1_VCIN    I26 @BASEBOARD_FAB2_LIB.BASEBOARD_FAB2(SCH_1):PAGE210
     2    GND @BASEBOARD_FAB2_LIB.BASEBOARD_FAB2(SCH_1):GND    I26 @BASEBOARD_FAB2_LIB.BASEBOARD_FAB2(SCH_1):PAGE210

C1C7 CAP_A_0402V-1.0UF,6.3V,10%,X6SA
     1 VR_PVCCIN_CPU1_VDD @BASEBOARD_FAB2_LIB.BASEBOARD_FAB2(SCH_1):VR_PVCCIN_CPU1_VDD    I41 @BASEBOARD_FAB2_LIB.BASEBOARD_FAB2(SCH_1):PAGE206
     2    GND @BASEBOARD_FAB2_LIB.BASEBOARD_FAB2(SCH_1):GND    I41 @BASEBOARD_FAB2_LIB.BASEBOARD_FAB2(SCH_1):PAGE206

C1C8 CAP_A_0402V-0.1UF,16V,10%,X7R,A
     1 VR_PVCCIN_CPU1_AVINSEN @BASEBOARD_FAB2_LIB.BASEBOARD_FAB2(SCH_1):VR_PVCCIN_CPU1_AVINSEN   I156 @BASEBOARD_FAB2_LIB.BASEBOARD_FAB2(SCH_1):PAGE206
     2    GND @BASEBOARD_FAB2_LIB.BASEBOARD_FAB2(SCH_1):GND   I156 @BASEBOARD_FAB2_LIB.BASEBOARD_FAB2(SCH_1):PAGE206

C1C9 CAP_A_0402V-0.1UF,16V,10%,X7R,A
     1 VR_PVCCIN_CPU1_VDD @BASEBOARD_FAB2_LIB.BASEBOARD_FAB2(SCH_1):VR_PVCCIN_CPU1_VDD    I42 @BASEBOARD_FAB2_LIB.BASEBOARD_FAB2(SCH_1):PAGE206
     2    GND @BASEBOARD_FAB2_LIB.BASEBOARD_FAB2(SCH_1):GND    I42 @BASEBOARD_FAB2_LIB.BASEBOARD_FAB2(SCH_1):PAGE206

C1C10 CAP_0402LF-220PF,50V,10%,X7R,AA
     1 A_TSENSE_PVCCIN_CPU1 @BASEBOARD_FAB2_LIB.BASEBOARD_FAB2(SCH_1):A_TSENSE_PVCCIN_CPU1    I69 @BASEBOARD_FAB2_LIB.BASEBOARD_FAB2(SCH_1):PAGE206
     2    GND @BASEBOARD_FAB2_LIB.BASEBOARD_FAB2(SCH_1):GND    I69 @BASEBOARD_FAB2_LIB.BASEBOARD_FAB2(SCH_1):PAGE206

C1C11 CAP_0402LF-220PF,50V,10%,X7R,AA
     1 A_TSENSE_PVSA_CPU1 @BASEBOARD_FAB2_LIB.BASEBOARD_FAB2(SCH_1):A_TSENSE_PVSA_CPU1    I71 @BASEBOARD_FAB2_LIB.BASEBOARD_FAB2(SCH_1):PAGE206
     2    GND @BASEBOARD_FAB2_LIB.BASEBOARD_FAB2(SCH_1):GND    I71 @BASEBOARD_FAB2_LIB.BASEBOARD_FAB2(SCH_1):PAGE206

C1C12 CAP_0402-0.220UF,16V,10%,X7R,AA
     1 VR_PVSA_CPU1_BOOT @BASEBOARD_FAB2_LIB.BASEBOARD_FAB2(SCH_1):VR_PVSA_CPU1_BOOT    I24 @BASEBOARD_FAB2_LIB.BASEBOARD_FAB2(SCH_1):PAGE210
     2 VR_PVSA_CPU1_PHASE @BASEBOARD_FAB2_LIB.BASEBOARD_FAB2(SCH_1):VR_PVSA_CPU1_PHASE    I24 @BASEBOARD_FAB2_LIB.BASEBOARD_FAB2(SCH_1):PAGE210

C1C13 CAP_A_0402V-1.0UF,6.3V,10%,X6SA
     1 VR_PVCCIN_CPU1_VD12 @BASEBOARD_FAB2_LIB.BASEBOARD_FAB2(SCH_1):VR_PVCCIN_CPU1_VD12    I29 @BASEBOARD_FAB2_LIB.BASEBOARD_FAB2(SCH_1):PAGE206
     2    GND @BASEBOARD_FAB2_LIB.BASEBOARD_FAB2(SCH_1):GND    I29 @BASEBOARD_FAB2_LIB.BASEBOARD_FAB2(SCH_1):PAGE206

C1C14 CAP_A_0402V-0.1UF,16V,10%,X7R,A
     1 VR_PVCCIN_CPU1_VD12 @BASEBOARD_FAB2_LIB.BASEBOARD_FAB2(SCH_1):VR_PVCCIN_CPU1_VD12    I31 @BASEBOARD_FAB2_LIB.BASEBOARD_FAB2(SCH_1):PAGE206
     2    GND @BASEBOARD_FAB2_LIB.BASEBOARD_FAB2(SCH_1):GND    I31 @BASEBOARD_FAB2_LIB.BASEBOARD_FAB2(SCH_1):PAGE206

C1C15 CAP_0402-1.0UF,16V,10%,X6S,D97A
     1 VR_FET_SW_P12V_STBY_PVCCIN_CPU1 @BASEBOARD_FAB2_LIB.BASEBOARD_FAB2(SCH_1):VR_FET_SW_P12V_STBY_PVCCIN_CPU1    I28 @BASEBOARD_FAB2_LIB.BASEBOARD_FAB2(SCH_1):PAGE210
     2    GND @BASEBOARD_FAB2_LIB.BASEBOARD_FAB2(SCH_1):GND    I28 @BASEBOARD_FAB2_LIB.BASEBOARD_FAB2(SCH_1):PAGE210

C1C16 CAP_0402LF-220PF,50V,10%,X7R,AA
     1 VSENSE_PVSA_CPU1_BVSP @BASEBOARD_FAB2_LIB.BASEBOARD_FAB2(SCH_1):VSENSE_PVSA_CPU1_BVSP    I68 @BASEBOARD_FAB2_LIB.BASEBOARD_FAB2(SCH_1):PAGE206
     2 VSENSE_PVSA_CPU1_N @BASEBOARD_FAB2_LIB.BASEBOARD_FAB2(SCH_1):VSENSE_PVSA_CPU1_N    I68 @BASEBOARD_FAB2_LIB.BASEBOARD_FAB2(SCH_1):PAGE206

C1C17 CAP_A_0402V-0.1UF,16V,10%,X7R,A
     1 VR_FET_SW_P12V_STBY_PVCCIN_CPU1 @BASEBOARD_FAB2_LIB.BASEBOARD_FAB2(SCH_1):VR_FET_SW_P12V_STBY_PVCCIN_CPU1    I27 @BASEBOARD_FAB2_LIB.BASEBOARD_FAB2(SCH_1):PAGE210
     2    GND @BASEBOARD_FAB2_LIB.BASEBOARD_FAB2(SCH_1):GND    I27 @BASEBOARD_FAB2_LIB.BASEBOARD_FAB2(SCH_1):PAGE210

C1C18 SC1U10V2KX-4-GP_SMD-BCG6-SC1U1A
     1 P5V_STBY @BASEBOARD_FAB2_LIB.BASEBOARD_FAB2(SCH_1):P5V_STBY    I89 @BASEBOARD_FAB2_LIB.BASEBOARD_FAB2(SCH_1):PAGE209
     2    GND @BASEBOARD_FAB2_LIB.BASEBOARD_FAB2(SCH_1):GND    I89 @BASEBOARD_FAB2_LIB.BASEBOARD_FAB2(SCH_1):PAGE209

C1C19 CAP_A_0603V-22.0UF,4V,20%,X6S,A
     1 PVSA_CPU1 @BASEBOARD_FAB2_LIB.BASEBOARD_FAB2(SCH_1):PVSA_CPU1     I8 @BASEBOARD_FAB2_LIB.BASEBOARD_FAB2(SCH_1):PAGE210
     2    GND @BASEBOARD_FAB2_LIB.BASEBOARD_FAB2(SCH_1):GND     I8 @BASEBOARD_FAB2_LIB.BASEBOARD_FAB2(SCH_1):PAGE210

C1C23 CAP_0402LF-1000PF,50V,10%,X7R,A
     1 VR_VRRDY_PVCCIN_CPU1 @BASEBOARD_FAB2_LIB.BASEBOARD_FAB2(SCH_1):VR_VRRDY_PVCCIN_CPU1   I114 @BASEBOARD_FAB2_LIB.BASEBOARD_FAB2(SCH_1):PAGE206
     2    GND @BASEBOARD_FAB2_LIB.BASEBOARD_FAB2(SCH_1):GND   I114 @BASEBOARD_FAB2_LIB.BASEBOARD_FAB2(SCH_1):PAGE206

C1C24 CAP_0402-0.220UF,16V,10%,X7R,AA
     1 VR_PVCCIN_CPU1_PH5_BOOT @BASEBOARD_FAB2_LIB.BASEBOARD_FAB2(SCH_1):VR_PVCCIN_CPU1_PH5_BOOT    I20 @BASEBOARD_FAB2_LIB.BASEBOARD_FAB2(SCH_1):PAGE209
     2 VR_PVCCIN_CPU1_PH5_PHASE @BASEBOARD_FAB2_LIB.BASEBOARD_FAB2(SCH_1):VR_PVCCIN_CPU1_PH5_PHASE    I20 @BASEBOARD_FAB2_LIB.BASEBOARD_FAB2(SCH_1):PAGE209

C1C25 CAP_A_0402V-0.1UF,16V,10%,X7R,A
     1 VR_FET_SW_P12V_STBY_PVCCIN_CPU1 @BASEBOARD_FAB2_LIB.BASEBOARD_FAB2(SCH_1):VR_FET_SW_P12V_STBY_PVCCIN_CPU1    I17 @BASEBOARD_FAB2_LIB.BASEBOARD_FAB2(SCH_1):PAGE209
     2    GND @BASEBOARD_FAB2_LIB.BASEBOARD_FAB2(SCH_1):GND    I17 @BASEBOARD_FAB2_LIB.BASEBOARD_FAB2(SCH_1):PAGE209

C1C26 CAP_0402-1.0UF,16V,10%,X6S,D97A
     1 VR_FET_SW_P12V_STBY_PVCCIN_CPU1 @BASEBOARD_FAB2_LIB.BASEBOARD_FAB2(SCH_1):VR_FET_SW_P12V_STBY_PVCCIN_CPU1    I16 @BASEBOARD_FAB2_LIB.BASEBOARD_FAB2(SCH_1):PAGE209
     2    GND @BASEBOARD_FAB2_LIB.BASEBOARD_FAB2(SCH_1):GND    I16 @BASEBOARD_FAB2_LIB.BASEBOARD_FAB2(SCH_1):PAGE209

C1D1 CAP_0402LF-220PF,50V,10%,X7R,AA
     1 VSENSE_PVCCIN_CPU1_AVSP @BASEBOARD_FAB2_LIB.BASEBOARD_FAB2(SCH_1):VSENSE_PVCCIN_CPU1_AVSP    I78 @BASEBOARD_FAB2_LIB.BASEBOARD_FAB2(SCH_1):PAGE206
     2 VSENSE_PVCCIN_CPU1_N @BASEBOARD_FAB2_LIB.BASEBOARD_FAB2(SCH_1):VSENSE_PVCCIN_CPU1_N    I78 @BASEBOARD_FAB2_LIB.BASEBOARD_FAB2(SCH_1):PAGE206

C1D3 CAP_A_0603V-22.0UF,4V,20%,X6S,A
     1 PVCCIN_CPU1 @BASEBOARD_FAB2_LIB.BASEBOARD_FAB2(SCH_1):PVCCIN_CPU1    I22 @BASEBOARD_FAB2_LIB.BASEBOARD_FAB2(SCH_1):PAGE208
     2    GND @BASEBOARD_FAB2_LIB.BASEBOARD_FAB2(SCH_1):GND    I22 @BASEBOARD_FAB2_LIB.BASEBOARD_FAB2(SCH_1):PAGE208

C1D5 SC1U10V2KX-4-GP_SMD-BCG6-SC1U1A
     1 P5V_STBY @BASEBOARD_FAB2_LIB.BASEBOARD_FAB2(SCH_1):P5V_STBY   I119 @BASEBOARD_FAB2_LIB.BASEBOARD_FAB2(SCH_1):PAGE208
     2    GND @BASEBOARD_FAB2_LIB.BASEBOARD_FAB2(SCH_1):GND   I119 @BASEBOARD_FAB2_LIB.BASEBOARD_FAB2(SCH_1):PAGE208

C1D6 CAP_0402-0.22UF,16V,10%,X7R,A3A
     1 P5V_STBY @BASEBOARD_FAB2_LIB.BASEBOARD_FAB2(SCH_1):P5V_STBY    I46 @BASEBOARD_FAB2_LIB.BASEBOARD_FAB2(SCH_1):PAGE208
     2    GND @BASEBOARD_FAB2_LIB.BASEBOARD_FAB2(SCH_1):GND    I46 @BASEBOARD_FAB2_LIB.BASEBOARD_FAB2(SCH_1):PAGE208

C1D7 CAP_0402-1.0UF,16V,10%,X6S,D97A
     1 VR_PVCCIN_CPU1_PH4_VCIN @BASEBOARD_FAB2_LIB.BASEBOARD_FAB2(SCH_1):VR_PVCCIN_CPU1_PH4_VCIN    I50 @BASEBOARD_FAB2_LIB.BASEBOARD_FAB2(SCH_1):PAGE208
     2    GND @BASEBOARD_FAB2_LIB.BASEBOARD_FAB2(SCH_1):GND    I50 @BASEBOARD_FAB2_LIB.BASEBOARD_FAB2(SCH_1):PAGE208

C1D9 CAP_A_0402V-0.1UF,16V,10%,X7R,A
     1 P12V_STBY @BASEBOARD_FAB2_LIB.BASEBOARD_FAB2(SCH_1):P12V_STBY   I187 @BASEBOARD_FAB2_LIB.BASEBOARD_FAB2(SCH_1):PAGE200
     2 AGND_HSC @BASEBOARD_FAB2_LIB.BASEBOARD_FAB2(SCH_1):AGND_HSC   I187 @BASEBOARD_FAB2_LIB.BASEBOARD_FAB2(SCH_1):PAGE200

C1D10 CAP_0402-0.220UF,16V,10%,X7R,AA
     1 VR_PVCCIN_CPU1_PH4_BOOT @BASEBOARD_FAB2_LIB.BASEBOARD_FAB2(SCH_1):VR_PVCCIN_CPU1_PH4_BOOT    I48 @BASEBOARD_FAB2_LIB.BASEBOARD_FAB2(SCH_1):PAGE208
     2 VR_PVCCIN_CPU1_PH4_PHASE @BASEBOARD_FAB2_LIB.BASEBOARD_FAB2(SCH_1):VR_PVCCIN_CPU1_PH4_PHASE    I48 @BASEBOARD_FAB2_LIB.BASEBOARD_FAB2(SCH_1):PAGE208

C1D11 CAP_A_0402V-0.1UF,16V,10%,X7R,A
     1 FM_P12V_HOTSWAP0_EN @BASEBOARD_FAB2_LIB.BASEBOARD_FAB2(SCH_1):FM_P12V_HOTSWAP0_EN    I53 @BASEBOARD_FAB2_LIB.BASEBOARD_FAB2(SCH_1):PAGE199
     2 AGND_HSC @BASEBOARD_FAB2_LIB.BASEBOARD_FAB2(SCH_1):AGND_HSC    I53 @BASEBOARD_FAB2_LIB.BASEBOARD_FAB2(SCH_1):PAGE199

C1D12 CAP_0402-1.0UF,16V,10%,X6S,D97A
     1 VR_FET_SW_P12V_STBY_PVCCIN_CPU1 @BASEBOARD_FAB2_LIB.BASEBOARD_FAB2(SCH_1):VR_FET_SW_P12V_STBY_PVCCIN_CPU1    I52 @BASEBOARD_FAB2_LIB.BASEBOARD_FAB2(SCH_1):PAGE208
     2    GND @BASEBOARD_FAB2_LIB.BASEBOARD_FAB2(SCH_1):GND    I52 @BASEBOARD_FAB2_LIB.BASEBOARD_FAB2(SCH_1):PAGE208

C1D13 CAP_A_0402V-0.1UF,16V,10%,X7R,A
     1 VR_FET_SW_P12V_STBY_PVCCIN_CPU1 @BASEBOARD_FAB2_LIB.BASEBOARD_FAB2(SCH_1):VR_FET_SW_P12V_STBY_PVCCIN_CPU1    I51 @BASEBOARD_FAB2_LIB.BASEBOARD_FAB2(SCH_1):PAGE208
     2    GND @BASEBOARD_FAB2_LIB.BASEBOARD_FAB2(SCH_1):GND    I51 @BASEBOARD_FAB2_LIB.BASEBOARD_FAB2(SCH_1):PAGE208

C1D14 CAP_A_0603V-22.0UF,4V,20%,X6S,A
     1 PVCCIN_CPU1 @BASEBOARD_FAB2_LIB.BASEBOARD_FAB2(SCH_1):PVCCIN_CPU1     I9 @BASEBOARD_FAB2_LIB.BASEBOARD_FAB2(SCH_1):PAGE208
     2    GND @BASEBOARD_FAB2_LIB.BASEBOARD_FAB2(SCH_1):GND     I9 @BASEBOARD_FAB2_LIB.BASEBOARD_FAB2(SCH_1):PAGE208

C1D15 SC1U10V2KX-4-GP_SMD-BCG6-SC1U1A
     1 P5V_STBY @BASEBOARD_FAB2_LIB.BASEBOARD_FAB2(SCH_1):P5V_STBY   I118 @BASEBOARD_FAB2_LIB.BASEBOARD_FAB2(SCH_1):PAGE208
     2    GND @BASEBOARD_FAB2_LIB.BASEBOARD_FAB2(SCH_1):GND   I118 @BASEBOARD_FAB2_LIB.BASEBOARD_FAB2(SCH_1):PAGE208

C1D16 CAP_0402-0.22UF,16V,10%,X7R,A3A
     1 P5V_STBY @BASEBOARD_FAB2_LIB.BASEBOARD_FAB2(SCH_1):P5V_STBY    I38 @BASEBOARD_FAB2_LIB.BASEBOARD_FAB2(SCH_1):PAGE208
     2    GND @BASEBOARD_FAB2_LIB.BASEBOARD_FAB2(SCH_1):GND    I38 @BASEBOARD_FAB2_LIB.BASEBOARD_FAB2(SCH_1):PAGE208

C1D17 CAP_0402-1.0UF,16V,10%,X6S,D97A
     1 VR_PVCCIN_CPU1_PH3_VCIN @BASEBOARD_FAB2_LIB.BASEBOARD_FAB2(SCH_1):VR_PVCCIN_CPU1_PH3_VCIN    I43 @BASEBOARD_FAB2_LIB.BASEBOARD_FAB2(SCH_1):PAGE208
     2    GND @BASEBOARD_FAB2_LIB.BASEBOARD_FAB2(SCH_1):GND    I43 @BASEBOARD_FAB2_LIB.BASEBOARD_FAB2(SCH_1):PAGE208

C1D19 CAP_0402-1.0UF,16V,10%,X6S,D97A
     1 A_HSC_VCAP @BASEBOARD_FAB2_LIB.BASEBOARD_FAB2(SCH_1):A_HSC_VCAP   I119 @BASEBOARD_FAB2_LIB.BASEBOARD_FAB2(SCH_1):PAGE199
     2 AGND_HSC @BASEBOARD_FAB2_LIB.BASEBOARD_FAB2(SCH_1):AGND_HSC   I119 @BASEBOARD_FAB2_LIB.BASEBOARD_FAB2(SCH_1):PAGE199

C1D20 CAP_0402-0.220UF,16V,10%,X7R,AA
     1 VR_PVCCIN_CPU1_PH3_BOOT @BASEBOARD_FAB2_LIB.BASEBOARD_FAB2(SCH_1):VR_PVCCIN_CPU1_PH3_BOOT    I40 @BASEBOARD_FAB2_LIB.BASEBOARD_FAB2(SCH_1):PAGE208
     2 VR_PVCCIN_CPU1_PH3_PHASE @BASEBOARD_FAB2_LIB.BASEBOARD_FAB2(SCH_1):VR_PVCCIN_CPU1_PH3_PHASE    I40 @BASEBOARD_FAB2_LIB.BASEBOARD_FAB2(SCH_1):PAGE208

C1D21 CAP_A_0402V-0.1UF,16V,10%,X7R,A
     1 A_HSC_PSET @BASEBOARD_FAB2_LIB.BASEBOARD_FAB2(SCH_1):A_HSC_PSET   I121 @BASEBOARD_FAB2_LIB.BASEBOARD_FAB2(SCH_1):PAGE199
     2 AGND_HSC @BASEBOARD_FAB2_LIB.BASEBOARD_FAB2(SCH_1):AGND_HSC   I121 @BASEBOARD_FAB2_LIB.BASEBOARD_FAB2(SCH_1):PAGE199

C1D22 CAP_A_0402V-0.1UF,16V,10%,EMPTA
     1 A_HSC_MON @BASEBOARD_FAB2_LIB.BASEBOARD_FAB2(SCH_1):A_HSC_MON    I42 @BASEBOARD_FAB2_LIB.BASEBOARD_FAB2(SCH_1):PAGE200
     2 A_HSC_MOP @BASEBOARD_FAB2_LIB.BASEBOARD_FAB2(SCH_1):A_HSC_MOP    I42 @BASEBOARD_FAB2_LIB.BASEBOARD_FAB2(SCH_1):PAGE200

C1D23 CAP_0402-1.0UF,16V,10%,X6S,D97A
     1 VR_FET_SW_P12V_STBY_PVCCIN_CPU1 @BASEBOARD_FAB2_LIB.BASEBOARD_FAB2(SCH_1):VR_FET_SW_P12V_STBY_PVCCIN_CPU1    I45 @BASEBOARD_FAB2_LIB.BASEBOARD_FAB2(SCH_1):PAGE208
     2    GND @BASEBOARD_FAB2_LIB.BASEBOARD_FAB2(SCH_1):GND    I45 @BASEBOARD_FAB2_LIB.BASEBOARD_FAB2(SCH_1):PAGE208

C1D24 CAP_A_0603V-22.0UF,4V,20%,X6S,A
     1 PVCCIN_CPU1 @BASEBOARD_FAB2_LIB.BASEBOARD_FAB2(SCH_1):PVCCIN_CPU1    I42 @BASEBOARD_FAB2_LIB.BASEBOARD_FAB2(SCH_1):PAGE209
     2    GND @BASEBOARD_FAB2_LIB.BASEBOARD_FAB2(SCH_1):GND    I42 @BASEBOARD_FAB2_LIB.BASEBOARD_FAB2(SCH_1):PAGE209

C1D25 CAP_0402-1.0UF,16V,10%,X6S,D97A
     1 P12V_HSC_VCC @BASEBOARD_FAB2_LIB.BASEBOARD_FAB2(SCH_1):P12V_HSC_VCC     I3 @BASEBOARD_FAB2_LIB.BASEBOARD_FAB2(SCH_1):PAGE199
     2 AGND_HSC @BASEBOARD_FAB2_LIB.BASEBOARD_FAB2(SCH_1):AGND_HSC     I3 @BASEBOARD_FAB2_LIB.BASEBOARD_FAB2(SCH_1):PAGE199

C1D26 CAP_A_0402V-0.1UF,16V,10%,X7R,A
     1 A_HSC_UV @BASEBOARD_FAB2_LIB.BASEBOARD_FAB2(SCH_1):A_HSC_UV   I107 @BASEBOARD_FAB2_LIB.BASEBOARD_FAB2(SCH_1):PAGE199
     2 AGND_HSC @BASEBOARD_FAB2_LIB.BASEBOARD_FAB2(SCH_1):AGND_HSC   I107 @BASEBOARD_FAB2_LIB.BASEBOARD_FAB2(SCH_1):PAGE199

C1D27 CAP_A_0402V-0.1UF,16V,10%,X7R,A
     1 A_HSC_OV @BASEBOARD_FAB2_LIB.BASEBOARD_FAB2(SCH_1):A_HSC_OV     I7 @BASEBOARD_FAB2_LIB.BASEBOARD_FAB2(SCH_1):PAGE199
     2 AGND_HSC @BASEBOARD_FAB2_LIB.BASEBOARD_FAB2(SCH_1):AGND_HSC     I7 @BASEBOARD_FAB2_LIB.BASEBOARD_FAB2(SCH_1):PAGE199

C1D28 CAP_A_0402V-0.1UF,16V,10%,X7R,A
     1 VR_FET_SW_P12V_STBY_PVCCIN_CPU1 @BASEBOARD_FAB2_LIB.BASEBOARD_FAB2(SCH_1):VR_FET_SW_P12V_STBY_PVCCIN_CPU1    I44 @BASEBOARD_FAB2_LIB.BASEBOARD_FAB2(SCH_1):PAGE208
     2    GND @BASEBOARD_FAB2_LIB.BASEBOARD_FAB2(SCH_1):GND    I44 @BASEBOARD_FAB2_LIB.BASEBOARD_FAB2(SCH_1):PAGE208

C1D32 CAP_0402-1.0UF,16V,10%,X6S,D97A
     1 VR_PVCCIN_CPU1_PH5_VCIN @BASEBOARD_FAB2_LIB.BASEBOARD_FAB2(SCH_1):VR_PVCCIN_CPU1_PH5_VCIN    I18 @BASEBOARD_FAB2_LIB.BASEBOARD_FAB2(SCH_1):PAGE209
     2    GND @BASEBOARD_FAB2_LIB.BASEBOARD_FAB2(SCH_1):GND    I18 @BASEBOARD_FAB2_LIB.BASEBOARD_FAB2(SCH_1):PAGE209

C1D33 CAP_0402-0.22UF,16V,10%,X7R,A3A
     1 P5V_STBY @BASEBOARD_FAB2_LIB.BASEBOARD_FAB2(SCH_1):P5V_STBY    I22 @BASEBOARD_FAB2_LIB.BASEBOARD_FAB2(SCH_1):PAGE209
     2    GND @BASEBOARD_FAB2_LIB.BASEBOARD_FAB2(SCH_1):GND    I22 @BASEBOARD_FAB2_LIB.BASEBOARD_FAB2(SCH_1):PAGE209

C1D34 CAP_A_0402V-0.1UF,16V,10%,X7R,A
     1 VR_FET_SW_P12V_STBY_PVCCIN_CPU1 @BASEBOARD_FAB2_LIB.BASEBOARD_FAB2(SCH_1):VR_FET_SW_P12V_STBY_PVCCIN_CPU1    I41 @BASEBOARD_FAB2_LIB.BASEBOARD_FAB2(SCH_1):PAGE207
     2    GND @BASEBOARD_FAB2_LIB.BASEBOARD_FAB2(SCH_1):GND    I41 @BASEBOARD_FAB2_LIB.BASEBOARD_FAB2(SCH_1):PAGE207

C1D35 CAP_0402-1.0UF,16V,10%,X6S,D97A
     1 VR_FET_SW_P12V_STBY_PVCCIN_CPU1 @BASEBOARD_FAB2_LIB.BASEBOARD_FAB2(SCH_1):VR_FET_SW_P12V_STBY_PVCCIN_CPU1    I42 @BASEBOARD_FAB2_LIB.BASEBOARD_FAB2(SCH_1):PAGE207
     2    GND @BASEBOARD_FAB2_LIB.BASEBOARD_FAB2(SCH_1):GND    I42 @BASEBOARD_FAB2_LIB.BASEBOARD_FAB2(SCH_1):PAGE207

C1D36 CAP_0402-0.220UF,16V,10%,X7R,AA
     1 VR_PVCCIN_CPU1_PH2_BOOT @BASEBOARD_FAB2_LIB.BASEBOARD_FAB2(SCH_1):VR_PVCCIN_CPU1_PH2_BOOT    I38 @BASEBOARD_FAB2_LIB.BASEBOARD_FAB2(SCH_1):PAGE207
     2 VR_PVCCIN_CPU1_PH2_PHASE @BASEBOARD_FAB2_LIB.BASEBOARD_FAB2(SCH_1):VR_PVCCIN_CPU1_PH2_PHASE    I38 @BASEBOARD_FAB2_LIB.BASEBOARD_FAB2(SCH_1):PAGE207

C1E2 CAP_1206-0.068UF,50V,20%,X7R,1A
     1 A_HSC_C @BASEBOARD_FAB2_LIB.BASEBOARD_FAB2(SCH_1):A_HSC_C   I155 @BASEBOARD_FAB2_LIB.BASEBOARD_FAB2(SCH_1):PAGE200
     2    GND @BASEBOARD_FAB2_LIB.BASEBOARD_FAB2(SCH_1):GND   I155 @BASEBOARD_FAB2_LIB.BASEBOARD_FAB2(SCH_1):PAGE200

C1E3 CAP_A_0603V-22.0UF,4V,20%,X6S,A
     1 PVCCIN_CPU1 @BASEBOARD_FAB2_LIB.BASEBOARD_FAB2(SCH_1):PVCCIN_CPU1    I18 @BASEBOARD_FAB2_LIB.BASEBOARD_FAB2(SCH_1):PAGE207
     2    GND @BASEBOARD_FAB2_LIB.BASEBOARD_FAB2(SCH_1):GND    I18 @BASEBOARD_FAB2_LIB.BASEBOARD_FAB2(SCH_1):PAGE207

C1E6 SC1U10V2KX-4-GP_SMD-BCG6-SC1U1A
     1 P5V_STBY @BASEBOARD_FAB2_LIB.BASEBOARD_FAB2(SCH_1):P5V_STBY   I110 @BASEBOARD_FAB2_LIB.BASEBOARD_FAB2(SCH_1):PAGE207
     2    GND @BASEBOARD_FAB2_LIB.BASEBOARD_FAB2(SCH_1):GND   I110 @BASEBOARD_FAB2_LIB.BASEBOARD_FAB2(SCH_1):PAGE207

C1E7 CAP_0402-0.22UF,16V,10%,X7R,A3A
     1 P5V_STBY @BASEBOARD_FAB2_LIB.BASEBOARD_FAB2(SCH_1):P5V_STBY    I28 @BASEBOARD_FAB2_LIB.BASEBOARD_FAB2(SCH_1):PAGE207
     2    GND @BASEBOARD_FAB2_LIB.BASEBOARD_FAB2(SCH_1):GND    I28 @BASEBOARD_FAB2_LIB.BASEBOARD_FAB2(SCH_1):PAGE207

C1E8 CAP_0402-1.0UF,16V,10%,X6S,D97A
     1 VR_PVCCIN_CPU1_PH1_VCIN @BASEBOARD_FAB2_LIB.BASEBOARD_FAB2(SCH_1):VR_PVCCIN_CPU1_PH1_VCIN    I32 @BASEBOARD_FAB2_LIB.BASEBOARD_FAB2(SCH_1):PAGE207
     2    GND @BASEBOARD_FAB2_LIB.BASEBOARD_FAB2(SCH_1):GND    I32 @BASEBOARD_FAB2_LIB.BASEBOARD_FAB2(SCH_1):PAGE207

C1E9 CAP_A_0603V-22.0UF,4V,20%,X6S,A
     1 PVCCIN_CPU1 @BASEBOARD_FAB2_LIB.BASEBOARD_FAB2(SCH_1):PVCCIN_CPU1    I58 @BASEBOARD_FAB2_LIB.BASEBOARD_FAB2(SCH_1):PAGE207
     2    GND @BASEBOARD_FAB2_LIB.BASEBOARD_FAB2(SCH_1):GND    I58 @BASEBOARD_FAB2_LIB.BASEBOARD_FAB2(SCH_1):PAGE207

C1E11 CAP_0402-0.220UF,16V,10%,X7R,AA
     1 VR_PVCCIN_CPU1_PH1_BOOT @BASEBOARD_FAB2_LIB.BASEBOARD_FAB2(SCH_1):VR_PVCCIN_CPU1_PH1_BOOT    I30 @BASEBOARD_FAB2_LIB.BASEBOARD_FAB2(SCH_1):PAGE207
     2 VR_PVCCIN_CPU1_PH1_PHASE @BASEBOARD_FAB2_LIB.BASEBOARD_FAB2(SCH_1):VR_PVCCIN_CPU1_PH1_PHASE    I30 @BASEBOARD_FAB2_LIB.BASEBOARD_FAB2(SCH_1):PAGE207

C1E12 CAP_0805-10UF,16V,10%,X6S,C953A
     1 P12V_PSU @BASEBOARD_FAB2_LIB.BASEBOARD_FAB2(SCH_1):P12V_PSU    I32 @BASEBOARD_FAB2_LIB.BASEBOARD_FAB2(SCH_1):PAGE195
     2    GND @BASEBOARD_FAB2_LIB.BASEBOARD_FAB2(SCH_1):GND    I32 @BASEBOARD_FAB2_LIB.BASEBOARD_FAB2(SCH_1):PAGE195

C1E13 CAP_0402-1.0UF,16V,10%,X6S,D97A
     1 VR_FET_SW_P12V_STBY_PVCCIN_CPU1 @BASEBOARD_FAB2_LIB.BASEBOARD_FAB2(SCH_1):VR_FET_SW_P12V_STBY_PVCCIN_CPU1    I34 @BASEBOARD_FAB2_LIB.BASEBOARD_FAB2(SCH_1):PAGE207
     2    GND @BASEBOARD_FAB2_LIB.BASEBOARD_FAB2(SCH_1):GND    I34 @BASEBOARD_FAB2_LIB.BASEBOARD_FAB2(SCH_1):PAGE207

C1E14 CAP_A_0402V-0.1UF,16V,10%,X7R,A
     1 VR_FET_SW_P12V_STBY_PVCCIN_CPU1 @BASEBOARD_FAB2_LIB.BASEBOARD_FAB2(SCH_1):VR_FET_SW_P12V_STBY_PVCCIN_CPU1    I33 @BASEBOARD_FAB2_LIB.BASEBOARD_FAB2(SCH_1):PAGE207
     2    GND @BASEBOARD_FAB2_LIB.BASEBOARD_FAB2(SCH_1):GND    I33 @BASEBOARD_FAB2_LIB.BASEBOARD_FAB2(SCH_1):PAGE207

C1E15 CAP_0805-10UF,16V,10%,X6S,C953A
     1 P12V_PSU @BASEBOARD_FAB2_LIB.BASEBOARD_FAB2(SCH_1):P12V_PSU    I35 @BASEBOARD_FAB2_LIB.BASEBOARD_FAB2(SCH_1):PAGE195
     2    GND @BASEBOARD_FAB2_LIB.BASEBOARD_FAB2(SCH_1):GND    I35 @BASEBOARD_FAB2_LIB.BASEBOARD_FAB2(SCH_1):PAGE195

C1E16 CAP_A_0402V-0.1UF,16V,10%,X7R,A
     1 P12V_PSU @BASEBOARD_FAB2_LIB.BASEBOARD_FAB2(SCH_1):P12V_PSU    I39 @BASEBOARD_FAB2_LIB.BASEBOARD_FAB2(SCH_1):PAGE195
     2    GND @BASEBOARD_FAB2_LIB.BASEBOARD_FAB2(SCH_1):GND    I39 @BASEBOARD_FAB2_LIB.BASEBOARD_FAB2(SCH_1):PAGE195

C1E17 CAP_A_0402V-0.1UF,16V,10%,X7R,A
     1 P12V_PSU @BASEBOARD_FAB2_LIB.BASEBOARD_FAB2(SCH_1):P12V_PSU    I38 @BASEBOARD_FAB2_LIB.BASEBOARD_FAB2(SCH_1):PAGE195
     2    GND @BASEBOARD_FAB2_LIB.BASEBOARD_FAB2(SCH_1):GND    I38 @BASEBOARD_FAB2_LIB.BASEBOARD_FAB2(SCH_1):PAGE195

C1E18 CAPP_2626-270UF,16V,20%,OSCON,A
     1 VR_FET_SW_P12V_STBY_PVCCIN_CPU1 @BASEBOARD_FAB2_LIB.BASEBOARD_FAB2(SCH_1):VR_FET_SW_P12V_STBY_PVCCIN_CPU1    I37 @BASEBOARD_FAB2_LIB.BASEBOARD_FAB2(SCH_1):PAGE209
     2    GND @BASEBOARD_FAB2_LIB.BASEBOARD_FAB2(SCH_1):GND    I37 @BASEBOARD_FAB2_LIB.BASEBOARD_FAB2(SCH_1):PAGE209

C1E19 CAP_0402LF-47.0PF,50V,5%,EMPTYA
     1 ISENSE_TMP421_2_DXP @BASEBOARD_FAB2_LIB.BASEBOARD_FAB2(SCH_1):ISENSE_TMP421_2_DXP    I24 @BASEBOARD_FAB2_LIB.BASEBOARD_FAB2(SCH_1):PAGE167
     2 ISENSE_TMP421_2_DXN @BASEBOARD_FAB2_LIB.BASEBOARD_FAB2(SCH_1):ISENSE_TMP421_2_DXN    I24 @BASEBOARD_FAB2_LIB.BASEBOARD_FAB2(SCH_1):PAGE167

C1E20 CAP_A_0402V-0.1UF,16V,10%,X7R,A
     1 P12V_FAN @BASEBOARD_FAB2_LIB.BASEBOARD_FAB2(SCH_1):P12V_FAN     I4 @BASEBOARD_FAB2_LIB.BASEBOARD_FAB2(SCH_1):PAGE161
     2    GND @BASEBOARD_FAB2_LIB.BASEBOARD_FAB2(SCH_1):GND     I4 @BASEBOARD_FAB2_LIB.BASEBOARD_FAB2(SCH_1):PAGE161

C1E21 CAP_0805-10UF,16V,10%,X6S,C953A
     1 P12V_FAN @BASEBOARD_FAB2_LIB.BASEBOARD_FAB2(SCH_1):P12V_FAN     I3 @BASEBOARD_FAB2_LIB.BASEBOARD_FAB2(SCH_1):PAGE161
     2    GND @BASEBOARD_FAB2_LIB.BASEBOARD_FAB2(SCH_1):GND     I3 @BASEBOARD_FAB2_LIB.BASEBOARD_FAB2(SCH_1):PAGE161

C1E22 CAP_A_0402V-0.1UF,16V,10%,X7R,A
     1 P3V3_STBY @BASEBOARD_FAB2_LIB.BASEBOARD_FAB2(SCH_1):P3V3_STBY   I113 @BASEBOARD_FAB2_LIB.BASEBOARD_FAB2(SCH_1):PAGE161
     2    GND @BASEBOARD_FAB2_LIB.BASEBOARD_FAB2(SCH_1):GND   I113 @BASEBOARD_FAB2_LIB.BASEBOARD_FAB2(SCH_1):PAGE161

C1E23 SC1U10V2KX-4-GP_SMD-BCG6-SC1U1A
     1 P5V_STBY @BASEBOARD_FAB2_LIB.BASEBOARD_FAB2(SCH_1):P5V_STBY   I109 @BASEBOARD_FAB2_LIB.BASEBOARD_FAB2(SCH_1):PAGE207
     2    GND @BASEBOARD_FAB2_LIB.BASEBOARD_FAB2(SCH_1):GND   I109 @BASEBOARD_FAB2_LIB.BASEBOARD_FAB2(SCH_1):PAGE207

C1E24 CAP_0402-1.0UF,16V,10%,X6S,D97A
     1 VR_PVCCIN_CPU1_PH2_VCIN @BASEBOARD_FAB2_LIB.BASEBOARD_FAB2(SCH_1):VR_PVCCIN_CPU1_PH2_VCIN    I40 @BASEBOARD_FAB2_LIB.BASEBOARD_FAB2(SCH_1):PAGE207
     2    GND @BASEBOARD_FAB2_LIB.BASEBOARD_FAB2(SCH_1):GND    I40 @BASEBOARD_FAB2_LIB.BASEBOARD_FAB2(SCH_1):PAGE207

C1E25 CAP_0402-0.22UF,16V,10%,X7R,A3A
     1 P5V_STBY @BASEBOARD_FAB2_LIB.BASEBOARD_FAB2(SCH_1):P5V_STBY    I36 @BASEBOARD_FAB2_LIB.BASEBOARD_FAB2(SCH_1):PAGE207
     2    GND @BASEBOARD_FAB2_LIB.BASEBOARD_FAB2(SCH_1):GND    I36 @BASEBOARD_FAB2_LIB.BASEBOARD_FAB2(SCH_1):PAGE207

C1F2 CAP_0402-0.22UF,16V,10%,X7R,A3A
     1 P3E_CPU1_PE3_MP_C_TXP<7> @BASEBOARD_FAB2_LIB.BASEBOARD_FAB2(SCH_1):P3E_CPU1_PE3_MP_C_TXP(7)    I90 @BASEBOARD_FAB2_LIB.BASEBOARD_FAB2(SCH_1):PAGE181
     2 P3E_CPU1_PE3_MP_TXP<7> @BASEBOARD_FAB2_LIB.BASEBOARD_FAB2(SCH_1):P3E_CPU1_PE3_MP_TXP(7)    I90 @BASEBOARD_FAB2_LIB.BASEBOARD_FAB2(SCH_1):PAGE181

C1F3 CAP_0402-0.22UF,16V,10%,X7R,A3A
     1 P3E_CPU1_PE3_MP_C_TXN<7> @BASEBOARD_FAB2_LIB.BASEBOARD_FAB2(SCH_1):P3E_CPU1_PE3_MP_C_TXN(7)    I76 @BASEBOARD_FAB2_LIB.BASEBOARD_FAB2(SCH_1):PAGE181
     2 P3E_CPU1_PE3_MP_TXN<7> @BASEBOARD_FAB2_LIB.BASEBOARD_FAB2(SCH_1):P3E_CPU1_PE3_MP_TXN(7)    I76 @BASEBOARD_FAB2_LIB.BASEBOARD_FAB2(SCH_1):PAGE181

C1F4 CAP_0402-0.22UF,16V,10%,X7R,A3A
     1 P3E_CPU1_PE3_MP_C_TXN<6> @BASEBOARD_FAB2_LIB.BASEBOARD_FAB2(SCH_1):P3E_CPU1_PE3_MP_C_TXN(6)    I91 @BASEBOARD_FAB2_LIB.BASEBOARD_FAB2(SCH_1):PAGE181
     2 P3E_CPU1_PE3_MP_TXN<6> @BASEBOARD_FAB2_LIB.BASEBOARD_FAB2(SCH_1):P3E_CPU1_PE3_MP_TXN(6)    I91 @BASEBOARD_FAB2_LIB.BASEBOARD_FAB2(SCH_1):PAGE181

C1F5 CAP_0402-0.22UF,16V,10%,X7R,A3A
     1 P3E_CPU1_PE3_MP_C_TXP<6> @BASEBOARD_FAB2_LIB.BASEBOARD_FAB2(SCH_1):P3E_CPU1_PE3_MP_C_TXP(6)    I77 @BASEBOARD_FAB2_LIB.BASEBOARD_FAB2(SCH_1):PAGE181
     2 P3E_CPU1_PE3_MP_TXP<6> @BASEBOARD_FAB2_LIB.BASEBOARD_FAB2(SCH_1):P3E_CPU1_PE3_MP_TXP(6)    I77 @BASEBOARD_FAB2_LIB.BASEBOARD_FAB2(SCH_1):PAGE181

C1F6 CAP_0402-0.22UF,16V,10%,X7R,A3A
     1 P3E_CPU1_PE3_MP_C_TXP<5> @BASEBOARD_FAB2_LIB.BASEBOARD_FAB2(SCH_1):P3E_CPU1_PE3_MP_C_TXP(5)    I88 @BASEBOARD_FAB2_LIB.BASEBOARD_FAB2(SCH_1):PAGE181
     2 P3E_CPU1_PE3_MP_TXP<5> @BASEBOARD_FAB2_LIB.BASEBOARD_FAB2(SCH_1):P3E_CPU1_PE3_MP_TXP(5)    I88 @BASEBOARD_FAB2_LIB.BASEBOARD_FAB2(SCH_1):PAGE181

C1F7 CAPP_4040LF-470UF,16V,20%,ALUMA
     1 P12V_STBY @BASEBOARD_FAB2_LIB.BASEBOARD_FAB2(SCH_1):P12V_STBY    I85 @BASEBOARD_FAB2_LIB.BASEBOARD_FAB2(SCH_1):PAGE195
     2    GND @BASEBOARD_FAB2_LIB.BASEBOARD_FAB2(SCH_1):GND    I85 @BASEBOARD_FAB2_LIB.BASEBOARD_FAB2(SCH_1):PAGE195

C1F8 CAP_0402-0.22UF,16V,10%,X7R,A3A
     1 P3E_CPU1_PE3_MP_C_TXN<5> @BASEBOARD_FAB2_LIB.BASEBOARD_FAB2(SCH_1):P3E_CPU1_PE3_MP_C_TXN(5)    I73 @BASEBOARD_FAB2_LIB.BASEBOARD_FAB2(SCH_1):PAGE181
     2 P3E_CPU1_PE3_MP_TXN<5> @BASEBOARD_FAB2_LIB.BASEBOARD_FAB2(SCH_1):P3E_CPU1_PE3_MP_TXN(5)    I73 @BASEBOARD_FAB2_LIB.BASEBOARD_FAB2(SCH_1):PAGE181

C1F9 CAP_A_0402V-0.01UF,25V,10%,X7RA
     1 FAN_TACH0 @BASEBOARD_FAB2_LIB.BASEBOARD_FAB2(SCH_1):FAN_TACH0    I46 @BASEBOARD_FAB2_LIB.BASEBOARD_FAB2(SCH_1):PAGE161
     2    GND @BASEBOARD_FAB2_LIB.BASEBOARD_FAB2(SCH_1):GND    I46 @BASEBOARD_FAB2_LIB.BASEBOARD_FAB2(SCH_1):PAGE161

C1F10 CAP_0402-0.22UF,16V,10%,X7R,A3A
     1 P3E_CPU1_PE3_MP_C_TXN<4> @BASEBOARD_FAB2_LIB.BASEBOARD_FAB2(SCH_1):P3E_CPU1_PE3_MP_C_TXN(4)    I87 @BASEBOARD_FAB2_LIB.BASEBOARD_FAB2(SCH_1):PAGE181
     2 P3E_CPU1_PE3_MP_TXN<4> @BASEBOARD_FAB2_LIB.BASEBOARD_FAB2(SCH_1):P3E_CPU1_PE3_MP_TXN(4)    I87 @BASEBOARD_FAB2_LIB.BASEBOARD_FAB2(SCH_1):PAGE181

C1F11 CAP_0402-0.22UF,16V,10%,X7R,A3A
     1 P3E_CPU1_PE3_MP_C_TXP<4> @BASEBOARD_FAB2_LIB.BASEBOARD_FAB2(SCH_1):P3E_CPU1_PE3_MP_C_TXP(4)    I74 @BASEBOARD_FAB2_LIB.BASEBOARD_FAB2(SCH_1):PAGE181
     2 P3E_CPU1_PE3_MP_TXP<4> @BASEBOARD_FAB2_LIB.BASEBOARD_FAB2(SCH_1):P3E_CPU1_PE3_MP_TXP(4)    I74 @BASEBOARD_FAB2_LIB.BASEBOARD_FAB2(SCH_1):PAGE181

C1F12 CAP_0402-0.22UF,16V,10%,X7R,A3A
     1 P3E_CPU1_PE3_MP_C_TXP<3> @BASEBOARD_FAB2_LIB.BASEBOARD_FAB2(SCH_1):P3E_CPU1_PE3_MP_C_TXP(3)    I75 @BASEBOARD_FAB2_LIB.BASEBOARD_FAB2(SCH_1):PAGE181
     2 P3E_CPU1_PE3_MP_TXP<3> @BASEBOARD_FAB2_LIB.BASEBOARD_FAB2(SCH_1):P3E_CPU1_PE3_MP_TXP(3)    I75 @BASEBOARD_FAB2_LIB.BASEBOARD_FAB2(SCH_1):PAGE181

C1F13 CAP_0402-0.22UF,16V,10%,X7R,A3A
     1 P3E_CPU1_PE3_MP_C_TXN<3> @BASEBOARD_FAB2_LIB.BASEBOARD_FAB2(SCH_1):P3E_CPU1_PE3_MP_C_TXN(3)    I89 @BASEBOARD_FAB2_LIB.BASEBOARD_FAB2(SCH_1):PAGE181
     2 P3E_CPU1_PE3_MP_TXN<3> @BASEBOARD_FAB2_LIB.BASEBOARD_FAB2(SCH_1):P3E_CPU1_PE3_MP_TXN(3)    I89 @BASEBOARD_FAB2_LIB.BASEBOARD_FAB2(SCH_1):PAGE181

C1F14 CAP_0402-0.22UF,16V,10%,X7R,A3A
     1 P3E_CPU1_PE3_MP_C_TXP<2> @BASEBOARD_FAB2_LIB.BASEBOARD_FAB2(SCH_1):P3E_CPU1_PE3_MP_C_TXP(2)    I70 @BASEBOARD_FAB2_LIB.BASEBOARD_FAB2(SCH_1):PAGE181
     2 P3E_CPU1_PE3_MP_TXP<2> @BASEBOARD_FAB2_LIB.BASEBOARD_FAB2(SCH_1):P3E_CPU1_PE3_MP_TXP(2)    I70 @BASEBOARD_FAB2_LIB.BASEBOARD_FAB2(SCH_1):PAGE181

C1F15 CAP_0402-0.22UF,16V,10%,X7R,A3A
     1 P3E_CPU1_PE3_MP_C_TXN<2> @BASEBOARD_FAB2_LIB.BASEBOARD_FAB2(SCH_1):P3E_CPU1_PE3_MP_C_TXN(2)    I78 @BASEBOARD_FAB2_LIB.BASEBOARD_FAB2(SCH_1):PAGE181
     2 P3E_CPU1_PE3_MP_TXN<2> @BASEBOARD_FAB2_LIB.BASEBOARD_FAB2(SCH_1):P3E_CPU1_PE3_MP_TXN(2)    I78 @BASEBOARD_FAB2_LIB.BASEBOARD_FAB2(SCH_1):PAGE181

C1F16 CAP_0402-0.22UF,16V,10%,X7R,A3A
     1 P3E_CPU1_PE3_MP_C_TXN<1> @BASEBOARD_FAB2_LIB.BASEBOARD_FAB2(SCH_1):P3E_CPU1_PE3_MP_C_TXN(1)    I79 @BASEBOARD_FAB2_LIB.BASEBOARD_FAB2(SCH_1):PAGE181
     2 P3E_CPU1_PE3_MP_TXN<1> @BASEBOARD_FAB2_LIB.BASEBOARD_FAB2(SCH_1):P3E_CPU1_PE3_MP_TXN(1)    I79 @BASEBOARD_FAB2_LIB.BASEBOARD_FAB2(SCH_1):PAGE181

C1F17 CAP_0402-0.22UF,16V,10%,X7R,A3A
     1 P3E_CPU1_PE3_MP_C_TXP<1> @BASEBOARD_FAB2_LIB.BASEBOARD_FAB2(SCH_1):P3E_CPU1_PE3_MP_C_TXP(1)    I71 @BASEBOARD_FAB2_LIB.BASEBOARD_FAB2(SCH_1):PAGE181
     2 P3E_CPU1_PE3_MP_TXP<1> @BASEBOARD_FAB2_LIB.BASEBOARD_FAB2(SCH_1):P3E_CPU1_PE3_MP_TXP(1)    I71 @BASEBOARD_FAB2_LIB.BASEBOARD_FAB2(SCH_1):PAGE181

C1F18 CAP_0402-0.22UF,16V,10%,X7R,A3A
     1 P3E_CPU1_PE3_MP_C_TXP<0> @BASEBOARD_FAB2_LIB.BASEBOARD_FAB2(SCH_1):P3E_CPU1_PE3_MP_C_TXP(0)    I72 @BASEBOARD_FAB2_LIB.BASEBOARD_FAB2(SCH_1):PAGE181
     2 P3E_CPU1_PE3_MP_TXP<0> @BASEBOARD_FAB2_LIB.BASEBOARD_FAB2(SCH_1):P3E_CPU1_PE3_MP_TXP(0)    I72 @BASEBOARD_FAB2_LIB.BASEBOARD_FAB2(SCH_1):PAGE181

C1F19 CAP_A_0402V-0.01UF,25V,10%,X7RA
     1 M_G_CPU_VREF @BASEBOARD_FAB2_LIB.BASEBOARD_FAB2(SCH_1):M_G_CPU_VREF     I8 @BASEBOARD_FAB2_LIB.BASEBOARD_FAB2(SCH_1):PAGE100
     2    GND @BASEBOARD_FAB2_LIB.BASEBOARD_FAB2(SCH_1):GND     I8 @BASEBOARD_FAB2_LIB.BASEBOARD_FAB2(SCH_1):PAGE100

C1F20 CAP_0402-0.22UF,16V,10%,X7R,A3A
     1 P3E_CPU1_PE3_MP_C_TXN<0> @BASEBOARD_FAB2_LIB.BASEBOARD_FAB2(SCH_1):P3E_CPU1_PE3_MP_C_TXN(0)    I86 @BASEBOARD_FAB2_LIB.BASEBOARD_FAB2(SCH_1):PAGE181
     2 P3E_CPU1_PE3_MP_TXN<0> @BASEBOARD_FAB2_LIB.BASEBOARD_FAB2(SCH_1):P3E_CPU1_PE3_MP_TXN(0)    I86 @BASEBOARD_FAB2_LIB.BASEBOARD_FAB2(SCH_1):PAGE181

C1F21 SC1U10V2KX-4-GP_SMD-BCG6-SC1U1A
     1 P5V_STBY @BASEBOARD_FAB2_LIB.BASEBOARD_FAB2(SCH_1):P5V_STBY   I154 @BASEBOARD_FAB2_LIB.BASEBOARD_FAB2(SCH_1):PAGE224
     2    GND @BASEBOARD_FAB2_LIB.BASEBOARD_FAB2(SCH_1):GND   I154 @BASEBOARD_FAB2_LIB.BASEBOARD_FAB2(SCH_1):PAGE224

C1F22 CAP_A_0402V-0.01UF,25V,10%,X7RA
     1 M_G_VREF @BASEBOARD_FAB2_LIB.BASEBOARD_FAB2(SCH_1):M_G_VREF   I181 @BASEBOARD_FAB2_LIB.BASEBOARD_FAB2(SCH_1):PAGE77
     2    GND @BASEBOARD_FAB2_LIB.BASEBOARD_FAB2(SCH_1):GND   I181 @BASEBOARD_FAB2_LIB.BASEBOARD_FAB2(SCH_1):PAGE77

C1F26 CAP_0402-0.220UF,16V,10%,X7R,AA
     1 VR_PVDDQ_GHJ_PH2_BOOT @BASEBOARD_FAB2_LIB.BASEBOARD_FAB2(SCH_1):VR_PVDDQ_GHJ_PH2_BOOT    I75 @BASEBOARD_FAB2_LIB.BASEBOARD_FAB2(SCH_1):PAGE224
     2 VR_PVDDQ_GHJ_PH2_PHASE @BASEBOARD_FAB2_LIB.BASEBOARD_FAB2(SCH_1):VR_PVDDQ_GHJ_PH2_PHASE    I75 @BASEBOARD_FAB2_LIB.BASEBOARD_FAB2(SCH_1):PAGE224

C1F27 CAP_0402-1.0UF,16V,10%,X6S,D97A
     1 VR_FET_SW_P12V_STBY_PVDDQ_GHJ @BASEBOARD_FAB2_LIB.BASEBOARD_FAB2(SCH_1):VR_FET_SW_P12V_STBY_PVDDQ_GHJ    I48 @BASEBOARD_FAB2_LIB.BASEBOARD_FAB2(SCH_1):PAGE224
     2    GND @BASEBOARD_FAB2_LIB.BASEBOARD_FAB2(SCH_1):GND    I48 @BASEBOARD_FAB2_LIB.BASEBOARD_FAB2(SCH_1):PAGE224

C1F28 CAP_A_0402V-0.1UF,16V,10%,X7R,A
     1 VR_FET_SW_P12V_STBY_PVDDQ_GHJ @BASEBOARD_FAB2_LIB.BASEBOARD_FAB2(SCH_1):VR_FET_SW_P12V_STBY_PVDDQ_GHJ    I78 @BASEBOARD_FAB2_LIB.BASEBOARD_FAB2(SCH_1):PAGE224
     2    GND @BASEBOARD_FAB2_LIB.BASEBOARD_FAB2(SCH_1):GND    I78 @BASEBOARD_FAB2_LIB.BASEBOARD_FAB2(SCH_1):PAGE224

C1G2 SC22U16V5MX-4-GP_SMD-BCG5-SC22A
     1 VR_FET_SW_P12V_STBY_PVDDQ_GHJ @BASEBOARD_FAB2_LIB.BASEBOARD_FAB2(SCH_1):VR_FET_SW_P12V_STBY_PVDDQ_GHJ   I250 @BASEBOARD_FAB2_LIB.BASEBOARD_FAB2(SCH_1):PAGE225
     2    GND @BASEBOARD_FAB2_LIB.BASEBOARD_FAB2(SCH_1):GND   I250 @BASEBOARD_FAB2_LIB.BASEBOARD_FAB2(SCH_1):PAGE225

C1G4 SC1U10V2KX-4-GP_SMD-BCG6-SC1U1A
     1 P5V_STBY @BASEBOARD_FAB2_LIB.BASEBOARD_FAB2(SCH_1):P5V_STBY   I155 @BASEBOARD_FAB2_LIB.BASEBOARD_FAB2(SCH_1):PAGE224
     2    GND @BASEBOARD_FAB2_LIB.BASEBOARD_FAB2(SCH_1):GND   I155 @BASEBOARD_FAB2_LIB.BASEBOARD_FAB2(SCH_1):PAGE224

C1G5 CAP_0402-0.22UF,16V,10%,X7R,A3A
     1 P5V_STBY @BASEBOARD_FAB2_LIB.BASEBOARD_FAB2(SCH_1):P5V_STBY    I54 @BASEBOARD_FAB2_LIB.BASEBOARD_FAB2(SCH_1):PAGE224
     2    GND @BASEBOARD_FAB2_LIB.BASEBOARD_FAB2(SCH_1):GND    I54 @BASEBOARD_FAB2_LIB.BASEBOARD_FAB2(SCH_1):PAGE224

C1G6 CAP_0402-1.0UF,16V,10%,X6S,D97A
     1 VR_PVDDQ_GHJ_PH1_VCIN @BASEBOARD_FAB2_LIB.BASEBOARD_FAB2(SCH_1):VR_PVDDQ_GHJ_PH1_VCIN    I50 @BASEBOARD_FAB2_LIB.BASEBOARD_FAB2(SCH_1):PAGE224
     2    GND @BASEBOARD_FAB2_LIB.BASEBOARD_FAB2(SCH_1):GND    I50 @BASEBOARD_FAB2_LIB.BASEBOARD_FAB2(SCH_1):PAGE224

C1G7 ST270U2D5VBM-GP_SMD-TCG2-ST270A
     1 VR_FET_SW_P12V_STBY_PVDDQ_GHJ @BASEBOARD_FAB2_LIB.BASEBOARD_FAB2(SCH_1):VR_FET_SW_P12V_STBY_PVDDQ_GHJ   I329 @BASEBOARD_FAB2_LIB.BASEBOARD_FAB2(SCH_1):PAGE225
     2    GND @BASEBOARD_FAB2_LIB.BASEBOARD_FAB2(SCH_1):GND   I329 @BASEBOARD_FAB2_LIB.BASEBOARD_FAB2(SCH_1):PAGE225

C1G8 CAP_A_0402V-0.01UF,25V,10%,X7RA
     1 M_H_CPU_VREF @BASEBOARD_FAB2_LIB.BASEBOARD_FAB2(SCH_1):M_H_CPU_VREF    I26 @BASEBOARD_FAB2_LIB.BASEBOARD_FAB2(SCH_1):PAGE100
     2    GND @BASEBOARD_FAB2_LIB.BASEBOARD_FAB2(SCH_1):GND    I26 @BASEBOARD_FAB2_LIB.BASEBOARD_FAB2(SCH_1):PAGE100

C1G10 CAP_A_0402V-0.01UF,25V,10%,X7RA
     1 M_H_VREF @BASEBOARD_FAB2_LIB.BASEBOARD_FAB2(SCH_1):M_H_VREF     I3 @BASEBOARD_FAB2_LIB.BASEBOARD_FAB2(SCH_1):PAGE80
     2    GND @BASEBOARD_FAB2_LIB.BASEBOARD_FAB2(SCH_1):GND     I3 @BASEBOARD_FAB2_LIB.BASEBOARD_FAB2(SCH_1):PAGE80

C1G11 CAP_0402-0.220UF,16V,10%,X7R,AA
     1 VR_PVDDQ_GHJ_PH1_BOOT @BASEBOARD_FAB2_LIB.BASEBOARD_FAB2(SCH_1):VR_PVDDQ_GHJ_PH1_BOOT    I44 @BASEBOARD_FAB2_LIB.BASEBOARD_FAB2(SCH_1):PAGE224
     2 VR_PVDDQ_GHJ_PH1_PHASE @BASEBOARD_FAB2_LIB.BASEBOARD_FAB2(SCH_1):VR_PVDDQ_GHJ_PH1_PHASE    I44 @BASEBOARD_FAB2_LIB.BASEBOARD_FAB2(SCH_1):PAGE224

C1G12 ST270U2D5VBM-GP_SMD-TCG2-ST270A
     1 VR_FET_SW_P12V_STBY_PVDDQ_GHJ @BASEBOARD_FAB2_LIB.BASEBOARD_FAB2(SCH_1):VR_FET_SW_P12V_STBY_PVDDQ_GHJ   I328 @BASEBOARD_FAB2_LIB.BASEBOARD_FAB2(SCH_1):PAGE225
     2    GND @BASEBOARD_FAB2_LIB.BASEBOARD_FAB2(SCH_1):GND   I328 @BASEBOARD_FAB2_LIB.BASEBOARD_FAB2(SCH_1):PAGE225

C1G13 CAP_0402-1.0UF,16V,10%,X6S,D97A
     1 VR_FET_SW_P12V_STBY_PVDDQ_GHJ @BASEBOARD_FAB2_LIB.BASEBOARD_FAB2(SCH_1):VR_FET_SW_P12V_STBY_PVDDQ_GHJ    I79 @BASEBOARD_FAB2_LIB.BASEBOARD_FAB2(SCH_1):PAGE224
     2    GND @BASEBOARD_FAB2_LIB.BASEBOARD_FAB2(SCH_1):GND    I79 @BASEBOARD_FAB2_LIB.BASEBOARD_FAB2(SCH_1):PAGE224

C1G14 CAP_A_0402V-0.1UF,16V,10%,X7R,A
     1 VR_FET_SW_P12V_STBY_PVDDQ_GHJ @BASEBOARD_FAB2_LIB.BASEBOARD_FAB2(SCH_1):VR_FET_SW_P12V_STBY_PVDDQ_GHJ    I51 @BASEBOARD_FAB2_LIB.BASEBOARD_FAB2(SCH_1):PAGE224
     2    GND @BASEBOARD_FAB2_LIB.BASEBOARD_FAB2(SCH_1):GND    I51 @BASEBOARD_FAB2_LIB.BASEBOARD_FAB2(SCH_1):PAGE224

C1G15 ST270U2D5VBM-GP_SMD-TCG2-ST270A
     1 VR_FET_SW_P12V_STBY_PVDDQ_GHJ @BASEBOARD_FAB2_LIB.BASEBOARD_FAB2(SCH_1):VR_FET_SW_P12V_STBY_PVDDQ_GHJ   I327 @BASEBOARD_FAB2_LIB.BASEBOARD_FAB2(SCH_1):PAGE225
     2    GND @BASEBOARD_FAB2_LIB.BASEBOARD_FAB2(SCH_1):GND   I327 @BASEBOARD_FAB2_LIB.BASEBOARD_FAB2(SCH_1):PAGE225

C1G16 CAP_0402LF-220PF,50V,10%,X7R,AA
     1 VR_PVDDQ_GHJ_AVSP @BASEBOARD_FAB2_LIB.BASEBOARD_FAB2(SCH_1):VR_PVDDQ_GHJ_AVSP    I12 @BASEBOARD_FAB2_LIB.BASEBOARD_FAB2(SCH_1):PAGE223
     2 VSENSE_PVDDQ_GHJ_N @BASEBOARD_FAB2_LIB.BASEBOARD_FAB2(SCH_1):VSENSE_PVDDQ_GHJ_N    I12 @BASEBOARD_FAB2_LIB.BASEBOARD_FAB2(SCH_1):PAGE223

C1G17 CAP_0805LF-22UF,4V,20%,X6S,C95A
     1 PVDDQ_GHJ @BASEBOARD_FAB2_LIB.BASEBOARD_FAB2(SCH_1):PVDDQ_GHJ     I6 @BASEBOARD_FAB2_LIB.BASEBOARD_FAB2(SCH_1):PAGE224
     2    GND @BASEBOARD_FAB2_LIB.BASEBOARD_FAB2(SCH_1):GND     I6 @BASEBOARD_FAB2_LIB.BASEBOARD_FAB2(SCH_1):PAGE224

C1G18 CAP_A_0402V-0.01UF,25V,10%,X7RA
     1 M_J_CPU_VREF @BASEBOARD_FAB2_LIB.BASEBOARD_FAB2(SCH_1):M_J_CPU_VREF    I42 @BASEBOARD_FAB2_LIB.BASEBOARD_FAB2(SCH_1):PAGE100
     2    GND @BASEBOARD_FAB2_LIB.BASEBOARD_FAB2(SCH_1):GND    I42 @BASEBOARD_FAB2_LIB.BASEBOARD_FAB2(SCH_1):PAGE100

C1G19 CAP_A_0402V-0.01UF,25V,10%,X7RA
     1 M_J_VREF @BASEBOARD_FAB2_LIB.BASEBOARD_FAB2(SCH_1):M_J_VREF   I180 @BASEBOARD_FAB2_LIB.BASEBOARD_FAB2(SCH_1):PAGE82
     2    GND @BASEBOARD_FAB2_LIB.BASEBOARD_FAB2(SCH_1):GND   I180 @BASEBOARD_FAB2_LIB.BASEBOARD_FAB2(SCH_1):PAGE82

C1G20 CAP_0805LF-22UF,4V,20%,X6S,C95A
     1 PVDDQ_GHJ @BASEBOARD_FAB2_LIB.BASEBOARD_FAB2(SCH_1):PVDDQ_GHJ    I68 @BASEBOARD_FAB2_LIB.BASEBOARD_FAB2(SCH_1):PAGE224
     2    GND @BASEBOARD_FAB2_LIB.BASEBOARD_FAB2(SCH_1):GND    I68 @BASEBOARD_FAB2_LIB.BASEBOARD_FAB2(SCH_1):PAGE224

C1G21 CAP_0402LF-1000PF,50V,10%,X7R,A
     1 PWRGD_PVDDQ_GHJ_R @BASEBOARD_FAB2_LIB.BASEBOARD_FAB2(SCH_1):PWRGD_PVDDQ_GHJ_R    I40 @BASEBOARD_FAB2_LIB.BASEBOARD_FAB2(SCH_1):PAGE223
     2    GND @BASEBOARD_FAB2_LIB.BASEBOARD_FAB2(SCH_1):GND    I40 @BASEBOARD_FAB2_LIB.BASEBOARD_FAB2(SCH_1):PAGE223

C1G22 CAP_A_0402V-0.1UF,16V,10%,X7R,A
     1 VR_PVDDQ_GHJ_VD12 @BASEBOARD_FAB2_LIB.BASEBOARD_FAB2(SCH_1):VR_PVDDQ_GHJ_VD12    I43 @BASEBOARD_FAB2_LIB.BASEBOARD_FAB2(SCH_1):PAGE223
     2    GND @BASEBOARD_FAB2_LIB.BASEBOARD_FAB2(SCH_1):GND    I43 @BASEBOARD_FAB2_LIB.BASEBOARD_FAB2(SCH_1):PAGE223

C1G23 CAP_A_0402V-1.0UF,6.3V,10%,X6SA
     1 VR_PVDDQ_GHJ_VD12 @BASEBOARD_FAB2_LIB.BASEBOARD_FAB2(SCH_1):VR_PVDDQ_GHJ_VD12    I44 @BASEBOARD_FAB2_LIB.BASEBOARD_FAB2(SCH_1):PAGE223
     2    GND @BASEBOARD_FAB2_LIB.BASEBOARD_FAB2(SCH_1):GND    I44 @BASEBOARD_FAB2_LIB.BASEBOARD_FAB2(SCH_1):PAGE223

C1G24 CAP_0402LF-220PF,50V,10%,X7R,AA
     1 A_TSENSE_PVDDQ_GHJ @BASEBOARD_FAB2_LIB.BASEBOARD_FAB2(SCH_1):A_TSENSE_PVDDQ_GHJ    I27 @BASEBOARD_FAB2_LIB.BASEBOARD_FAB2(SCH_1):PAGE223
     2    GND @BASEBOARD_FAB2_LIB.BASEBOARD_FAB2(SCH_1):GND    I27 @BASEBOARD_FAB2_LIB.BASEBOARD_FAB2(SCH_1):PAGE223

C1G25 CAP_A_0402V-0.1UF,16V,10%,X7R,A
     1 VR_PVDDQ_GHJ_VDD @BASEBOARD_FAB2_LIB.BASEBOARD_FAB2(SCH_1):VR_PVDDQ_GHJ_VDD    I35 @BASEBOARD_FAB2_LIB.BASEBOARD_FAB2(SCH_1):PAGE223
     2    GND @BASEBOARD_FAB2_LIB.BASEBOARD_FAB2(SCH_1):GND    I35 @BASEBOARD_FAB2_LIB.BASEBOARD_FAB2(SCH_1):PAGE223

C1G27 CAP_A_0402V-1.0UF,6.3V,10%,X6SA
     1 VR_PVDDQ_GHJ_VDD @BASEBOARD_FAB2_LIB.BASEBOARD_FAB2(SCH_1):VR_PVDDQ_GHJ_VDD    I36 @BASEBOARD_FAB2_LIB.BASEBOARD_FAB2(SCH_1):PAGE223
     2    GND @BASEBOARD_FAB2_LIB.BASEBOARD_FAB2(SCH_1):GND    I36 @BASEBOARD_FAB2_LIB.BASEBOARD_FAB2(SCH_1):PAGE223

C1G28 CAP_0402-1.0UF,16V,10%,X6S,D97A
     1 VR_PVDDQ_GHJ_PH2_VCIN @BASEBOARD_FAB2_LIB.BASEBOARD_FAB2(SCH_1):VR_PVDDQ_GHJ_PH2_VCIN    I77 @BASEBOARD_FAB2_LIB.BASEBOARD_FAB2(SCH_1):PAGE224
     2    GND @BASEBOARD_FAB2_LIB.BASEBOARD_FAB2(SCH_1):GND    I77 @BASEBOARD_FAB2_LIB.BASEBOARD_FAB2(SCH_1):PAGE224

C1G29 CAP_0402-0.22UF,16V,10%,X7R,A3A
     1 P5V_STBY @BASEBOARD_FAB2_LIB.BASEBOARD_FAB2(SCH_1):P5V_STBY    I72 @BASEBOARD_FAB2_LIB.BASEBOARD_FAB2(SCH_1):PAGE224
     2    GND @BASEBOARD_FAB2_LIB.BASEBOARD_FAB2(SCH_1):GND    I72 @BASEBOARD_FAB2_LIB.BASEBOARD_FAB2(SCH_1):PAGE224

C1L1 CAP_0402-1.0UF,16V,10%,X6S,D97A
     1 P3V3_STBY @BASEBOARD_FAB2_LIB.BASEBOARD_FAB2(SCH_1):P3V3_STBY   I136 @BASEBOARD_FAB2_LIB.BASEBOARD_FAB2(SCH_1):PAGE112
     2    GND @BASEBOARD_FAB2_LIB.BASEBOARD_FAB2(SCH_1):GND   I136 @BASEBOARD_FAB2_LIB.BASEBOARD_FAB2(SCH_1):PAGE112

C1L4 CAP_A_0402V-0.1UF,16V,10%,X7R,A
     1 P5V_STBY @BASEBOARD_FAB2_LIB.BASEBOARD_FAB2(SCH_1):P5V_STBY    I64 @BASEBOARD_FAB2_LIB.BASEBOARD_FAB2(SCH_1):PAGE175
     2    GND @BASEBOARD_FAB2_LIB.BASEBOARD_FAB2(SCH_1):GND    I64 @BASEBOARD_FAB2_LIB.BASEBOARD_FAB2(SCH_1):PAGE175

C1L5 CAP_A_0402V-1.0UF,6.3V,10%,X6SA
     1 P1V05_PCH_STBY @BASEBOARD_FAB2_LIB.BASEBOARD_FAB2(SCH_1):P1V05_PCH_STBY    I30 @BASEBOARD_FAB2_LIB.BASEBOARD_FAB2(SCH_1):PAGE111
     2    GND @BASEBOARD_FAB2_LIB.BASEBOARD_FAB2(SCH_1):GND    I30 @BASEBOARD_FAB2_LIB.BASEBOARD_FAB2(SCH_1):PAGE111

C1L8 CAP_A_0402V-0.1UF,16V,10%,X7R,A
     1 XDP_PWRGD_RST_N @BASEBOARD_FAB2_LIB.BASEBOARD_FAB2(SCH_1):XDP_PWRGD_RST_N    I14 @BASEBOARD_FAB2_LIB.BASEBOARD_FAB2(SCH_1):PAGE111
     2    GND @BASEBOARD_FAB2_LIB.BASEBOARD_FAB2(SCH_1):GND    I14 @BASEBOARD_FAB2_LIB.BASEBOARD_FAB2(SCH_1):PAGE111

C1L9 CAP_A_0402V-0.1UF,16V,10%,X7R,A
     1 P3V3_STBY @BASEBOARD_FAB2_LIB.BASEBOARD_FAB2(SCH_1):P3V3_STBY    I38 @BASEBOARD_FAB2_LIB.BASEBOARD_FAB2(SCH_1):PAGE175
     2    GND @BASEBOARD_FAB2_LIB.BASEBOARD_FAB2(SCH_1):GND    I38 @BASEBOARD_FAB2_LIB.BASEBOARD_FAB2(SCH_1):PAGE175

C1L10 CAP_A_0402V-1.0UF,6.3V,10%,X6SA
     1 FP_RST_BTN_R_N @BASEBOARD_FAB2_LIB.BASEBOARD_FAB2(SCH_1):FP_RST_BTN_R_N    I19 @BASEBOARD_FAB2_LIB.BASEBOARD_FAB2(SCH_1):PAGE175
     2    GND @BASEBOARD_FAB2_LIB.BASEBOARD_FAB2(SCH_1):GND    I19 @BASEBOARD_FAB2_LIB.BASEBOARD_FAB2(SCH_1):PAGE175

C1L11 CAP_A_0402V-0.1UF,16V,10%,X7R,A
     1 P3V3_STBY @BASEBOARD_FAB2_LIB.BASEBOARD_FAB2(SCH_1):P3V3_STBY    I87 @BASEBOARD_FAB2_LIB.BASEBOARD_FAB2(SCH_1):PAGE111
     2    GND @BASEBOARD_FAB2_LIB.BASEBOARD_FAB2(SCH_1):GND    I87 @BASEBOARD_FAB2_LIB.BASEBOARD_FAB2(SCH_1):PAGE111

C1L16 CAP_A_0402V-0.1UF,16V,10%,X7R,A
     1   P3V3 @BASEBOARD_FAB2_LIB.BASEBOARD_FAB2(SCH_1):P3V3    I81 @BASEBOARD_FAB2_LIB.BASEBOARD_FAB2(SCH_1):PAGE196
     2    GND @BASEBOARD_FAB2_LIB.BASEBOARD_FAB2(SCH_1):GND    I81 @BASEBOARD_FAB2_LIB.BASEBOARD_FAB2(SCH_1):PAGE196

C1L17 CAP_A_0402V-0.1UF,16V,10%,X7R,A
     1 P3V3_STBY @BASEBOARD_FAB2_LIB.BASEBOARD_FAB2(SCH_1):P3V3_STBY    I37 @BASEBOARD_FAB2_LIB.BASEBOARD_FAB2(SCH_1):PAGE175
     2    GND @BASEBOARD_FAB2_LIB.BASEBOARD_FAB2(SCH_1):GND    I37 @BASEBOARD_FAB2_LIB.BASEBOARD_FAB2(SCH_1):PAGE175

C1L18 CAP_A_0402V-1.0UF,6.3V,10%,X6SA
     1 FP_PWR_BTN_R1_N @BASEBOARD_FAB2_LIB.BASEBOARD_FAB2(SCH_1):FP_PWR_BTN_R1_N    I11 @BASEBOARD_FAB2_LIB.BASEBOARD_FAB2(SCH_1):PAGE175
     2    GND @BASEBOARD_FAB2_LIB.BASEBOARD_FAB2(SCH_1):GND    I11 @BASEBOARD_FAB2_LIB.BASEBOARD_FAB2(SCH_1):PAGE175

C1L19 CAP_0402-1.0UF,16V,10%,X6S,D97A
     1 P3V3_STBY @BASEBOARD_FAB2_LIB.BASEBOARD_FAB2(SCH_1):P3V3_STBY   I140 @BASEBOARD_FAB2_LIB.BASEBOARD_FAB2(SCH_1):PAGE112
     2    GND @BASEBOARD_FAB2_LIB.BASEBOARD_FAB2(SCH_1):GND   I140 @BASEBOARD_FAB2_LIB.BASEBOARD_FAB2(SCH_1):PAGE112

C1L20 CAP_A_0402V-0.01UF,25V,10%,X7RA
     1 P3V3_STBY @BASEBOARD_FAB2_LIB.BASEBOARD_FAB2(SCH_1):P3V3_STBY   I267 @BASEBOARD_FAB2_LIB.BASEBOARD_FAB2(SCH_1):PAGE113
     2    GND @BASEBOARD_FAB2_LIB.BASEBOARD_FAB2(SCH_1):GND   I267 @BASEBOARD_FAB2_LIB.BASEBOARD_FAB2(SCH_1):PAGE113

C1L119 CAP_0402-1.0UF,16V,10%,X6S,D97A
     1 P3V3_STBY @BASEBOARD_FAB2_LIB.BASEBOARD_FAB2(SCH_1):P3V3_STBY    I69 @BASEBOARD_FAB2_LIB.BASEBOARD_FAB2(SCH_1):PAGE189
     2    GND @BASEBOARD_FAB2_LIB.BASEBOARD_FAB2(SCH_1):GND    I69 @BASEBOARD_FAB2_LIB.BASEBOARD_FAB2(SCH_1):PAGE189

C1M3 CAP_A_0402V-1.0UF,6.3V,10%,X6SA
     1   P3V3 @BASEBOARD_FAB2_LIB.BASEBOARD_FAB2(SCH_1):P3V3    I20 @BASEBOARD_FAB2_LIB.BASEBOARD_FAB2(SCH_1):PAGE177
     2    GND @BASEBOARD_FAB2_LIB.BASEBOARD_FAB2(SCH_1):GND    I20 @BASEBOARD_FAB2_LIB.BASEBOARD_FAB2(SCH_1):PAGE177

C1M4 CAP_0402LF-47.0PF,50V,5%,EMPTYA
     1 ISENSE_TMP421_1_DXP @BASEBOARD_FAB2_LIB.BASEBOARD_FAB2(SCH_1):ISENSE_TMP421_1_DXP     I7 @BASEBOARD_FAB2_LIB.BASEBOARD_FAB2(SCH_1):PAGE167
     2 ISENSE_TMP421_1_DXN @BASEBOARD_FAB2_LIB.BASEBOARD_FAB2(SCH_1):ISENSE_TMP421_1_DXN     I7 @BASEBOARD_FAB2_LIB.BASEBOARD_FAB2(SCH_1):PAGE167

C1M5 CAPP_3018-68UF,16V,20%,TANT,72A
     1 P12V_STBY @BASEBOARD_FAB2_LIB.BASEBOARD_FAB2(SCH_1):P12V_STBY   I103 @BASEBOARD_FAB2_LIB.BASEBOARD_FAB2(SCH_1):PAGE195
     2    GND @BASEBOARD_FAB2_LIB.BASEBOARD_FAB2(SCH_1):GND   I103 @BASEBOARD_FAB2_LIB.BASEBOARD_FAB2(SCH_1):PAGE195

C1M6 CAP_0402-0.22UF,16V,10%,X7R,A3A
     1 P3E_CPU0_PE3_OCP_TXP<15> @BASEBOARD_FAB2_LIB.BASEBOARD_FAB2(SCH_1):P3E_CPU0_PE3_OCP_TXP(15)   I109 @BASEBOARD_FAB2_LIB.BASEBOARD_FAB2(SCH_1):PAGE106
     2 P3E_OCP_CPU0_PE3_C_TXP<15> @BASEBOARD_FAB2_LIB.BASEBOARD_FAB2(SCH_1):P3E_OCP_CPU0_PE3_C_TXP(15)   I109 @BASEBOARD_FAB2_LIB.BASEBOARD_FAB2(SCH_1):PAGE106

C1M7 CAP_0402-0.22UF,16V,10%,X7R,A3A
     1 P3E_CPU0_PE3_OCP_TXN<15> @BASEBOARD_FAB2_LIB.BASEBOARD_FAB2(SCH_1):P3E_CPU0_PE3_OCP_TXN(15)   I122 @BASEBOARD_FAB2_LIB.BASEBOARD_FAB2(SCH_1):PAGE106
     2 P3E_OCP_CPU0_PE3_C_TXN<15> @BASEBOARD_FAB2_LIB.BASEBOARD_FAB2(SCH_1):P3E_OCP_CPU0_PE3_C_TXN(15)   I122 @BASEBOARD_FAB2_LIB.BASEBOARD_FAB2(SCH_1):PAGE106

C1M8 CAP_0402-0.22UF,16V,10%,X7R,A3A
     1 P3E_CPU0_PE3_OCP_TXP<14> @BASEBOARD_FAB2_LIB.BASEBOARD_FAB2(SCH_1):P3E_CPU0_PE3_OCP_TXP(14)   I105 @BASEBOARD_FAB2_LIB.BASEBOARD_FAB2(SCH_1):PAGE106
     2 P3E_OCP_CPU0_PE3_C_TXP<14> @BASEBOARD_FAB2_LIB.BASEBOARD_FAB2(SCH_1):P3E_OCP_CPU0_PE3_C_TXP(14)   I105 @BASEBOARD_FAB2_LIB.BASEBOARD_FAB2(SCH_1):PAGE106

C1M9 CAP_0402-0.22UF,16V,10%,X7R,A3A
     1 P3E_CPU0_PE3_OCP_TXN<14> @BASEBOARD_FAB2_LIB.BASEBOARD_FAB2(SCH_1):P3E_CPU0_PE3_OCP_TXN(14)   I114 @BASEBOARD_FAB2_LIB.BASEBOARD_FAB2(SCH_1):PAGE106
     2 P3E_OCP_CPU0_PE3_C_TXN<14> @BASEBOARD_FAB2_LIB.BASEBOARD_FAB2(SCH_1):P3E_OCP_CPU0_PE3_C_TXN(14)   I114 @BASEBOARD_FAB2_LIB.BASEBOARD_FAB2(SCH_1):PAGE106

C1M10 CAP_0402-0.22UF,16V,10%,X7R,A3A
     1 P3E_CPU0_PE3_OCP_TXP<13> @BASEBOARD_FAB2_LIB.BASEBOARD_FAB2(SCH_1):P3E_CPU0_PE3_OCP_TXP(13)   I102 @BASEBOARD_FAB2_LIB.BASEBOARD_FAB2(SCH_1):PAGE106
     2 P3E_OCP_CPU0_PE3_C_TXP<13> @BASEBOARD_FAB2_LIB.BASEBOARD_FAB2(SCH_1):P3E_OCP_CPU0_PE3_C_TXP(13)   I102 @BASEBOARD_FAB2_LIB.BASEBOARD_FAB2(SCH_1):PAGE106

C1M11 CAP_0402-0.22UF,16V,10%,X7R,A3A
     1 P3E_CPU0_PE3_OCP_TXN<13> @BASEBOARD_FAB2_LIB.BASEBOARD_FAB2(SCH_1):P3E_CPU0_PE3_OCP_TXN(13)   I117 @BASEBOARD_FAB2_LIB.BASEBOARD_FAB2(SCH_1):PAGE106
     2 P3E_OCP_CPU0_PE3_C_TXN<13> @BASEBOARD_FAB2_LIB.BASEBOARD_FAB2(SCH_1):P3E_OCP_CPU0_PE3_C_TXN(13)   I117 @BASEBOARD_FAB2_LIB.BASEBOARD_FAB2(SCH_1):PAGE106

C1M12 CAP_0402-0.22UF,16V,10%,X7R,A3A
     1 P3E_CPU0_PE3_OCP_TXP<12> @BASEBOARD_FAB2_LIB.BASEBOARD_FAB2(SCH_1):P3E_CPU0_PE3_OCP_TXP(12)   I100 @BASEBOARD_FAB2_LIB.BASEBOARD_FAB2(SCH_1):PAGE106
     2 P3E_OCP_CPU0_PE3_C_TXP<12> @BASEBOARD_FAB2_LIB.BASEBOARD_FAB2(SCH_1):P3E_OCP_CPU0_PE3_C_TXP(12)   I100 @BASEBOARD_FAB2_LIB.BASEBOARD_FAB2(SCH_1):PAGE106

C1M13 CAP_0402-0.22UF,16V,10%,X7R,A3A
     1 P3E_CPU0_PE3_OCP_TXN<12> @BASEBOARD_FAB2_LIB.BASEBOARD_FAB2(SCH_1):P3E_CPU0_PE3_OCP_TXN(12)   I111 @BASEBOARD_FAB2_LIB.BASEBOARD_FAB2(SCH_1):PAGE106
     2 P3E_OCP_CPU0_PE3_C_TXN<12> @BASEBOARD_FAB2_LIB.BASEBOARD_FAB2(SCH_1):P3E_OCP_CPU0_PE3_C_TXN(12)   I111 @BASEBOARD_FAB2_LIB.BASEBOARD_FAB2(SCH_1):PAGE106

C1M14 CAP_0402-0.22UF,16V,10%,X7R,A3A
     1 P3E_CPU0_PE3_OCP_TXP<11> @BASEBOARD_FAB2_LIB.BASEBOARD_FAB2(SCH_1):P3E_CPU0_PE3_OCP_TXP(11)    I85 @BASEBOARD_FAB2_LIB.BASEBOARD_FAB2(SCH_1):PAGE106
     2 P3E_OCP_CPU0_PE3_C_TXP<11> @BASEBOARD_FAB2_LIB.BASEBOARD_FAB2(SCH_1):P3E_OCP_CPU0_PE3_C_TXP(11)    I85 @BASEBOARD_FAB2_LIB.BASEBOARD_FAB2(SCH_1):PAGE106

C1M15 CAP_0402-0.22UF,16V,10%,X7R,A3A
     1 P3E_CPU0_PE3_OCP_TXN<11> @BASEBOARD_FAB2_LIB.BASEBOARD_FAB2(SCH_1):P3E_CPU0_PE3_OCP_TXN(11)    I95 @BASEBOARD_FAB2_LIB.BASEBOARD_FAB2(SCH_1):PAGE106
     2 P3E_OCP_CPU0_PE3_C_TXN<11> @BASEBOARD_FAB2_LIB.BASEBOARD_FAB2(SCH_1):P3E_OCP_CPU0_PE3_C_TXN(11)    I95 @BASEBOARD_FAB2_LIB.BASEBOARD_FAB2(SCH_1):PAGE106

C1M16 CAP_0402-0.22UF,16V,10%,X7R,A3A
     1 P3E_CPU0_PE3_OCP_TXP<10> @BASEBOARD_FAB2_LIB.BASEBOARD_FAB2(SCH_1):P3E_CPU0_PE3_OCP_TXP(10)    I82 @BASEBOARD_FAB2_LIB.BASEBOARD_FAB2(SCH_1):PAGE106
     2 P3E_OCP_CPU0_PE3_C_TXP<10> @BASEBOARD_FAB2_LIB.BASEBOARD_FAB2(SCH_1):P3E_OCP_CPU0_PE3_C_TXP(10)    I82 @BASEBOARD_FAB2_LIB.BASEBOARD_FAB2(SCH_1):PAGE106

C1M17 CAP_0402-0.22UF,16V,10%,X7R,A3A
     1 P3E_CPU0_PE3_OCP_TXN<10> @BASEBOARD_FAB2_LIB.BASEBOARD_FAB2(SCH_1):P3E_CPU0_PE3_OCP_TXN(10)    I92 @BASEBOARD_FAB2_LIB.BASEBOARD_FAB2(SCH_1):PAGE106
     2 P3E_OCP_CPU0_PE3_C_TXN<10> @BASEBOARD_FAB2_LIB.BASEBOARD_FAB2(SCH_1):P3E_OCP_CPU0_PE3_C_TXN(10)    I92 @BASEBOARD_FAB2_LIB.BASEBOARD_FAB2(SCH_1):PAGE106

C1M18 CAP_0402-0.22UF,16V,10%,X7R,A3A
     1 P3E_CPU0_PE3_OCP_TXP<9> @BASEBOARD_FAB2_LIB.BASEBOARD_FAB2(SCH_1):P3E_CPU0_PE3_OCP_TXP(9)    I78 @BASEBOARD_FAB2_LIB.BASEBOARD_FAB2(SCH_1):PAGE106
     2 P3E_OCP_CPU0_PE3_C_TXP<9> @BASEBOARD_FAB2_LIB.BASEBOARD_FAB2(SCH_1):P3E_OCP_CPU0_PE3_C_TXP(9)    I78 @BASEBOARD_FAB2_LIB.BASEBOARD_FAB2(SCH_1):PAGE106

C1M19 CAP_0402-0.22UF,16V,10%,X7R,A3A
     1 P3E_CPU0_PE3_OCP_TXN<9> @BASEBOARD_FAB2_LIB.BASEBOARD_FAB2(SCH_1):P3E_CPU0_PE3_OCP_TXN(9)    I90 @BASEBOARD_FAB2_LIB.BASEBOARD_FAB2(SCH_1):PAGE106
     2 P3E_OCP_CPU0_PE3_C_TXN<9> @BASEBOARD_FAB2_LIB.BASEBOARD_FAB2(SCH_1):P3E_OCP_CPU0_PE3_C_TXN(9)    I90 @BASEBOARD_FAB2_LIB.BASEBOARD_FAB2(SCH_1):PAGE106

C1M20 CAP_A_0402V-0.1UF,16V,10%,X7R,A
     1 P3V3_STBY @BASEBOARD_FAB2_LIB.BASEBOARD_FAB2(SCH_1):P3V3_STBY   I270 @BASEBOARD_FAB2_LIB.BASEBOARD_FAB2(SCH_1):PAGE186
     2    GND @BASEBOARD_FAB2_LIB.BASEBOARD_FAB2(SCH_1):GND   I270 @BASEBOARD_FAB2_LIB.BASEBOARD_FAB2(SCH_1):PAGE186

C1M21 CAP_A_0402V-1.0UF,6.3V,10%,X6SA
     1   P3V3 @BASEBOARD_FAB2_LIB.BASEBOARD_FAB2(SCH_1):P3V3   I334 @BASEBOARD_FAB2_LIB.BASEBOARD_FAB2(SCH_1):PAGE186
     2    GND @BASEBOARD_FAB2_LIB.BASEBOARD_FAB2(SCH_1):GND   I334 @BASEBOARD_FAB2_LIB.BASEBOARD_FAB2(SCH_1):PAGE186

C1M22 CAP_A_0402V-0.1UF,16V,10%,X7R,A
     1 P12V_STBY @BASEBOARD_FAB2_LIB.BASEBOARD_FAB2(SCH_1):P12V_STBY     I8 @BASEBOARD_FAB2_LIB.BASEBOARD_FAB2(SCH_1):PAGE186
     2    GND @BASEBOARD_FAB2_LIB.BASEBOARD_FAB2(SCH_1):GND     I8 @BASEBOARD_FAB2_LIB.BASEBOARD_FAB2(SCH_1):PAGE186

C1M23 CAP_A_0402V-0.1UF,16V,10%,X7R,A
     1 P12V_STBY @BASEBOARD_FAB2_LIB.BASEBOARD_FAB2(SCH_1):P12V_STBY     I7 @BASEBOARD_FAB2_LIB.BASEBOARD_FAB2(SCH_1):PAGE186
     2    GND @BASEBOARD_FAB2_LIB.BASEBOARD_FAB2(SCH_1):GND     I7 @BASEBOARD_FAB2_LIB.BASEBOARD_FAB2(SCH_1):PAGE186

C1M24 CAP_A_0402V-0.1UF,16V,10%,X7R,A
     1   P3V3 @BASEBOARD_FAB2_LIB.BASEBOARD_FAB2(SCH_1):P3V3    I10 @BASEBOARD_FAB2_LIB.BASEBOARD_FAB2(SCH_1):PAGE186
     2    GND @BASEBOARD_FAB2_LIB.BASEBOARD_FAB2(SCH_1):GND    I10 @BASEBOARD_FAB2_LIB.BASEBOARD_FAB2(SCH_1):PAGE186

C1M25 CAP_A_0402V-1.0UF,6.3V,10%,X6SA
     1 P3V3_STBY @BASEBOARD_FAB2_LIB.BASEBOARD_FAB2(SCH_1):P3V3_STBY   I335 @BASEBOARD_FAB2_LIB.BASEBOARD_FAB2(SCH_1):PAGE186
     2    GND @BASEBOARD_FAB2_LIB.BASEBOARD_FAB2(SCH_1):GND   I335 @BASEBOARD_FAB2_LIB.BASEBOARD_FAB2(SCH_1):PAGE186

C1M26 CAP_0805-10UF,16V,10%,X6S,C953A
     1 P12V_STBY @BASEBOARD_FAB2_LIB.BASEBOARD_FAB2(SCH_1):P12V_STBY     I6 @BASEBOARD_FAB2_LIB.BASEBOARD_FAB2(SCH_1):PAGE186
     2    GND @BASEBOARD_FAB2_LIB.BASEBOARD_FAB2(SCH_1):GND     I6 @BASEBOARD_FAB2_LIB.BASEBOARD_FAB2(SCH_1):PAGE186

C1M27 CAP_0805-10UF,16V,10%,X6S,C953A
     1 P12V_STBY @BASEBOARD_FAB2_LIB.BASEBOARD_FAB2(SCH_1):P12V_STBY     I3 @BASEBOARD_FAB2_LIB.BASEBOARD_FAB2(SCH_1):PAGE186
     2    GND @BASEBOARD_FAB2_LIB.BASEBOARD_FAB2(SCH_1):GND     I3 @BASEBOARD_FAB2_LIB.BASEBOARD_FAB2(SCH_1):PAGE186

C1M28 CAP_A_0402V-0.01UF,25V,10%,X7RA
     1 P3V3_STBY @BASEBOARD_FAB2_LIB.BASEBOARD_FAB2(SCH_1):P3V3_STBY   I119 @BASEBOARD_FAB2_LIB.BASEBOARD_FAB2(SCH_1):PAGE113
     2    GND @BASEBOARD_FAB2_LIB.BASEBOARD_FAB2(SCH_1):GND   I119 @BASEBOARD_FAB2_LIB.BASEBOARD_FAB2(SCH_1):PAGE113

C1M29 CAP_A_0402V-0.1UF,16V,10%,X7R,A
     1 P1V8_MCP_CPU0 @BASEBOARD_FAB2_LIB.BASEBOARD_FAB2(SCH_1):P1V8_MCP_CPU0   I147 @BASEBOARD_FAB2_LIB.BASEBOARD_FAB2(SCH_1):PAGE113
     2    GND @BASEBOARD_FAB2_LIB.BASEBOARD_FAB2(SCH_1):GND   I147 @BASEBOARD_FAB2_LIB.BASEBOARD_FAB2(SCH_1):PAGE113

C1M30 CAP_A_0402V-0.01UF,25V,10%,X7RA
     1 P3V3_STBY @BASEBOARD_FAB2_LIB.BASEBOARD_FAB2(SCH_1):P3V3_STBY   I131 @BASEBOARD_FAB2_LIB.BASEBOARD_FAB2(SCH_1):PAGE112
     2    GND @BASEBOARD_FAB2_LIB.BASEBOARD_FAB2(SCH_1):GND   I131 @BASEBOARD_FAB2_LIB.BASEBOARD_FAB2(SCH_1):PAGE112

C1M31 CAP_A_0402V-0.01UF,25V,10%,X7RA
     1 P3V3_STBY @BASEBOARD_FAB2_LIB.BASEBOARD_FAB2(SCH_1):P3V3_STBY   I116 @BASEBOARD_FAB2_LIB.BASEBOARD_FAB2(SCH_1):PAGE113
     2    GND @BASEBOARD_FAB2_LIB.BASEBOARD_FAB2(SCH_1):GND   I116 @BASEBOARD_FAB2_LIB.BASEBOARD_FAB2(SCH_1):PAGE113

C1M32 CAP_A_0402V-1.0UF,6.3V,10%,X6SA
     1 P3V3_STBY @BASEBOARD_FAB2_LIB.BASEBOARD_FAB2(SCH_1):P3V3_STBY   I117 @BASEBOARD_FAB2_LIB.BASEBOARD_FAB2(SCH_1):PAGE113
     2    GND @BASEBOARD_FAB2_LIB.BASEBOARD_FAB2(SCH_1):GND   I117 @BASEBOARD_FAB2_LIB.BASEBOARD_FAB2(SCH_1):PAGE113

C1M33 CAP_A_0402V-0.1UF,16V,10%,X7R,A
     1 JTAG_MCP_TMS_R1 @BASEBOARD_FAB2_LIB.BASEBOARD_FAB2(SCH_1):JTAG_MCP_TMS_R1   I248 @BASEBOARD_FAB2_LIB.BASEBOARD_FAB2(SCH_1):PAGE113
     2    GND @BASEBOARD_FAB2_LIB.BASEBOARD_FAB2(SCH_1):GND   I248 @BASEBOARD_FAB2_LIB.BASEBOARD_FAB2(SCH_1):PAGE113

C1M34 CAP_A_0402V-0.01UF,25V,10%,X7RA
     1 P3V3_STBY @BASEBOARD_FAB2_LIB.BASEBOARD_FAB2(SCH_1):P3V3_STBY   I265 @BASEBOARD_FAB2_LIB.BASEBOARD_FAB2(SCH_1):PAGE113
     2    GND @BASEBOARD_FAB2_LIB.BASEBOARD_FAB2(SCH_1):GND   I265 @BASEBOARD_FAB2_LIB.BASEBOARD_FAB2(SCH_1):PAGE113

C1M35 CAP_A_0402V-0.01UF,25V,10%,X7RA
     1 P3V3_STBY @BASEBOARD_FAB2_LIB.BASEBOARD_FAB2(SCH_1):P3V3_STBY   I266 @BASEBOARD_FAB2_LIB.BASEBOARD_FAB2(SCH_1):PAGE113
     2    GND @BASEBOARD_FAB2_LIB.BASEBOARD_FAB2(SCH_1):GND   I266 @BASEBOARD_FAB2_LIB.BASEBOARD_FAB2(SCH_1):PAGE113

C1M36 CAP_A_0402V-0.01UF,25V,10%,X7RA
     1 P3V3_STBY @BASEBOARD_FAB2_LIB.BASEBOARD_FAB2(SCH_1):P3V3_STBY    I42 @BASEBOARD_FAB2_LIB.BASEBOARD_FAB2(SCH_1):PAGE112
     2    GND @BASEBOARD_FAB2_LIB.BASEBOARD_FAB2(SCH_1):GND    I42 @BASEBOARD_FAB2_LIB.BASEBOARD_FAB2(SCH_1):PAGE112

C1M37 CAP_A_0402V-1.0UF,6.3V,10%,X6SA
     1 P3V3_STBY @BASEBOARD_FAB2_LIB.BASEBOARD_FAB2(SCH_1):P3V3_STBY    I47 @BASEBOARD_FAB2_LIB.BASEBOARD_FAB2(SCH_1):PAGE112
     2    GND @BASEBOARD_FAB2_LIB.BASEBOARD_FAB2(SCH_1):GND    I47 @BASEBOARD_FAB2_LIB.BASEBOARD_FAB2(SCH_1):PAGE112

C1M38 CAP_A_0402V-0.1UF,16V,10%,X7R,A
     1 P5V_TPS2061 @BASEBOARD_FAB2_LIB.BASEBOARD_FAB2(SCH_1):P5V_TPS2061   I108 @BASEBOARD_FAB2_LIB.BASEBOARD_FAB2(SCH_1):PAGE176
     2    GND @BASEBOARD_FAB2_LIB.BASEBOARD_FAB2(SCH_1):GND   I108 @BASEBOARD_FAB2_LIB.BASEBOARD_FAB2(SCH_1):PAGE176

C1R1 CAP_0402-0.22UF,16V,10%,X7R,A3A
     1 P3E_CPU0_PE3_OCP_TXN<0> @BASEBOARD_FAB2_LIB.BASEBOARD_FAB2(SCH_1):P3E_CPU0_PE3_OCP_TXN(0)    I29 @BASEBOARD_FAB2_LIB.BASEBOARD_FAB2(SCH_1):PAGE106
     2 P3E_OCP_CPU0_PE3_C_TXN<0> @BASEBOARD_FAB2_LIB.BASEBOARD_FAB2(SCH_1):P3E_OCP_CPU0_PE3_C_TXN(0)    I29 @BASEBOARD_FAB2_LIB.BASEBOARD_FAB2(SCH_1):PAGE106

C1R2 CAP_0402-0.22UF,16V,10%,X7R,A3A
     1 P3E_CPU0_PE3_OCP_TXP<0> @BASEBOARD_FAB2_LIB.BASEBOARD_FAB2(SCH_1):P3E_CPU0_PE3_OCP_TXP(0)    I10 @BASEBOARD_FAB2_LIB.BASEBOARD_FAB2(SCH_1):PAGE106
     2 P3E_OCP_CPU0_PE3_C_TXP<0> @BASEBOARD_FAB2_LIB.BASEBOARD_FAB2(SCH_1):P3E_OCP_CPU0_PE3_C_TXP(0)    I10 @BASEBOARD_FAB2_LIB.BASEBOARD_FAB2(SCH_1):PAGE106

C1R3 CAP_0402-0.22UF,16V,10%,X7R,A3A
     1 P3E_CPU0_PE3_OCP_TXN<1> @BASEBOARD_FAB2_LIB.BASEBOARD_FAB2(SCH_1):P3E_CPU0_PE3_OCP_TXN(1)    I37 @BASEBOARD_FAB2_LIB.BASEBOARD_FAB2(SCH_1):PAGE106
     2 P3E_OCP_CPU0_PE3_C_TXN<1> @BASEBOARD_FAB2_LIB.BASEBOARD_FAB2(SCH_1):P3E_OCP_CPU0_PE3_C_TXN(1)    I37 @BASEBOARD_FAB2_LIB.BASEBOARD_FAB2(SCH_1):PAGE106

C1R4 CAP_0402-0.22UF,16V,10%,X7R,A3A
     1 P3E_CPU0_PE3_OCP_TXP<1> @BASEBOARD_FAB2_LIB.BASEBOARD_FAB2(SCH_1):P3E_CPU0_PE3_OCP_TXP(1)    I26 @BASEBOARD_FAB2_LIB.BASEBOARD_FAB2(SCH_1):PAGE106
     2 P3E_OCP_CPU0_PE3_C_TXP<1> @BASEBOARD_FAB2_LIB.BASEBOARD_FAB2(SCH_1):P3E_OCP_CPU0_PE3_C_TXP(1)    I26 @BASEBOARD_FAB2_LIB.BASEBOARD_FAB2(SCH_1):PAGE106

C1R5 CAP_0402-0.22UF,16V,10%,X7R,A3A
     1 P3E_CPU0_PE3_OCP_TXN<2> @BASEBOARD_FAB2_LIB.BASEBOARD_FAB2(SCH_1):P3E_CPU0_PE3_OCP_TXN(2)    I59 @BASEBOARD_FAB2_LIB.BASEBOARD_FAB2(SCH_1):PAGE106
     2 P3E_OCP_CPU0_PE3_C_TXN<2> @BASEBOARD_FAB2_LIB.BASEBOARD_FAB2(SCH_1):P3E_OCP_CPU0_PE3_C_TXN(2)    I59 @BASEBOARD_FAB2_LIB.BASEBOARD_FAB2(SCH_1):PAGE106

C1R6 CAP_0402-0.22UF,16V,10%,X7R,A3A
     1 P3E_CPU0_PE3_OCP_TXP<2> @BASEBOARD_FAB2_LIB.BASEBOARD_FAB2(SCH_1):P3E_CPU0_PE3_OCP_TXP(2)    I40 @BASEBOARD_FAB2_LIB.BASEBOARD_FAB2(SCH_1):PAGE106
     2 P3E_OCP_CPU0_PE3_C_TXP<2> @BASEBOARD_FAB2_LIB.BASEBOARD_FAB2(SCH_1):P3E_OCP_CPU0_PE3_C_TXP(2)    I40 @BASEBOARD_FAB2_LIB.BASEBOARD_FAB2(SCH_1):PAGE106

C1R7 CAP_0402-0.22UF,16V,10%,X7R,A3A
     1 P3E_CPU0_PE3_OCP_TXN<3> @BASEBOARD_FAB2_LIB.BASEBOARD_FAB2(SCH_1):P3E_CPU0_PE3_OCP_TXN(3)    I70 @BASEBOARD_FAB2_LIB.BASEBOARD_FAB2(SCH_1):PAGE106
     2 P3E_OCP_CPU0_PE3_C_TXN<3> @BASEBOARD_FAB2_LIB.BASEBOARD_FAB2(SCH_1):P3E_OCP_CPU0_PE3_C_TXN(3)    I70 @BASEBOARD_FAB2_LIB.BASEBOARD_FAB2(SCH_1):PAGE106

C1R8 CAP_0402-0.22UF,16V,10%,X7R,A3A
     1 P3E_CPU0_PE3_OCP_TXP<3> @BASEBOARD_FAB2_LIB.BASEBOARD_FAB2(SCH_1):P3E_CPU0_PE3_OCP_TXP(3)    I55 @BASEBOARD_FAB2_LIB.BASEBOARD_FAB2(SCH_1):PAGE106
     2 P3E_OCP_CPU0_PE3_C_TXP<3> @BASEBOARD_FAB2_LIB.BASEBOARD_FAB2(SCH_1):P3E_OCP_CPU0_PE3_C_TXP(3)    I55 @BASEBOARD_FAB2_LIB.BASEBOARD_FAB2(SCH_1):PAGE106

C1R9 CAP_0402-0.22UF,16V,10%,X7R,A3A
     1 P3E_CPU0_PE3_OCP_TXN<4> @BASEBOARD_FAB2_LIB.BASEBOARD_FAB2(SCH_1):P3E_CPU0_PE3_OCP_TXN(4)   I134 @BASEBOARD_FAB2_LIB.BASEBOARD_FAB2(SCH_1):PAGE106
     2 P3E_OCP_CPU0_PE3_C_TXN<4> @BASEBOARD_FAB2_LIB.BASEBOARD_FAB2(SCH_1):P3E_OCP_CPU0_PE3_C_TXN(4)   I134 @BASEBOARD_FAB2_LIB.BASEBOARD_FAB2(SCH_1):PAGE106

C1R10 CAP_0402-0.22UF,16V,10%,X7R,A3A
     1 P3E_CPU0_PE3_OCP_TXP<4> @BASEBOARD_FAB2_LIB.BASEBOARD_FAB2(SCH_1):P3E_CPU0_PE3_OCP_TXP(4)   I128 @BASEBOARD_FAB2_LIB.BASEBOARD_FAB2(SCH_1):PAGE106
     2 P3E_OCP_CPU0_PE3_C_TXP<4> @BASEBOARD_FAB2_LIB.BASEBOARD_FAB2(SCH_1):P3E_OCP_CPU0_PE3_C_TXP(4)   I128 @BASEBOARD_FAB2_LIB.BASEBOARD_FAB2(SCH_1):PAGE106

C1R13 CAP_0603-10UF,6.3V,20%,X6S,E15A
     1 P3V3_STBY @BASEBOARD_FAB2_LIB.BASEBOARD_FAB2(SCH_1):P3V3_STBY   I142 @BASEBOARD_FAB2_LIB.BASEBOARD_FAB2(SCH_1):PAGE139
     2    GND @BASEBOARD_FAB2_LIB.BASEBOARD_FAB2(SCH_1):GND   I142 @BASEBOARD_FAB2_LIB.BASEBOARD_FAB2(SCH_1):PAGE139

C1R14 CAP_A_0402V-0.1UF,16V,10%,X7R,A
     1 P3V3_STBY @BASEBOARD_FAB2_LIB.BASEBOARD_FAB2(SCH_1):P3V3_STBY   I145 @BASEBOARD_FAB2_LIB.BASEBOARD_FAB2(SCH_1):PAGE139
     2    GND @BASEBOARD_FAB2_LIB.BASEBOARD_FAB2(SCH_1):GND   I145 @BASEBOARD_FAB2_LIB.BASEBOARD_FAB2(SCH_1):PAGE139

C1R15 CAP_A_0402V-0.1UF,16V,10%,X7R,A
     1 P0V9_LAN @BASEBOARD_FAB2_LIB.BASEBOARD_FAB2(SCH_1):P0V9_LAN   I160 @BASEBOARD_FAB2_LIB.BASEBOARD_FAB2(SCH_1):PAGE139
     2    GND @BASEBOARD_FAB2_LIB.BASEBOARD_FAB2(SCH_1):GND   I160 @BASEBOARD_FAB2_LIB.BASEBOARD_FAB2(SCH_1):PAGE139

C1R16 CAP_0603-10UF,6.3V,20%,X6S,E15A
     1 P0V9_LAN @BASEBOARD_FAB2_LIB.BASEBOARD_FAB2(SCH_1):P0V9_LAN   I161 @BASEBOARD_FAB2_LIB.BASEBOARD_FAB2(SCH_1):PAGE139
     2    GND @BASEBOARD_FAB2_LIB.BASEBOARD_FAB2(SCH_1):GND   I161 @BASEBOARD_FAB2_LIB.BASEBOARD_FAB2(SCH_1):PAGE139

C1R17 CAP_0603-10UF,6.3V,20%,X6S,E15A
     1 P1V5_LAN @BASEBOARD_FAB2_LIB.BASEBOARD_FAB2(SCH_1):P1V5_LAN   I153 @BASEBOARD_FAB2_LIB.BASEBOARD_FAB2(SCH_1):PAGE139
     2    GND @BASEBOARD_FAB2_LIB.BASEBOARD_FAB2(SCH_1):GND   I153 @BASEBOARD_FAB2_LIB.BASEBOARD_FAB2(SCH_1):PAGE139

C1R18 CAP_A_0402V-0.1UF,16V,10%,X7R,A
     1 P0V9_LAN @BASEBOARD_FAB2_LIB.BASEBOARD_FAB2(SCH_1):P0V9_LAN   I157 @BASEBOARD_FAB2_LIB.BASEBOARD_FAB2(SCH_1):PAGE139
     2    GND @BASEBOARD_FAB2_LIB.BASEBOARD_FAB2(SCH_1):GND   I157 @BASEBOARD_FAB2_LIB.BASEBOARD_FAB2(SCH_1):PAGE139

C1R19 CAP_A_0402V-0.1UF,16V,10%,X7R,A
     1 P1V5_LAN @BASEBOARD_FAB2_LIB.BASEBOARD_FAB2(SCH_1):P1V5_LAN   I151 @BASEBOARD_FAB2_LIB.BASEBOARD_FAB2(SCH_1):PAGE139
     2    GND @BASEBOARD_FAB2_LIB.BASEBOARD_FAB2(SCH_1):GND   I151 @BASEBOARD_FAB2_LIB.BASEBOARD_FAB2(SCH_1):PAGE139

C1R20 CAP_A_0402V-0.1UF,16V,10%,X7R,A
     1 P3V3_STBY @BASEBOARD_FAB2_LIB.BASEBOARD_FAB2(SCH_1):P3V3_STBY   I143 @BASEBOARD_FAB2_LIB.BASEBOARD_FAB2(SCH_1):PAGE139
     2    GND @BASEBOARD_FAB2_LIB.BASEBOARD_FAB2(SCH_1):GND   I143 @BASEBOARD_FAB2_LIB.BASEBOARD_FAB2(SCH_1):PAGE139

C1R21 CAP_A_0402V-0.1UF,16V,10%,X7R,A
     1 P3V3_STBY @BASEBOARD_FAB2_LIB.BASEBOARD_FAB2(SCH_1):P3V3_STBY   I146 @BASEBOARD_FAB2_LIB.BASEBOARD_FAB2(SCH_1):PAGE139
     2    GND @BASEBOARD_FAB2_LIB.BASEBOARD_FAB2(SCH_1):GND   I146 @BASEBOARD_FAB2_LIB.BASEBOARD_FAB2(SCH_1):PAGE139

C1R22 CAP_0603-10UF,6.3V,20%,X6S,E15A
     1 P3V3_STBY @BASEBOARD_FAB2_LIB.BASEBOARD_FAB2(SCH_1):P3V3_STBY   I136 @BASEBOARD_FAB2_LIB.BASEBOARD_FAB2(SCH_1):PAGE139
     2    GND @BASEBOARD_FAB2_LIB.BASEBOARD_FAB2(SCH_1):GND   I136 @BASEBOARD_FAB2_LIB.BASEBOARD_FAB2(SCH_1):PAGE139

C1R23 CAPP_3018-68UF,16V,20%,TANT,72A
     1 P12V_STBY @BASEBOARD_FAB2_LIB.BASEBOARD_FAB2(SCH_1):P12V_STBY   I101 @BASEBOARD_FAB2_LIB.BASEBOARD_FAB2(SCH_1):PAGE195
     2    GND @BASEBOARD_FAB2_LIB.BASEBOARD_FAB2(SCH_1):GND   I101 @BASEBOARD_FAB2_LIB.BASEBOARD_FAB2(SCH_1):PAGE195

C1R24 CAP_A_0402V-0.1UF,16V,10%,X7R,A
     1 P0V9_LAN @BASEBOARD_FAB2_LIB.BASEBOARD_FAB2(SCH_1):P0V9_LAN   I159 @BASEBOARD_FAB2_LIB.BASEBOARD_FAB2(SCH_1):PAGE139
     2    GND @BASEBOARD_FAB2_LIB.BASEBOARD_FAB2(SCH_1):GND   I159 @BASEBOARD_FAB2_LIB.BASEBOARD_FAB2(SCH_1):PAGE139

C1R25 CAP_A_0402V-0.1UF,16V,10%,X7R,A
     1 P3V3_STBY @BASEBOARD_FAB2_LIB.BASEBOARD_FAB2(SCH_1):P3V3_STBY     I3 @BASEBOARD_FAB2_LIB.BASEBOARD_FAB2(SCH_1):PAGE140
     2    GND @BASEBOARD_FAB2_LIB.BASEBOARD_FAB2(SCH_1):GND     I3 @BASEBOARD_FAB2_LIB.BASEBOARD_FAB2(SCH_1):PAGE140

C1R26 CAP_A_0402V-0.1UF,16V,10%,X7R,A
     1 P1V5_LAN @BASEBOARD_FAB2_LIB.BASEBOARD_FAB2(SCH_1):P1V5_LAN   I149 @BASEBOARD_FAB2_LIB.BASEBOARD_FAB2(SCH_1):PAGE139
     2    GND @BASEBOARD_FAB2_LIB.BASEBOARD_FAB2(SCH_1):GND   I149 @BASEBOARD_FAB2_LIB.BASEBOARD_FAB2(SCH_1):PAGE139

C1R27 CAP_A_0402V-0.1UF,16V,10%,X7R,A
     1 P3V3_STBY @BASEBOARD_FAB2_LIB.BASEBOARD_FAB2(SCH_1):P3V3_STBY    I30 @BASEBOARD_FAB2_LIB.BASEBOARD_FAB2(SCH_1):PAGE170
     2    GND @BASEBOARD_FAB2_LIB.BASEBOARD_FAB2(SCH_1):GND    I30 @BASEBOARD_FAB2_LIB.BASEBOARD_FAB2(SCH_1):PAGE170

C1R28 CAP_A_0402V-0.1UF,16V,10%,X7R,A
     1 P3V3_STBY @BASEBOARD_FAB2_LIB.BASEBOARD_FAB2(SCH_1):P3V3_STBY    I49 @BASEBOARD_FAB2_LIB.BASEBOARD_FAB2(SCH_1):PAGE170
     2    GND @BASEBOARD_FAB2_LIB.BASEBOARD_FAB2(SCH_1):GND    I49 @BASEBOARD_FAB2_LIB.BASEBOARD_FAB2(SCH_1):PAGE170

C1R29 CAP_A_0402V-0.1UF,16V,10%,X7R,A
     1 P1V5_LAN @BASEBOARD_FAB2_LIB.BASEBOARD_FAB2(SCH_1):P1V5_LAN   I150 @BASEBOARD_FAB2_LIB.BASEBOARD_FAB2(SCH_1):PAGE139
     2    GND @BASEBOARD_FAB2_LIB.BASEBOARD_FAB2(SCH_1):GND   I150 @BASEBOARD_FAB2_LIB.BASEBOARD_FAB2(SCH_1):PAGE139

C1R30 CAP_0603-10UF,6.3V,20%,X6S,E15A
     1 P1V5_LAN @BASEBOARD_FAB2_LIB.BASEBOARD_FAB2(SCH_1):P1V5_LAN   I135 @BASEBOARD_FAB2_LIB.BASEBOARD_FAB2(SCH_1):PAGE139
     2    GND @BASEBOARD_FAB2_LIB.BASEBOARD_FAB2(SCH_1):GND   I135 @BASEBOARD_FAB2_LIB.BASEBOARD_FAB2(SCH_1):PAGE139

C1R31 CAP_A_0402V-0.1UF,16V,10%,X7R,A
     1 P1V5_LAN @BASEBOARD_FAB2_LIB.BASEBOARD_FAB2(SCH_1):P1V5_LAN   I152 @BASEBOARD_FAB2_LIB.BASEBOARD_FAB2(SCH_1):PAGE139
     2    GND @BASEBOARD_FAB2_LIB.BASEBOARD_FAB2(SCH_1):GND   I152 @BASEBOARD_FAB2_LIB.BASEBOARD_FAB2(SCH_1):PAGE139

C1T3 CAP_A_0402V-0.1UF,16V,10%,X7R,A
     1 P3V3_STBY @BASEBOARD_FAB2_LIB.BASEBOARD_FAB2(SCH_1):P3V3_STBY   I144 @BASEBOARD_FAB2_LIB.BASEBOARD_FAB2(SCH_1):PAGE139
     2    GND @BASEBOARD_FAB2_LIB.BASEBOARD_FAB2(SCH_1):GND   I144 @BASEBOARD_FAB2_LIB.BASEBOARD_FAB2(SCH_1):PAGE139

C1T4 CAP_0603-10UF,6.3V,20%,X6S,E15A
     1 P0V9_LAN @BASEBOARD_FAB2_LIB.BASEBOARD_FAB2(SCH_1):P0V9_LAN   I134 @BASEBOARD_FAB2_LIB.BASEBOARD_FAB2(SCH_1):PAGE139
     2    GND @BASEBOARD_FAB2_LIB.BASEBOARD_FAB2(SCH_1):GND   I134 @BASEBOARD_FAB2_LIB.BASEBOARD_FAB2(SCH_1):PAGE139

C1T5 CAP_A_0402V-0.1UF,16V,10%,X7R,A
     1 P0V9_LAN @BASEBOARD_FAB2_LIB.BASEBOARD_FAB2(SCH_1):P0V9_LAN   I158 @BASEBOARD_FAB2_LIB.BASEBOARD_FAB2(SCH_1):PAGE139
     2    GND @BASEBOARD_FAB2_LIB.BASEBOARD_FAB2(SCH_1):GND   I158 @BASEBOARD_FAB2_LIB.BASEBOARD_FAB2(SCH_1):PAGE139

C1T7 CAP_0603-10UF,6.3V,20%,X6S,E15A
     1 P3V3_STBY @BASEBOARD_FAB2_LIB.BASEBOARD_FAB2(SCH_1):P3V3_STBY    I22 @BASEBOARD_FAB2_LIB.BASEBOARD_FAB2(SCH_1):PAGE239
     2    GND @BASEBOARD_FAB2_LIB.BASEBOARD_FAB2(SCH_1):GND    I22 @BASEBOARD_FAB2_LIB.BASEBOARD_FAB2(SCH_1):PAGE239

C1T10 CAP_A_0402V-0.1UF,16V,10%,X7R,A
     1 P3V3_STBY @BASEBOARD_FAB2_LIB.BASEBOARD_FAB2(SCH_1):P3V3_STBY    I70 @BASEBOARD_FAB2_LIB.BASEBOARD_FAB2(SCH_1):PAGE158
     2    GND @BASEBOARD_FAB2_LIB.BASEBOARD_FAB2(SCH_1):GND    I70 @BASEBOARD_FAB2_LIB.BASEBOARD_FAB2(SCH_1):PAGE158

C1T11 CAP_A_0402V-0.1UF,16V,10%,X7R,A
     1 P3V3_STBY @BASEBOARD_FAB2_LIB.BASEBOARD_FAB2(SCH_1):P3V3_STBY    I97 @BASEBOARD_FAB2_LIB.BASEBOARD_FAB2(SCH_1):PAGE158
     2    GND @BASEBOARD_FAB2_LIB.BASEBOARD_FAB2(SCH_1):GND    I97 @BASEBOARD_FAB2_LIB.BASEBOARD_FAB2(SCH_1):PAGE158

C1T15 CAP_0603-10UF,6.3V,20%,X6S,E15A
     1 P1V2_AUX_BMC @BASEBOARD_FAB2_LIB.BASEBOARD_FAB2(SCH_1):P1V2_AUX_BMC    I12 @BASEBOARD_FAB2_LIB.BASEBOARD_FAB2(SCH_1):PAGE239
     2    GND @BASEBOARD_FAB2_LIB.BASEBOARD_FAB2(SCH_1):GND    I12 @BASEBOARD_FAB2_LIB.BASEBOARD_FAB2(SCH_1):PAGE239

C1T21 CAP_A_0402V-1.0UF,6.3V,10%,X6SA
     1 PVCCIO_CPU0 @BASEBOARD_FAB2_LIB.BASEBOARD_FAB2(SCH_1):PVCCIO_CPU0    I20 @BASEBOARD_FAB2_LIB.BASEBOARD_FAB2(SCH_1):PAGE148
     2    GND @BASEBOARD_FAB2_LIB.BASEBOARD_FAB2(SCH_1):GND    I20 @BASEBOARD_FAB2_LIB.BASEBOARD_FAB2(SCH_1):PAGE148

C1T56 CAP_A_0402V-0.1UF,16V,10%,X7R,A
     1 P3V3_STBY @BASEBOARD_FAB2_LIB.BASEBOARD_FAB2(SCH_1):P3V3_STBY   I184 @BASEBOARD_FAB2_LIB.BASEBOARD_FAB2(SCH_1):PAGE155
     2    GND @BASEBOARD_FAB2_LIB.BASEBOARD_FAB2(SCH_1):GND   I184 @BASEBOARD_FAB2_LIB.BASEBOARD_FAB2(SCH_1):PAGE155

C1U19 CAP_0402-1.0UF,16V,10%,X6S,D97A
     1   P3V3 @BASEBOARD_FAB2_LIB.BASEBOARD_FAB2(SCH_1):P3V3    I18 @BASEBOARD_FAB2_LIB.BASEBOARD_FAB2(SCH_1):PAGE152
     2    GND @BASEBOARD_FAB2_LIB.BASEBOARD_FAB2(SCH_1):GND    I18 @BASEBOARD_FAB2_LIB.BASEBOARD_FAB2(SCH_1):PAGE152

C1U21 CAP_0402LF-47.0PF,50V,5%,COG,AA
     1 A_P1V05_STBY_PCH_SENSOR @BASEBOARD_FAB2_LIB.BASEBOARD_FAB2(SCH_1):A_P1V05_STBY_PCH_SENSOR    I56 @BASEBOARD_FAB2_LIB.BASEBOARD_FAB2(SCH_1):PAGE169
     2    GND @BASEBOARD_FAB2_LIB.BASEBOARD_FAB2(SCH_1):GND    I56 @BASEBOARD_FAB2_LIB.BASEBOARD_FAB2(SCH_1):PAGE169

C1U22 CAP_A_0402V-0.1UF,16V,10%,X7R,A
     1 P0V7_GTL2014_2 @BASEBOARD_FAB2_LIB.BASEBOARD_FAB2(SCH_1):P0V7_GTL2014_2    I27 @BASEBOARD_FAB2_LIB.BASEBOARD_FAB2(SCH_1):PAGE152
     2    GND @BASEBOARD_FAB2_LIB.BASEBOARD_FAB2(SCH_1):GND    I27 @BASEBOARD_FAB2_LIB.BASEBOARD_FAB2(SCH_1):PAGE152

C1W7 CAP_0603-10UF,6.3V,20%,X6S,E15A
     1 P3V3_STBY @BASEBOARD_FAB2_LIB.BASEBOARD_FAB2(SCH_1):P3V3_STBY    I92 @BASEBOARD_FAB2_LIB.BASEBOARD_FAB2(SCH_1):PAGE239
     2    GND @BASEBOARD_FAB2_LIB.BASEBOARD_FAB2(SCH_1):GND    I92 @BASEBOARD_FAB2_LIB.BASEBOARD_FAB2(SCH_1):PAGE239

C1W15 CAP_0603-10UF,6.3V,20%,X6S,E15A
     1 P2V5_AUX_BMC @BASEBOARD_FAB2_LIB.BASEBOARD_FAB2(SCH_1):P2V5_AUX_BMC    I83 @BASEBOARD_FAB2_LIB.BASEBOARD_FAB2(SCH_1):PAGE239
     2    GND @BASEBOARD_FAB2_LIB.BASEBOARD_FAB2(SCH_1):GND    I83 @BASEBOARD_FAB2_LIB.BASEBOARD_FAB2(SCH_1):PAGE239

C1W16 CAP_0402LF-1000PF,50V,10%,X7R,A
     1 A_HSC_TEMP @BASEBOARD_FAB2_LIB.BASEBOARD_FAB2(SCH_1):A_HSC_TEMP   I132 @BASEBOARD_FAB2_LIB.BASEBOARD_FAB2(SCH_1):PAGE199
     2    GND @BASEBOARD_FAB2_LIB.BASEBOARD_FAB2(SCH_1):GND   I132 @BASEBOARD_FAB2_LIB.BASEBOARD_FAB2(SCH_1):PAGE199

C1W17 CAP_0805-10UF,16V,10%,EMPTY,C9A
     1 P3V3_STBY_MNG_RMII @BASEBOARD_FAB2_LIB.BASEBOARD_FAB2(SCH_1):P3V3_STBY_MNG_RMII   I139 @BASEBOARD_FAB2_LIB.BASEBOARD_FAB2(SCH_1):PAGE101
     2    GND @BASEBOARD_FAB2_LIB.BASEBOARD_FAB2(SCH_1):GND   I139 @BASEBOARD_FAB2_LIB.BASEBOARD_FAB2(SCH_1):PAGE101

C1W18 CAP_A_0402V-0.1UF,16V,10%,X7R,A
     1 P3V3_STBY @BASEBOARD_FAB2_LIB.BASEBOARD_FAB2(SCH_1):P3V3_STBY   I163 @BASEBOARD_FAB2_LIB.BASEBOARD_FAB2(SCH_1):PAGE176
     2    GND @BASEBOARD_FAB2_LIB.BASEBOARD_FAB2(SCH_1):GND   I163 @BASEBOARD_FAB2_LIB.BASEBOARD_FAB2(SCH_1):PAGE176

C1W19 CAP_A_0402V-0.1UF,16V,10%,X7R,A
     1 P3V3_STBY @BASEBOARD_FAB2_LIB.BASEBOARD_FAB2(SCH_1):P3V3_STBY   I166 @BASEBOARD_FAB2_LIB.BASEBOARD_FAB2(SCH_1):PAGE176
     2    GND @BASEBOARD_FAB2_LIB.BASEBOARD_FAB2(SCH_1):GND   I166 @BASEBOARD_FAB2_LIB.BASEBOARD_FAB2(SCH_1):PAGE176

C1W20 CAP_0402-0.22UF,16V,10%,X7R,A3A
     1 BMC_M_CLK @BASEBOARD_FAB2_LIB.BASEBOARD_FAB2(SCH_1):BMC_M_CLK   I220 @BASEBOARD_FAB2_LIB.BASEBOARD_FAB2(SCH_1):PAGE151
     2    GND @BASEBOARD_FAB2_LIB.BASEBOARD_FAB2(SCH_1):GND   I220 @BASEBOARD_FAB2_LIB.BASEBOARD_FAB2(SCH_1):PAGE151

C1W21 CAP_0603LF-0.033UF,50V,10%,X7RA
     1 A_USB2AVRES @BASEBOARD_FAB2_LIB.BASEBOARD_FAB2(SCH_1):A_USB2AVRES   I160 @BASEBOARD_FAB2_LIB.BASEBOARD_FAB2(SCH_1):PAGE146
     2    GND @BASEBOARD_FAB2_LIB.BASEBOARD_FAB2(SCH_1):GND   I160 @BASEBOARD_FAB2_LIB.BASEBOARD_FAB2(SCH_1):PAGE146

C2A1 CAP_A_0603V-47UF,4V,20%,X5R,60A
     1 PVDDQ_KLM @BASEBOARD_FAB2_LIB.BASEBOARD_FAB2(SCH_1):PVDDQ_KLM   I282 @BASEBOARD_FAB2_LIB.BASEBOARD_FAB2(SCH_1):PAGE228
     2    GND @BASEBOARD_FAB2_LIB.BASEBOARD_FAB2(SCH_1):GND   I282 @BASEBOARD_FAB2_LIB.BASEBOARD_FAB2(SCH_1):PAGE228

C2A2 CAP_A_0603V-47UF,4V,20%,X5R,60A
     1 PVDDQ_KLM @BASEBOARD_FAB2_LIB.BASEBOARD_FAB2(SCH_1):PVDDQ_KLM   I283 @BASEBOARD_FAB2_LIB.BASEBOARD_FAB2(SCH_1):PAGE228
     2    GND @BASEBOARD_FAB2_LIB.BASEBOARD_FAB2(SCH_1):GND   I283 @BASEBOARD_FAB2_LIB.BASEBOARD_FAB2(SCH_1):PAGE228

C2A3 CAP_A_0603V-47UF,4V,20%,X5R,60A
     1 PVDDQ_KLM @BASEBOARD_FAB2_LIB.BASEBOARD_FAB2(SCH_1):PVDDQ_KLM   I296 @BASEBOARD_FAB2_LIB.BASEBOARD_FAB2(SCH_1):PAGE228
     2    GND @BASEBOARD_FAB2_LIB.BASEBOARD_FAB2(SCH_1):GND   I296 @BASEBOARD_FAB2_LIB.BASEBOARD_FAB2(SCH_1):PAGE228

C2A4 CAP_A_0603V-47UF,4V,20%,X5R,60A
     1 PVDDQ_KLM @BASEBOARD_FAB2_LIB.BASEBOARD_FAB2(SCH_1):PVDDQ_KLM   I292 @BASEBOARD_FAB2_LIB.BASEBOARD_FAB2(SCH_1):PAGE228
     2    GND @BASEBOARD_FAB2_LIB.BASEBOARD_FAB2(SCH_1):GND   I292 @BASEBOARD_FAB2_LIB.BASEBOARD_FAB2(SCH_1):PAGE228

C2A5 CAP_A_0603V-47UF,4V,20%,X5R,60A
     1 PVDDQ_KLM @BASEBOARD_FAB2_LIB.BASEBOARD_FAB2(SCH_1):PVDDQ_KLM   I199 @BASEBOARD_FAB2_LIB.BASEBOARD_FAB2(SCH_1):PAGE228
     2    GND @BASEBOARD_FAB2_LIB.BASEBOARD_FAB2(SCH_1):GND   I199 @BASEBOARD_FAB2_LIB.BASEBOARD_FAB2(SCH_1):PAGE228

C2A6 CAP_A_0603V-47UF,4V,20%,X5R,60A
     1 PVDDQ_KLM @BASEBOARD_FAB2_LIB.BASEBOARD_FAB2(SCH_1):PVDDQ_KLM   I273 @BASEBOARD_FAB2_LIB.BASEBOARD_FAB2(SCH_1):PAGE228
     2    GND @BASEBOARD_FAB2_LIB.BASEBOARD_FAB2(SCH_1):GND   I273 @BASEBOARD_FAB2_LIB.BASEBOARD_FAB2(SCH_1):PAGE228

C2A7 CAP_A_0603V-47UF,4V,20%,X5R,60A
     1 PVDDQ_KLM @BASEBOARD_FAB2_LIB.BASEBOARD_FAB2(SCH_1):PVDDQ_KLM   I274 @BASEBOARD_FAB2_LIB.BASEBOARD_FAB2(SCH_1):PAGE228
     2    GND @BASEBOARD_FAB2_LIB.BASEBOARD_FAB2(SCH_1):GND   I274 @BASEBOARD_FAB2_LIB.BASEBOARD_FAB2(SCH_1):PAGE228

C2A8 CAP_0805-100UF,4V,20%,X5R,6024A
     1 PVDDQ_KLM @BASEBOARD_FAB2_LIB.BASEBOARD_FAB2(SCH_1):PVDDQ_KLM   I309 @BASEBOARD_FAB2_LIB.BASEBOARD_FAB2(SCH_1):PAGE228
     2    GND @BASEBOARD_FAB2_LIB.BASEBOARD_FAB2(SCH_1):GND   I309 @BASEBOARD_FAB2_LIB.BASEBOARD_FAB2(SCH_1):PAGE228

C2A9 CAP_A_0603V-47UF,4V,20%,X5R,60A
     1 PVDDQ_KLM @BASEBOARD_FAB2_LIB.BASEBOARD_FAB2(SCH_1):PVDDQ_KLM   I277 @BASEBOARD_FAB2_LIB.BASEBOARD_FAB2(SCH_1):PAGE228
     2    GND @BASEBOARD_FAB2_LIB.BASEBOARD_FAB2(SCH_1):GND   I277 @BASEBOARD_FAB2_LIB.BASEBOARD_FAB2(SCH_1):PAGE228

C2A10 CAP_A_0603V-47UF,4V,20%,X5R,60A
     1 PVDDQ_KLM @BASEBOARD_FAB2_LIB.BASEBOARD_FAB2(SCH_1):PVDDQ_KLM   I278 @BASEBOARD_FAB2_LIB.BASEBOARD_FAB2(SCH_1):PAGE228
     2    GND @BASEBOARD_FAB2_LIB.BASEBOARD_FAB2(SCH_1):GND   I278 @BASEBOARD_FAB2_LIB.BASEBOARD_FAB2(SCH_1):PAGE228

C2A11 CAP_A_0603V-47UF,4V,20%,X5R,60A
     1 PVDDQ_KLM @BASEBOARD_FAB2_LIB.BASEBOARD_FAB2(SCH_1):PVDDQ_KLM   I279 @BASEBOARD_FAB2_LIB.BASEBOARD_FAB2(SCH_1):PAGE228
     2    GND @BASEBOARD_FAB2_LIB.BASEBOARD_FAB2(SCH_1):GND   I279 @BASEBOARD_FAB2_LIB.BASEBOARD_FAB2(SCH_1):PAGE228

C2A12 CAP_A_0603V-47UF,4V,20%,X5R,60A
     1 PVDDQ_KLM @BASEBOARD_FAB2_LIB.BASEBOARD_FAB2(SCH_1):PVDDQ_KLM   I281 @BASEBOARD_FAB2_LIB.BASEBOARD_FAB2(SCH_1):PAGE228
     2    GND @BASEBOARD_FAB2_LIB.BASEBOARD_FAB2(SCH_1):GND   I281 @BASEBOARD_FAB2_LIB.BASEBOARD_FAB2(SCH_1):PAGE228

C2A13 CAP_A_0603V-47UF,4V,20%,X5R,60A
     1 PVDDQ_KLM @BASEBOARD_FAB2_LIB.BASEBOARD_FAB2(SCH_1):PVDDQ_KLM   I280 @BASEBOARD_FAB2_LIB.BASEBOARD_FAB2(SCH_1):PAGE228
     2    GND @BASEBOARD_FAB2_LIB.BASEBOARD_FAB2(SCH_1):GND   I280 @BASEBOARD_FAB2_LIB.BASEBOARD_FAB2(SCH_1):PAGE228

C2A14 CAP_A_0603V-47UF,4V,20%,X5R,60A
     1 PVDDQ_KLM @BASEBOARD_FAB2_LIB.BASEBOARD_FAB2(SCH_1):PVDDQ_KLM   I272 @BASEBOARD_FAB2_LIB.BASEBOARD_FAB2(SCH_1):PAGE228
     2    GND @BASEBOARD_FAB2_LIB.BASEBOARD_FAB2(SCH_1):GND   I272 @BASEBOARD_FAB2_LIB.BASEBOARD_FAB2(SCH_1):PAGE228

C2A15 CAP_A_0603V-47UF,4V,20%,X5R,60A
     1 PVDDQ_KLM @BASEBOARD_FAB2_LIB.BASEBOARD_FAB2(SCH_1):PVDDQ_KLM   I271 @BASEBOARD_FAB2_LIB.BASEBOARD_FAB2(SCH_1):PAGE228
     2    GND @BASEBOARD_FAB2_LIB.BASEBOARD_FAB2(SCH_1):GND   I271 @BASEBOARD_FAB2_LIB.BASEBOARD_FAB2(SCH_1):PAGE228

C2A16 CAP_0805-100UF,4V,20%,X5R,6024A
     1 PVDDQ_KLM @BASEBOARD_FAB2_LIB.BASEBOARD_FAB2(SCH_1):PVDDQ_KLM   I313 @BASEBOARD_FAB2_LIB.BASEBOARD_FAB2(SCH_1):PAGE228
     2    GND @BASEBOARD_FAB2_LIB.BASEBOARD_FAB2(SCH_1):GND   I313 @BASEBOARD_FAB2_LIB.BASEBOARD_FAB2(SCH_1):PAGE228

C2B1 CAP_A_0603V-47UF,4V,20%,X5R,60A
     1 PVDDQ_KLM @BASEBOARD_FAB2_LIB.BASEBOARD_FAB2(SCH_1):PVDDQ_KLM   I200 @BASEBOARD_FAB2_LIB.BASEBOARD_FAB2(SCH_1):PAGE228
     2    GND @BASEBOARD_FAB2_LIB.BASEBOARD_FAB2(SCH_1):GND   I200 @BASEBOARD_FAB2_LIB.BASEBOARD_FAB2(SCH_1):PAGE228

C2B2 CAP_A_0603V-47UF,4V,20%,X5R,60A
     1 PVDDQ_KLM @BASEBOARD_FAB2_LIB.BASEBOARD_FAB2(SCH_1):PVDDQ_KLM   I204 @BASEBOARD_FAB2_LIB.BASEBOARD_FAB2(SCH_1):PAGE228
     2    GND @BASEBOARD_FAB2_LIB.BASEBOARD_FAB2(SCH_1):GND   I204 @BASEBOARD_FAB2_LIB.BASEBOARD_FAB2(SCH_1):PAGE228

C2D1 CAP_A_0603V-22.0UF,4V,20%,X6S,A
     1 PVDDQ_KLM @BASEBOARD_FAB2_LIB.BASEBOARD_FAB2(SCH_1):PVDDQ_KLM   I258 @BASEBOARD_FAB2_LIB.BASEBOARD_FAB2(SCH_1):PAGE228
     2    GND @BASEBOARD_FAB2_LIB.BASEBOARD_FAB2(SCH_1):GND   I258 @BASEBOARD_FAB2_LIB.BASEBOARD_FAB2(SCH_1):PAGE228

C2D2 CAP_A_0603V-22.0UF,4V,20%,X6S,A
     1 PVDDQ_KLM @BASEBOARD_FAB2_LIB.BASEBOARD_FAB2(SCH_1):PVDDQ_KLM   I257 @BASEBOARD_FAB2_LIB.BASEBOARD_FAB2(SCH_1):PAGE228
     2    GND @BASEBOARD_FAB2_LIB.BASEBOARD_FAB2(SCH_1):GND   I257 @BASEBOARD_FAB2_LIB.BASEBOARD_FAB2(SCH_1):PAGE228

C2D3 CAP_A_0603V-22.0UF,4V,20%,X6S,A
     1 PVDDQ_KLM @BASEBOARD_FAB2_LIB.BASEBOARD_FAB2(SCH_1):PVDDQ_KLM   I256 @BASEBOARD_FAB2_LIB.BASEBOARD_FAB2(SCH_1):PAGE228
     2    GND @BASEBOARD_FAB2_LIB.BASEBOARD_FAB2(SCH_1):GND   I256 @BASEBOARD_FAB2_LIB.BASEBOARD_FAB2(SCH_1):PAGE228

C2D4 CAP_A_0603V-22.0UF,4V,20%,X6S,A
     1 PVDDQ_KLM @BASEBOARD_FAB2_LIB.BASEBOARD_FAB2(SCH_1):PVDDQ_KLM   I265 @BASEBOARD_FAB2_LIB.BASEBOARD_FAB2(SCH_1):PAGE228
     2    GND @BASEBOARD_FAB2_LIB.BASEBOARD_FAB2(SCH_1):GND   I265 @BASEBOARD_FAB2_LIB.BASEBOARD_FAB2(SCH_1):PAGE228

C2D5 CAP_A_0603V-22.0UF,4V,20%,X6S,A
     1 PVDDQ_KLM @BASEBOARD_FAB2_LIB.BASEBOARD_FAB2(SCH_1):PVDDQ_KLM   I266 @BASEBOARD_FAB2_LIB.BASEBOARD_FAB2(SCH_1):PAGE228
     2    GND @BASEBOARD_FAB2_LIB.BASEBOARD_FAB2(SCH_1):GND   I266 @BASEBOARD_FAB2_LIB.BASEBOARD_FAB2(SCH_1):PAGE228

C2D6 CAP_A_0603V-22.0UF,4V,20%,X6S,A
     1 PVDDQ_KLM @BASEBOARD_FAB2_LIB.BASEBOARD_FAB2(SCH_1):PVDDQ_KLM   I267 @BASEBOARD_FAB2_LIB.BASEBOARD_FAB2(SCH_1):PAGE228
     2    GND @BASEBOARD_FAB2_LIB.BASEBOARD_FAB2(SCH_1):GND   I267 @BASEBOARD_FAB2_LIB.BASEBOARD_FAB2(SCH_1):PAGE228

C2D7 CAP_A_0603V-22.0UF,4V,20%,X6S,A
     1 PVDDQ_KLM @BASEBOARD_FAB2_LIB.BASEBOARD_FAB2(SCH_1):PVDDQ_KLM   I264 @BASEBOARD_FAB2_LIB.BASEBOARD_FAB2(SCH_1):PAGE228
     2    GND @BASEBOARD_FAB2_LIB.BASEBOARD_FAB2(SCH_1):GND   I264 @BASEBOARD_FAB2_LIB.BASEBOARD_FAB2(SCH_1):PAGE228

C2D8 CAP_0603LF-10UF,4V,20%,X6S,E15A
     1 PVSA_CPU1 @BASEBOARD_FAB2_LIB.BASEBOARD_FAB2(SCH_1):PVSA_CPU1    I33 @BASEBOARD_FAB2_LIB.BASEBOARD_FAB2(SCH_1):PAGE76
     2    GND @BASEBOARD_FAB2_LIB.BASEBOARD_FAB2(SCH_1):GND    I33 @BASEBOARD_FAB2_LIB.BASEBOARD_FAB2(SCH_1):PAGE76

C2D9 CAP_0603LF-10UF,4V,20%,X6S,E15A
     1 PVSA_CPU1 @BASEBOARD_FAB2_LIB.BASEBOARD_FAB2(SCH_1):PVSA_CPU1    I43 @BASEBOARD_FAB2_LIB.BASEBOARD_FAB2(SCH_1):PAGE76
     2    GND @BASEBOARD_FAB2_LIB.BASEBOARD_FAB2(SCH_1):GND    I43 @BASEBOARD_FAB2_LIB.BASEBOARD_FAB2(SCH_1):PAGE76

C2D10 CAP_0603LF-10UF,4V,20%,X6S,E15A
     1 PVSA_CPU1 @BASEBOARD_FAB2_LIB.BASEBOARD_FAB2(SCH_1):PVSA_CPU1    I37 @BASEBOARD_FAB2_LIB.BASEBOARD_FAB2(SCH_1):PAGE76
     2    GND @BASEBOARD_FAB2_LIB.BASEBOARD_FAB2(SCH_1):GND    I37 @BASEBOARD_FAB2_LIB.BASEBOARD_FAB2(SCH_1):PAGE76

C2D11 CAP_0603LF-10UF,4V,20%,X6S,E15A
     1 PVSA_CPU1 @BASEBOARD_FAB2_LIB.BASEBOARD_FAB2(SCH_1):PVSA_CPU1    I42 @BASEBOARD_FAB2_LIB.BASEBOARD_FAB2(SCH_1):PAGE76
     2    GND @BASEBOARD_FAB2_LIB.BASEBOARD_FAB2(SCH_1):GND    I42 @BASEBOARD_FAB2_LIB.BASEBOARD_FAB2(SCH_1):PAGE76

C2D12 CAP_A_0603V-22.0UF,4V,20%,X6S,A
     1 PVCCIN_CPU1 @BASEBOARD_FAB2_LIB.BASEBOARD_FAB2(SCH_1):PVCCIN_CPU1    I59 @BASEBOARD_FAB2_LIB.BASEBOARD_FAB2(SCH_1):PAGE76
     2    GND @BASEBOARD_FAB2_LIB.BASEBOARD_FAB2(SCH_1):GND    I59 @BASEBOARD_FAB2_LIB.BASEBOARD_FAB2(SCH_1):PAGE76

C2D13 CAP_A_0603V-22.0UF,4V,20%,X6S,A
     1 PVCCIN_CPU1 @BASEBOARD_FAB2_LIB.BASEBOARD_FAB2(SCH_1):PVCCIN_CPU1    I73 @BASEBOARD_FAB2_LIB.BASEBOARD_FAB2(SCH_1):PAGE76
     2    GND @BASEBOARD_FAB2_LIB.BASEBOARD_FAB2(SCH_1):GND    I73 @BASEBOARD_FAB2_LIB.BASEBOARD_FAB2(SCH_1):PAGE76

C2D14 CAP_A_0603V-22.0UF,4V,20%,X6S,A
     1 PVCCIN_CPU1 @BASEBOARD_FAB2_LIB.BASEBOARD_FAB2(SCH_1):PVCCIN_CPU1    I76 @BASEBOARD_FAB2_LIB.BASEBOARD_FAB2(SCH_1):PAGE76
     2    GND @BASEBOARD_FAB2_LIB.BASEBOARD_FAB2(SCH_1):GND    I76 @BASEBOARD_FAB2_LIB.BASEBOARD_FAB2(SCH_1):PAGE76

C2D15 CAP_A_0603V-22.0UF,4V,20%,X6S,A
     1 PVCCIN_CPU1 @BASEBOARD_FAB2_LIB.BASEBOARD_FAB2(SCH_1):PVCCIN_CPU1   I159 @BASEBOARD_FAB2_LIB.BASEBOARD_FAB2(SCH_1):PAGE76
     2    GND @BASEBOARD_FAB2_LIB.BASEBOARD_FAB2(SCH_1):GND   I159 @BASEBOARD_FAB2_LIB.BASEBOARD_FAB2(SCH_1):PAGE76

C2D16 CAP_A_0603V-22.0UF,4V,20%,X6S,A
     1 PVCCIN_CPU1 @BASEBOARD_FAB2_LIB.BASEBOARD_FAB2(SCH_1):PVCCIN_CPU1   I124 @BASEBOARD_FAB2_LIB.BASEBOARD_FAB2(SCH_1):PAGE76
     2    GND @BASEBOARD_FAB2_LIB.BASEBOARD_FAB2(SCH_1):GND   I124 @BASEBOARD_FAB2_LIB.BASEBOARD_FAB2(SCH_1):PAGE76

C2D17 CAP_A_0603V-22.0UF,4V,20%,X6S,A
     1 PVCCIN_CPU1 @BASEBOARD_FAB2_LIB.BASEBOARD_FAB2(SCH_1):PVCCIN_CPU1   I114 @BASEBOARD_FAB2_LIB.BASEBOARD_FAB2(SCH_1):PAGE76
     2    GND @BASEBOARD_FAB2_LIB.BASEBOARD_FAB2(SCH_1):GND   I114 @BASEBOARD_FAB2_LIB.BASEBOARD_FAB2(SCH_1):PAGE76

C2D18 CAP_A_0603V-22.0UF,4V,20%,X6S,A
     1 PVCCMCP_CPU1 @BASEBOARD_FAB2_LIB.BASEBOARD_FAB2(SCH_1):PVCCMCP_CPU1   I197 @BASEBOARD_FAB2_LIB.BASEBOARD_FAB2(SCH_1):PAGE76
     2    GND @BASEBOARD_FAB2_LIB.BASEBOARD_FAB2(SCH_1):GND   I197 @BASEBOARD_FAB2_LIB.BASEBOARD_FAB2(SCH_1):PAGE76

C2D19 CAP_A_0603V-22.0UF,4V,20%,X6S,A
     1 PVCCIN_CPU1 @BASEBOARD_FAB2_LIB.BASEBOARD_FAB2(SCH_1):PVCCIN_CPU1    I75 @BASEBOARD_FAB2_LIB.BASEBOARD_FAB2(SCH_1):PAGE76
     2    GND @BASEBOARD_FAB2_LIB.BASEBOARD_FAB2(SCH_1):GND    I75 @BASEBOARD_FAB2_LIB.BASEBOARD_FAB2(SCH_1):PAGE76

C2D20 CAP_A_0603V-22.0UF,4V,20%,X6S,A
     1 PVCCIN_CPU1 @BASEBOARD_FAB2_LIB.BASEBOARD_FAB2(SCH_1):PVCCIN_CPU1    I79 @BASEBOARD_FAB2_LIB.BASEBOARD_FAB2(SCH_1):PAGE76
     2    GND @BASEBOARD_FAB2_LIB.BASEBOARD_FAB2(SCH_1):GND    I79 @BASEBOARD_FAB2_LIB.BASEBOARD_FAB2(SCH_1):PAGE76

C2D21 CAP_A_0603V-22.0UF,4V,20%,X6S,A
     1 PVCCIN_CPU1 @BASEBOARD_FAB2_LIB.BASEBOARD_FAB2(SCH_1):PVCCIN_CPU1    I65 @BASEBOARD_FAB2_LIB.BASEBOARD_FAB2(SCH_1):PAGE76
     2    GND @BASEBOARD_FAB2_LIB.BASEBOARD_FAB2(SCH_1):GND    I65 @BASEBOARD_FAB2_LIB.BASEBOARD_FAB2(SCH_1):PAGE76

C2D22 CAP_A_0603V-22.0UF,4V,20%,X6S,A
     1 PVCCIN_CPU1 @BASEBOARD_FAB2_LIB.BASEBOARD_FAB2(SCH_1):PVCCIN_CPU1    I61 @BASEBOARD_FAB2_LIB.BASEBOARD_FAB2(SCH_1):PAGE76
     2    GND @BASEBOARD_FAB2_LIB.BASEBOARD_FAB2(SCH_1):GND    I61 @BASEBOARD_FAB2_LIB.BASEBOARD_FAB2(SCH_1):PAGE76

C2D23 CAP_A_0603V-22.0UF,4V,20%,X6S,A
     1 PVCCIN_CPU1 @BASEBOARD_FAB2_LIB.BASEBOARD_FAB2(SCH_1):PVCCIN_CPU1   I112 @BASEBOARD_FAB2_LIB.BASEBOARD_FAB2(SCH_1):PAGE76
     2    GND @BASEBOARD_FAB2_LIB.BASEBOARD_FAB2(SCH_1):GND   I112 @BASEBOARD_FAB2_LIB.BASEBOARD_FAB2(SCH_1):PAGE76

C2D24 CAP_A_0603V-22.0UF,4V,20%,X6S,A
     1 PVCCIN_CPU1 @BASEBOARD_FAB2_LIB.BASEBOARD_FAB2(SCH_1):PVCCIN_CPU1    I80 @BASEBOARD_FAB2_LIB.BASEBOARD_FAB2(SCH_1):PAGE76
     2    GND @BASEBOARD_FAB2_LIB.BASEBOARD_FAB2(SCH_1):GND    I80 @BASEBOARD_FAB2_LIB.BASEBOARD_FAB2(SCH_1):PAGE76

C2D25 CAP_A_0603V-22.0UF,4V,20%,X6S,A
     1 PVCCIN_CPU1 @BASEBOARD_FAB2_LIB.BASEBOARD_FAB2(SCH_1):PVCCIN_CPU1    I82 @BASEBOARD_FAB2_LIB.BASEBOARD_FAB2(SCH_1):PAGE76
     2    GND @BASEBOARD_FAB2_LIB.BASEBOARD_FAB2(SCH_1):GND    I82 @BASEBOARD_FAB2_LIB.BASEBOARD_FAB2(SCH_1):PAGE76

C2D26 CAP_A_0603V-22.0UF,4V,20%,X6S,A
     1 PVCCIN_CPU1 @BASEBOARD_FAB2_LIB.BASEBOARD_FAB2(SCH_1):PVCCIN_CPU1   I108 @BASEBOARD_FAB2_LIB.BASEBOARD_FAB2(SCH_1):PAGE76
     2    GND @BASEBOARD_FAB2_LIB.BASEBOARD_FAB2(SCH_1):GND   I108 @BASEBOARD_FAB2_LIB.BASEBOARD_FAB2(SCH_1):PAGE76

C2D27 CAP_A_0603V-22.0UF,4V,20%,X6S,A
     1 PVCCIN_CPU1 @BASEBOARD_FAB2_LIB.BASEBOARD_FAB2(SCH_1):PVCCIN_CPU1    I66 @BASEBOARD_FAB2_LIB.BASEBOARD_FAB2(SCH_1):PAGE76
     2    GND @BASEBOARD_FAB2_LIB.BASEBOARD_FAB2(SCH_1):GND    I66 @BASEBOARD_FAB2_LIB.BASEBOARD_FAB2(SCH_1):PAGE76

C2D28 CAP_A_0603V-22.0UF,4V,20%,X6S,A
     1 PVCCMCP_CPU1 @BASEBOARD_FAB2_LIB.BASEBOARD_FAB2(SCH_1):PVCCMCP_CPU1   I198 @BASEBOARD_FAB2_LIB.BASEBOARD_FAB2(SCH_1):PAGE76
     2    GND @BASEBOARD_FAB2_LIB.BASEBOARD_FAB2(SCH_1):GND   I198 @BASEBOARD_FAB2_LIB.BASEBOARD_FAB2(SCH_1):PAGE76

C2D29 CAP_A_0603V-22.0UF,4V,20%,X6S,A
     1 PVCCMCP_CPU1 @BASEBOARD_FAB2_LIB.BASEBOARD_FAB2(SCH_1):PVCCMCP_CPU1   I199 @BASEBOARD_FAB2_LIB.BASEBOARD_FAB2(SCH_1):PAGE76
     2    GND @BASEBOARD_FAB2_LIB.BASEBOARD_FAB2(SCH_1):GND   I199 @BASEBOARD_FAB2_LIB.BASEBOARD_FAB2(SCH_1):PAGE76

C2D30 CAP_A_0603V-22.0UF,4V,20%,X6S,A
     1 PVCCIN_CPU1 @BASEBOARD_FAB2_LIB.BASEBOARD_FAB2(SCH_1):PVCCIN_CPU1    I83 @BASEBOARD_FAB2_LIB.BASEBOARD_FAB2(SCH_1):PAGE76
     2    GND @BASEBOARD_FAB2_LIB.BASEBOARD_FAB2(SCH_1):GND    I83 @BASEBOARD_FAB2_LIB.BASEBOARD_FAB2(SCH_1):PAGE76

C2D31 CAP_A_0603V-22.0UF,4V,20%,X6S,A
     1 PVCCIN_CPU1 @BASEBOARD_FAB2_LIB.BASEBOARD_FAB2(SCH_1):PVCCIN_CPU1    I63 @BASEBOARD_FAB2_LIB.BASEBOARD_FAB2(SCH_1):PAGE76
     2    GND @BASEBOARD_FAB2_LIB.BASEBOARD_FAB2(SCH_1):GND    I63 @BASEBOARD_FAB2_LIB.BASEBOARD_FAB2(SCH_1):PAGE76

C2D32 CAP_A_0603V-22.0UF,4V,20%,X6S,A
     1 PVCCIN_CPU1 @BASEBOARD_FAB2_LIB.BASEBOARD_FAB2(SCH_1):PVCCIN_CPU1    I90 @BASEBOARD_FAB2_LIB.BASEBOARD_FAB2(SCH_1):PAGE76
     2    GND @BASEBOARD_FAB2_LIB.BASEBOARD_FAB2(SCH_1):GND    I90 @BASEBOARD_FAB2_LIB.BASEBOARD_FAB2(SCH_1):PAGE76

C2D33 CAP_A_0603V-22.0UF,4V,20%,X6S,A
     1 PVCCIN_CPU1 @BASEBOARD_FAB2_LIB.BASEBOARD_FAB2(SCH_1):PVCCIN_CPU1    I85 @BASEBOARD_FAB2_LIB.BASEBOARD_FAB2(SCH_1):PAGE76
     2    GND @BASEBOARD_FAB2_LIB.BASEBOARD_FAB2(SCH_1):GND    I85 @BASEBOARD_FAB2_LIB.BASEBOARD_FAB2(SCH_1):PAGE76

C2D34 CAP_A_0603V-22.0UF,4V,20%,X6S,A
     1 PVCCIN_CPU1 @BASEBOARD_FAB2_LIB.BASEBOARD_FAB2(SCH_1):PVCCIN_CPU1   I122 @BASEBOARD_FAB2_LIB.BASEBOARD_FAB2(SCH_1):PAGE76
     2    GND @BASEBOARD_FAB2_LIB.BASEBOARD_FAB2(SCH_1):GND   I122 @BASEBOARD_FAB2_LIB.BASEBOARD_FAB2(SCH_1):PAGE76

C2D35 CAP_A_0603V-22.0UF,4V,20%,X6S,A
     1 PVCCIN_CPU1 @BASEBOARD_FAB2_LIB.BASEBOARD_FAB2(SCH_1):PVCCIN_CPU1   I161 @BASEBOARD_FAB2_LIB.BASEBOARD_FAB2(SCH_1):PAGE76
     2    GND @BASEBOARD_FAB2_LIB.BASEBOARD_FAB2(SCH_1):GND   I161 @BASEBOARD_FAB2_LIB.BASEBOARD_FAB2(SCH_1):PAGE76

C2D36 CAP_A_0603V-22.0UF,4V,20%,X6S,A
     1 PVCCIN_CPU1 @BASEBOARD_FAB2_LIB.BASEBOARD_FAB2(SCH_1):PVCCIN_CPU1    I70 @BASEBOARD_FAB2_LIB.BASEBOARD_FAB2(SCH_1):PAGE76
     2    GND @BASEBOARD_FAB2_LIB.BASEBOARD_FAB2(SCH_1):GND    I70 @BASEBOARD_FAB2_LIB.BASEBOARD_FAB2(SCH_1):PAGE76

C2D37 CAP_A_0603V-22.0UF,4V,20%,X6S,A
     1 PVCCIN_CPU1 @BASEBOARD_FAB2_LIB.BASEBOARD_FAB2(SCH_1):PVCCIN_CPU1   I119 @BASEBOARD_FAB2_LIB.BASEBOARD_FAB2(SCH_1):PAGE76
     2    GND @BASEBOARD_FAB2_LIB.BASEBOARD_FAB2(SCH_1):GND   I119 @BASEBOARD_FAB2_LIB.BASEBOARD_FAB2(SCH_1):PAGE76

C2D38 CAP_A_0603V-22.0UF,4V,20%,X6S,A
     1 PVCCIN_CPU1 @BASEBOARD_FAB2_LIB.BASEBOARD_FAB2(SCH_1):PVCCIN_CPU1   I160 @BASEBOARD_FAB2_LIB.BASEBOARD_FAB2(SCH_1):PAGE76
     2    GND @BASEBOARD_FAB2_LIB.BASEBOARD_FAB2(SCH_1):GND   I160 @BASEBOARD_FAB2_LIB.BASEBOARD_FAB2(SCH_1):PAGE76

C2D39 CAP_A_0603V-22.0UF,4V,20%,X6S,A
     1 PVCCMCP_CPU1 @BASEBOARD_FAB2_LIB.BASEBOARD_FAB2(SCH_1):PVCCMCP_CPU1   I165 @BASEBOARD_FAB2_LIB.BASEBOARD_FAB2(SCH_1):PAGE76
     2    GND @BASEBOARD_FAB2_LIB.BASEBOARD_FAB2(SCH_1):GND   I165 @BASEBOARD_FAB2_LIB.BASEBOARD_FAB2(SCH_1):PAGE76

C2D40 CAP_A_0603V-22.0UF,4V,20%,X6S,A
     1 PVCCMCP_CPU1 @BASEBOARD_FAB2_LIB.BASEBOARD_FAB2(SCH_1):PVCCMCP_CPU1    I10 @BASEBOARD_FAB2_LIB.BASEBOARD_FAB2(SCH_1):PAGE76
     2    GND @BASEBOARD_FAB2_LIB.BASEBOARD_FAB2(SCH_1):GND    I10 @BASEBOARD_FAB2_LIB.BASEBOARD_FAB2(SCH_1):PAGE76

C2D41 CAP_A_0603V-22.0UF,4V,20%,X6S,A
     1 PVDDQ_GHJ @BASEBOARD_FAB2_LIB.BASEBOARD_FAB2(SCH_1):PVDDQ_GHJ   I271 @BASEBOARD_FAB2_LIB.BASEBOARD_FAB2(SCH_1):PAGE225
     2    GND @BASEBOARD_FAB2_LIB.BASEBOARD_FAB2(SCH_1):GND   I271 @BASEBOARD_FAB2_LIB.BASEBOARD_FAB2(SCH_1):PAGE225

C2D42 CAP_A_0603V-22.0UF,4V,20%,X6S,A
     1 PVDDQ_GHJ @BASEBOARD_FAB2_LIB.BASEBOARD_FAB2(SCH_1):PVDDQ_GHJ   I273 @BASEBOARD_FAB2_LIB.BASEBOARD_FAB2(SCH_1):PAGE225
     2    GND @BASEBOARD_FAB2_LIB.BASEBOARD_FAB2(SCH_1):GND   I273 @BASEBOARD_FAB2_LIB.BASEBOARD_FAB2(SCH_1):PAGE225

C2D43 CAP_A_0603V-22.0UF,4V,20%,X6S,A
     1 PVDDQ_GHJ @BASEBOARD_FAB2_LIB.BASEBOARD_FAB2(SCH_1):PVDDQ_GHJ   I270 @BASEBOARD_FAB2_LIB.BASEBOARD_FAB2(SCH_1):PAGE225
     2    GND @BASEBOARD_FAB2_LIB.BASEBOARD_FAB2(SCH_1):GND   I270 @BASEBOARD_FAB2_LIB.BASEBOARD_FAB2(SCH_1):PAGE225

C2D44 CAP_A_0603V-22.0UF,4V,20%,X6S,A
     1 PVDDQ_GHJ @BASEBOARD_FAB2_LIB.BASEBOARD_FAB2(SCH_1):PVDDQ_GHJ   I272 @BASEBOARD_FAB2_LIB.BASEBOARD_FAB2(SCH_1):PAGE225
     2    GND @BASEBOARD_FAB2_LIB.BASEBOARD_FAB2(SCH_1):GND   I272 @BASEBOARD_FAB2_LIB.BASEBOARD_FAB2(SCH_1):PAGE225

C2D45 CAP_A_0603V-22.0UF,4V,20%,X6S,A
     1 PVDDQ_GHJ @BASEBOARD_FAB2_LIB.BASEBOARD_FAB2(SCH_1):PVDDQ_GHJ   I261 @BASEBOARD_FAB2_LIB.BASEBOARD_FAB2(SCH_1):PAGE225
     2    GND @BASEBOARD_FAB2_LIB.BASEBOARD_FAB2(SCH_1):GND   I261 @BASEBOARD_FAB2_LIB.BASEBOARD_FAB2(SCH_1):PAGE225

C2D46 CAP_A_0603V-22.0UF,4V,20%,X6S,A
     1 PVDDQ_GHJ @BASEBOARD_FAB2_LIB.BASEBOARD_FAB2(SCH_1):PVDDQ_GHJ   I264 @BASEBOARD_FAB2_LIB.BASEBOARD_FAB2(SCH_1):PAGE225
     2    GND @BASEBOARD_FAB2_LIB.BASEBOARD_FAB2(SCH_1):GND   I264 @BASEBOARD_FAB2_LIB.BASEBOARD_FAB2(SCH_1):PAGE225

C2D47 CAP_A_0603V-22.0UF,4V,20%,X6S,A
     1 PVDDQ_GHJ @BASEBOARD_FAB2_LIB.BASEBOARD_FAB2(SCH_1):PVDDQ_GHJ   I263 @BASEBOARD_FAB2_LIB.BASEBOARD_FAB2(SCH_1):PAGE225
     2    GND @BASEBOARD_FAB2_LIB.BASEBOARD_FAB2(SCH_1):GND   I263 @BASEBOARD_FAB2_LIB.BASEBOARD_FAB2(SCH_1):PAGE225

C2F1 CAP_A_0603V-47UF,4V,20%,X5R,60A
     1 PVDDQ_GHJ @BASEBOARD_FAB2_LIB.BASEBOARD_FAB2(SCH_1):PVDDQ_GHJ   I201 @BASEBOARD_FAB2_LIB.BASEBOARD_FAB2(SCH_1):PAGE225
     2    GND @BASEBOARD_FAB2_LIB.BASEBOARD_FAB2(SCH_1):GND   I201 @BASEBOARD_FAB2_LIB.BASEBOARD_FAB2(SCH_1):PAGE225

C2F2 CAP_A_0603V-47UF,4V,20%,X5R,60A
     1 PVTT_GHJ @BASEBOARD_FAB2_LIB.BASEBOARD_FAB2(SCH_1):PVTT_GHJ    I28 @BASEBOARD_FAB2_LIB.BASEBOARD_FAB2(SCH_1):PAGE229
     2    GND @BASEBOARD_FAB2_LIB.BASEBOARD_FAB2(SCH_1):GND    I28 @BASEBOARD_FAB2_LIB.BASEBOARD_FAB2(SCH_1):PAGE229

C2G1 CAP_A_0603V-47UF,4V,20%,X5R,60A
     1 PVDDQ_GHJ @BASEBOARD_FAB2_LIB.BASEBOARD_FAB2(SCH_1):PVDDQ_GHJ   I277 @BASEBOARD_FAB2_LIB.BASEBOARD_FAB2(SCH_1):PAGE225
     2    GND @BASEBOARD_FAB2_LIB.BASEBOARD_FAB2(SCH_1):GND   I277 @BASEBOARD_FAB2_LIB.BASEBOARD_FAB2(SCH_1):PAGE225

C2G2 CAP_A_0603V-47UF,4V,20%,X5R,60A
     1 PVDDQ_GHJ @BASEBOARD_FAB2_LIB.BASEBOARD_FAB2(SCH_1):PVDDQ_GHJ   I279 @BASEBOARD_FAB2_LIB.BASEBOARD_FAB2(SCH_1):PAGE225
     2    GND @BASEBOARD_FAB2_LIB.BASEBOARD_FAB2(SCH_1):GND   I279 @BASEBOARD_FAB2_LIB.BASEBOARD_FAB2(SCH_1):PAGE225

C2G3 CAP_A_0603V-47UF,4V,20%,X5R,60A
     1 PVDDQ_GHJ @BASEBOARD_FAB2_LIB.BASEBOARD_FAB2(SCH_1):PVDDQ_GHJ   I280 @BASEBOARD_FAB2_LIB.BASEBOARD_FAB2(SCH_1):PAGE225
     2    GND @BASEBOARD_FAB2_LIB.BASEBOARD_FAB2(SCH_1):GND   I280 @BASEBOARD_FAB2_LIB.BASEBOARD_FAB2(SCH_1):PAGE225

C2G4 CAP_A_0603V-47UF,4V,20%,X5R,60A
     1 PVDDQ_GHJ @BASEBOARD_FAB2_LIB.BASEBOARD_FAB2(SCH_1):PVDDQ_GHJ   I281 @BASEBOARD_FAB2_LIB.BASEBOARD_FAB2(SCH_1):PAGE225
     2    GND @BASEBOARD_FAB2_LIB.BASEBOARD_FAB2(SCH_1):GND   I281 @BASEBOARD_FAB2_LIB.BASEBOARD_FAB2(SCH_1):PAGE225

C2G5 CAP_A_0603V-47UF,4V,20%,X5R,60A
     1 PVDDQ_GHJ @BASEBOARD_FAB2_LIB.BASEBOARD_FAB2(SCH_1):PVDDQ_GHJ   I282 @BASEBOARD_FAB2_LIB.BASEBOARD_FAB2(SCH_1):PAGE225
     2    GND @BASEBOARD_FAB2_LIB.BASEBOARD_FAB2(SCH_1):GND   I282 @BASEBOARD_FAB2_LIB.BASEBOARD_FAB2(SCH_1):PAGE225

C2G6 CAP_A_0603V-47UF,4V,20%,X5R,60A
     1 PVDDQ_GHJ @BASEBOARD_FAB2_LIB.BASEBOARD_FAB2(SCH_1):PVDDQ_GHJ   I283 @BASEBOARD_FAB2_LIB.BASEBOARD_FAB2(SCH_1):PAGE225
     2    GND @BASEBOARD_FAB2_LIB.BASEBOARD_FAB2(SCH_1):GND   I283 @BASEBOARD_FAB2_LIB.BASEBOARD_FAB2(SCH_1):PAGE225

C2G7 CAP_0805-100UF,4V,20%,X5R,6024A
     1 PVDDQ_GHJ @BASEBOARD_FAB2_LIB.BASEBOARD_FAB2(SCH_1):PVDDQ_GHJ   I312 @BASEBOARD_FAB2_LIB.BASEBOARD_FAB2(SCH_1):PAGE225
     2    GND @BASEBOARD_FAB2_LIB.BASEBOARD_FAB2(SCH_1):GND   I312 @BASEBOARD_FAB2_LIB.BASEBOARD_FAB2(SCH_1):PAGE225

C2G8 CAP_A_0603V-47UF,4V,20%,X5R,60A
     1 PVDDQ_GHJ @BASEBOARD_FAB2_LIB.BASEBOARD_FAB2(SCH_1):PVDDQ_GHJ   I197 @BASEBOARD_FAB2_LIB.BASEBOARD_FAB2(SCH_1):PAGE225
     2    GND @BASEBOARD_FAB2_LIB.BASEBOARD_FAB2(SCH_1):GND   I197 @BASEBOARD_FAB2_LIB.BASEBOARD_FAB2(SCH_1):PAGE225

C2G9 CAP_A_0603V-47UF,4V,20%,X5R,60A
     1 PVDDQ_GHJ @BASEBOARD_FAB2_LIB.BASEBOARD_FAB2(SCH_1):PVDDQ_GHJ   I278 @BASEBOARD_FAB2_LIB.BASEBOARD_FAB2(SCH_1):PAGE225
     2    GND @BASEBOARD_FAB2_LIB.BASEBOARD_FAB2(SCH_1):GND   I278 @BASEBOARD_FAB2_LIB.BASEBOARD_FAB2(SCH_1):PAGE225

C2G10 CAP_A_0603V-47UF,4V,20%,X5R,60A
     1 PVDDQ_GHJ @BASEBOARD_FAB2_LIB.BASEBOARD_FAB2(SCH_1):PVDDQ_GHJ   I274 @BASEBOARD_FAB2_LIB.BASEBOARD_FAB2(SCH_1):PAGE225
     2    GND @BASEBOARD_FAB2_LIB.BASEBOARD_FAB2(SCH_1):GND   I274 @BASEBOARD_FAB2_LIB.BASEBOARD_FAB2(SCH_1):PAGE225

C2G11 CAP_A_0603V-47UF,4V,20%,X5R,60A
     1 PVDDQ_GHJ @BASEBOARD_FAB2_LIB.BASEBOARD_FAB2(SCH_1):PVDDQ_GHJ   I275 @BASEBOARD_FAB2_LIB.BASEBOARD_FAB2(SCH_1):PAGE225
     2    GND @BASEBOARD_FAB2_LIB.BASEBOARD_FAB2(SCH_1):GND   I275 @BASEBOARD_FAB2_LIB.BASEBOARD_FAB2(SCH_1):PAGE225

C2G12 CAP_A_0603V-47UF,4V,20%,X5R,60A
     1 PVDDQ_GHJ @BASEBOARD_FAB2_LIB.BASEBOARD_FAB2(SCH_1):PVDDQ_GHJ   I276 @BASEBOARD_FAB2_LIB.BASEBOARD_FAB2(SCH_1):PAGE225
     2    GND @BASEBOARD_FAB2_LIB.BASEBOARD_FAB2(SCH_1):GND   I276 @BASEBOARD_FAB2_LIB.BASEBOARD_FAB2(SCH_1):PAGE225

C2G13 CAP_A_0603V-47UF,4V,20%,X5R,60A
     1 PVDDQ_GHJ @BASEBOARD_FAB2_LIB.BASEBOARD_FAB2(SCH_1):PVDDQ_GHJ   I286 @BASEBOARD_FAB2_LIB.BASEBOARD_FAB2(SCH_1):PAGE225
     2    GND @BASEBOARD_FAB2_LIB.BASEBOARD_FAB2(SCH_1):GND   I286 @BASEBOARD_FAB2_LIB.BASEBOARD_FAB2(SCH_1):PAGE225

C2G14 CAP_A_0603V-47UF,4V,20%,X5R,60A
     1 PVDDQ_GHJ @BASEBOARD_FAB2_LIB.BASEBOARD_FAB2(SCH_1):PVDDQ_GHJ   I287 @BASEBOARD_FAB2_LIB.BASEBOARD_FAB2(SCH_1):PAGE225
     2    GND @BASEBOARD_FAB2_LIB.BASEBOARD_FAB2(SCH_1):GND   I287 @BASEBOARD_FAB2_LIB.BASEBOARD_FAB2(SCH_1):PAGE225

C2G15 CAP_A_0603V-47UF,4V,20%,X5R,60A
     1 PVDDQ_GHJ @BASEBOARD_FAB2_LIB.BASEBOARD_FAB2(SCH_1):PVDDQ_GHJ   I200 @BASEBOARD_FAB2_LIB.BASEBOARD_FAB2(SCH_1):PAGE225
     2    GND @BASEBOARD_FAB2_LIB.BASEBOARD_FAB2(SCH_1):GND   I200 @BASEBOARD_FAB2_LIB.BASEBOARD_FAB2(SCH_1):PAGE225

C2G16 CAP_0805-100UF,4V,20%,X5R,6024A
     1 PVDDQ_GHJ @BASEBOARD_FAB2_LIB.BASEBOARD_FAB2(SCH_1):PVDDQ_GHJ   I311 @BASEBOARD_FAB2_LIB.BASEBOARD_FAB2(SCH_1):PAGE225
     2    GND @BASEBOARD_FAB2_LIB.BASEBOARD_FAB2(SCH_1):GND   I311 @BASEBOARD_FAB2_LIB.BASEBOARD_FAB2(SCH_1):PAGE225

C2L2 CAP_0402LF-220PF,50V,10%,X7R,AA
     1 VR_P1V05_PCH_STBY_AVSP @BASEBOARD_FAB2_LIB.BASEBOARD_FAB2(SCH_1):VR_P1V05_PCH_STBY_AVSP   I153 @BASEBOARD_FAB2_LIB.BASEBOARD_FAB2(SCH_1):PAGE235
     2 VSENSE_P1V05_PCH_STBY_AVSN @BASEBOARD_FAB2_LIB.BASEBOARD_FAB2(SCH_1):VSENSE_P1V05_PCH_STBY_AVSN   I153 @BASEBOARD_FAB2_LIB.BASEBOARD_FAB2(SCH_1):PAGE235

C2L3 CAP_A_0402V-0.01UF,25V,10%,X7RA
     1 SATA6G_PCH_PCIE_UP_SATA_RXN<3> @BASEBOARD_FAB2_LIB.BASEBOARD_FAB2(SCH_1):SATA6G_PCH_PCIE_UP_SATA_RXN(3)   I194 @BASEBOARD_FAB2_LIB.BASEBOARD_FAB2(SCH_1):PAGE173
     2 SATA6G_P3_RX_C_DN @BASEBOARD_FAB2_LIB.BASEBOARD_FAB2(SCH_1):SATA6G_P3_RX_C_DN   I194 @BASEBOARD_FAB2_LIB.BASEBOARD_FAB2(SCH_1):PAGE173

C2L4 CAP_A_0402V-0.01UF,25V,10%,X7RA
     1 SATA6G_PCH_PCIE_UP_SATA_RXP<3> @BASEBOARD_FAB2_LIB.BASEBOARD_FAB2(SCH_1):SATA6G_PCH_PCIE_UP_SATA_RXP(3)   I192 @BASEBOARD_FAB2_LIB.BASEBOARD_FAB2(SCH_1):PAGE173
     2 SATA6G_P3_RX_C_DP @BASEBOARD_FAB2_LIB.BASEBOARD_FAB2(SCH_1):SATA6G_P3_RX_C_DP   I192 @BASEBOARD_FAB2_LIB.BASEBOARD_FAB2(SCH_1):PAGE173

C2L5 CAP_A_0402V-0.01UF,25V,10%,X7RA
     1 SATA6G_PCH_PCIE_UP_SATA_RXN<7> @BASEBOARD_FAB2_LIB.BASEBOARD_FAB2(SCH_1):SATA6G_PCH_PCIE_UP_SATA_RXN(7)   I209 @BASEBOARD_FAB2_LIB.BASEBOARD_FAB2(SCH_1):PAGE173
     2 SATA6G_P7_RX_C_DN @BASEBOARD_FAB2_LIB.BASEBOARD_FAB2(SCH_1):SATA6G_P7_RX_C_DN   I209 @BASEBOARD_FAB2_LIB.BASEBOARD_FAB2(SCH_1):PAGE173

C2L6 CAP_A_0402V-0.01UF,25V,10%,X7RA
     1 SATA6G_PCH_PCIE_UP_SATA_RXN<1> @BASEBOARD_FAB2_LIB.BASEBOARD_FAB2(SCH_1):SATA6G_PCH_PCIE_UP_SATA_RXN(1)   I166 @BASEBOARD_FAB2_LIB.BASEBOARD_FAB2(SCH_1):PAGE173
     2 SATA6G_P1_RX_C_DN @BASEBOARD_FAB2_LIB.BASEBOARD_FAB2(SCH_1):SATA6G_P1_RX_C_DN   I166 @BASEBOARD_FAB2_LIB.BASEBOARD_FAB2(SCH_1):PAGE173

C2L7 CAP_A_0402V-0.01UF,25V,10%,X7RA
     1 SATA6G_PCH_PCIE_UP_SATA_RXP<7> @BASEBOARD_FAB2_LIB.BASEBOARD_FAB2(SCH_1):SATA6G_PCH_PCIE_UP_SATA_RXP(7)   I206 @BASEBOARD_FAB2_LIB.BASEBOARD_FAB2(SCH_1):PAGE173
     2 SATA6G_P7_RX_C_DP @BASEBOARD_FAB2_LIB.BASEBOARD_FAB2(SCH_1):SATA6G_P7_RX_C_DP   I206 @BASEBOARD_FAB2_LIB.BASEBOARD_FAB2(SCH_1):PAGE173

C2L8 CAP_A_0402V-1.0UF,6.3V,10%,X6SA
     1 VR_PVNN_PCH_VDD @BASEBOARD_FAB2_LIB.BASEBOARD_FAB2(SCH_1):VR_PVNN_PCH_VDD   I151 @BASEBOARD_FAB2_LIB.BASEBOARD_FAB2(SCH_1):PAGE235
     2    GND @BASEBOARD_FAB2_LIB.BASEBOARD_FAB2(SCH_1):GND   I151 @BASEBOARD_FAB2_LIB.BASEBOARD_FAB2(SCH_1):PAGE235

C2L9 CAP_A_0402V-0.01UF,25V,10%,X7RA
     1 SATA6G_PCH_PCIE_UP_SATA_RXN<5> @BASEBOARD_FAB2_LIB.BASEBOARD_FAB2(SCH_1):SATA6G_PCH_PCIE_UP_SATA_RXN(5)   I207 @BASEBOARD_FAB2_LIB.BASEBOARD_FAB2(SCH_1):PAGE173
     2 SATA6G_P5_RX_C_DN @BASEBOARD_FAB2_LIB.BASEBOARD_FAB2(SCH_1):SATA6G_P5_RX_C_DN   I207 @BASEBOARD_FAB2_LIB.BASEBOARD_FAB2(SCH_1):PAGE173

C2L10 CAP_A_0402V-0.01UF,25V,10%,X7RA
     1 SATA6G_PCH_PCIE_UP_SATA_RXP<1> @BASEBOARD_FAB2_LIB.BASEBOARD_FAB2(SCH_1):SATA6G_PCH_PCIE_UP_SATA_RXP(1)   I173 @BASEBOARD_FAB2_LIB.BASEBOARD_FAB2(SCH_1):PAGE173
     2 SATA6G_P1_RX_C_DP @BASEBOARD_FAB2_LIB.BASEBOARD_FAB2(SCH_1):SATA6G_P1_RX_C_DP   I173 @BASEBOARD_FAB2_LIB.BASEBOARD_FAB2(SCH_1):PAGE173

C2L11 CAP_A_0402V-0.1UF,16V,10%,X7R,A
     1 VR_PVNN_PCH_VDD @BASEBOARD_FAB2_LIB.BASEBOARD_FAB2(SCH_1):VR_PVNN_PCH_VDD   I169 @BASEBOARD_FAB2_LIB.BASEBOARD_FAB2(SCH_1):PAGE235
     2    GND @BASEBOARD_FAB2_LIB.BASEBOARD_FAB2(SCH_1):GND   I169 @BASEBOARD_FAB2_LIB.BASEBOARD_FAB2(SCH_1):PAGE235

C2L12 CAP_A_0402V-0.01UF,25V,10%,X7RA
     1 SATA6G_PCH_PCIE_UP_SATA_RXP<5> @BASEBOARD_FAB2_LIB.BASEBOARD_FAB2(SCH_1):SATA6G_PCH_PCIE_UP_SATA_RXP(5)   I196 @BASEBOARD_FAB2_LIB.BASEBOARD_FAB2(SCH_1):PAGE173
     2 SATA6G_P5_RX_C_DP @BASEBOARD_FAB2_LIB.BASEBOARD_FAB2(SCH_1):SATA6G_P5_RX_C_DP   I196 @BASEBOARD_FAB2_LIB.BASEBOARD_FAB2(SCH_1):PAGE173

C2L13 CAP_A_0402V-0.01UF,25V,10%,X7RA
     1 SATA6G_PCH_PCIE_UP_SATA_RXN<2> @BASEBOARD_FAB2_LIB.BASEBOARD_FAB2(SCH_1):SATA6G_PCH_PCIE_UP_SATA_RXN(2)   I165 @BASEBOARD_FAB2_LIB.BASEBOARD_FAB2(SCH_1):PAGE173
     2 SATA6G_P2_RX_C_DN @BASEBOARD_FAB2_LIB.BASEBOARD_FAB2(SCH_1):SATA6G_P2_RX_C_DN   I165 @BASEBOARD_FAB2_LIB.BASEBOARD_FAB2(SCH_1):PAGE173

C2L14 CAP_A_0402V-0.01UF,25V,10%,X7RA
     1 SATA6G_PCH_PCIE_UP_SATA_RXN<6> @BASEBOARD_FAB2_LIB.BASEBOARD_FAB2(SCH_1):SATA6G_PCH_PCIE_UP_SATA_RXN(6)   I208 @BASEBOARD_FAB2_LIB.BASEBOARD_FAB2(SCH_1):PAGE173
     2 SATA6G_P6_RX_C_DN @BASEBOARD_FAB2_LIB.BASEBOARD_FAB2(SCH_1):SATA6G_P6_RX_C_DN   I208 @BASEBOARD_FAB2_LIB.BASEBOARD_FAB2(SCH_1):PAGE173

C2L15 CAP_A_0402V-0.01UF,25V,10%,X7RA
     1 SATA6G_PCH_PCIE_UP_SATA_RXP<2> @BASEBOARD_FAB2_LIB.BASEBOARD_FAB2(SCH_1):SATA6G_PCH_PCIE_UP_SATA_RXP(2)   I191 @BASEBOARD_FAB2_LIB.BASEBOARD_FAB2(SCH_1):PAGE173
     2 SATA6G_P2_RX_C_DP @BASEBOARD_FAB2_LIB.BASEBOARD_FAB2(SCH_1):SATA6G_P2_RX_C_DP   I191 @BASEBOARD_FAB2_LIB.BASEBOARD_FAB2(SCH_1):PAGE173

C2L16 CAP_A_0402V-0.01UF,25V,10%,X7RA
     1 SATA6G_PCH_PCIE_UP_SATA_RXP<6> @BASEBOARD_FAB2_LIB.BASEBOARD_FAB2(SCH_1):SATA6G_PCH_PCIE_UP_SATA_RXP(6)   I205 @BASEBOARD_FAB2_LIB.BASEBOARD_FAB2(SCH_1):PAGE173
     2 SATA6G_P6_RX_C_DP @BASEBOARD_FAB2_LIB.BASEBOARD_FAB2(SCH_1):SATA6G_P6_RX_C_DP   I205 @BASEBOARD_FAB2_LIB.BASEBOARD_FAB2(SCH_1):PAGE173

C2L17 CAP_A_0402V-0.01UF,25V,10%,X7RA
     1 SATA6G_PCH_PCIE_UP_SATA_RXN<0> @BASEBOARD_FAB2_LIB.BASEBOARD_FAB2(SCH_1):SATA6G_PCH_PCIE_UP_SATA_RXN(0)   I174 @BASEBOARD_FAB2_LIB.BASEBOARD_FAB2(SCH_1):PAGE173
     2 SATA6G_P0_RX_C_DN @BASEBOARD_FAB2_LIB.BASEBOARD_FAB2(SCH_1):SATA6G_P0_RX_C_DN   I174 @BASEBOARD_FAB2_LIB.BASEBOARD_FAB2(SCH_1):PAGE173

C2L18 CAP_A_0402V-0.01UF,25V,10%,X7RA
     1 SATA6G_PCH_PCIE_UP_SATA_RXN<4> @BASEBOARD_FAB2_LIB.BASEBOARD_FAB2(SCH_1):SATA6G_PCH_PCIE_UP_SATA_RXN(4)   I197 @BASEBOARD_FAB2_LIB.BASEBOARD_FAB2(SCH_1):PAGE173
     2 SATA6G_P4_RX_C_DN @BASEBOARD_FAB2_LIB.BASEBOARD_FAB2(SCH_1):SATA6G_P4_RX_C_DN   I197 @BASEBOARD_FAB2_LIB.BASEBOARD_FAB2(SCH_1):PAGE173

C2L19 CAP_A_0402V-0.01UF,25V,10%,X7RA
     1 SATA6G_PCH_PCIE_UP_SATA_RXP<0> @BASEBOARD_FAB2_LIB.BASEBOARD_FAB2(SCH_1):SATA6G_PCH_PCIE_UP_SATA_RXP(0)   I172 @BASEBOARD_FAB2_LIB.BASEBOARD_FAB2(SCH_1):PAGE173
     2 SATA6G_P0_RX_C_DP @BASEBOARD_FAB2_LIB.BASEBOARD_FAB2(SCH_1):SATA6G_P0_RX_C_DP   I172 @BASEBOARD_FAB2_LIB.BASEBOARD_FAB2(SCH_1):PAGE173

C2L20 CAP_A_0402V-0.01UF,25V,10%,X7RA
     1 SATA6G_PCH_PCIE_UP_SATA_RXP<4> @BASEBOARD_FAB2_LIB.BASEBOARD_FAB2(SCH_1):SATA6G_PCH_PCIE_UP_SATA_RXP(4)   I195 @BASEBOARD_FAB2_LIB.BASEBOARD_FAB2(SCH_1):PAGE173
     2 SATA6G_P4_RX_C_DP @BASEBOARD_FAB2_LIB.BASEBOARD_FAB2(SCH_1):SATA6G_P4_RX_C_DP   I195 @BASEBOARD_FAB2_LIB.BASEBOARD_FAB2(SCH_1):PAGE173

C2L21 CAP_A_0402V-0.01UF,25V,10%,X7RA
     1 SATA6G_P7_TX_C_DN @BASEBOARD_FAB2_LIB.BASEBOARD_FAB2(SCH_1):SATA6G_P7_TX_C_DN   I259 @BASEBOARD_FAB2_LIB.BASEBOARD_FAB2(SCH_1):PAGE173
     2 SATA6G_PCH_PCIE_UP_SATA_TXN<7> @BASEBOARD_FAB2_LIB.BASEBOARD_FAB2(SCH_1):SATA6G_PCH_PCIE_UP_SATA_TXN(7)   I259 @BASEBOARD_FAB2_LIB.BASEBOARD_FAB2(SCH_1):PAGE173

C2L22 CAP_A_0402V-0.01UF,25V,10%,X7RA
     1 SATA6G_P3_TX_C_DN @BASEBOARD_FAB2_LIB.BASEBOARD_FAB2(SCH_1):SATA6G_P3_TX_C_DN   I234 @BASEBOARD_FAB2_LIB.BASEBOARD_FAB2(SCH_1):PAGE173
     2 SATA6G_PCH_PCIE_UP_SATA_TXN<3> @BASEBOARD_FAB2_LIB.BASEBOARD_FAB2(SCH_1):SATA6G_PCH_PCIE_UP_SATA_TXN(3)   I234 @BASEBOARD_FAB2_LIB.BASEBOARD_FAB2(SCH_1):PAGE173

C2L23 CAP_A_0402V-0.01UF,25V,10%,X7RA
     1 SATA6G_P3_TX_C_DP @BASEBOARD_FAB2_LIB.BASEBOARD_FAB2(SCH_1):SATA6G_P3_TX_C_DP   I241 @BASEBOARD_FAB2_LIB.BASEBOARD_FAB2(SCH_1):PAGE173
     2 SATA6G_PCH_PCIE_UP_SATA_TXP<3> @BASEBOARD_FAB2_LIB.BASEBOARD_FAB2(SCH_1):SATA6G_PCH_PCIE_UP_SATA_TXP(3)   I241 @BASEBOARD_FAB2_LIB.BASEBOARD_FAB2(SCH_1):PAGE173

C2L24 CAP_A_0402V-0.01UF,25V,10%,X7RA
     1 SATA6G_P7_TX_C_DP @BASEBOARD_FAB2_LIB.BASEBOARD_FAB2(SCH_1):SATA6G_P7_TX_C_DP   I258 @BASEBOARD_FAB2_LIB.BASEBOARD_FAB2(SCH_1):PAGE173
     2 SATA6G_PCH_PCIE_UP_SATA_TXP<7> @BASEBOARD_FAB2_LIB.BASEBOARD_FAB2(SCH_1):SATA6G_PCH_PCIE_UP_SATA_TXP(7)   I258 @BASEBOARD_FAB2_LIB.BASEBOARD_FAB2(SCH_1):PAGE173

C2L25 CAPP_SM-470UF,2V,20%,ALUM,6990A
     1 P1V05_PCH_STBY @BASEBOARD_FAB2_LIB.BASEBOARD_FAB2(SCH_1):P1V05_PCH_STBY    I79 @BASEBOARD_FAB2_LIB.BASEBOARD_FAB2(SCH_1):PAGE236
     2    GND @BASEBOARD_FAB2_LIB.BASEBOARD_FAB2(SCH_1):GND    I79 @BASEBOARD_FAB2_LIB.BASEBOARD_FAB2(SCH_1):PAGE236

C2L26 CAP_A_0402V-0.01UF,25V,10%,X7RA
     1 SATA6G_P5_TX_C_DN @BASEBOARD_FAB2_LIB.BASEBOARD_FAB2(SCH_1):SATA6G_P5_TX_C_DN   I255 @BASEBOARD_FAB2_LIB.BASEBOARD_FAB2(SCH_1):PAGE173
     2 SATA6G_PCH_PCIE_UP_SATA_TXN<5> @BASEBOARD_FAB2_LIB.BASEBOARD_FAB2(SCH_1):SATA6G_PCH_PCIE_UP_SATA_TXN(5)   I255 @BASEBOARD_FAB2_LIB.BASEBOARD_FAB2(SCH_1):PAGE173

C2L27 CAP_A_0402V-0.01UF,25V,10%,X7RA
     1 SATA6G_P5_TX_C_DP @BASEBOARD_FAB2_LIB.BASEBOARD_FAB2(SCH_1):SATA6G_P5_TX_C_DP   I240 @BASEBOARD_FAB2_LIB.BASEBOARD_FAB2(SCH_1):PAGE173
     2 SATA6G_PCH_PCIE_UP_SATA_TXP<5> @BASEBOARD_FAB2_LIB.BASEBOARD_FAB2(SCH_1):SATA6G_PCH_PCIE_UP_SATA_TXP(5)   I240 @BASEBOARD_FAB2_LIB.BASEBOARD_FAB2(SCH_1):PAGE173

C2L32 CAP_0805-47UF,4V,20%,X6S,C9533A
     1 P1V8_PCH_STBY @BASEBOARD_FAB2_LIB.BASEBOARD_FAB2(SCH_1):P1V8_PCH_STBY    I79 @BASEBOARD_FAB2_LIB.BASEBOARD_FAB2(SCH_1):PAGE237
     2    GND @BASEBOARD_FAB2_LIB.BASEBOARD_FAB2(SCH_1):GND    I79 @BASEBOARD_FAB2_LIB.BASEBOARD_FAB2(SCH_1):PAGE237

C2L37 CAP_A_0402V-0.01UF,25V,10%,X7RA
     1 SATA6G_P4_TX_C_DN @BASEBOARD_FAB2_LIB.BASEBOARD_FAB2(SCH_1):SATA6G_P4_TX_C_DN   I238 @BASEBOARD_FAB2_LIB.BASEBOARD_FAB2(SCH_1):PAGE173
     2 SATA6G_PCH_PCIE_UP_SATA_TXN<4> @BASEBOARD_FAB2_LIB.BASEBOARD_FAB2(SCH_1):SATA6G_PCH_PCIE_UP_SATA_TXN(4)   I238 @BASEBOARD_FAB2_LIB.BASEBOARD_FAB2(SCH_1):PAGE173

C2L38 CAP_A_0402V-0.01UF,25V,10%,X7RA
     1 SATA6G_P6_TX_C_DN @BASEBOARD_FAB2_LIB.BASEBOARD_FAB2(SCH_1):SATA6G_P6_TX_C_DN   I256 @BASEBOARD_FAB2_LIB.BASEBOARD_FAB2(SCH_1):PAGE173
     2 SATA6G_PCH_PCIE_UP_SATA_TXN<6> @BASEBOARD_FAB2_LIB.BASEBOARD_FAB2(SCH_1):SATA6G_PCH_PCIE_UP_SATA_TXN(6)   I256 @BASEBOARD_FAB2_LIB.BASEBOARD_FAB2(SCH_1):PAGE173

C2L39 CAP_A_0402V-0.01UF,25V,10%,X7RA
     1 SATA6G_P0_TX_C_DP @BASEBOARD_FAB2_LIB.BASEBOARD_FAB2(SCH_1):SATA6G_P0_TX_C_DP   I221 @BASEBOARD_FAB2_LIB.BASEBOARD_FAB2(SCH_1):PAGE173
     2 SATA6G_PCH_PCIE_UP_SATA_TXP<0> @BASEBOARD_FAB2_LIB.BASEBOARD_FAB2(SCH_1):SATA6G_PCH_PCIE_UP_SATA_TXP(0)   I221 @BASEBOARD_FAB2_LIB.BASEBOARD_FAB2(SCH_1):PAGE173

C2L40 CAP_A_0402V-0.01UF,25V,10%,X7RA
     1 SATA6G_P0_TX_C_DN @BASEBOARD_FAB2_LIB.BASEBOARD_FAB2(SCH_1):SATA6G_P0_TX_C_DN   I220 @BASEBOARD_FAB2_LIB.BASEBOARD_FAB2(SCH_1):PAGE173
     2 SATA6G_PCH_PCIE_UP_SATA_TXN<0> @BASEBOARD_FAB2_LIB.BASEBOARD_FAB2(SCH_1):SATA6G_PCH_PCIE_UP_SATA_TXN(0)   I220 @BASEBOARD_FAB2_LIB.BASEBOARD_FAB2(SCH_1):PAGE173

C2L41 CAP_A_0402V-0.01UF,25V,10%,X7RA
     1 SATA6G_P2_TX_C_DP @BASEBOARD_FAB2_LIB.BASEBOARD_FAB2(SCH_1):SATA6G_P2_TX_C_DP   I242 @BASEBOARD_FAB2_LIB.BASEBOARD_FAB2(SCH_1):PAGE173
     2 SATA6G_PCH_PCIE_UP_SATA_TXP<2> @BASEBOARD_FAB2_LIB.BASEBOARD_FAB2(SCH_1):SATA6G_PCH_PCIE_UP_SATA_TXP(2)   I242 @BASEBOARD_FAB2_LIB.BASEBOARD_FAB2(SCH_1):PAGE173

C2L42 CAP_A_0402V-0.01UF,25V,10%,X7RA
     1 SATA6G_P2_TX_C_DN @BASEBOARD_FAB2_LIB.BASEBOARD_FAB2(SCH_1):SATA6G_P2_TX_C_DN   I233 @BASEBOARD_FAB2_LIB.BASEBOARD_FAB2(SCH_1):PAGE173
     2 SATA6G_PCH_PCIE_UP_SATA_TXN<2> @BASEBOARD_FAB2_LIB.BASEBOARD_FAB2(SCH_1):SATA6G_PCH_PCIE_UP_SATA_TXN(2)   I233 @BASEBOARD_FAB2_LIB.BASEBOARD_FAB2(SCH_1):PAGE173

C2L43 CAP_A_0402V-0.01UF,25V,10%,X7RA
     1 SATA6G_P1_TX_C_DP @BASEBOARD_FAB2_LIB.BASEBOARD_FAB2(SCH_1):SATA6G_P1_TX_C_DP   I222 @BASEBOARD_FAB2_LIB.BASEBOARD_FAB2(SCH_1):PAGE173
     2 SATA6G_PCH_PCIE_UP_SATA_TXP<1> @BASEBOARD_FAB2_LIB.BASEBOARD_FAB2(SCH_1):SATA6G_PCH_PCIE_UP_SATA_TXP(1)   I222 @BASEBOARD_FAB2_LIB.BASEBOARD_FAB2(SCH_1):PAGE173

C2L44 CAP_A_0402V-0.01UF,25V,10%,X7RA
     1 SATA6G_P1_TX_C_DN @BASEBOARD_FAB2_LIB.BASEBOARD_FAB2(SCH_1):SATA6G_P1_TX_C_DN   I228 @BASEBOARD_FAB2_LIB.BASEBOARD_FAB2(SCH_1):PAGE173
     2 SATA6G_PCH_PCIE_UP_SATA_TXN<1> @BASEBOARD_FAB2_LIB.BASEBOARD_FAB2(SCH_1):SATA6G_PCH_PCIE_UP_SATA_TXN(1)   I228 @BASEBOARD_FAB2_LIB.BASEBOARD_FAB2(SCH_1):PAGE173

C2L45 CAP_0805-22UF,6.3V,20%,X6S,C95A
     1 P1V8_PCH_STBY @BASEBOARD_FAB2_LIB.BASEBOARD_FAB2(SCH_1):P1V8_PCH_STBY    I12 @BASEBOARD_FAB2_LIB.BASEBOARD_FAB2(SCH_1):PAGE237
     2    GND @BASEBOARD_FAB2_LIB.BASEBOARD_FAB2(SCH_1):GND    I12 @BASEBOARD_FAB2_LIB.BASEBOARD_FAB2(SCH_1):PAGE237

C2L46 CAPP_SM-470UF,2V,20%,ALUM,6990A
     1 P1V05_PCH_STBY @BASEBOARD_FAB2_LIB.BASEBOARD_FAB2(SCH_1):P1V05_PCH_STBY    I77 @BASEBOARD_FAB2_LIB.BASEBOARD_FAB2(SCH_1):PAGE236
     2    GND @BASEBOARD_FAB2_LIB.BASEBOARD_FAB2(SCH_1):GND    I77 @BASEBOARD_FAB2_LIB.BASEBOARD_FAB2(SCH_1):PAGE236

C2L47 CAP_A_0402V-0.01UF,25V,10%,X7RA
     1 SATA6G_P4_TX_C_DP @BASEBOARD_FAB2_LIB.BASEBOARD_FAB2(SCH_1):SATA6G_P4_TX_C_DP   I239 @BASEBOARD_FAB2_LIB.BASEBOARD_FAB2(SCH_1):PAGE173
     2 SATA6G_PCH_PCIE_UP_SATA_TXP<4> @BASEBOARD_FAB2_LIB.BASEBOARD_FAB2(SCH_1):SATA6G_PCH_PCIE_UP_SATA_TXP(4)   I239 @BASEBOARD_FAB2_LIB.BASEBOARD_FAB2(SCH_1):PAGE173

C2L48 CAP_A_0402V-0.01UF,25V,10%,X7RA
     1 SATA6G_P6_TX_C_DP @BASEBOARD_FAB2_LIB.BASEBOARD_FAB2(SCH_1):SATA6G_P6_TX_C_DP   I257 @BASEBOARD_FAB2_LIB.BASEBOARD_FAB2(SCH_1):PAGE173
     2 SATA6G_PCH_PCIE_UP_SATA_TXP<6> @BASEBOARD_FAB2_LIB.BASEBOARD_FAB2(SCH_1):SATA6G_PCH_PCIE_UP_SATA_TXP(6)   I257 @BASEBOARD_FAB2_LIB.BASEBOARD_FAB2(SCH_1):PAGE173

C2L49 CAP_A_0402V-0.01UF,25V,10%,X7RA
     1 SATA6G_S1_RX_C_DP @BASEBOARD_FAB2_LIB.BASEBOARD_FAB2(SCH_1):SATA6G_S1_RX_C_DP     I5 @BASEBOARD_FAB2_LIB.BASEBOARD_FAB2(SCH_1):PAGE172
     2 SATA6G_S1_RX_DP @BASEBOARD_FAB2_LIB.BASEBOARD_FAB2(SCH_1):SATA6G_S1_RX_DP     I5 @BASEBOARD_FAB2_LIB.BASEBOARD_FAB2(SCH_1):PAGE172

C2L50 CAP_A_0402V-0.01UF,25V,10%,X7RA
     1 SATA6G_S1_RX_C_DN @BASEBOARD_FAB2_LIB.BASEBOARD_FAB2(SCH_1):SATA6G_S1_RX_C_DN     I7 @BASEBOARD_FAB2_LIB.BASEBOARD_FAB2(SCH_1):PAGE172
     2 SATA6G_S1_RX_DN @BASEBOARD_FAB2_LIB.BASEBOARD_FAB2(SCH_1):SATA6G_S1_RX_DN     I7 @BASEBOARD_FAB2_LIB.BASEBOARD_FAB2(SCH_1):PAGE172

C2L51 CAP_A_0402V-0.01UF,25V,10%,X7RA
     1 SATA6G_S1_TX_C_DN @BASEBOARD_FAB2_LIB.BASEBOARD_FAB2(SCH_1):SATA6G_S1_TX_C_DN     I8 @BASEBOARD_FAB2_LIB.BASEBOARD_FAB2(SCH_1):PAGE172
     2 SATA6G_S1_TX_DN @BASEBOARD_FAB2_LIB.BASEBOARD_FAB2(SCH_1):SATA6G_S1_TX_DN     I8 @BASEBOARD_FAB2_LIB.BASEBOARD_FAB2(SCH_1):PAGE172

C2L52 CAP_A_0402V-0.01UF,25V,10%,X7RA
     1 SATA6G_S1_TX_C_DP @BASEBOARD_FAB2_LIB.BASEBOARD_FAB2(SCH_1):SATA6G_S1_TX_C_DP     I6 @BASEBOARD_FAB2_LIB.BASEBOARD_FAB2(SCH_1):PAGE172
     2 SATA6G_S1_TX_DP @BASEBOARD_FAB2_LIB.BASEBOARD_FAB2(SCH_1):SATA6G_S1_TX_DP     I6 @BASEBOARD_FAB2_LIB.BASEBOARD_FAB2(SCH_1):PAGE172

C2M1 CAP_A_0603V-22.0UF,4V,20%,X6S,A
     1 P1V8_PCH_STBY @BASEBOARD_FAB2_LIB.BASEBOARD_FAB2(SCH_1):P1V8_PCH_STBY    I43 @BASEBOARD_FAB2_LIB.BASEBOARD_FAB2(SCH_1):PAGE130
     2    GND @BASEBOARD_FAB2_LIB.BASEBOARD_FAB2(SCH_1):GND    I43 @BASEBOARD_FAB2_LIB.BASEBOARD_FAB2(SCH_1):PAGE130

C2M2 CAP_A_0603V-22.0UF,4V,20%,X6S,A
     1 P1V8_PCH_STBY @BASEBOARD_FAB2_LIB.BASEBOARD_FAB2(SCH_1):P1V8_PCH_STBY    I45 @BASEBOARD_FAB2_LIB.BASEBOARD_FAB2(SCH_1):PAGE130
     2    GND @BASEBOARD_FAB2_LIB.BASEBOARD_FAB2(SCH_1):GND    I45 @BASEBOARD_FAB2_LIB.BASEBOARD_FAB2(SCH_1):PAGE130

C2M3 CAP_A_0402V-0.1UF,16V,10%,X7R,A
     1 P2E_SSB_BMC_TX_DN @BASEBOARD_FAB2_LIB.BASEBOARD_FAB2(SCH_1):P2E_SSB_BMC_TX_DN   I239 @BASEBOARD_FAB2_LIB.BASEBOARD_FAB2(SCH_1):PAGE116
     2 P2E_SSB_BMC_TX_C_DN @BASEBOARD_FAB2_LIB.BASEBOARD_FAB2(SCH_1):P2E_SSB_BMC_TX_C_DN   I239 @BASEBOARD_FAB2_LIB.BASEBOARD_FAB2(SCH_1):PAGE116

C2M4 CAP_A_0402V-0.1UF,16V,10%,X7R,A
     1 P2E_SSB_BMC_TX_DP @BASEBOARD_FAB2_LIB.BASEBOARD_FAB2(SCH_1):P2E_SSB_BMC_TX_DP   I238 @BASEBOARD_FAB2_LIB.BASEBOARD_FAB2(SCH_1):PAGE116
     2 P2E_SSB_BMC_TX_C_DP @BASEBOARD_FAB2_LIB.BASEBOARD_FAB2(SCH_1):P2E_SSB_BMC_TX_C_DP   I238 @BASEBOARD_FAB2_LIB.BASEBOARD_FAB2(SCH_1):PAGE116

C2M5 CAP_0603LF-10UF,4V,20%,X6S,E15A
     1 P1V05_PCH_STBY_WM20_PLL @BASEBOARD_FAB2_LIB.BASEBOARD_FAB2(SCH_1):P1V05_PCH_STBY_WM20_PLL    I43 @BASEBOARD_FAB2_LIB.BASEBOARD_FAB2(SCH_1):PAGE127
     2    GND @BASEBOARD_FAB2_LIB.BASEBOARD_FAB2(SCH_1):GND    I43 @BASEBOARD_FAB2_LIB.BASEBOARD_FAB2(SCH_1):PAGE127

C2M6 CAP_A_0402V-1.0UF,6.3V,10%,X6SA
     1 P1V05_PCH_STBY @BASEBOARD_FAB2_LIB.BASEBOARD_FAB2(SCH_1):P1V05_PCH_STBY    I76 @BASEBOARD_FAB2_LIB.BASEBOARD_FAB2(SCH_1):PAGE127
     2    GND @BASEBOARD_FAB2_LIB.BASEBOARD_FAB2(SCH_1):GND    I76 @BASEBOARD_FAB2_LIB.BASEBOARD_FAB2(SCH_1):PAGE127

C2M7 CAP_A_0402V-1.0UF,6.3V,10%,X6SA
     1 P1V05_PCH_STBY_WM20_PLL @BASEBOARD_FAB2_LIB.BASEBOARD_FAB2(SCH_1):P1V05_PCH_STBY_WM20_PLL    I44 @BASEBOARD_FAB2_LIB.BASEBOARD_FAB2(SCH_1):PAGE127
     2    GND @BASEBOARD_FAB2_LIB.BASEBOARD_FAB2(SCH_1):GND    I44 @BASEBOARD_FAB2_LIB.BASEBOARD_FAB2(SCH_1):PAGE127

C2M8 CAP_A_0402V-1.0UF,6.3V,10%,X6SA
     1 P1V05_PCH_STBY @BASEBOARD_FAB2_LIB.BASEBOARD_FAB2(SCH_1):P1V05_PCH_STBY    I74 @BASEBOARD_FAB2_LIB.BASEBOARD_FAB2(SCH_1):PAGE127
     2    GND @BASEBOARD_FAB2_LIB.BASEBOARD_FAB2(SCH_1):GND    I74 @BASEBOARD_FAB2_LIB.BASEBOARD_FAB2(SCH_1):PAGE127

C2M9 CAP_A_0402V-1.0UF,6.3V,10%,X6SA
     1 P1V05_PCH_STBY_WM26_PLL @BASEBOARD_FAB2_LIB.BASEBOARD_FAB2(SCH_1):P1V05_PCH_STBY_WM26_PLL    I50 @BASEBOARD_FAB2_LIB.BASEBOARD_FAB2(SCH_1):PAGE127
     2    GND @BASEBOARD_FAB2_LIB.BASEBOARD_FAB2(SCH_1):GND    I50 @BASEBOARD_FAB2_LIB.BASEBOARD_FAB2(SCH_1):PAGE127

C2M10 CAP_0603LF-10UF,4V,20%,X6S,E15A
     1 P1V05_PCH_STBY_WM26_PLL @BASEBOARD_FAB2_LIB.BASEBOARD_FAB2(SCH_1):P1V05_PCH_STBY_WM26_PLL    I49 @BASEBOARD_FAB2_LIB.BASEBOARD_FAB2(SCH_1):PAGE127
     2    GND @BASEBOARD_FAB2_LIB.BASEBOARD_FAB2(SCH_1):GND    I49 @BASEBOARD_FAB2_LIB.BASEBOARD_FAB2(SCH_1):PAGE127

C2M11 CAP_0805-47UF,4V,20%,X6S,C9533A
     1 P1V05_PCH_STBY @BASEBOARD_FAB2_LIB.BASEBOARD_FAB2(SCH_1):P1V05_PCH_STBY    I35 @BASEBOARD_FAB2_LIB.BASEBOARD_FAB2(SCH_1):PAGE131
     2    GND @BASEBOARD_FAB2_LIB.BASEBOARD_FAB2(SCH_1):GND    I35 @BASEBOARD_FAB2_LIB.BASEBOARD_FAB2(SCH_1):PAGE131

C2M12 CAP_A_0603V-22.0UF,4V,20%,X6S,A
     1 P1V05_PCH_STBY @BASEBOARD_FAB2_LIB.BASEBOARD_FAB2(SCH_1):P1V05_PCH_STBY    I52 @BASEBOARD_FAB2_LIB.BASEBOARD_FAB2(SCH_1):PAGE131
     2    GND @BASEBOARD_FAB2_LIB.BASEBOARD_FAB2(SCH_1):GND    I52 @BASEBOARD_FAB2_LIB.BASEBOARD_FAB2(SCH_1):PAGE131

C2M13 CAP_A_0603V-22.0UF,4V,20%,X6S,A
     1 P1V05_PCH_STBY @BASEBOARD_FAB2_LIB.BASEBOARD_FAB2(SCH_1):P1V05_PCH_STBY    I48 @BASEBOARD_FAB2_LIB.BASEBOARD_FAB2(SCH_1):PAGE131
     2    GND @BASEBOARD_FAB2_LIB.BASEBOARD_FAB2(SCH_1):GND    I48 @BASEBOARD_FAB2_LIB.BASEBOARD_FAB2(SCH_1):PAGE131

C2M14 CAP_0402-0.22UF,16V,10%,X7R,A3A
     1 P3E_CPU0_PE3_OCP_TXP<8> @BASEBOARD_FAB2_LIB.BASEBOARD_FAB2(SCH_1):P3E_CPU0_PE3_OCP_TXP(8)    I76 @BASEBOARD_FAB2_LIB.BASEBOARD_FAB2(SCH_1):PAGE106
     2 P3E_OCP_CPU0_PE3_C_TXP<8> @BASEBOARD_FAB2_LIB.BASEBOARD_FAB2(SCH_1):P3E_OCP_CPU0_PE3_C_TXP(8)    I76 @BASEBOARD_FAB2_LIB.BASEBOARD_FAB2(SCH_1):PAGE106

C2M15 CAP_0402-0.22UF,16V,10%,X7R,A3A
     1 P3E_CPU0_PE3_OCP_TXN<8> @BASEBOARD_FAB2_LIB.BASEBOARD_FAB2(SCH_1):P3E_CPU0_PE3_OCP_TXN(8)    I86 @BASEBOARD_FAB2_LIB.BASEBOARD_FAB2(SCH_1):PAGE106
     2 P3E_OCP_CPU0_PE3_C_TXN<8> @BASEBOARD_FAB2_LIB.BASEBOARD_FAB2(SCH_1):P3E_OCP_CPU0_PE3_C_TXN(8)    I86 @BASEBOARD_FAB2_LIB.BASEBOARD_FAB2(SCH_1):PAGE106

C2M16 CAP_A_0402V-1.0UF,6.3V,10%,X6SA
     1 P3V3_STBY @BASEBOARD_FAB2_LIB.BASEBOARD_FAB2(SCH_1):P3V3_STBY    I37 @BASEBOARD_FAB2_LIB.BASEBOARD_FAB2(SCH_1):PAGE130
     2    GND @BASEBOARD_FAB2_LIB.BASEBOARD_FAB2(SCH_1):GND    I37 @BASEBOARD_FAB2_LIB.BASEBOARD_FAB2(SCH_1):PAGE130

C2M17 CAP_0805-47UF,4V,20%,X6S,C9533A
     1 P1V05_PCH_STBY @BASEBOARD_FAB2_LIB.BASEBOARD_FAB2(SCH_1):P1V05_PCH_STBY    I34 @BASEBOARD_FAB2_LIB.BASEBOARD_FAB2(SCH_1):PAGE131
     2    GND @BASEBOARD_FAB2_LIB.BASEBOARD_FAB2(SCH_1):GND    I34 @BASEBOARD_FAB2_LIB.BASEBOARD_FAB2(SCH_1):PAGE131

C2M18 CAP_A_0402V-1.0UF,6.3V,10%,X6SA
     1 P1V05_PCH_STBY @BASEBOARD_FAB2_LIB.BASEBOARD_FAB2(SCH_1):P1V05_PCH_STBY    I29 @BASEBOARD_FAB2_LIB.BASEBOARD_FAB2(SCH_1):PAGE131
     2    GND @BASEBOARD_FAB2_LIB.BASEBOARD_FAB2(SCH_1):GND    I29 @BASEBOARD_FAB2_LIB.BASEBOARD_FAB2(SCH_1):PAGE131

C2M19 CAP_A_0402V-1.0UF,6.3V,10%,X6SA
     1 P1V05_PCH_STBY @BASEBOARD_FAB2_LIB.BASEBOARD_FAB2(SCH_1):P1V05_PCH_STBY    I31 @BASEBOARD_FAB2_LIB.BASEBOARD_FAB2(SCH_1):PAGE131
     2    GND @BASEBOARD_FAB2_LIB.BASEBOARD_FAB2(SCH_1):GND    I31 @BASEBOARD_FAB2_LIB.BASEBOARD_FAB2(SCH_1):PAGE131

C2M20 CAP_A_0402V-1.0UF,6.3V,10%,X6SA
     1 P1V05_PCH_STBY @BASEBOARD_FAB2_LIB.BASEBOARD_FAB2(SCH_1):P1V05_PCH_STBY    I39 @BASEBOARD_FAB2_LIB.BASEBOARD_FAB2(SCH_1):PAGE131
     2    GND @BASEBOARD_FAB2_LIB.BASEBOARD_FAB2(SCH_1):GND    I39 @BASEBOARD_FAB2_LIB.BASEBOARD_FAB2(SCH_1):PAGE131

C2M21 CAP_A_0402V-1.0UF,6.3V,10%,X6SA
     1 P1V05_PCH_STBY @BASEBOARD_FAB2_LIB.BASEBOARD_FAB2(SCH_1):P1V05_PCH_STBY    I28 @BASEBOARD_FAB2_LIB.BASEBOARD_FAB2(SCH_1):PAGE131
     2    GND @BASEBOARD_FAB2_LIB.BASEBOARD_FAB2(SCH_1):GND    I28 @BASEBOARD_FAB2_LIB.BASEBOARD_FAB2(SCH_1):PAGE131

C2M22 CAP_A_0402V-1.0UF,6.3V,10%,X6SA
     1 P1V05_PCH_STBY @BASEBOARD_FAB2_LIB.BASEBOARD_FAB2(SCH_1):P1V05_PCH_STBY    I27 @BASEBOARD_FAB2_LIB.BASEBOARD_FAB2(SCH_1):PAGE131
     2    GND @BASEBOARD_FAB2_LIB.BASEBOARD_FAB2(SCH_1):GND    I27 @BASEBOARD_FAB2_LIB.BASEBOARD_FAB2(SCH_1):PAGE131

C2M23 CAP_A_0402V-0.1UF,16V,10%,X7R,A
     1 PE_PCH_SPRV_TX_DP @BASEBOARD_FAB2_LIB.BASEBOARD_FAB2(SCH_1):PE_PCH_SPRV_TX_DP    I89 @BASEBOARD_FAB2_LIB.BASEBOARD_FAB2(SCH_1):PAGE139
     2 PE_PCH_SPRV_TX_C_DP @BASEBOARD_FAB2_LIB.BASEBOARD_FAB2(SCH_1):PE_PCH_SPRV_TX_C_DP    I89 @BASEBOARD_FAB2_LIB.BASEBOARD_FAB2(SCH_1):PAGE139

C2M24 CAP_A_0402V-0.1UF,16V,10%,X7R,A
     1 PE_PCH_SPRV_TX_DN @BASEBOARD_FAB2_LIB.BASEBOARD_FAB2(SCH_1):PE_PCH_SPRV_TX_DN    I90 @BASEBOARD_FAB2_LIB.BASEBOARD_FAB2(SCH_1):PAGE139
     2 PE_PCH_SPRV_TX_C_DN @BASEBOARD_FAB2_LIB.BASEBOARD_FAB2(SCH_1):PE_PCH_SPRV_TX_C_DN    I90 @BASEBOARD_FAB2_LIB.BASEBOARD_FAB2(SCH_1):PAGE139

C2M25 CAP_A_0402V-1.0UF,6.3V,10%,X6SA
     1 P1V05_PCH_STBY @BASEBOARD_FAB2_LIB.BASEBOARD_FAB2(SCH_1):P1V05_PCH_STBY    I78 @BASEBOARD_FAB2_LIB.BASEBOARD_FAB2(SCH_1):PAGE127
     2    GND @BASEBOARD_FAB2_LIB.BASEBOARD_FAB2(SCH_1):GND    I78 @BASEBOARD_FAB2_LIB.BASEBOARD_FAB2(SCH_1):PAGE127

C2N2 CAP_A_0402V-1.0UF,6.3V,10%,X6SA
     1 P1V05_PCH_STBY @BASEBOARD_FAB2_LIB.BASEBOARD_FAB2(SCH_1):P1V05_PCH_STBY    I41 @BASEBOARD_FAB2_LIB.BASEBOARD_FAB2(SCH_1):PAGE131
     2    GND @BASEBOARD_FAB2_LIB.BASEBOARD_FAB2(SCH_1):GND    I41 @BASEBOARD_FAB2_LIB.BASEBOARD_FAB2(SCH_1):PAGE131

C2N3 CAP_A_0402V-1.0UF,6.3V,10%,X6SA
     1 PVNN_PCH_STBY @BASEBOARD_FAB2_LIB.BASEBOARD_FAB2(SCH_1):PVNN_PCH_STBY    I27 @BASEBOARD_FAB2_LIB.BASEBOARD_FAB2(SCH_1):PAGE132
     2    GND @BASEBOARD_FAB2_LIB.BASEBOARD_FAB2(SCH_1):GND    I27 @BASEBOARD_FAB2_LIB.BASEBOARD_FAB2(SCH_1):PAGE132

C2N4 CAP_A_0402V-1.0UF,6.3V,10%,X6SA
     1 PVNN_PCH_STBY @BASEBOARD_FAB2_LIB.BASEBOARD_FAB2(SCH_1):PVNN_PCH_STBY    I28 @BASEBOARD_FAB2_LIB.BASEBOARD_FAB2(SCH_1):PAGE132
     2    GND @BASEBOARD_FAB2_LIB.BASEBOARD_FAB2(SCH_1):GND    I28 @BASEBOARD_FAB2_LIB.BASEBOARD_FAB2(SCH_1):PAGE132

C2N5 CAP_A_0402V-1.0UF,6.3V,10%,X6SA
     1 P1V05_PCH_STBY_KR_PLL @BASEBOARD_FAB2_LIB.BASEBOARD_FAB2(SCH_1):P1V05_PCH_STBY_KR_PLL    I65 @BASEBOARD_FAB2_LIB.BASEBOARD_FAB2(SCH_1):PAGE127
     2    GND @BASEBOARD_FAB2_LIB.BASEBOARD_FAB2(SCH_1):GND    I65 @BASEBOARD_FAB2_LIB.BASEBOARD_FAB2(SCH_1):PAGE127

C2N6 CAP_0603LF-10UF,4V,20%,X6S,E15A
     1 P1V05_PCH_STBY_KR_PLL @BASEBOARD_FAB2_LIB.BASEBOARD_FAB2(SCH_1):P1V05_PCH_STBY_KR_PLL    I64 @BASEBOARD_FAB2_LIB.BASEBOARD_FAB2(SCH_1):PAGE127
     2    GND @BASEBOARD_FAB2_LIB.BASEBOARD_FAB2(SCH_1):GND    I64 @BASEBOARD_FAB2_LIB.BASEBOARD_FAB2(SCH_1):PAGE127

C2N7 CAP_A_0402V-1.0UF,6.3V,10%,X6SA
     1 P1V05_PCH_STBY @BASEBOARD_FAB2_LIB.BASEBOARD_FAB2(SCH_1):P1V05_PCH_STBY    I43 @BASEBOARD_FAB2_LIB.BASEBOARD_FAB2(SCH_1):PAGE131
     2    GND @BASEBOARD_FAB2_LIB.BASEBOARD_FAB2(SCH_1):GND    I43 @BASEBOARD_FAB2_LIB.BASEBOARD_FAB2(SCH_1):PAGE131

C2N8 CAP_A_0402V-1.0UF,6.3V,10%,X6SA
     1 P1V05_PCH_STBY @BASEBOARD_FAB2_LIB.BASEBOARD_FAB2(SCH_1):P1V05_PCH_STBY    I47 @BASEBOARD_FAB2_LIB.BASEBOARD_FAB2(SCH_1):PAGE131
     2    GND @BASEBOARD_FAB2_LIB.BASEBOARD_FAB2(SCH_1):GND    I47 @BASEBOARD_FAB2_LIB.BASEBOARD_FAB2(SCH_1):PAGE131

C2N9 CAP_A_0402V-1.0UF,6.3V,10%,X6SA
     1 PVNN_PCH_STBY @BASEBOARD_FAB2_LIB.BASEBOARD_FAB2(SCH_1):PVNN_PCH_STBY    I26 @BASEBOARD_FAB2_LIB.BASEBOARD_FAB2(SCH_1):PAGE132
     2    GND @BASEBOARD_FAB2_LIB.BASEBOARD_FAB2(SCH_1):GND    I26 @BASEBOARD_FAB2_LIB.BASEBOARD_FAB2(SCH_1):PAGE132

C2N10 CAP_A_0603V-22.0UF,4V,20%,X6S,A
     1 P1V05_PCH_STBY @BASEBOARD_FAB2_LIB.BASEBOARD_FAB2(SCH_1):P1V05_PCH_STBY    I50 @BASEBOARD_FAB2_LIB.BASEBOARD_FAB2(SCH_1):PAGE131
     2    GND @BASEBOARD_FAB2_LIB.BASEBOARD_FAB2(SCH_1):GND    I50 @BASEBOARD_FAB2_LIB.BASEBOARD_FAB2(SCH_1):PAGE131

C2N11 CAP_A_0402V-1.0UF,6.3V,10%,X6SA
     1 PVNN_PCH_STBY @BASEBOARD_FAB2_LIB.BASEBOARD_FAB2(SCH_1):PVNN_PCH_STBY    I30 @BASEBOARD_FAB2_LIB.BASEBOARD_FAB2(SCH_1):PAGE132
     2    GND @BASEBOARD_FAB2_LIB.BASEBOARD_FAB2(SCH_1):GND    I30 @BASEBOARD_FAB2_LIB.BASEBOARD_FAB2(SCH_1):PAGE132

C2N12 CAP_A_0402V-1.0UF,6.3V,10%,X6SA
     1 PVNN_PCH_STBY @BASEBOARD_FAB2_LIB.BASEBOARD_FAB2(SCH_1):PVNN_PCH_STBY    I29 @BASEBOARD_FAB2_LIB.BASEBOARD_FAB2(SCH_1):PAGE132
     2    GND @BASEBOARD_FAB2_LIB.BASEBOARD_FAB2(SCH_1):GND    I29 @BASEBOARD_FAB2_LIB.BASEBOARD_FAB2(SCH_1):PAGE132

C2N13 CAP_A_0402V-1.0UF,6.3V,10%,X6SA
     1 P1V05_PCH_STBY @BASEBOARD_FAB2_LIB.BASEBOARD_FAB2(SCH_1):P1V05_PCH_STBY    I40 @BASEBOARD_FAB2_LIB.BASEBOARD_FAB2(SCH_1):PAGE131
     2    GND @BASEBOARD_FAB2_LIB.BASEBOARD_FAB2(SCH_1):GND    I40 @BASEBOARD_FAB2_LIB.BASEBOARD_FAB2(SCH_1):PAGE131

C2N14 CAP_0603-10UF,6.3V,20%,X6S,E15A
     1 P3V3_STBY @BASEBOARD_FAB2_LIB.BASEBOARD_FAB2(SCH_1):P3V3_STBY    I25 @BASEBOARD_FAB2_LIB.BASEBOARD_FAB2(SCH_1):PAGE130
     2    GND @BASEBOARD_FAB2_LIB.BASEBOARD_FAB2(SCH_1):GND    I25 @BASEBOARD_FAB2_LIB.BASEBOARD_FAB2(SCH_1):PAGE130

C2N15 CAP_A_0402V-1.0UF,6.3V,10%,X6SA
     1 P1V8_PCH_STBY @BASEBOARD_FAB2_LIB.BASEBOARD_FAB2(SCH_1):P1V8_PCH_STBY    I47 @BASEBOARD_FAB2_LIB.BASEBOARD_FAB2(SCH_1):PAGE130
     2    GND @BASEBOARD_FAB2_LIB.BASEBOARD_FAB2(SCH_1):GND    I47 @BASEBOARD_FAB2_LIB.BASEBOARD_FAB2(SCH_1):PAGE130

C2N16 CAP_A_0402V-1.0UF,6.3V,10%,X6SA
     1 P1V8_PCH_STBY @BASEBOARD_FAB2_LIB.BASEBOARD_FAB2(SCH_1):P1V8_PCH_STBY    I52 @BASEBOARD_FAB2_LIB.BASEBOARD_FAB2(SCH_1):PAGE130
     2    GND @BASEBOARD_FAB2_LIB.BASEBOARD_FAB2(SCH_1):GND    I52 @BASEBOARD_FAB2_LIB.BASEBOARD_FAB2(SCH_1):PAGE130

C2N17 CAP_0603-10UF,6.3V,20%,X6S,E15A
     1 P3V3_STBY @BASEBOARD_FAB2_LIB.BASEBOARD_FAB2(SCH_1):P3V3_STBY    I28 @BASEBOARD_FAB2_LIB.BASEBOARD_FAB2(SCH_1):PAGE130
     2    GND @BASEBOARD_FAB2_LIB.BASEBOARD_FAB2(SCH_1):GND    I28 @BASEBOARD_FAB2_LIB.BASEBOARD_FAB2(SCH_1):PAGE130

C2N18 CAP_A_0402V-1.0UF,6.3V,10%,X6SA
     1 P3V3_STBY @BASEBOARD_FAB2_LIB.BASEBOARD_FAB2(SCH_1):P3V3_STBY    I29 @BASEBOARD_FAB2_LIB.BASEBOARD_FAB2(SCH_1):PAGE130
     2    GND @BASEBOARD_FAB2_LIB.BASEBOARD_FAB2(SCH_1):GND    I29 @BASEBOARD_FAB2_LIB.BASEBOARD_FAB2(SCH_1):PAGE130

C2N19 CAP_A_0402V-1.0UF,6.3V,10%,X6SA
     1 P3V3_STBY @BASEBOARD_FAB2_LIB.BASEBOARD_FAB2(SCH_1):P3V3_STBY     I7 @BASEBOARD_FAB2_LIB.BASEBOARD_FAB2(SCH_1):PAGE130
     2    GND @BASEBOARD_FAB2_LIB.BASEBOARD_FAB2(SCH_1):GND     I7 @BASEBOARD_FAB2_LIB.BASEBOARD_FAB2(SCH_1):PAGE130

C2N20 CAP_A_0402V-1.0UF,6.3V,10%,X6SA
     1 P3V3_STBY @BASEBOARD_FAB2_LIB.BASEBOARD_FAB2(SCH_1):P3V3_STBY    I12 @BASEBOARD_FAB2_LIB.BASEBOARD_FAB2(SCH_1):PAGE130
     2    GND @BASEBOARD_FAB2_LIB.BASEBOARD_FAB2(SCH_1):GND    I12 @BASEBOARD_FAB2_LIB.BASEBOARD_FAB2(SCH_1):PAGE130

C2N21 CAP_0603-10UF,6.3V,20%,X6S,E15A
     1 P3V3_STBY @BASEBOARD_FAB2_LIB.BASEBOARD_FAB2(SCH_1):P3V3_STBY    I15 @BASEBOARD_FAB2_LIB.BASEBOARD_FAB2(SCH_1):PAGE130
     2    GND @BASEBOARD_FAB2_LIB.BASEBOARD_FAB2(SCH_1):GND    I15 @BASEBOARD_FAB2_LIB.BASEBOARD_FAB2(SCH_1):PAGE130

C2N22 CAP_0603-10UF,6.3V,20%,X6S,E15A
     1 P3V3_STBY @BASEBOARD_FAB2_LIB.BASEBOARD_FAB2(SCH_1):P3V3_STBY     I9 @BASEBOARD_FAB2_LIB.BASEBOARD_FAB2(SCH_1):PAGE130
     2    GND @BASEBOARD_FAB2_LIB.BASEBOARD_FAB2(SCH_1):GND     I9 @BASEBOARD_FAB2_LIB.BASEBOARD_FAB2(SCH_1):PAGE130

C2N23 CAP_0603-10UF,6.3V,20%,X6S,E15A
     1 P3V3_STBY @BASEBOARD_FAB2_LIB.BASEBOARD_FAB2(SCH_1):P3V3_STBY    I24 @BASEBOARD_FAB2_LIB.BASEBOARD_FAB2(SCH_1):PAGE130
     2    GND @BASEBOARD_FAB2_LIB.BASEBOARD_FAB2(SCH_1):GND    I24 @BASEBOARD_FAB2_LIB.BASEBOARD_FAB2(SCH_1):PAGE130

C2N24 CAP_0603-10UF,6.3V,20%,X6S,E15A
     1 P3V3_STBY @BASEBOARD_FAB2_LIB.BASEBOARD_FAB2(SCH_1):P3V3_STBY     I8 @BASEBOARD_FAB2_LIB.BASEBOARD_FAB2(SCH_1):PAGE130
     2    GND @BASEBOARD_FAB2_LIB.BASEBOARD_FAB2(SCH_1):GND     I8 @BASEBOARD_FAB2_LIB.BASEBOARD_FAB2(SCH_1):PAGE130

C2N25 CAP_A_0402V-1.0UF,6.3V,10%,X6SA
     1 P3V3_STBY @BASEBOARD_FAB2_LIB.BASEBOARD_FAB2(SCH_1):P3V3_STBY    I34 @BASEBOARD_FAB2_LIB.BASEBOARD_FAB2(SCH_1):PAGE130
     2    GND @BASEBOARD_FAB2_LIB.BASEBOARD_FAB2(SCH_1):GND    I34 @BASEBOARD_FAB2_LIB.BASEBOARD_FAB2(SCH_1):PAGE130

C2N26 CAP_A_0402V-1.0UF,6.3V,10%,X6SA
     1 P3V3_STBY @BASEBOARD_FAB2_LIB.BASEBOARD_FAB2(SCH_1):P3V3_STBY     I4 @BASEBOARD_FAB2_LIB.BASEBOARD_FAB2(SCH_1):PAGE130
     2    GND @BASEBOARD_FAB2_LIB.BASEBOARD_FAB2(SCH_1):GND     I4 @BASEBOARD_FAB2_LIB.BASEBOARD_FAB2(SCH_1):PAGE130

C2P1 CAP_A_0402V-0.1UF,16V,10%,X7R,A
     1 P3V3_STBY @BASEBOARD_FAB2_LIB.BASEBOARD_FAB2(SCH_1):P3V3_STBY     I8 @BASEBOARD_FAB2_LIB.BASEBOARD_FAB2(SCH_1):PAGE170
     2    GND @BASEBOARD_FAB2_LIB.BASEBOARD_FAB2(SCH_1):GND     I8 @BASEBOARD_FAB2_LIB.BASEBOARD_FAB2(SCH_1):PAGE170

C2P2 CAP_A_0402V-0.1UF,16V,10%,X7R,A
     1 P3V3_STBY @BASEBOARD_FAB2_LIB.BASEBOARD_FAB2(SCH_1):P3V3_STBY     I9 @BASEBOARD_FAB2_LIB.BASEBOARD_FAB2(SCH_1):PAGE192
     2    GND @BASEBOARD_FAB2_LIB.BASEBOARD_FAB2(SCH_1):GND     I9 @BASEBOARD_FAB2_LIB.BASEBOARD_FAB2(SCH_1):PAGE192

C2P3 CAP_A_0402V-0.1UF,16V,10%,X7R,A
     1 P3V3_STBY @BASEBOARD_FAB2_LIB.BASEBOARD_FAB2(SCH_1):P3V3_STBY    I22 @BASEBOARD_FAB2_LIB.BASEBOARD_FAB2(SCH_1):PAGE192
     2    GND @BASEBOARD_FAB2_LIB.BASEBOARD_FAB2(SCH_1):GND    I22 @BASEBOARD_FAB2_LIB.BASEBOARD_FAB2(SCH_1):PAGE192

C2P4 CAP_A_0402V-0.1UF,16V,10%,X7R,A
     1 P3V3_STBY @BASEBOARD_FAB2_LIB.BASEBOARD_FAB2(SCH_1):P3V3_STBY    I16 @BASEBOARD_FAB2_LIB.BASEBOARD_FAB2(SCH_1):PAGE192
     2    GND @BASEBOARD_FAB2_LIB.BASEBOARD_FAB2(SCH_1):GND    I16 @BASEBOARD_FAB2_LIB.BASEBOARD_FAB2(SCH_1):PAGE192

C2P5 CAP_A_0402V-0.1UF,16V,10%,X7R,A
     1 P3V3_STBY @BASEBOARD_FAB2_LIB.BASEBOARD_FAB2(SCH_1):P3V3_STBY     I3 @BASEBOARD_FAB2_LIB.BASEBOARD_FAB2(SCH_1):PAGE192
     2    GND @BASEBOARD_FAB2_LIB.BASEBOARD_FAB2(SCH_1):GND     I3 @BASEBOARD_FAB2_LIB.BASEBOARD_FAB2(SCH_1):PAGE192

C2P6 CAP_A_0402V-0.1UF,16V,10%,X7R,A
     1 P3V3_STBY @BASEBOARD_FAB2_LIB.BASEBOARD_FAB2(SCH_1):P3V3_STBY    I18 @BASEBOARD_FAB2_LIB.BASEBOARD_FAB2(SCH_1):PAGE192
     2    GND @BASEBOARD_FAB2_LIB.BASEBOARD_FAB2(SCH_1):GND    I18 @BASEBOARD_FAB2_LIB.BASEBOARD_FAB2(SCH_1):PAGE192

C2P7 CAP_A_0402V-0.1UF,16V,10%,X7R,A
     1 P3V3_STBY @BASEBOARD_FAB2_LIB.BASEBOARD_FAB2(SCH_1):P3V3_STBY    I20 @BASEBOARD_FAB2_LIB.BASEBOARD_FAB2(SCH_1):PAGE192
     2    GND @BASEBOARD_FAB2_LIB.BASEBOARD_FAB2(SCH_1):GND    I20 @BASEBOARD_FAB2_LIB.BASEBOARD_FAB2(SCH_1):PAGE192

C2P8 CAP_A_0402V-0.01UF,25V,10%,X7RA
     1 P3V3_STBY @BASEBOARD_FAB2_LIB.BASEBOARD_FAB2(SCH_1):P3V3_STBY     I1 @BASEBOARD_FAB2_LIB.BASEBOARD_FAB2(SCH_1):PAGE192
     2    GND @BASEBOARD_FAB2_LIB.BASEBOARD_FAB2(SCH_1):GND     I1 @BASEBOARD_FAB2_LIB.BASEBOARD_FAB2(SCH_1):PAGE192

C2P9 CAP_A_0402V-0.1UF,16V,10%,X7R,A
     1 P3V3_STBY @BASEBOARD_FAB2_LIB.BASEBOARD_FAB2(SCH_1):P3V3_STBY   I117 @BASEBOARD_FAB2_LIB.BASEBOARD_FAB2(SCH_1):PAGE185
     2    GND @BASEBOARD_FAB2_LIB.BASEBOARD_FAB2(SCH_1):GND   I117 @BASEBOARD_FAB2_LIB.BASEBOARD_FAB2(SCH_1):PAGE185

C2P10 CAP_1206LF-22UF,16V,10%,X6S,D3A
     1 P12V_STBY @BASEBOARD_FAB2_LIB.BASEBOARD_FAB2(SCH_1):P12V_STBY    I41 @BASEBOARD_FAB2_LIB.BASEBOARD_FAB2(SCH_1):PAGE188
     2    GND @BASEBOARD_FAB2_LIB.BASEBOARD_FAB2(SCH_1):GND    I41 @BASEBOARD_FAB2_LIB.BASEBOARD_FAB2(SCH_1):PAGE188

C2P11 CAP_A_0402V-0.1UF,16V,10%,X7R,A
     1 P12V_STBY @BASEBOARD_FAB2_LIB.BASEBOARD_FAB2(SCH_1):P12V_STBY    I21 @BASEBOARD_FAB2_LIB.BASEBOARD_FAB2(SCH_1):PAGE188
     2    GND @BASEBOARD_FAB2_LIB.BASEBOARD_FAB2(SCH_1):GND    I21 @BASEBOARD_FAB2_LIB.BASEBOARD_FAB2(SCH_1):PAGE188

C2P12 CAP_A_0402V-0.1UF,16V,10%,X7R,A
     1 P12V_STBY @BASEBOARD_FAB2_LIB.BASEBOARD_FAB2(SCH_1):P12V_STBY    I23 @BASEBOARD_FAB2_LIB.BASEBOARD_FAB2(SCH_1):PAGE188
     2    GND @BASEBOARD_FAB2_LIB.BASEBOARD_FAB2(SCH_1):GND    I23 @BASEBOARD_FAB2_LIB.BASEBOARD_FAB2(SCH_1):PAGE188

C2P13 CAP_A_0402V-0.1UF,16V,10%,X7R,A
     1 P12V_STBY @BASEBOARD_FAB2_LIB.BASEBOARD_FAB2(SCH_1):P12V_STBY    I57 @BASEBOARD_FAB2_LIB.BASEBOARD_FAB2(SCH_1):PAGE188
     2    GND @BASEBOARD_FAB2_LIB.BASEBOARD_FAB2(SCH_1):GND    I57 @BASEBOARD_FAB2_LIB.BASEBOARD_FAB2(SCH_1):PAGE188

C2P14 CAP_A_0402V-0.1UF,16V,10%,X7R,A
     1 P12V_STBY @BASEBOARD_FAB2_LIB.BASEBOARD_FAB2(SCH_1):P12V_STBY    I56 @BASEBOARD_FAB2_LIB.BASEBOARD_FAB2(SCH_1):PAGE188
     2    GND @BASEBOARD_FAB2_LIB.BASEBOARD_FAB2(SCH_1):GND    I56 @BASEBOARD_FAB2_LIB.BASEBOARD_FAB2(SCH_1):PAGE188

C2P15 CAP_A_0402V-0.1UF,16V,10%,X7R,A
     1 P12V_STBY @BASEBOARD_FAB2_LIB.BASEBOARD_FAB2(SCH_1):P12V_STBY    I55 @BASEBOARD_FAB2_LIB.BASEBOARD_FAB2(SCH_1):PAGE188
     2    GND @BASEBOARD_FAB2_LIB.BASEBOARD_FAB2(SCH_1):GND    I55 @BASEBOARD_FAB2_LIB.BASEBOARD_FAB2(SCH_1):PAGE188

C2P16 CAP_A_0402V-0.1UF,16V,10%,X7R,A
     1 P12V_STBY @BASEBOARD_FAB2_LIB.BASEBOARD_FAB2(SCH_1):P12V_STBY    I53 @BASEBOARD_FAB2_LIB.BASEBOARD_FAB2(SCH_1):PAGE188
     2    GND @BASEBOARD_FAB2_LIB.BASEBOARD_FAB2(SCH_1):GND    I53 @BASEBOARD_FAB2_LIB.BASEBOARD_FAB2(SCH_1):PAGE188

C2R1 CAP_A_0402V-0.1UF,16V,10%,X7R,A
     1 P3V3_STBY @BASEBOARD_FAB2_LIB.BASEBOARD_FAB2(SCH_1):P3V3_STBY     I8 @BASEBOARD_FAB2_LIB.BASEBOARD_FAB2(SCH_1):PAGE192
     2    GND @BASEBOARD_FAB2_LIB.BASEBOARD_FAB2(SCH_1):GND     I8 @BASEBOARD_FAB2_LIB.BASEBOARD_FAB2(SCH_1):PAGE192

C2R2 CAP_A_0402V-0.1UF,16V,10%,X7R,A
     1 P3V3_STBY @BASEBOARD_FAB2_LIB.BASEBOARD_FAB2(SCH_1):P3V3_STBY    I28 @BASEBOARD_FAB2_LIB.BASEBOARD_FAB2(SCH_1):PAGE192
     2    GND @BASEBOARD_FAB2_LIB.BASEBOARD_FAB2(SCH_1):GND    I28 @BASEBOARD_FAB2_LIB.BASEBOARD_FAB2(SCH_1):PAGE192

C2R3 CAP_A_0402V-0.1UF,16V,10%,X7R,A
     1 P3V3_STBY @BASEBOARD_FAB2_LIB.BASEBOARD_FAB2(SCH_1):P3V3_STBY    I19 @BASEBOARD_FAB2_LIB.BASEBOARD_FAB2(SCH_1):PAGE192
     2    GND @BASEBOARD_FAB2_LIB.BASEBOARD_FAB2(SCH_1):GND    I19 @BASEBOARD_FAB2_LIB.BASEBOARD_FAB2(SCH_1):PAGE192

C2R4 CAP_A_0402V-0.1UF,16V,10%,X7R,A
     1 P3V3_STBY @BASEBOARD_FAB2_LIB.BASEBOARD_FAB2(SCH_1):P3V3_STBY    I21 @BASEBOARD_FAB2_LIB.BASEBOARD_FAB2(SCH_1):PAGE192
     2    GND @BASEBOARD_FAB2_LIB.BASEBOARD_FAB2(SCH_1):GND    I21 @BASEBOARD_FAB2_LIB.BASEBOARD_FAB2(SCH_1):PAGE192

C2R5 CAP_A_0402V-0.1UF,16V,10%,X7R,A
     1 P3V3_STBY @BASEBOARD_FAB2_LIB.BASEBOARD_FAB2(SCH_1):P3V3_STBY    I15 @BASEBOARD_FAB2_LIB.BASEBOARD_FAB2(SCH_1):PAGE192
     2    GND @BASEBOARD_FAB2_LIB.BASEBOARD_FAB2(SCH_1):GND    I15 @BASEBOARD_FAB2_LIB.BASEBOARD_FAB2(SCH_1):PAGE192

C2R6 CAP_0402LF-470PF,50V,10%,EMPTYA
     1 FM_PS_EN @BASEBOARD_FAB2_LIB.BASEBOARD_FAB2(SCH_1):FM_PS_EN    I40 @BASEBOARD_FAB2_LIB.BASEBOARD_FAB2(SCH_1):PAGE181
     2    GND @BASEBOARD_FAB2_LIB.BASEBOARD_FAB2(SCH_1):GND    I40 @BASEBOARD_FAB2_LIB.BASEBOARD_FAB2(SCH_1):PAGE181

C2R7 CAP_0402-0.22UF,16V,10%,X7R,A3A
     1 P3E_CPU0_PE3_OCP_TXN<6> @BASEBOARD_FAB2_LIB.BASEBOARD_FAB2(SCH_1):P3E_CPU0_PE3_OCP_TXN(6)   I123 @BASEBOARD_FAB2_LIB.BASEBOARD_FAB2(SCH_1):PAGE106
     2 P3E_OCP_CPU0_PE3_C_TXN<6> @BASEBOARD_FAB2_LIB.BASEBOARD_FAB2(SCH_1):P3E_OCP_CPU0_PE3_C_TXN(6)   I123 @BASEBOARD_FAB2_LIB.BASEBOARD_FAB2(SCH_1):PAGE106

C2R8 CAP_0402-0.22UF,16V,10%,X7R,A3A
     1 P3E_CPU0_PE3_OCP_TXP<6> @BASEBOARD_FAB2_LIB.BASEBOARD_FAB2(SCH_1):P3E_CPU0_PE3_OCP_TXP(6)   I141 @BASEBOARD_FAB2_LIB.BASEBOARD_FAB2(SCH_1):PAGE106
     2 P3E_OCP_CPU0_PE3_C_TXP<6> @BASEBOARD_FAB2_LIB.BASEBOARD_FAB2(SCH_1):P3E_OCP_CPU0_PE3_C_TXP(6)   I141 @BASEBOARD_FAB2_LIB.BASEBOARD_FAB2(SCH_1):PAGE106

C2R9 CAP_0402-0.22UF,16V,10%,X7R,A3A
     1 P3E_CPU0_PE3_OCP_TXN<7> @BASEBOARD_FAB2_LIB.BASEBOARD_FAB2(SCH_1):P3E_CPU0_PE3_OCP_TXN(7)   I147 @BASEBOARD_FAB2_LIB.BASEBOARD_FAB2(SCH_1):PAGE106
     2 P3E_OCP_CPU0_PE3_C_TXN<7> @BASEBOARD_FAB2_LIB.BASEBOARD_FAB2(SCH_1):P3E_OCP_CPU0_PE3_C_TXN(7)   I147 @BASEBOARD_FAB2_LIB.BASEBOARD_FAB2(SCH_1):PAGE106

C2R10 CAP_0402-0.22UF,16V,10%,X7R,A3A
     1 P3E_CPU0_PE3_OCP_TXP<7> @BASEBOARD_FAB2_LIB.BASEBOARD_FAB2(SCH_1):P3E_CPU0_PE3_OCP_TXP(7)   I142 @BASEBOARD_FAB2_LIB.BASEBOARD_FAB2(SCH_1):PAGE106
     2 P3E_OCP_CPU0_PE3_C_TXP<7> @BASEBOARD_FAB2_LIB.BASEBOARD_FAB2(SCH_1):P3E_OCP_CPU0_PE3_C_TXP(7)   I142 @BASEBOARD_FAB2_LIB.BASEBOARD_FAB2(SCH_1):PAGE106

C2R11 SC4D7U16V3KX-GP_SMD-BCG5-SC4D7A
     1 P5V_STBY @BASEBOARD_FAB2_LIB.BASEBOARD_FAB2(SCH_1):P5V_STBY   I191 @BASEBOARD_FAB2_LIB.BASEBOARD_FAB2(SCH_1):PAGE240
     2 AGND_P3V3_STBY @BASEBOARD_FAB2_LIB.BASEBOARD_FAB2(SCH_1):AGND_P3V3_STBY   I191 @BASEBOARD_FAB2_LIB.BASEBOARD_FAB2(SCH_1):PAGE240

C2R12 CAP_A_0402V-1.0UF,6.3V,10%,X6SA
     1 FP_NMI_BTN_OUT_N @BASEBOARD_FAB2_LIB.BASEBOARD_FAB2(SCH_1):FP_NMI_BTN_OUT_N   I353 @BASEBOARD_FAB2_LIB.BASEBOARD_FAB2(SCH_1):PAGE157
     2    GND @BASEBOARD_FAB2_LIB.BASEBOARD_FAB2(SCH_1):GND   I353 @BASEBOARD_FAB2_LIB.BASEBOARD_FAB2(SCH_1):PAGE157

C2R13 CAP_0402-0.22UF,16V,10%,X7R,A3A
     1 P3E_CPU0_PE3_OCP_TXN<5> @BASEBOARD_FAB2_LIB.BASEBOARD_FAB2(SCH_1):P3E_CPU0_PE3_OCP_TXN(5)   I137 @BASEBOARD_FAB2_LIB.BASEBOARD_FAB2(SCH_1):PAGE106
     2 P3E_OCP_CPU0_PE3_C_TXN<5> @BASEBOARD_FAB2_LIB.BASEBOARD_FAB2(SCH_1):P3E_OCP_CPU0_PE3_C_TXN(5)   I137 @BASEBOARD_FAB2_LIB.BASEBOARD_FAB2(SCH_1):PAGE106

C2R14 CAP_0402-0.22UF,16V,10%,X7R,A3A
     1 P3E_CPU0_PE3_OCP_TXP<5> @BASEBOARD_FAB2_LIB.BASEBOARD_FAB2(SCH_1):P3E_CPU0_PE3_OCP_TXP(5)   I130 @BASEBOARD_FAB2_LIB.BASEBOARD_FAB2(SCH_1):PAGE106
     2 P3E_OCP_CPU0_PE3_C_TXP<5> @BASEBOARD_FAB2_LIB.BASEBOARD_FAB2(SCH_1):P3E_OCP_CPU0_PE3_C_TXP(5)   I130 @BASEBOARD_FAB2_LIB.BASEBOARD_FAB2(SCH_1):PAGE106

C2R15 CAP_A_0402V-0.1UF,16V,10%,X7R,A
     1 P12V_STBY @BASEBOARD_FAB2_LIB.BASEBOARD_FAB2(SCH_1):P12V_STBY     I2 @BASEBOARD_FAB2_LIB.BASEBOARD_FAB2(SCH_1):PAGE188
     2    GND @BASEBOARD_FAB2_LIB.BASEBOARD_FAB2(SCH_1):GND     I2 @BASEBOARD_FAB2_LIB.BASEBOARD_FAB2(SCH_1):PAGE188

C2R16 CAP_A_0402V-0.1UF,16V,10%,X7R,A
     1 P12V_STBY @BASEBOARD_FAB2_LIB.BASEBOARD_FAB2(SCH_1):P12V_STBY    I40 @BASEBOARD_FAB2_LIB.BASEBOARD_FAB2(SCH_1):PAGE188
     2    GND @BASEBOARD_FAB2_LIB.BASEBOARD_FAB2(SCH_1):GND    I40 @BASEBOARD_FAB2_LIB.BASEBOARD_FAB2(SCH_1):PAGE188

C2R17 CAP_A_0402V-0.1UF,16V,10%,X7R,A
     1 P12V_STBY @BASEBOARD_FAB2_LIB.BASEBOARD_FAB2(SCH_1):P12V_STBY    I25 @BASEBOARD_FAB2_LIB.BASEBOARD_FAB2(SCH_1):PAGE188
     2    GND @BASEBOARD_FAB2_LIB.BASEBOARD_FAB2(SCH_1):GND    I25 @BASEBOARD_FAB2_LIB.BASEBOARD_FAB2(SCH_1):PAGE188

C2R18 CAP_A_0402V-0.1UF,16V,10%,X7R,A
     1 P12V_STBY @BASEBOARD_FAB2_LIB.BASEBOARD_FAB2(SCH_1):P12V_STBY     I3 @BASEBOARD_FAB2_LIB.BASEBOARD_FAB2(SCH_1):PAGE188
     2    GND @BASEBOARD_FAB2_LIB.BASEBOARD_FAB2(SCH_1):GND     I3 @BASEBOARD_FAB2_LIB.BASEBOARD_FAB2(SCH_1):PAGE188

C2T1 CAP_A_0402V-0.1UF,16V,10%,X7R,A
     1 P3V3_STBY @BASEBOARD_FAB2_LIB.BASEBOARD_FAB2(SCH_1):P3V3_STBY    I94 @BASEBOARD_FAB2_LIB.BASEBOARD_FAB2(SCH_1):PAGE154
     2    GND @BASEBOARD_FAB2_LIB.BASEBOARD_FAB2(SCH_1):GND    I94 @BASEBOARD_FAB2_LIB.BASEBOARD_FAB2(SCH_1):PAGE154

C2T2 CAP_A_0402V-0.1UF,16V,10%,X7R,A
     1   P3V3 @BASEBOARD_FAB2_LIB.BASEBOARD_FAB2(SCH_1):P3V3   I131 @BASEBOARD_FAB2_LIB.BASEBOARD_FAB2(SCH_1):PAGE185
     2    GND @BASEBOARD_FAB2_LIB.BASEBOARD_FAB2(SCH_1):GND   I131 @BASEBOARD_FAB2_LIB.BASEBOARD_FAB2(SCH_1):PAGE185

C2T3 CAP_A_0402V-0.1UF,16V,10%,X7R,A
     1 P3V3_STBY @BASEBOARD_FAB2_LIB.BASEBOARD_FAB2(SCH_1):P3V3_STBY   I370 @BASEBOARD_FAB2_LIB.BASEBOARD_FAB2(SCH_1):PAGE157
     2    GND @BASEBOARD_FAB2_LIB.BASEBOARD_FAB2(SCH_1):GND   I370 @BASEBOARD_FAB2_LIB.BASEBOARD_FAB2(SCH_1):PAGE157

C2T4 CAP_A_0402V-0.1UF,16V,10%,X7R,A
     1   P3V3 @BASEBOARD_FAB2_LIB.BASEBOARD_FAB2(SCH_1):P3V3   I132 @BASEBOARD_FAB2_LIB.BASEBOARD_FAB2(SCH_1):PAGE185
     2    GND @BASEBOARD_FAB2_LIB.BASEBOARD_FAB2(SCH_1):GND   I132 @BASEBOARD_FAB2_LIB.BASEBOARD_FAB2(SCH_1):PAGE185

C2T5 CAP_A_0402V-0.1UF,16V,10%,X7R,A
     1   P3V3 @BASEBOARD_FAB2_LIB.BASEBOARD_FAB2(SCH_1):P3V3   I135 @BASEBOARD_FAB2_LIB.BASEBOARD_FAB2(SCH_1):PAGE185
     2    GND @BASEBOARD_FAB2_LIB.BASEBOARD_FAB2(SCH_1):GND   I135 @BASEBOARD_FAB2_LIB.BASEBOARD_FAB2(SCH_1):PAGE185

C2T6 CAP_0805-22UF,6.3V,20%,X6S,C95A
     1 P3V3_STBY @BASEBOARD_FAB2_LIB.BASEBOARD_FAB2(SCH_1):P3V3_STBY   I160 @BASEBOARD_FAB2_LIB.BASEBOARD_FAB2(SCH_1):PAGE240
     2    GND @BASEBOARD_FAB2_LIB.BASEBOARD_FAB2(SCH_1):GND   I160 @BASEBOARD_FAB2_LIB.BASEBOARD_FAB2(SCH_1):PAGE240

C2T7 CAP_0805-22UF,6.3V,20%,X6S,C95A
     1 P3V3_STBY @BASEBOARD_FAB2_LIB.BASEBOARD_FAB2(SCH_1):P3V3_STBY   I158 @BASEBOARD_FAB2_LIB.BASEBOARD_FAB2(SCH_1):PAGE240
     2    GND @BASEBOARD_FAB2_LIB.BASEBOARD_FAB2(SCH_1):GND   I158 @BASEBOARD_FAB2_LIB.BASEBOARD_FAB2(SCH_1):PAGE240

C2T8 CAP_A_0402V-0.1UF,16V,10%,X7R,A
     1 P3V3_STBY @BASEBOARD_FAB2_LIB.BASEBOARD_FAB2(SCH_1):P3V3_STBY   I135 @BASEBOARD_FAB2_LIB.BASEBOARD_FAB2(SCH_1):PAGE154
     2    GND @BASEBOARD_FAB2_LIB.BASEBOARD_FAB2(SCH_1):GND   I135 @BASEBOARD_FAB2_LIB.BASEBOARD_FAB2(SCH_1):PAGE154

C2T9 CAP_0805-22UF,6.3V,20%,X6S,C95A
     1 P3V3_STBY @BASEBOARD_FAB2_LIB.BASEBOARD_FAB2(SCH_1):P3V3_STBY   I174 @BASEBOARD_FAB2_LIB.BASEBOARD_FAB2(SCH_1):PAGE240
     2    GND @BASEBOARD_FAB2_LIB.BASEBOARD_FAB2(SCH_1):GND   I174 @BASEBOARD_FAB2_LIB.BASEBOARD_FAB2(SCH_1):PAGE240

C2T10 CAP_0402-0.22UF,16V,10%,X7R,A3A
     1 P3E_PCH_M2_TX_C_DP<1> @BASEBOARD_FAB2_LIB.BASEBOARD_FAB2(SCH_1):P3E_PCH_M2_TX_C_DP(1)   I168 @BASEBOARD_FAB2_LIB.BASEBOARD_FAB2(SCH_1):PAGE185
     2 P3E_PCH_M2_TX_DP<1> @BASEBOARD_FAB2_LIB.BASEBOARD_FAB2(SCH_1):P3E_PCH_M2_TX_DP(1)   I168 @BASEBOARD_FAB2_LIB.BASEBOARD_FAB2(SCH_1):PAGE185

C2T11 CAP_0402-0.22UF,16V,10%,X7R,A3A
     1 P3E_PCH_M2_TX_C_DN<1> @BASEBOARD_FAB2_LIB.BASEBOARD_FAB2(SCH_1):P3E_PCH_M2_TX_C_DN(1)   I167 @BASEBOARD_FAB2_LIB.BASEBOARD_FAB2(SCH_1):PAGE185
     2 P3E_PCH_M2_TX_DN<1> @BASEBOARD_FAB2_LIB.BASEBOARD_FAB2(SCH_1):P3E_PCH_M2_TX_DN(1)   I167 @BASEBOARD_FAB2_LIB.BASEBOARD_FAB2(SCH_1):PAGE185

C2T12 CAP_A_0402V-0.1UF,16V,10%,X7R,A
     1 P3V3_STBY @BASEBOARD_FAB2_LIB.BASEBOARD_FAB2(SCH_1):P3V3_STBY   I132 @BASEBOARD_FAB2_LIB.BASEBOARD_FAB2(SCH_1):PAGE154
     2    GND @BASEBOARD_FAB2_LIB.BASEBOARD_FAB2(SCH_1):GND   I132 @BASEBOARD_FAB2_LIB.BASEBOARD_FAB2(SCH_1):PAGE154

C2T13 CAP_0402-0.22UF,16V,10%,X7R,A3A
     1 P3E_PCH_M2_TX_C_DP<2> @BASEBOARD_FAB2_LIB.BASEBOARD_FAB2(SCH_1):P3E_PCH_M2_TX_C_DP(2)   I172 @BASEBOARD_FAB2_LIB.BASEBOARD_FAB2(SCH_1):PAGE185
     2 P3E_PCH_M2_TX_DP<2> @BASEBOARD_FAB2_LIB.BASEBOARD_FAB2(SCH_1):P3E_PCH_M2_TX_DP(2)   I172 @BASEBOARD_FAB2_LIB.BASEBOARD_FAB2(SCH_1):PAGE185

C2T14 CAP_0402-0.22UF,16V,10%,X7R,A3A
     1 P3E_PCH_M2_TX_C_DN<2> @BASEBOARD_FAB2_LIB.BASEBOARD_FAB2(SCH_1):P3E_PCH_M2_TX_C_DN(2)   I171 @BASEBOARD_FAB2_LIB.BASEBOARD_FAB2(SCH_1):PAGE185
     2 P3E_PCH_M2_TX_DN<2> @BASEBOARD_FAB2_LIB.BASEBOARD_FAB2(SCH_1):P3E_PCH_M2_TX_DN(2)   I171 @BASEBOARD_FAB2_LIB.BASEBOARD_FAB2(SCH_1):PAGE185

C2T15 CAP_A_0402V-0.1UF,16V,10%,X7R,A
     1   P3V3 @BASEBOARD_FAB2_LIB.BASEBOARD_FAB2(SCH_1):P3V3   I127 @BASEBOARD_FAB2_LIB.BASEBOARD_FAB2(SCH_1):PAGE185
     2    GND @BASEBOARD_FAB2_LIB.BASEBOARD_FAB2(SCH_1):GND   I127 @BASEBOARD_FAB2_LIB.BASEBOARD_FAB2(SCH_1):PAGE185

C2T16 CAP_A_0402V-0.1UF,16V,10%,X7R,A
     1   P3V3 @BASEBOARD_FAB2_LIB.BASEBOARD_FAB2(SCH_1):P3V3   I126 @BASEBOARD_FAB2_LIB.BASEBOARD_FAB2(SCH_1):PAGE185
     2    GND @BASEBOARD_FAB2_LIB.BASEBOARD_FAB2(SCH_1):GND   I126 @BASEBOARD_FAB2_LIB.BASEBOARD_FAB2(SCH_1):PAGE185

C2T17 CAP_A_0402V-0.1UF,16V,10%,X7R,A
     1 P3V3_STBY_MNG @BASEBOARD_FAB2_LIB.BASEBOARD_FAB2(SCH_1):P3V3_STBY_MNG   I112 @BASEBOARD_FAB2_LIB.BASEBOARD_FAB2(SCH_1):PAGE101
     2    GND @BASEBOARD_FAB2_LIB.BASEBOARD_FAB2(SCH_1):GND   I112 @BASEBOARD_FAB2_LIB.BASEBOARD_FAB2(SCH_1):PAGE101

C2T18 CAP_A_0402V-0.01UF,25V,10%,X7RA
     1 P3V3_STBY_MNG_CPU @BASEBOARD_FAB2_LIB.BASEBOARD_FAB2(SCH_1):P3V3_STBY_MNG_CPU   I104 @BASEBOARD_FAB2_LIB.BASEBOARD_FAB2(SCH_1):PAGE101
     2    GND @BASEBOARD_FAB2_LIB.BASEBOARD_FAB2(SCH_1):GND   I104 @BASEBOARD_FAB2_LIB.BASEBOARD_FAB2(SCH_1):PAGE101

C2T19 CAP_A_0402V-1.0UF,6.3V,10%,X6SA
     1 P3V3_STBY_MNG_CPU @BASEBOARD_FAB2_LIB.BASEBOARD_FAB2(SCH_1):P3V3_STBY_MNG_CPU   I106 @BASEBOARD_FAB2_LIB.BASEBOARD_FAB2(SCH_1):PAGE101
     2    GND @BASEBOARD_FAB2_LIB.BASEBOARD_FAB2(SCH_1):GND   I106 @BASEBOARD_FAB2_LIB.BASEBOARD_FAB2(SCH_1):PAGE101

C2T20 CAP_0402-0.22UF,16V,10%,X7R,A3A
     1 P3E_PCH_M2_TX_C_DP<3> @BASEBOARD_FAB2_LIB.BASEBOARD_FAB2(SCH_1):P3E_PCH_M2_TX_C_DP(3)   I179 @BASEBOARD_FAB2_LIB.BASEBOARD_FAB2(SCH_1):PAGE185
     2 P3E_PCH_M2_TX_DP<3> @BASEBOARD_FAB2_LIB.BASEBOARD_FAB2(SCH_1):P3E_PCH_M2_TX_DP(3)   I179 @BASEBOARD_FAB2_LIB.BASEBOARD_FAB2(SCH_1):PAGE185

C2T21 CAP_A_0402V-0.1UF,16V,10%,X7R,A
     1   P3V3 @BASEBOARD_FAB2_LIB.BASEBOARD_FAB2(SCH_1):P3V3   I124 @BASEBOARD_FAB2_LIB.BASEBOARD_FAB2(SCH_1):PAGE185
     2    GND @BASEBOARD_FAB2_LIB.BASEBOARD_FAB2(SCH_1):GND   I124 @BASEBOARD_FAB2_LIB.BASEBOARD_FAB2(SCH_1):PAGE185

C2T22 CAP_0805-10UF,16V,10%,X6S,C953A
     1 P3V3_STBY_MNG @BASEBOARD_FAB2_LIB.BASEBOARD_FAB2(SCH_1):P3V3_STBY_MNG   I113 @BASEBOARD_FAB2_LIB.BASEBOARD_FAB2(SCH_1):PAGE101
     2    GND @BASEBOARD_FAB2_LIB.BASEBOARD_FAB2(SCH_1):GND   I113 @BASEBOARD_FAB2_LIB.BASEBOARD_FAB2(SCH_1):PAGE101

C2T23 CAP_0402-0.22UF,16V,10%,X7R,A3A
     1 P3E_PCH_M2_TX_C_DN<3> @BASEBOARD_FAB2_LIB.BASEBOARD_FAB2(SCH_1):P3E_PCH_M2_TX_C_DN(3)   I180 @BASEBOARD_FAB2_LIB.BASEBOARD_FAB2(SCH_1):PAGE185
     2 P3E_PCH_M2_TX_DN<3> @BASEBOARD_FAB2_LIB.BASEBOARD_FAB2(SCH_1):P3E_PCH_M2_TX_DN(3)   I180 @BASEBOARD_FAB2_LIB.BASEBOARD_FAB2(SCH_1):PAGE185

C2T24 CAP_A_0402V-0.1UF,16V,10%,X7R,A
     1   P3V3 @BASEBOARD_FAB2_LIB.BASEBOARD_FAB2(SCH_1):P3V3   I129 @BASEBOARD_FAB2_LIB.BASEBOARD_FAB2(SCH_1):PAGE185
     2    GND @BASEBOARD_FAB2_LIB.BASEBOARD_FAB2(SCH_1):GND   I129 @BASEBOARD_FAB2_LIB.BASEBOARD_FAB2(SCH_1):PAGE185

C2T25 CAP_A_0402V-0.1UF,16V,10%,X7R,A
     1 P3V3_STBY_MNG @BASEBOARD_FAB2_LIB.BASEBOARD_FAB2(SCH_1):P3V3_STBY_MNG   I111 @BASEBOARD_FAB2_LIB.BASEBOARD_FAB2(SCH_1):PAGE101
     2    GND @BASEBOARD_FAB2_LIB.BASEBOARD_FAB2(SCH_1):GND   I111 @BASEBOARD_FAB2_LIB.BASEBOARD_FAB2(SCH_1):PAGE101

C2T26 CAP_A_0402V-0.1UF,16V,10%,X7R,A
     1   P3V3 @BASEBOARD_FAB2_LIB.BASEBOARD_FAB2(SCH_1):P3V3   I123 @BASEBOARD_FAB2_LIB.BASEBOARD_FAB2(SCH_1):PAGE185
     2    GND @BASEBOARD_FAB2_LIB.BASEBOARD_FAB2(SCH_1):GND   I123 @BASEBOARD_FAB2_LIB.BASEBOARD_FAB2(SCH_1):PAGE185

C2T27 CAP_A_0402V-0.01UF,25V,10%,X7RA
     1 P3V3_STBY_MNG_RGMII @BASEBOARD_FAB2_LIB.BASEBOARD_FAB2(SCH_1):P3V3_STBY_MNG_RGMII    I90 @BASEBOARD_FAB2_LIB.BASEBOARD_FAB2(SCH_1):PAGE101
     2    GND @BASEBOARD_FAB2_LIB.BASEBOARD_FAB2(SCH_1):GND    I90 @BASEBOARD_FAB2_LIB.BASEBOARD_FAB2(SCH_1):PAGE101

C2T28 CAP_A_0402V-1.0UF,6.3V,10%,X6SA
     1 P3V3_STBY @BASEBOARD_FAB2_LIB.BASEBOARD_FAB2(SCH_1):P3V3_STBY   I116 @BASEBOARD_FAB2_LIB.BASEBOARD_FAB2(SCH_1):PAGE101
     2    GND @BASEBOARD_FAB2_LIB.BASEBOARD_FAB2(SCH_1):GND   I116 @BASEBOARD_FAB2_LIB.BASEBOARD_FAB2(SCH_1):PAGE101

C2T29 CAP_A_0402V-0.1UF,16V,10%,X7R,A
     1   P3V3 @BASEBOARD_FAB2_LIB.BASEBOARD_FAB2(SCH_1):P3V3   I120 @BASEBOARD_FAB2_LIB.BASEBOARD_FAB2(SCH_1):PAGE185
     2    GND @BASEBOARD_FAB2_LIB.BASEBOARD_FAB2(SCH_1):GND   I120 @BASEBOARD_FAB2_LIB.BASEBOARD_FAB2(SCH_1):PAGE185

C2T30 CAP_A_0402V-0.1UF,16V,10%,X7R,A
     1 P3V3_STBY_MNG @BASEBOARD_FAB2_LIB.BASEBOARD_FAB2(SCH_1):P3V3_STBY_MNG   I110 @BASEBOARD_FAB2_LIB.BASEBOARD_FAB2(SCH_1):PAGE101
     2    GND @BASEBOARD_FAB2_LIB.BASEBOARD_FAB2(SCH_1):GND   I110 @BASEBOARD_FAB2_LIB.BASEBOARD_FAB2(SCH_1):PAGE101

C2T31 CAP_A_0402V-1.0UF,6.3V,10%,X6SA
     1 P3V3_STBY_MNG_RGMII @BASEBOARD_FAB2_LIB.BASEBOARD_FAB2(SCH_1):P3V3_STBY_MNG_RGMII    I89 @BASEBOARD_FAB2_LIB.BASEBOARD_FAB2(SCH_1):PAGE101
     2    GND @BASEBOARD_FAB2_LIB.BASEBOARD_FAB2(SCH_1):GND    I89 @BASEBOARD_FAB2_LIB.BASEBOARD_FAB2(SCH_1):PAGE101

C2T32 CAP_A_0402V-0.1UF,16V,10%,X7R,A
     1 P0V7_GTL2104_5_VREF @BASEBOARD_FAB2_LIB.BASEBOARD_FAB2(SCH_1):P0V7_GTL2104_5_VREF    I95 @BASEBOARD_FAB2_LIB.BASEBOARD_FAB2(SCH_1):PAGE93
     2    GND @BASEBOARD_FAB2_LIB.BASEBOARD_FAB2(SCH_1):GND    I95 @BASEBOARD_FAB2_LIB.BASEBOARD_FAB2(SCH_1):PAGE93

C2T33 CAP_A_0402V-1.0UF,6.3V,10%,X6SA
     1   P3V3 @BASEBOARD_FAB2_LIB.BASEBOARD_FAB2(SCH_1):P3V3    I72 @BASEBOARD_FAB2_LIB.BASEBOARD_FAB2(SCH_1):PAGE93
     2    GND @BASEBOARD_FAB2_LIB.BASEBOARD_FAB2(SCH_1):GND    I72 @BASEBOARD_FAB2_LIB.BASEBOARD_FAB2(SCH_1):PAGE93

C2T34 CAP_A_0402V-0.1UF,16V,10%,X7R,A
     1 P3V3_STBY_MNG @BASEBOARD_FAB2_LIB.BASEBOARD_FAB2(SCH_1):P3V3_STBY_MNG   I109 @BASEBOARD_FAB2_LIB.BASEBOARD_FAB2(SCH_1):PAGE101
     2    GND @BASEBOARD_FAB2_LIB.BASEBOARD_FAB2(SCH_1):GND   I109 @BASEBOARD_FAB2_LIB.BASEBOARD_FAB2(SCH_1):PAGE101

C2T35 CAP_A_0402V-0.1UF,16V,10%,X7R,A
     1 P3V3_STBY @BASEBOARD_FAB2_LIB.BASEBOARD_FAB2(SCH_1):P3V3_STBY   I273 @BASEBOARD_FAB2_LIB.BASEBOARD_FAB2(SCH_1):PAGE156
     2    GND @BASEBOARD_FAB2_LIB.BASEBOARD_FAB2(SCH_1):GND   I273 @BASEBOARD_FAB2_LIB.BASEBOARD_FAB2(SCH_1):PAGE156

C2T36 CAP_A_0402V-0.1UF,16V,10%,X7R,A
     1 P3V3_STBY @BASEBOARD_FAB2_LIB.BASEBOARD_FAB2(SCH_1):P3V3_STBY    I43 @BASEBOARD_FAB2_LIB.BASEBOARD_FAB2(SCH_1):PAGE198
     2    GND @BASEBOARD_FAB2_LIB.BASEBOARD_FAB2(SCH_1):GND    I43 @BASEBOARD_FAB2_LIB.BASEBOARD_FAB2(SCH_1):PAGE198

C2T37 CAP_A_0402V-0.01UF,25V,10%,X7RA
     1 P3V3_STBY_MNG_RMII @BASEBOARD_FAB2_LIB.BASEBOARD_FAB2(SCH_1):P3V3_STBY_MNG_RMII    I99 @BASEBOARD_FAB2_LIB.BASEBOARD_FAB2(SCH_1):PAGE101
     2    GND @BASEBOARD_FAB2_LIB.BASEBOARD_FAB2(SCH_1):GND    I99 @BASEBOARD_FAB2_LIB.BASEBOARD_FAB2(SCH_1):PAGE101

C2T38 CAP_A_0402V-1.0UF,6.3V,10%,X6SA
     1 P3V3_STBY_MNG_RMII @BASEBOARD_FAB2_LIB.BASEBOARD_FAB2(SCH_1):P3V3_STBY_MNG_RMII    I97 @BASEBOARD_FAB2_LIB.BASEBOARD_FAB2(SCH_1):PAGE101
     2    GND @BASEBOARD_FAB2_LIB.BASEBOARD_FAB2(SCH_1):GND    I97 @BASEBOARD_FAB2_LIB.BASEBOARD_FAB2(SCH_1):PAGE101

C2U1 CAP_0805-10UF,16V,10%,X6S,C953A
     1 P3V3_STBY @BASEBOARD_FAB2_LIB.BASEBOARD_FAB2(SCH_1):P3V3_STBY    I44 @BASEBOARD_FAB2_LIB.BASEBOARD_FAB2(SCH_1):PAGE198
     2    GND @BASEBOARD_FAB2_LIB.BASEBOARD_FAB2(SCH_1):GND    I44 @BASEBOARD_FAB2_LIB.BASEBOARD_FAB2(SCH_1):PAGE198

C2U2 CAP_0805-10UF,16V,10%,X6S,C953A
     1   P3V3 @BASEBOARD_FAB2_LIB.BASEBOARD_FAB2(SCH_1):P3V3    I47 @BASEBOARD_FAB2_LIB.BASEBOARD_FAB2(SCH_1):PAGE198
     2    GND @BASEBOARD_FAB2_LIB.BASEBOARD_FAB2(SCH_1):GND    I47 @BASEBOARD_FAB2_LIB.BASEBOARD_FAB2(SCH_1):PAGE198

C2U3 CAP_0402-0.22UF,16V,10%,X7R,A3A
     1 P3E_CPU0_PE1_PCH_RXP<0> @BASEBOARD_FAB2_LIB.BASEBOARD_FAB2(SCH_1):P3E_CPU0_PE1_PCH_RXP(0)   I272 @BASEBOARD_FAB2_LIB.BASEBOARD_FAB2(SCH_1):PAGE107
     2 P3E_CPU0_PE1_SS_RXP<0> @BASEBOARD_FAB2_LIB.BASEBOARD_FAB2(SCH_1):P3E_CPU0_PE1_SS_RXP(0)   I272 @BASEBOARD_FAB2_LIB.BASEBOARD_FAB2(SCH_1):PAGE107

C2U4 CAP_0402-0.22UF,16V,10%,X7R,A3A
     1 P3E_CPU0_PE1_PCH_RXN<0> @BASEBOARD_FAB2_LIB.BASEBOARD_FAB2(SCH_1):P3E_CPU0_PE1_PCH_RXN(0)   I257 @BASEBOARD_FAB2_LIB.BASEBOARD_FAB2(SCH_1):PAGE107
     2 P3E_CPU0_PE1_SS_RXN<0> @BASEBOARD_FAB2_LIB.BASEBOARD_FAB2(SCH_1):P3E_CPU0_PE1_SS_RXN(0)   I257 @BASEBOARD_FAB2_LIB.BASEBOARD_FAB2(SCH_1):PAGE107

C2U5 CAP_0402-0.22UF,16V,10%,X7R,A3A
     1 P3E_CPU0_PE1_PCH_RXP<1> @BASEBOARD_FAB2_LIB.BASEBOARD_FAB2(SCH_1):P3E_CPU0_PE1_PCH_RXP(1)   I274 @BASEBOARD_FAB2_LIB.BASEBOARD_FAB2(SCH_1):PAGE107
     2 P3E_CPU0_PE1_SS_RXP<1> @BASEBOARD_FAB2_LIB.BASEBOARD_FAB2(SCH_1):P3E_CPU0_PE1_SS_RXP(1)   I274 @BASEBOARD_FAB2_LIB.BASEBOARD_FAB2(SCH_1):PAGE107

C2U6 CAP_0402-0.22UF,16V,10%,X7R,A3A
     1 P3E_CPU0_PE1_PCH_RXN<1> @BASEBOARD_FAB2_LIB.BASEBOARD_FAB2(SCH_1):P3E_CPU0_PE1_PCH_RXN(1)   I260 @BASEBOARD_FAB2_LIB.BASEBOARD_FAB2(SCH_1):PAGE107
     2 P3E_CPU0_PE1_SS_RXN<1> @BASEBOARD_FAB2_LIB.BASEBOARD_FAB2(SCH_1):P3E_CPU0_PE1_SS_RXN(1)   I260 @BASEBOARD_FAB2_LIB.BASEBOARD_FAB2(SCH_1):PAGE107

C2U7 CAP_0402-0.22UF,16V,10%,X7R,A3A
     1 P3E_CPU0_PE1_PCH_RXP<2> @BASEBOARD_FAB2_LIB.BASEBOARD_FAB2(SCH_1):P3E_CPU0_PE1_PCH_RXP(2)   I277 @BASEBOARD_FAB2_LIB.BASEBOARD_FAB2(SCH_1):PAGE107
     2 P3E_CPU0_PE1_SS_RXP<2> @BASEBOARD_FAB2_LIB.BASEBOARD_FAB2(SCH_1):P3E_CPU0_PE1_SS_RXP(2)   I277 @BASEBOARD_FAB2_LIB.BASEBOARD_FAB2(SCH_1):PAGE107

C2U8 CAP_0402-0.22UF,16V,10%,X7R,A3A
     1 P3E_CPU0_PE1_PCH_RXN<2> @BASEBOARD_FAB2_LIB.BASEBOARD_FAB2(SCH_1):P3E_CPU0_PE1_PCH_RXN(2)   I264 @BASEBOARD_FAB2_LIB.BASEBOARD_FAB2(SCH_1):PAGE107
     2 P3E_CPU0_PE1_SS_RXN<2> @BASEBOARD_FAB2_LIB.BASEBOARD_FAB2(SCH_1):P3E_CPU0_PE1_SS_RXN(2)   I264 @BASEBOARD_FAB2_LIB.BASEBOARD_FAB2(SCH_1):PAGE107

C2U9 CAP_0402-0.22UF,16V,10%,X7R,A3A
     1 P3E_CPU0_PE1_PCH_RXP<3> @BASEBOARD_FAB2_LIB.BASEBOARD_FAB2(SCH_1):P3E_CPU0_PE1_PCH_RXP(3)   I279 @BASEBOARD_FAB2_LIB.BASEBOARD_FAB2(SCH_1):PAGE107
     2 P3E_CPU0_PE1_SS_RXP<3> @BASEBOARD_FAB2_LIB.BASEBOARD_FAB2(SCH_1):P3E_CPU0_PE1_SS_RXP(3)   I279 @BASEBOARD_FAB2_LIB.BASEBOARD_FAB2(SCH_1):PAGE107

C2U10 CAP_0402-0.22UF,16V,10%,X7R,A3A
     1 P3E_CPU0_PE1_PCH_RXN<3> @BASEBOARD_FAB2_LIB.BASEBOARD_FAB2(SCH_1):P3E_CPU0_PE1_PCH_RXN(3)   I267 @BASEBOARD_FAB2_LIB.BASEBOARD_FAB2(SCH_1):PAGE107
     2 P3E_CPU0_PE1_SS_RXN<3> @BASEBOARD_FAB2_LIB.BASEBOARD_FAB2(SCH_1):P3E_CPU0_PE1_SS_RXN(3)   I267 @BASEBOARD_FAB2_LIB.BASEBOARD_FAB2(SCH_1):PAGE107

C2U11 CAP_0402-0.22UF,16V,10%,X7R,A3A
     1 P3E_CPU0_PE1_PCH_RXP<4> @BASEBOARD_FAB2_LIB.BASEBOARD_FAB2(SCH_1):P3E_CPU0_PE1_PCH_RXP(4)   I278 @BASEBOARD_FAB2_LIB.BASEBOARD_FAB2(SCH_1):PAGE107
     2 P3E_CPU0_PE1_SS_RXP<4> @BASEBOARD_FAB2_LIB.BASEBOARD_FAB2(SCH_1):P3E_CPU0_PE1_SS_RXP(4)   I278 @BASEBOARD_FAB2_LIB.BASEBOARD_FAB2(SCH_1):PAGE107

C2U12 CAP_0402-0.22UF,16V,10%,X7R,A3A
     1 P3E_CPU0_PE1_PCH_RXN<4> @BASEBOARD_FAB2_LIB.BASEBOARD_FAB2(SCH_1):P3E_CPU0_PE1_PCH_RXN(4)   I265 @BASEBOARD_FAB2_LIB.BASEBOARD_FAB2(SCH_1):PAGE107
     2 P3E_CPU0_PE1_SS_RXN<4> @BASEBOARD_FAB2_LIB.BASEBOARD_FAB2(SCH_1):P3E_CPU0_PE1_SS_RXN(4)   I265 @BASEBOARD_FAB2_LIB.BASEBOARD_FAB2(SCH_1):PAGE107

C2U13 CAP_0402-0.22UF,16V,10%,X7R,A3A
     1 P3E_CPU0_PE1_PCH_RXP<5> @BASEBOARD_FAB2_LIB.BASEBOARD_FAB2(SCH_1):P3E_CPU0_PE1_PCH_RXP(5)   I297 @BASEBOARD_FAB2_LIB.BASEBOARD_FAB2(SCH_1):PAGE107
     2 P3E_CPU0_PE1_SS_RXP<5> @BASEBOARD_FAB2_LIB.BASEBOARD_FAB2(SCH_1):P3E_CPU0_PE1_SS_RXP(5)   I297 @BASEBOARD_FAB2_LIB.BASEBOARD_FAB2(SCH_1):PAGE107

C2U14 CAP_0402-0.22UF,16V,10%,X7R,A3A
     1 P3E_CPU0_PE1_PCH_RXN<5> @BASEBOARD_FAB2_LIB.BASEBOARD_FAB2(SCH_1):P3E_CPU0_PE1_PCH_RXN(5)   I287 @BASEBOARD_FAB2_LIB.BASEBOARD_FAB2(SCH_1):PAGE107
     2 P3E_CPU0_PE1_SS_RXN<5> @BASEBOARD_FAB2_LIB.BASEBOARD_FAB2(SCH_1):P3E_CPU0_PE1_SS_RXN(5)   I287 @BASEBOARD_FAB2_LIB.BASEBOARD_FAB2(SCH_1):PAGE107

C2U15 CAP_0402-0.22UF,16V,10%,X7R,A3A
     1 P3E_CPU0_PE1_PCH_RXP<6> @BASEBOARD_FAB2_LIB.BASEBOARD_FAB2(SCH_1):P3E_CPU0_PE1_PCH_RXP(6)   I296 @BASEBOARD_FAB2_LIB.BASEBOARD_FAB2(SCH_1):PAGE107
     2 P3E_CPU0_PE1_SS_RXP<6> @BASEBOARD_FAB2_LIB.BASEBOARD_FAB2(SCH_1):P3E_CPU0_PE1_SS_RXP(6)   I296 @BASEBOARD_FAB2_LIB.BASEBOARD_FAB2(SCH_1):PAGE107

C2U16 CAP_0402-0.22UF,16V,10%,X7R,A3A
     1 P3E_CPU0_PE1_PCH_RXN<6> @BASEBOARD_FAB2_LIB.BASEBOARD_FAB2(SCH_1):P3E_CPU0_PE1_PCH_RXN(6)   I286 @BASEBOARD_FAB2_LIB.BASEBOARD_FAB2(SCH_1):PAGE107
     2 P3E_CPU0_PE1_SS_RXN<6> @BASEBOARD_FAB2_LIB.BASEBOARD_FAB2(SCH_1):P3E_CPU0_PE1_SS_RXN(6)   I286 @BASEBOARD_FAB2_LIB.BASEBOARD_FAB2(SCH_1):PAGE107

C2U17 CAP_0402-0.22UF,16V,10%,X7R,A3A
     1 P3E_CPU0_PE1_PCH_RXP<7> @BASEBOARD_FAB2_LIB.BASEBOARD_FAB2(SCH_1):P3E_CPU0_PE1_PCH_RXP(7)   I300 @BASEBOARD_FAB2_LIB.BASEBOARD_FAB2(SCH_1):PAGE107
     2 P3E_CPU0_PE1_SS_RXP<7> @BASEBOARD_FAB2_LIB.BASEBOARD_FAB2(SCH_1):P3E_CPU0_PE1_SS_RXP(7)   I300 @BASEBOARD_FAB2_LIB.BASEBOARD_FAB2(SCH_1):PAGE107

C2U18 CAP_0402-0.22UF,16V,10%,X7R,A3A
     1 P3E_CPU0_PE1_PCH_RXN<7> @BASEBOARD_FAB2_LIB.BASEBOARD_FAB2(SCH_1):P3E_CPU0_PE1_PCH_RXN(7)   I294 @BASEBOARD_FAB2_LIB.BASEBOARD_FAB2(SCH_1):PAGE107
     2 P3E_CPU0_PE1_SS_RXN<7> @BASEBOARD_FAB2_LIB.BASEBOARD_FAB2(SCH_1):P3E_CPU0_PE1_SS_RXN(7)   I294 @BASEBOARD_FAB2_LIB.BASEBOARD_FAB2(SCH_1):PAGE107

C2U19 CAP_A_0402V-0.1UF,16V,10%,X7R,A
     1   P3V3 @BASEBOARD_FAB2_LIB.BASEBOARD_FAB2(SCH_1):P3V3    I46 @BASEBOARD_FAB2_LIB.BASEBOARD_FAB2(SCH_1):PAGE198
     2    GND @BASEBOARD_FAB2_LIB.BASEBOARD_FAB2(SCH_1):GND    I46 @BASEBOARD_FAB2_LIB.BASEBOARD_FAB2(SCH_1):PAGE198

C2U20 CAP_A_0402V-0.1UF,16V,10%,X7R,A
     1   P12V @BASEBOARD_FAB2_LIB.BASEBOARD_FAB2(SCH_1):P12V     I1 @BASEBOARD_FAB2_LIB.BASEBOARD_FAB2(SCH_1):PAGE108
     2    GND @BASEBOARD_FAB2_LIB.BASEBOARD_FAB2(SCH_1):GND     I1 @BASEBOARD_FAB2_LIB.BASEBOARD_FAB2(SCH_1):PAGE108

C2U21 CAP_A_0402V-0.1UF,16V,10%,X7R,A
     1   P3V3 @BASEBOARD_FAB2_LIB.BASEBOARD_FAB2(SCH_1):P3V3     I5 @BASEBOARD_FAB2_LIB.BASEBOARD_FAB2(SCH_1):PAGE108
     2    GND @BASEBOARD_FAB2_LIB.BASEBOARD_FAB2(SCH_1):GND     I5 @BASEBOARD_FAB2_LIB.BASEBOARD_FAB2(SCH_1):PAGE108

C2U22 CAP_A_0402V-0.1UF,16V,10%,X7R,A
     1 P3V3_STBY @BASEBOARD_FAB2_LIB.BASEBOARD_FAB2(SCH_1):P3V3_STBY   I318 @BASEBOARD_FAB2_LIB.BASEBOARD_FAB2(SCH_1):PAGE108
     2    GND @BASEBOARD_FAB2_LIB.BASEBOARD_FAB2(SCH_1):GND   I318 @BASEBOARD_FAB2_LIB.BASEBOARD_FAB2(SCH_1):PAGE108

C2U23 CAP_A_0402V-0.1UF,16V,10%,X7R,A
     1 P3V3_STBY @BASEBOARD_FAB2_LIB.BASEBOARD_FAB2(SCH_1):P3V3_STBY   I315 @BASEBOARD_FAB2_LIB.BASEBOARD_FAB2(SCH_1):PAGE108
     2    GND @BASEBOARD_FAB2_LIB.BASEBOARD_FAB2(SCH_1):GND   I315 @BASEBOARD_FAB2_LIB.BASEBOARD_FAB2(SCH_1):PAGE108

C2U24 CAP_A_0402V-0.1UF,16V,10%,X7R,A
     1   P12V @BASEBOARD_FAB2_LIB.BASEBOARD_FAB2(SCH_1):P12V     I2 @BASEBOARD_FAB2_LIB.BASEBOARD_FAB2(SCH_1):PAGE108
     2    GND @BASEBOARD_FAB2_LIB.BASEBOARD_FAB2(SCH_1):GND     I2 @BASEBOARD_FAB2_LIB.BASEBOARD_FAB2(SCH_1):PAGE108

C2U25 CAP_A_0402V-0.1UF,16V,10%,X7R,A
     1   P3V3 @BASEBOARD_FAB2_LIB.BASEBOARD_FAB2(SCH_1):P3V3     I7 @BASEBOARD_FAB2_LIB.BASEBOARD_FAB2(SCH_1):PAGE108
     2    GND @BASEBOARD_FAB2_LIB.BASEBOARD_FAB2(SCH_1):GND     I7 @BASEBOARD_FAB2_LIB.BASEBOARD_FAB2(SCH_1):PAGE108

C2U26 CAP_A_0402V-1.0UF,6.3V,10%,X6SA
     1 P3V3_RTC_STBY @BASEBOARD_FAB2_LIB.BASEBOARD_FAB2(SCH_1):P3V3_RTC_STBY   I102 @BASEBOARD_FAB2_LIB.BASEBOARD_FAB2(SCH_1):PAGE196
     2    GND @BASEBOARD_FAB2_LIB.BASEBOARD_FAB2(SCH_1):GND   I102 @BASEBOARD_FAB2_LIB.BASEBOARD_FAB2(SCH_1):PAGE196

C2U27 CAP_A_0402V-0.1UF,16V,10%,X7R,A
     1 P3V3_STBY @BASEBOARD_FAB2_LIB.BASEBOARD_FAB2(SCH_1):P3V3_STBY    I90 @BASEBOARD_FAB2_LIB.BASEBOARD_FAB2(SCH_1):PAGE161
     2    GND @BASEBOARD_FAB2_LIB.BASEBOARD_FAB2(SCH_1):GND    I90 @BASEBOARD_FAB2_LIB.BASEBOARD_FAB2(SCH_1):PAGE161

C2U28 CAP_A_0402V-0.1UF,16V,10%,X7R,A
     1 P3V3_STBY @BASEBOARD_FAB2_LIB.BASEBOARD_FAB2(SCH_1):P3V3_STBY    I93 @BASEBOARD_FAB2_LIB.BASEBOARD_FAB2(SCH_1):PAGE161
     2    GND @BASEBOARD_FAB2_LIB.BASEBOARD_FAB2(SCH_1):GND    I93 @BASEBOARD_FAB2_LIB.BASEBOARD_FAB2(SCH_1):PAGE161

C3A1 CAP_A_0603V-47UF,4V,20%,X5R,60A
     1 PVDDQ_KLM @BASEBOARD_FAB2_LIB.BASEBOARD_FAB2(SCH_1):PVDDQ_KLM   I275 @BASEBOARD_FAB2_LIB.BASEBOARD_FAB2(SCH_1):PAGE228
     2    GND @BASEBOARD_FAB2_LIB.BASEBOARD_FAB2(SCH_1):GND   I275 @BASEBOARD_FAB2_LIB.BASEBOARD_FAB2(SCH_1):PAGE228

C3A2 CAP_A_0603V-47UF,4V,20%,X5R,60A
     1 PVDDQ_KLM @BASEBOARD_FAB2_LIB.BASEBOARD_FAB2(SCH_1):PVDDQ_KLM   I276 @BASEBOARD_FAB2_LIB.BASEBOARD_FAB2(SCH_1):PAGE228
     2    GND @BASEBOARD_FAB2_LIB.BASEBOARD_FAB2(SCH_1):GND   I276 @BASEBOARD_FAB2_LIB.BASEBOARD_FAB2(SCH_1):PAGE228

C3A3 CAP_0603LF-10UF,4V,20%,X6S,E15A
     1 PVPP_KLM @BASEBOARD_FAB2_LIB.BASEBOARD_FAB2(SCH_1):PVPP_KLM    I97 @BASEBOARD_FAB2_LIB.BASEBOARD_FAB2(SCH_1):PAGE234
     2    GND @BASEBOARD_FAB2_LIB.BASEBOARD_FAB2(SCH_1):GND    I97 @BASEBOARD_FAB2_LIB.BASEBOARD_FAB2(SCH_1):PAGE234

C3A4 CAP_0603LF-10UF,4V,20%,X6S,E15A
     1 PVPP_KLM @BASEBOARD_FAB2_LIB.BASEBOARD_FAB2(SCH_1):PVPP_KLM    I93 @BASEBOARD_FAB2_LIB.BASEBOARD_FAB2(SCH_1):PAGE234
     2    GND @BASEBOARD_FAB2_LIB.BASEBOARD_FAB2(SCH_1):GND    I93 @BASEBOARD_FAB2_LIB.BASEBOARD_FAB2(SCH_1):PAGE234

C3A5 CAP_A_0603V-47UF,4V,20%,X5R,60A
     1 PVDDQ_KLM @BASEBOARD_FAB2_LIB.BASEBOARD_FAB2(SCH_1):PVDDQ_KLM   I270 @BASEBOARD_FAB2_LIB.BASEBOARD_FAB2(SCH_1):PAGE228
     2    GND @BASEBOARD_FAB2_LIB.BASEBOARD_FAB2(SCH_1):GND   I270 @BASEBOARD_FAB2_LIB.BASEBOARD_FAB2(SCH_1):PAGE228

C3A6 CAP_A_0603V-47UF,4V,20%,X5R,60A
     1 PVDDQ_KLM @BASEBOARD_FAB2_LIB.BASEBOARD_FAB2(SCH_1):PVDDQ_KLM   I269 @BASEBOARD_FAB2_LIB.BASEBOARD_FAB2(SCH_1):PAGE228
     2    GND @BASEBOARD_FAB2_LIB.BASEBOARD_FAB2(SCH_1):GND   I269 @BASEBOARD_FAB2_LIB.BASEBOARD_FAB2(SCH_1):PAGE228

C3A7 CAP_0603LF-10UF,4V,20%,X6S,E15A
     1 PVPP_KLM @BASEBOARD_FAB2_LIB.BASEBOARD_FAB2(SCH_1):PVPP_KLM    I95 @BASEBOARD_FAB2_LIB.BASEBOARD_FAB2(SCH_1):PAGE234
     2    GND @BASEBOARD_FAB2_LIB.BASEBOARD_FAB2(SCH_1):GND    I95 @BASEBOARD_FAB2_LIB.BASEBOARD_FAB2(SCH_1):PAGE234

C3A8 CAP_0603LF-10UF,4V,20%,X6S,E15A
     1 PVPP_KLM @BASEBOARD_FAB2_LIB.BASEBOARD_FAB2(SCH_1):PVPP_KLM    I86 @BASEBOARD_FAB2_LIB.BASEBOARD_FAB2(SCH_1):PAGE234
     2    GND @BASEBOARD_FAB2_LIB.BASEBOARD_FAB2(SCH_1):GND    I86 @BASEBOARD_FAB2_LIB.BASEBOARD_FAB2(SCH_1):PAGE234

C3B1 CAP_0603LF-10UF,4V,20%,X6S,E15A
     1 PVPP_KLM @BASEBOARD_FAB2_LIB.BASEBOARD_FAB2(SCH_1):PVPP_KLM    I94 @BASEBOARD_FAB2_LIB.BASEBOARD_FAB2(SCH_1):PAGE234
     2    GND @BASEBOARD_FAB2_LIB.BASEBOARD_FAB2(SCH_1):GND    I94 @BASEBOARD_FAB2_LIB.BASEBOARD_FAB2(SCH_1):PAGE234

C3B2 CAP_0603LF-10UF,4V,20%,X6S,E15A
     1 PVPP_KLM @BASEBOARD_FAB2_LIB.BASEBOARD_FAB2(SCH_1):PVPP_KLM    I84 @BASEBOARD_FAB2_LIB.BASEBOARD_FAB2(SCH_1):PAGE234
     2    GND @BASEBOARD_FAB2_LIB.BASEBOARD_FAB2(SCH_1):GND    I84 @BASEBOARD_FAB2_LIB.BASEBOARD_FAB2(SCH_1):PAGE234

C3B3 CAPP_7343LF-330UF,6.3V,20%,POSA
     1 PVPP_KLM @BASEBOARD_FAB2_LIB.BASEBOARD_FAB2(SCH_1):PVPP_KLM   I167 @BASEBOARD_FAB2_LIB.BASEBOARD_FAB2(SCH_1):PAGE234
     2    GND @BASEBOARD_FAB2_LIB.BASEBOARD_FAB2(SCH_1):GND   I167 @BASEBOARD_FAB2_LIB.BASEBOARD_FAB2(SCH_1):PAGE234

C3B4 CAP_A_0402V-0.1UF,16V,10%,X7R,A
     1 PVCCIO_CPU1 @BASEBOARD_FAB2_LIB.BASEBOARD_FAB2(SCH_1):PVCCIO_CPU1    I47 @BASEBOARD_FAB2_LIB.BASEBOARD_FAB2(SCH_1):PAGE99
     2    GND @BASEBOARD_FAB2_LIB.BASEBOARD_FAB2(SCH_1):GND    I47 @BASEBOARD_FAB2_LIB.BASEBOARD_FAB2(SCH_1):PAGE99

C3B5 CAP_A_0402V-0.1UF,16V,10%,X7R,A
     1 PVPP_KLM @BASEBOARD_FAB2_LIB.BASEBOARD_FAB2(SCH_1):PVPP_KLM    I53 @BASEBOARD_FAB2_LIB.BASEBOARD_FAB2(SCH_1):PAGE99
     2    GND @BASEBOARD_FAB2_LIB.BASEBOARD_FAB2(SCH_1):GND    I53 @BASEBOARD_FAB2_LIB.BASEBOARD_FAB2(SCH_1):PAGE99

C3B6 CAPP_3018-68UF,16V,20%,TANT,72A
     1 P12V_STBY @BASEBOARD_FAB2_LIB.BASEBOARD_FAB2(SCH_1):P12V_STBY   I100 @BASEBOARD_FAB2_LIB.BASEBOARD_FAB2(SCH_1):PAGE195
     2    GND @BASEBOARD_FAB2_LIB.BASEBOARD_FAB2(SCH_1):GND   I100 @BASEBOARD_FAB2_LIB.BASEBOARD_FAB2(SCH_1):PAGE195

C3C1 CAP_A_0402V-1.0UF,6.3V,10%,X6SA
     1 PVCCIOMCP_CPU1 @BASEBOARD_FAB2_LIB.BASEBOARD_FAB2(SCH_1):PVCCIOMCP_CPU1    I38 @BASEBOARD_FAB2_LIB.BASEBOARD_FAB2(SCH_1):PAGE193
     2    GND @BASEBOARD_FAB2_LIB.BASEBOARD_FAB2(SCH_1):GND    I38 @BASEBOARD_FAB2_LIB.BASEBOARD_FAB2(SCH_1):PAGE193

C3C2 CAP_A_0402V-1.0UF,6.3V,10%,X6SA
     1 PVCCIOMCP_CPU1 @BASEBOARD_FAB2_LIB.BASEBOARD_FAB2(SCH_1):PVCCIOMCP_CPU1    I31 @BASEBOARD_FAB2_LIB.BASEBOARD_FAB2(SCH_1):PAGE193
     2    GND @BASEBOARD_FAB2_LIB.BASEBOARD_FAB2(SCH_1):GND    I31 @BASEBOARD_FAB2_LIB.BASEBOARD_FAB2(SCH_1):PAGE193

C3D1 CAP_A_0603V-22.0UF,4V,20%,X6S,A
     1 PVDDQ_KLM @BASEBOARD_FAB2_LIB.BASEBOARD_FAB2(SCH_1):PVDDQ_KLM   I255 @BASEBOARD_FAB2_LIB.BASEBOARD_FAB2(SCH_1):PAGE228
     2    GND @BASEBOARD_FAB2_LIB.BASEBOARD_FAB2(SCH_1):GND   I255 @BASEBOARD_FAB2_LIB.BASEBOARD_FAB2(SCH_1):PAGE228

C3D2 CAP_A_0603V-22.0UF,4V,20%,X6S,A
     1 PVCCIN_CPU1 @BASEBOARD_FAB2_LIB.BASEBOARD_FAB2(SCH_1):PVCCIN_CPU1    I69 @BASEBOARD_FAB2_LIB.BASEBOARD_FAB2(SCH_1):PAGE76
     2    GND @BASEBOARD_FAB2_LIB.BASEBOARD_FAB2(SCH_1):GND    I69 @BASEBOARD_FAB2_LIB.BASEBOARD_FAB2(SCH_1):PAGE76

C3D3 CAP_0603LF-10UF,4V,20%,X6S,E15A
     1 P1V8_MCP_CPU1 @BASEBOARD_FAB2_LIB.BASEBOARD_FAB2(SCH_1):P1V8_MCP_CPU1    I25 @BASEBOARD_FAB2_LIB.BASEBOARD_FAB2(SCH_1):PAGE72
     2    GND @BASEBOARD_FAB2_LIB.BASEBOARD_FAB2(SCH_1):GND    I25 @BASEBOARD_FAB2_LIB.BASEBOARD_FAB2(SCH_1):PAGE72

C3D4 CAP_A_0603V-22.0UF,4V,20%,X6S,A
     1 PVCCMCP_CPU1 @BASEBOARD_FAB2_LIB.BASEBOARD_FAB2(SCH_1):PVCCMCP_CPU1     I5 @BASEBOARD_FAB2_LIB.BASEBOARD_FAB2(SCH_1):PAGE76
     2    GND @BASEBOARD_FAB2_LIB.BASEBOARD_FAB2(SCH_1):GND     I5 @BASEBOARD_FAB2_LIB.BASEBOARD_FAB2(SCH_1):PAGE76

C3D5 CAP_A_0603V-22.0UF,4V,20%,X6S,A
     1 PVCCMCP_CPU1 @BASEBOARD_FAB2_LIB.BASEBOARD_FAB2(SCH_1):PVCCMCP_CPU1     I3 @BASEBOARD_FAB2_LIB.BASEBOARD_FAB2(SCH_1):PAGE76
     2    GND @BASEBOARD_FAB2_LIB.BASEBOARD_FAB2(SCH_1):GND     I3 @BASEBOARD_FAB2_LIB.BASEBOARD_FAB2(SCH_1):PAGE76

C3D6 CAP_A_0603V-22.0UF,4V,20%,X6S,A
     1 PVCCMCP_CPU1 @BASEBOARD_FAB2_LIB.BASEBOARD_FAB2(SCH_1):PVCCMCP_CPU1   I170 @BASEBOARD_FAB2_LIB.BASEBOARD_FAB2(SCH_1):PAGE76
     2    GND @BASEBOARD_FAB2_LIB.BASEBOARD_FAB2(SCH_1):GND   I170 @BASEBOARD_FAB2_LIB.BASEBOARD_FAB2(SCH_1):PAGE76

C3D7 CAP_A_0603V-22.0UF,4V,20%,X6S,A
     1 PVCCMCP_CPU1 @BASEBOARD_FAB2_LIB.BASEBOARD_FAB2(SCH_1):PVCCMCP_CPU1   I164 @BASEBOARD_FAB2_LIB.BASEBOARD_FAB2(SCH_1):PAGE76
     2    GND @BASEBOARD_FAB2_LIB.BASEBOARD_FAB2(SCH_1):GND   I164 @BASEBOARD_FAB2_LIB.BASEBOARD_FAB2(SCH_1):PAGE76

C3D8 CAP_A_0603V-22.0UF,4V,20%,X6S,A
     1 PVCCIO_CPU1 @BASEBOARD_FAB2_LIB.BASEBOARD_FAB2(SCH_1):PVCCIO_CPU1    I18 @BASEBOARD_FAB2_LIB.BASEBOARD_FAB2(SCH_1):PAGE76
     2    GND @BASEBOARD_FAB2_LIB.BASEBOARD_FAB2(SCH_1):GND    I18 @BASEBOARD_FAB2_LIB.BASEBOARD_FAB2(SCH_1):PAGE76

C3D9 CAP_A_0603V-22.0UF,4V,20%,X6S,A
     1 PVCCIO_CPU1 @BASEBOARD_FAB2_LIB.BASEBOARD_FAB2(SCH_1):PVCCIO_CPU1    I15 @BASEBOARD_FAB2_LIB.BASEBOARD_FAB2(SCH_1):PAGE76
     2    GND @BASEBOARD_FAB2_LIB.BASEBOARD_FAB2(SCH_1):GND    I15 @BASEBOARD_FAB2_LIB.BASEBOARD_FAB2(SCH_1):PAGE76

C3D10 CAP_A_0603V-22.0UF,4V,20%,X6S,A
     1 PVCCMCP_CPU1 @BASEBOARD_FAB2_LIB.BASEBOARD_FAB2(SCH_1):PVCCMCP_CPU1   I196 @BASEBOARD_FAB2_LIB.BASEBOARD_FAB2(SCH_1):PAGE76
     2    GND @BASEBOARD_FAB2_LIB.BASEBOARD_FAB2(SCH_1):GND   I196 @BASEBOARD_FAB2_LIB.BASEBOARD_FAB2(SCH_1):PAGE76

C3D11 CAP_A_0603V-22.0UF,4V,20%,X6S,A
     1 PVCCMCP_CPU1 @BASEBOARD_FAB2_LIB.BASEBOARD_FAB2(SCH_1):PVCCMCP_CPU1     I7 @BASEBOARD_FAB2_LIB.BASEBOARD_FAB2(SCH_1):PAGE76
     2    GND @BASEBOARD_FAB2_LIB.BASEBOARD_FAB2(SCH_1):GND     I7 @BASEBOARD_FAB2_LIB.BASEBOARD_FAB2(SCH_1):PAGE76

C3D12 CAP_A_0603V-22.0UF,4V,20%,X6S,A
     1 PVCCMCP_CPU1 @BASEBOARD_FAB2_LIB.BASEBOARD_FAB2(SCH_1):PVCCMCP_CPU1     I4 @BASEBOARD_FAB2_LIB.BASEBOARD_FAB2(SCH_1):PAGE76
     2    GND @BASEBOARD_FAB2_LIB.BASEBOARD_FAB2(SCH_1):GND     I4 @BASEBOARD_FAB2_LIB.BASEBOARD_FAB2(SCH_1):PAGE76

C3D13 CAP_A_0603V-22.0UF,4V,20%,X6S,A
     1 PVCCMCP_CPU1 @BASEBOARD_FAB2_LIB.BASEBOARD_FAB2(SCH_1):PVCCMCP_CPU1     I8 @BASEBOARD_FAB2_LIB.BASEBOARD_FAB2(SCH_1):PAGE76
     2    GND @BASEBOARD_FAB2_LIB.BASEBOARD_FAB2(SCH_1):GND     I8 @BASEBOARD_FAB2_LIB.BASEBOARD_FAB2(SCH_1):PAGE76

C3D14 CAP_A_0603V-22.0UF,4V,20%,X6S,A
     1 PVCCMCP_CPU1 @BASEBOARD_FAB2_LIB.BASEBOARD_FAB2(SCH_1):PVCCMCP_CPU1   I171 @BASEBOARD_FAB2_LIB.BASEBOARD_FAB2(SCH_1):PAGE76
     2    GND @BASEBOARD_FAB2_LIB.BASEBOARD_FAB2(SCH_1):GND   I171 @BASEBOARD_FAB2_LIB.BASEBOARD_FAB2(SCH_1):PAGE76

C3D15 CAP_A_0603V-22.0UF,4V,20%,X6S,A
     1 PVCCIO_CPU1 @BASEBOARD_FAB2_LIB.BASEBOARD_FAB2(SCH_1):PVCCIO_CPU1   I174 @BASEBOARD_FAB2_LIB.BASEBOARD_FAB2(SCH_1):PAGE76
     2    GND @BASEBOARD_FAB2_LIB.BASEBOARD_FAB2(SCH_1):GND   I174 @BASEBOARD_FAB2_LIB.BASEBOARD_FAB2(SCH_1):PAGE76

C3D16 CAP_A_0603V-22.0UF,4V,20%,X6S,A
     1 PVCCIO_CPU1 @BASEBOARD_FAB2_LIB.BASEBOARD_FAB2(SCH_1):PVCCIO_CPU1   I176 @BASEBOARD_FAB2_LIB.BASEBOARD_FAB2(SCH_1):PAGE76
     2    GND @BASEBOARD_FAB2_LIB.BASEBOARD_FAB2(SCH_1):GND   I176 @BASEBOARD_FAB2_LIB.BASEBOARD_FAB2(SCH_1):PAGE76

C3D17 CAP_A_0603V-22.0UF,4V,20%,X6S,A
     1 PVCCMCP_CPU1 @BASEBOARD_FAB2_LIB.BASEBOARD_FAB2(SCH_1):PVCCMCP_CPU1   I166 @BASEBOARD_FAB2_LIB.BASEBOARD_FAB2(SCH_1):PAGE76
     2    GND @BASEBOARD_FAB2_LIB.BASEBOARD_FAB2(SCH_1):GND   I166 @BASEBOARD_FAB2_LIB.BASEBOARD_FAB2(SCH_1):PAGE76

C3D18 CAP_A_0603V-22.0UF,4V,20%,X6S,A
     1 PVCCMCP_CPU1 @BASEBOARD_FAB2_LIB.BASEBOARD_FAB2(SCH_1):PVCCMCP_CPU1   I169 @BASEBOARD_FAB2_LIB.BASEBOARD_FAB2(SCH_1):PAGE76
     2    GND @BASEBOARD_FAB2_LIB.BASEBOARD_FAB2(SCH_1):GND   I169 @BASEBOARD_FAB2_LIB.BASEBOARD_FAB2(SCH_1):PAGE76

C3D19 CAP_A_0603V-22.0UF,4V,20%,X6S,A
     1 PVCCMCP_CPU1 @BASEBOARD_FAB2_LIB.BASEBOARD_FAB2(SCH_1):PVCCMCP_CPU1   I208 @BASEBOARD_FAB2_LIB.BASEBOARD_FAB2(SCH_1):PAGE76
     2    GND @BASEBOARD_FAB2_LIB.BASEBOARD_FAB2(SCH_1):GND   I208 @BASEBOARD_FAB2_LIB.BASEBOARD_FAB2(SCH_1):PAGE76

C3D20 CAP_A_0603V-22.0UF,4V,20%,X6S,A
     1 PVCCMCP_CPU1 @BASEBOARD_FAB2_LIB.BASEBOARD_FAB2(SCH_1):PVCCMCP_CPU1   I207 @BASEBOARD_FAB2_LIB.BASEBOARD_FAB2(SCH_1):PAGE76
     2    GND @BASEBOARD_FAB2_LIB.BASEBOARD_FAB2(SCH_1):GND   I207 @BASEBOARD_FAB2_LIB.BASEBOARD_FAB2(SCH_1):PAGE76

C3D21 CAP_A_0603V-22.0UF,4V,20%,X6S,A
     1 PVCCMCP_CPU1 @BASEBOARD_FAB2_LIB.BASEBOARD_FAB2(SCH_1):PVCCMCP_CPU1     I1 @BASEBOARD_FAB2_LIB.BASEBOARD_FAB2(SCH_1):PAGE76
     2    GND @BASEBOARD_FAB2_LIB.BASEBOARD_FAB2(SCH_1):GND     I1 @BASEBOARD_FAB2_LIB.BASEBOARD_FAB2(SCH_1):PAGE76

C3D22 CAP_0805-10UF,16V,10%,X7R,G106A
     1 P3V3_DB1200 @BASEBOARD_FAB2_LIB.BASEBOARD_FAB2(SCH_1):P3V3_DB1200    I10 @BASEBOARD_FAB2_LIB.BASEBOARD_FAB2(SCH_1):PAGE102
     2    GND @BASEBOARD_FAB2_LIB.BASEBOARD_FAB2(SCH_1):GND    I10 @BASEBOARD_FAB2_LIB.BASEBOARD_FAB2(SCH_1):PAGE102

C3D23 CAP_A_0603V-22.0UF,4V,20%,X6S,A
     1 PVCCIO_CPU1 @BASEBOARD_FAB2_LIB.BASEBOARD_FAB2(SCH_1):PVCCIO_CPU1   I172 @BASEBOARD_FAB2_LIB.BASEBOARD_FAB2(SCH_1):PAGE76
     2    GND @BASEBOARD_FAB2_LIB.BASEBOARD_FAB2(SCH_1):GND   I172 @BASEBOARD_FAB2_LIB.BASEBOARD_FAB2(SCH_1):PAGE76

C3D24 CAP_A_0603V-22.0UF,4V,20%,X6S,A
     1 PVCCIO_CPU1 @BASEBOARD_FAB2_LIB.BASEBOARD_FAB2(SCH_1):PVCCIO_CPU1   I175 @BASEBOARD_FAB2_LIB.BASEBOARD_FAB2(SCH_1):PAGE76
     2    GND @BASEBOARD_FAB2_LIB.BASEBOARD_FAB2(SCH_1):GND   I175 @BASEBOARD_FAB2_LIB.BASEBOARD_FAB2(SCH_1):PAGE76

C3D25 CAP_A_0603V-22.0UF,4V,20%,X6S,A
     1 PVDDQ_GHJ @BASEBOARD_FAB2_LIB.BASEBOARD_FAB2(SCH_1):PVDDQ_GHJ   I262 @BASEBOARD_FAB2_LIB.BASEBOARD_FAB2(SCH_1):PAGE225
     2    GND @BASEBOARD_FAB2_LIB.BASEBOARD_FAB2(SCH_1):GND   I262 @BASEBOARD_FAB2_LIB.BASEBOARD_FAB2(SCH_1):PAGE225

C3D27 CAP_A_0402V-0.1UF,16V,10%,EMPTA
     1 VSENSE_PVCCIO_CPU1_SKT_VSEN @BASEBOARD_FAB2_LIB.BASEBOARD_FAB2(SCH_1):VSENSE_PVCCIO_CPU1_SKT_VSEN    I96 @BASEBOARD_FAB2_LIB.BASEBOARD_FAB2(SCH_1):PAGE214
     2 VSENSE_PVCCIO_CPU1_SKT_VRTN @BASEBOARD_FAB2_LIB.BASEBOARD_FAB2(SCH_1):VSENSE_PVCCIO_CPU1_SKT_VRTN    I96 @BASEBOARD_FAB2_LIB.BASEBOARD_FAB2(SCH_1):PAGE214

C3E1 CAP_A_0603V-22.0UF,4V,20%,X6S,A
     1 PVCCIO_CPU1 @BASEBOARD_FAB2_LIB.BASEBOARD_FAB2(SCH_1):PVCCIO_CPU1   I108 @BASEBOARD_FAB2_LIB.BASEBOARD_FAB2(SCH_1):PAGE214
     2    GND @BASEBOARD_FAB2_LIB.BASEBOARD_FAB2(SCH_1):GND   I108 @BASEBOARD_FAB2_LIB.BASEBOARD_FAB2(SCH_1):PAGE214

C3F1 CAP_A_0603V-47UF,4V,20%,X5R,60A
     1 P1V8_MCP_CPU1 @BASEBOARD_FAB2_LIB.BASEBOARD_FAB2(SCH_1):P1V8_MCP_CPU1   I140 @BASEBOARD_FAB2_LIB.BASEBOARD_FAB2(SCH_1):PAGE193
     2    GND @BASEBOARD_FAB2_LIB.BASEBOARD_FAB2(SCH_1):GND   I140 @BASEBOARD_FAB2_LIB.BASEBOARD_FAB2(SCH_1):PAGE193

C3F2 CAP_A_0402V-0.1UF,16V,10%,X7R,A
     1   P3V3 @BASEBOARD_FAB2_LIB.BASEBOARD_FAB2(SCH_1):P3V3    I34 @BASEBOARD_FAB2_LIB.BASEBOARD_FAB2(SCH_1):PAGE104
     2    GND @BASEBOARD_FAB2_LIB.BASEBOARD_FAB2(SCH_1):GND    I34 @BASEBOARD_FAB2_LIB.BASEBOARD_FAB2(SCH_1):PAGE104

C3F3 CAP_0603LF-10UF,4V,20%,X6S,E15A
     1 PVPP_GHJ @BASEBOARD_FAB2_LIB.BASEBOARD_FAB2(SCH_1):PVPP_GHJ   I116 @BASEBOARD_FAB2_LIB.BASEBOARD_FAB2(SCH_1):PAGE233
     2    GND @BASEBOARD_FAB2_LIB.BASEBOARD_FAB2(SCH_1):GND   I116 @BASEBOARD_FAB2_LIB.BASEBOARD_FAB2(SCH_1):PAGE233

C3F4 CAP_0603LF-10UF,4V,20%,X6S,E15A
     1 PVPP_GHJ @BASEBOARD_FAB2_LIB.BASEBOARD_FAB2(SCH_1):PVPP_GHJ   I117 @BASEBOARD_FAB2_LIB.BASEBOARD_FAB2(SCH_1):PAGE233
     2    GND @BASEBOARD_FAB2_LIB.BASEBOARD_FAB2(SCH_1):GND   I117 @BASEBOARD_FAB2_LIB.BASEBOARD_FAB2(SCH_1):PAGE233

C3G1 CAP_A_0603V-47UF,4V,20%,X5R,60A
     1 PVDDQ_GHJ @BASEBOARD_FAB2_LIB.BASEBOARD_FAB2(SCH_1):PVDDQ_GHJ   I284 @BASEBOARD_FAB2_LIB.BASEBOARD_FAB2(SCH_1):PAGE225
     2    GND @BASEBOARD_FAB2_LIB.BASEBOARD_FAB2(SCH_1):GND   I284 @BASEBOARD_FAB2_LIB.BASEBOARD_FAB2(SCH_1):PAGE225

C3G2 CAP_A_0603V-47UF,4V,20%,X5R,60A
     1 PVDDQ_GHJ @BASEBOARD_FAB2_LIB.BASEBOARD_FAB2(SCH_1):PVDDQ_GHJ   I285 @BASEBOARD_FAB2_LIB.BASEBOARD_FAB2(SCH_1):PAGE225
     2    GND @BASEBOARD_FAB2_LIB.BASEBOARD_FAB2(SCH_1):GND   I285 @BASEBOARD_FAB2_LIB.BASEBOARD_FAB2(SCH_1):PAGE225

C3G3 CAP_0603LF-10UF,4V,20%,X6S,E15A
     1 PVPP_GHJ @BASEBOARD_FAB2_LIB.BASEBOARD_FAB2(SCH_1):PVPP_GHJ   I118 @BASEBOARD_FAB2_LIB.BASEBOARD_FAB2(SCH_1):PAGE233
     2    GND @BASEBOARD_FAB2_LIB.BASEBOARD_FAB2(SCH_1):GND   I118 @BASEBOARD_FAB2_LIB.BASEBOARD_FAB2(SCH_1):PAGE233

C3G4 CAP_0603LF-10UF,4V,20%,X6S,E15A
     1 PVPP_GHJ @BASEBOARD_FAB2_LIB.BASEBOARD_FAB2(SCH_1):PVPP_GHJ   I133 @BASEBOARD_FAB2_LIB.BASEBOARD_FAB2(SCH_1):PAGE233
     2    GND @BASEBOARD_FAB2_LIB.BASEBOARD_FAB2(SCH_1):GND   I133 @BASEBOARD_FAB2_LIB.BASEBOARD_FAB2(SCH_1):PAGE233

C3G5 CAP_A_0603V-47UF,4V,20%,X5R,60A
     1 PVDDQ_GHJ @BASEBOARD_FAB2_LIB.BASEBOARD_FAB2(SCH_1):PVDDQ_GHJ   I288 @BASEBOARD_FAB2_LIB.BASEBOARD_FAB2(SCH_1):PAGE225
     2    GND @BASEBOARD_FAB2_LIB.BASEBOARD_FAB2(SCH_1):GND   I288 @BASEBOARD_FAB2_LIB.BASEBOARD_FAB2(SCH_1):PAGE225

C3G6 CAP_A_0603V-47UF,4V,20%,X5R,60A
     1 PVDDQ_GHJ @BASEBOARD_FAB2_LIB.BASEBOARD_FAB2(SCH_1):PVDDQ_GHJ   I289 @BASEBOARD_FAB2_LIB.BASEBOARD_FAB2(SCH_1):PAGE225
     2    GND @BASEBOARD_FAB2_LIB.BASEBOARD_FAB2(SCH_1):GND   I289 @BASEBOARD_FAB2_LIB.BASEBOARD_FAB2(SCH_1):PAGE225

C3G7 CAP_0603LF-10UF,4V,20%,X6S,E15A
     1 PVPP_GHJ @BASEBOARD_FAB2_LIB.BASEBOARD_FAB2(SCH_1):PVPP_GHJ   I132 @BASEBOARD_FAB2_LIB.BASEBOARD_FAB2(SCH_1):PAGE233
     2    GND @BASEBOARD_FAB2_LIB.BASEBOARD_FAB2(SCH_1):GND   I132 @BASEBOARD_FAB2_LIB.BASEBOARD_FAB2(SCH_1):PAGE233

C3G8 CAP_0603LF-10UF,4V,20%,X6S,E15A
     1 PVPP_GHJ @BASEBOARD_FAB2_LIB.BASEBOARD_FAB2(SCH_1):PVPP_GHJ   I135 @BASEBOARD_FAB2_LIB.BASEBOARD_FAB2(SCH_1):PAGE233
     2    GND @BASEBOARD_FAB2_LIB.BASEBOARD_FAB2(SCH_1):GND   I135 @BASEBOARD_FAB2_LIB.BASEBOARD_FAB2(SCH_1):PAGE233

C3L1 SC1U10V2KX-4-GP_SMD-BCG6-SC1U1A
     1 P5V_STBY @BASEBOARD_FAB2_LIB.BASEBOARD_FAB2(SCH_1):P5V_STBY   I180 @BASEBOARD_FAB2_LIB.BASEBOARD_FAB2(SCH_1):PAGE236
     2    GND @BASEBOARD_FAB2_LIB.BASEBOARD_FAB2(SCH_1):GND   I180 @BASEBOARD_FAB2_LIB.BASEBOARD_FAB2(SCH_1):PAGE236

C3L2 CAP_0805-10UF,16V,10%,X6S,C953A
     1 VR_FET_SW_P12V_STBY_PVDDQ_DEF @BASEBOARD_FAB2_LIB.BASEBOARD_FAB2(SCH_1):VR_FET_SW_P12V_STBY_PVDDQ_DEF    I45 @BASEBOARD_FAB2_LIB.BASEBOARD_FAB2(SCH_1):PAGE219
     2    GND @BASEBOARD_FAB2_LIB.BASEBOARD_FAB2(SCH_1):GND    I45 @BASEBOARD_FAB2_LIB.BASEBOARD_FAB2(SCH_1):PAGE219

C3L4 CAP_0805-10UF,16V,10%,X6S,C953A
     1 VR_FET_SW_P12V_STBY_PVDDQ_DEF @BASEBOARD_FAB2_LIB.BASEBOARD_FAB2(SCH_1):VR_FET_SW_P12V_STBY_PVDDQ_DEF    I46 @BASEBOARD_FAB2_LIB.BASEBOARD_FAB2(SCH_1):PAGE219
     2    GND @BASEBOARD_FAB2_LIB.BASEBOARD_FAB2(SCH_1):GND    I46 @BASEBOARD_FAB2_LIB.BASEBOARD_FAB2(SCH_1):PAGE219

C3L6 CAPP_3018-470UF,2.5V,20%,ALUM,A
     1 PVDDQ_DEF @BASEBOARD_FAB2_LIB.BASEBOARD_FAB2(SCH_1):PVDDQ_DEF    I75 @BASEBOARD_FAB2_LIB.BASEBOARD_FAB2(SCH_1):PAGE220
     2    GND @BASEBOARD_FAB2_LIB.BASEBOARD_FAB2(SCH_1):GND    I75 @BASEBOARD_FAB2_LIB.BASEBOARD_FAB2(SCH_1):PAGE220

C3L7 CAP_0805-10UF,16V,10%,X6S,C953A
     1 VR_FET_SW_P12V_STBY_PVDDQ_DEF @BASEBOARD_FAB2_LIB.BASEBOARD_FAB2(SCH_1):VR_FET_SW_P12V_STBY_PVDDQ_DEF    I31 @BASEBOARD_FAB2_LIB.BASEBOARD_FAB2(SCH_1):PAGE236
     2    GND @BASEBOARD_FAB2_LIB.BASEBOARD_FAB2(SCH_1):GND    I31 @BASEBOARD_FAB2_LIB.BASEBOARD_FAB2(SCH_1):PAGE236

C3L8 CAP_0805-10UF,16V,10%,X6S,C953A
     1 VR_FET_SW_P12V_STBY_PVDDQ_DEF @BASEBOARD_FAB2_LIB.BASEBOARD_FAB2(SCH_1):VR_FET_SW_P12V_STBY_PVDDQ_DEF    I26 @BASEBOARD_FAB2_LIB.BASEBOARD_FAB2(SCH_1):PAGE236
     2    GND @BASEBOARD_FAB2_LIB.BASEBOARD_FAB2(SCH_1):GND    I26 @BASEBOARD_FAB2_LIB.BASEBOARD_FAB2(SCH_1):PAGE236

C3L9 CAP_0805-10UF,16V,10%,X6S,C953A
     1 VR_FET_SW_P12V_STBY_PVDDQ_DEF @BASEBOARD_FAB2_LIB.BASEBOARD_FAB2(SCH_1):VR_FET_SW_P12V_STBY_PVDDQ_DEF    I29 @BASEBOARD_FAB2_LIB.BASEBOARD_FAB2(SCH_1):PAGE236
     2    GND @BASEBOARD_FAB2_LIB.BASEBOARD_FAB2(SCH_1):GND    I29 @BASEBOARD_FAB2_LIB.BASEBOARD_FAB2(SCH_1):PAGE236

C3L10 CAP_0805-10UF,16V,10%,X6S,C953A
     1 VR_FET_SW_P12V_STBY_PVDDQ_DEF @BASEBOARD_FAB2_LIB.BASEBOARD_FAB2(SCH_1):VR_FET_SW_P12V_STBY_PVDDQ_DEF    I32 @BASEBOARD_FAB2_LIB.BASEBOARD_FAB2(SCH_1):PAGE236
     2    GND @BASEBOARD_FAB2_LIB.BASEBOARD_FAB2(SCH_1):GND    I32 @BASEBOARD_FAB2_LIB.BASEBOARD_FAB2(SCH_1):PAGE236

C3L11 CAP_0805-10UF,16V,10%,X6S,C953A
     1 VR_FET_SW_P12V_STBY_PVDDQ_DEF @BASEBOARD_FAB2_LIB.BASEBOARD_FAB2(SCH_1):VR_FET_SW_P12V_STBY_PVDDQ_DEF    I24 @BASEBOARD_FAB2_LIB.BASEBOARD_FAB2(SCH_1):PAGE236
     2    GND @BASEBOARD_FAB2_LIB.BASEBOARD_FAB2(SCH_1):GND    I24 @BASEBOARD_FAB2_LIB.BASEBOARD_FAB2(SCH_1):PAGE236

C3L12 CAP_0805-10UF,16V,10%,X6S,C953A
     1 VR_FET_SW_P12V_STBY_PVDDQ_DEF @BASEBOARD_FAB2_LIB.BASEBOARD_FAB2(SCH_1):VR_FET_SW_P12V_STBY_PVDDQ_DEF    I23 @BASEBOARD_FAB2_LIB.BASEBOARD_FAB2(SCH_1):PAGE236
     2    GND @BASEBOARD_FAB2_LIB.BASEBOARD_FAB2(SCH_1):GND    I23 @BASEBOARD_FAB2_LIB.BASEBOARD_FAB2(SCH_1):PAGE236

C3L13 CAP_0805-10UF,16V,10%,X6S,C953A
     1 VR_FET_SW_P12V_STBY_PVDDQ_DEF @BASEBOARD_FAB2_LIB.BASEBOARD_FAB2(SCH_1):VR_FET_SW_P12V_STBY_PVDDQ_DEF    I47 @BASEBOARD_FAB2_LIB.BASEBOARD_FAB2(SCH_1):PAGE219
     2    GND @BASEBOARD_FAB2_LIB.BASEBOARD_FAB2(SCH_1):GND    I47 @BASEBOARD_FAB2_LIB.BASEBOARD_FAB2(SCH_1):PAGE219

C3L14 CAPP_3018-470UF,2.5V,20%,ALUM,A
     1 PVDDQ_DEF @BASEBOARD_FAB2_LIB.BASEBOARD_FAB2(SCH_1):PVDDQ_DEF    I76 @BASEBOARD_FAB2_LIB.BASEBOARD_FAB2(SCH_1):PAGE220
     2    GND @BASEBOARD_FAB2_LIB.BASEBOARD_FAB2(SCH_1):GND    I76 @BASEBOARD_FAB2_LIB.BASEBOARD_FAB2(SCH_1):PAGE220

C3L15 CAP_0805-10UF,16V,10%,X6S,C953A
     1 VR_FET_SW_P12V_STBY_PVDDQ_DEF @BASEBOARD_FAB2_LIB.BASEBOARD_FAB2(SCH_1):VR_FET_SW_P12V_STBY_PVDDQ_DEF    I84 @BASEBOARD_FAB2_LIB.BASEBOARD_FAB2(SCH_1):PAGE219
     2    GND @BASEBOARD_FAB2_LIB.BASEBOARD_FAB2(SCH_1):GND    I84 @BASEBOARD_FAB2_LIB.BASEBOARD_FAB2(SCH_1):PAGE219

C3L16 CAP_0805-10UF,16V,10%,X6S,C953A
     1 VR_FET_SW_P12V_STBY_PVDDQ_DEF @BASEBOARD_FAB2_LIB.BASEBOARD_FAB2(SCH_1):VR_FET_SW_P12V_STBY_PVDDQ_DEF    I81 @BASEBOARD_FAB2_LIB.BASEBOARD_FAB2(SCH_1):PAGE219
     2    GND @BASEBOARD_FAB2_LIB.BASEBOARD_FAB2(SCH_1):GND    I81 @BASEBOARD_FAB2_LIB.BASEBOARD_FAB2(SCH_1):PAGE219

C3L17 CAP_0805-10UF,16V,10%,X6S,C953A
     1 VR_FET_SW_P12V_STBY_PVDDQ_DEF @BASEBOARD_FAB2_LIB.BASEBOARD_FAB2(SCH_1):VR_FET_SW_P12V_STBY_PVDDQ_DEF    I80 @BASEBOARD_FAB2_LIB.BASEBOARD_FAB2(SCH_1):PAGE219
     2    GND @BASEBOARD_FAB2_LIB.BASEBOARD_FAB2(SCH_1):GND    I80 @BASEBOARD_FAB2_LIB.BASEBOARD_FAB2(SCH_1):PAGE219

C3L18 CAPP_SM-470UF,2V,20%,ALUM,6990A
     1 PVNN_PCH_STBY @BASEBOARD_FAB2_LIB.BASEBOARD_FAB2(SCH_1):PVNN_PCH_STBY    I71 @BASEBOARD_FAB2_LIB.BASEBOARD_FAB2(SCH_1):PAGE236
     2    GND @BASEBOARD_FAB2_LIB.BASEBOARD_FAB2(SCH_1):GND    I71 @BASEBOARD_FAB2_LIB.BASEBOARD_FAB2(SCH_1):PAGE236

C3L19 CAPP_SM-470UF,2V,20%,ALUM,6990A
     1 P1V05_PCH_STBY @BASEBOARD_FAB2_LIB.BASEBOARD_FAB2(SCH_1):P1V05_PCH_STBY    I76 @BASEBOARD_FAB2_LIB.BASEBOARD_FAB2(SCH_1):PAGE236
     2    GND @BASEBOARD_FAB2_LIB.BASEBOARD_FAB2(SCH_1):GND    I76 @BASEBOARD_FAB2_LIB.BASEBOARD_FAB2(SCH_1):PAGE236

C3L20 CAPP_SM-470UF,2V,20%,ALUM,6990A
     1 PVNN_PCH_STBY @BASEBOARD_FAB2_LIB.BASEBOARD_FAB2(SCH_1):PVNN_PCH_STBY    I73 @BASEBOARD_FAB2_LIB.BASEBOARD_FAB2(SCH_1):PAGE236
     2    GND @BASEBOARD_FAB2_LIB.BASEBOARD_FAB2(SCH_1):GND    I73 @BASEBOARD_FAB2_LIB.BASEBOARD_FAB2(SCH_1):PAGE236

C3L21 CAPP_SM-470UF,2V,20%,ALUM,6990A
     1 PVNN_PCH_STBY @BASEBOARD_FAB2_LIB.BASEBOARD_FAB2(SCH_1):PVNN_PCH_STBY    I74 @BASEBOARD_FAB2_LIB.BASEBOARD_FAB2(SCH_1):PAGE236
     2    GND @BASEBOARD_FAB2_LIB.BASEBOARD_FAB2(SCH_1):GND    I74 @BASEBOARD_FAB2_LIB.BASEBOARD_FAB2(SCH_1):PAGE236

C3L22 CAP_A_0603V-22.0UF,4V,20%,X6S,A
     1 PVNN_PCH_STBY @BASEBOARD_FAB2_LIB.BASEBOARD_FAB2(SCH_1):PVNN_PCH_STBY    I54 @BASEBOARD_FAB2_LIB.BASEBOARD_FAB2(SCH_1):PAGE132
     2    GND @BASEBOARD_FAB2_LIB.BASEBOARD_FAB2(SCH_1):GND    I54 @BASEBOARD_FAB2_LIB.BASEBOARD_FAB2(SCH_1):PAGE132

C3L23 CAP_A_0603V-22.0UF,4V,20%,X6S,A
     1 PVNN_PCH_STBY @BASEBOARD_FAB2_LIB.BASEBOARD_FAB2(SCH_1):PVNN_PCH_STBY    I52 @BASEBOARD_FAB2_LIB.BASEBOARD_FAB2(SCH_1):PAGE132
     2    GND @BASEBOARD_FAB2_LIB.BASEBOARD_FAB2(SCH_1):GND    I52 @BASEBOARD_FAB2_LIB.BASEBOARD_FAB2(SCH_1):PAGE132

C3L24 CAP_A_0603V-22.0UF,4V,20%,X6S,A
     1 PVNN_PCH_STBY @BASEBOARD_FAB2_LIB.BASEBOARD_FAB2(SCH_1):PVNN_PCH_STBY    I56 @BASEBOARD_FAB2_LIB.BASEBOARD_FAB2(SCH_1):PAGE132
     2    GND @BASEBOARD_FAB2_LIB.BASEBOARD_FAB2(SCH_1):GND    I56 @BASEBOARD_FAB2_LIB.BASEBOARD_FAB2(SCH_1):PAGE132

C3L25 CAP_A_0603V-22.0UF,4V,20%,X6S,A
     1 PVNN_PCH_STBY @BASEBOARD_FAB2_LIB.BASEBOARD_FAB2(SCH_1):PVNN_PCH_STBY     I1 @BASEBOARD_FAB2_LIB.BASEBOARD_FAB2(SCH_1):PAGE132
     2    GND @BASEBOARD_FAB2_LIB.BASEBOARD_FAB2(SCH_1):GND     I1 @BASEBOARD_FAB2_LIB.BASEBOARD_FAB2(SCH_1):PAGE132

C3L26 CAP_A_0603V-22.0UF,4V,20%,X6S,A
     1 PVNN_PCH_STBY @BASEBOARD_FAB2_LIB.BASEBOARD_FAB2(SCH_1):PVNN_PCH_STBY     I3 @BASEBOARD_FAB2_LIB.BASEBOARD_FAB2(SCH_1):PAGE132
     2    GND @BASEBOARD_FAB2_LIB.BASEBOARD_FAB2(SCH_1):GND     I3 @BASEBOARD_FAB2_LIB.BASEBOARD_FAB2(SCH_1):PAGE132

C3L27 CAP_A_0603V-22.0UF,4V,20%,X6S,A
     1 PVNN_PCH_STBY @BASEBOARD_FAB2_LIB.BASEBOARD_FAB2(SCH_1):PVNN_PCH_STBY     I4 @BASEBOARD_FAB2_LIB.BASEBOARD_FAB2(SCH_1):PAGE132
     2    GND @BASEBOARD_FAB2_LIB.BASEBOARD_FAB2(SCH_1):GND     I4 @BASEBOARD_FAB2_LIB.BASEBOARD_FAB2(SCH_1):PAGE132

C3L29 SC1U10V2KX-4-GP_SMD-BCG6-SC1U1A
     1 P5V_STBY @BASEBOARD_FAB2_LIB.BASEBOARD_FAB2(SCH_1):P5V_STBY   I181 @BASEBOARD_FAB2_LIB.BASEBOARD_FAB2(SCH_1):PAGE236
     2    GND @BASEBOARD_FAB2_LIB.BASEBOARD_FAB2(SCH_1):GND   I181 @BASEBOARD_FAB2_LIB.BASEBOARD_FAB2(SCH_1):PAGE236

C3M1 CAP_0402-0.22UF,16V,10%,X7R,A3A
     1 P3E_CPU0_PE1_PCH_R_RXN<15> @BASEBOARD_FAB2_LIB.BASEBOARD_FAB2(SCH_1):P3E_CPU0_PE1_PCH_R_RXN(15)   I255 @BASEBOARD_FAB2_LIB.BASEBOARD_FAB2(SCH_1):PAGE105
     2 P3E_CPU0_PE1_PCH_RXN<15> @BASEBOARD_FAB2_LIB.BASEBOARD_FAB2(SCH_1):P3E_CPU0_PE1_PCH_RXN(15)   I255 @BASEBOARD_FAB2_LIB.BASEBOARD_FAB2(SCH_1):PAGE105

C3M2 CAP_0402-0.22UF,16V,10%,X7R,A3A
     1 P3E_CPU0_PE1_PCH_R_RXP<15> @BASEBOARD_FAB2_LIB.BASEBOARD_FAB2(SCH_1):P3E_CPU0_PE1_PCH_R_RXP(15)   I247 @BASEBOARD_FAB2_LIB.BASEBOARD_FAB2(SCH_1):PAGE105
     2 P3E_CPU0_PE1_PCH_RXP<15> @BASEBOARD_FAB2_LIB.BASEBOARD_FAB2(SCH_1):P3E_CPU0_PE1_PCH_RXP(15)   I247 @BASEBOARD_FAB2_LIB.BASEBOARD_FAB2(SCH_1):PAGE105

C3M3 CAP_0402-0.22UF,16V,10%,X7R,A3A
     1 P3E_CPU0_PE1_PCH_R_RXP<12> @BASEBOARD_FAB2_LIB.BASEBOARD_FAB2(SCH_1):P3E_CPU0_PE1_PCH_R_RXP(12)   I232 @BASEBOARD_FAB2_LIB.BASEBOARD_FAB2(SCH_1):PAGE105
     2 P3E_CPU0_PE1_PCH_RXP<12> @BASEBOARD_FAB2_LIB.BASEBOARD_FAB2(SCH_1):P3E_CPU0_PE1_PCH_RXP(12)   I232 @BASEBOARD_FAB2_LIB.BASEBOARD_FAB2(SCH_1):PAGE105

C3M4 CAP_0402-0.22UF,16V,10%,X7R,A3A
     1 P3E_CPU0_PE1_PCH_R_RXN<12> @BASEBOARD_FAB2_LIB.BASEBOARD_FAB2(SCH_1):P3E_CPU0_PE1_PCH_R_RXN(12)   I244 @BASEBOARD_FAB2_LIB.BASEBOARD_FAB2(SCH_1):PAGE105
     2 P3E_CPU0_PE1_PCH_RXN<12> @BASEBOARD_FAB2_LIB.BASEBOARD_FAB2(SCH_1):P3E_CPU0_PE1_PCH_RXN(12)   I244 @BASEBOARD_FAB2_LIB.BASEBOARD_FAB2(SCH_1):PAGE105

C3M6 CAP_A_0603V-22.0UF,4V,20%,X6S,A
     1 PVNN_PCH_STBY @BASEBOARD_FAB2_LIB.BASEBOARD_FAB2(SCH_1):PVNN_PCH_STBY     I6 @BASEBOARD_FAB2_LIB.BASEBOARD_FAB2(SCH_1):PAGE132
     2    GND @BASEBOARD_FAB2_LIB.BASEBOARD_FAB2(SCH_1):GND     I6 @BASEBOARD_FAB2_LIB.BASEBOARD_FAB2(SCH_1):PAGE132

C3M7 CAP_A_0603V-22.0UF,4V,20%,X6S,A
     1 PVNN_PCH_STBY @BASEBOARD_FAB2_LIB.BASEBOARD_FAB2(SCH_1):PVNN_PCH_STBY     I2 @BASEBOARD_FAB2_LIB.BASEBOARD_FAB2(SCH_1):PAGE132
     2    GND @BASEBOARD_FAB2_LIB.BASEBOARD_FAB2(SCH_1):GND     I2 @BASEBOARD_FAB2_LIB.BASEBOARD_FAB2(SCH_1):PAGE132

C3M8 CAP_0805-10UF,16V,10%,X6S,C953A
     1 VR_FET_SW_P12V_STBY_PVPP_DEF @BASEBOARD_FAB2_LIB.BASEBOARD_FAB2(SCH_1):VR_FET_SW_P12V_STBY_PVPP_DEF   I259 @BASEBOARD_FAB2_LIB.BASEBOARD_FAB2(SCH_1):PAGE232
     2    GND @BASEBOARD_FAB2_LIB.BASEBOARD_FAB2(SCH_1):GND   I259 @BASEBOARD_FAB2_LIB.BASEBOARD_FAB2(SCH_1):PAGE232

C3M9 CAP_0402-1.0UF,16V,10%,X6S,D97A
     1 VR_FET_SW_P12V_STBY_PVPP_DEF @BASEBOARD_FAB2_LIB.BASEBOARD_FAB2(SCH_1):VR_FET_SW_P12V_STBY_PVPP_DEF   I207 @BASEBOARD_FAB2_LIB.BASEBOARD_FAB2(SCH_1):PAGE232
     2    GND @BASEBOARD_FAB2_LIB.BASEBOARD_FAB2(SCH_1):GND   I207 @BASEBOARD_FAB2_LIB.BASEBOARD_FAB2(SCH_1):PAGE232

C3M10 CAP_0603-4.7UF,6.3V,10%,X6S,E1A
     1 VR_VB_PVPP_DEF @BASEBOARD_FAB2_LIB.BASEBOARD_FAB2(SCH_1):VR_VB_PVPP_DEF   I253 @BASEBOARD_FAB2_LIB.BASEBOARD_FAB2(SCH_1):PAGE232
     2 AGND_PVPP_DEF @BASEBOARD_FAB2_LIB.BASEBOARD_FAB2(SCH_1):AGND_PVPP_DEF   I253 @BASEBOARD_FAB2_LIB.BASEBOARD_FAB2(SCH_1):PAGE232

C3M11 CAP_0402-0.22UF,16V,10%,X7R,A3A
     1 P3E_CPU0_PE1_PCH_R_RXP<14> @BASEBOARD_FAB2_LIB.BASEBOARD_FAB2(SCH_1):P3E_CPU0_PE1_PCH_R_RXP(14)   I234 @BASEBOARD_FAB2_LIB.BASEBOARD_FAB2(SCH_1):PAGE105
     2 P3E_CPU0_PE1_PCH_RXP<14> @BASEBOARD_FAB2_LIB.BASEBOARD_FAB2(SCH_1):P3E_CPU0_PE1_PCH_RXP(14)   I234 @BASEBOARD_FAB2_LIB.BASEBOARD_FAB2(SCH_1):PAGE105

C3M12 CAP_0402-0.22UF,16V,10%,X7R,A3A
     1 P3E_CPU0_PE1_PCH_R_RXN<14> @BASEBOARD_FAB2_LIB.BASEBOARD_FAB2(SCH_1):P3E_CPU0_PE1_PCH_R_RXN(14)   I246 @BASEBOARD_FAB2_LIB.BASEBOARD_FAB2(SCH_1):PAGE105
     2 P3E_CPU0_PE1_PCH_RXN<14> @BASEBOARD_FAB2_LIB.BASEBOARD_FAB2(SCH_1):P3E_CPU0_PE1_PCH_RXN(14)   I246 @BASEBOARD_FAB2_LIB.BASEBOARD_FAB2(SCH_1):PAGE105

C3M13 CAP_0402-0.22UF,16V,10%,X7R,A3A
     1 P3E_CPU0_PE1_PCH_R_RXP<13> @BASEBOARD_FAB2_LIB.BASEBOARD_FAB2(SCH_1):P3E_CPU0_PE1_PCH_R_RXP(13)   I239 @BASEBOARD_FAB2_LIB.BASEBOARD_FAB2(SCH_1):PAGE105
     2 P3E_CPU0_PE1_PCH_RXP<13> @BASEBOARD_FAB2_LIB.BASEBOARD_FAB2(SCH_1):P3E_CPU0_PE1_PCH_RXP(13)   I239 @BASEBOARD_FAB2_LIB.BASEBOARD_FAB2(SCH_1):PAGE105

C3M14 CAP_0402-0.22UF,16V,10%,X7R,A3A
     1 P3E_CPU0_PE1_PCH_R_RXN<13> @BASEBOARD_FAB2_LIB.BASEBOARD_FAB2(SCH_1):P3E_CPU0_PE1_PCH_R_RXN(13)   I253 @BASEBOARD_FAB2_LIB.BASEBOARD_FAB2(SCH_1):PAGE105
     2 P3E_CPU0_PE1_PCH_RXN<13> @BASEBOARD_FAB2_LIB.BASEBOARD_FAB2(SCH_1):P3E_CPU0_PE1_PCH_RXN(13)   I253 @BASEBOARD_FAB2_LIB.BASEBOARD_FAB2(SCH_1):PAGE105

C3M15 CAP_0805-10UF,16V,10%,X6S,C953A
     1 VR_FET_SW_P12V_STBY_PVPP_DEF @BASEBOARD_FAB2_LIB.BASEBOARD_FAB2(SCH_1):VR_FET_SW_P12V_STBY_PVPP_DEF   I260 @BASEBOARD_FAB2_LIB.BASEBOARD_FAB2(SCH_1):PAGE232
     2    GND @BASEBOARD_FAB2_LIB.BASEBOARD_FAB2(SCH_1):GND   I260 @BASEBOARD_FAB2_LIB.BASEBOARD_FAB2(SCH_1):PAGE232

C3M16 CAP_0805-10UF,16V,10%,X6S,C953A
     1 VR_FET_SW_P12V_STBY_PVPP_DEF @BASEBOARD_FAB2_LIB.BASEBOARD_FAB2(SCH_1):VR_FET_SW_P12V_STBY_PVPP_DEF   I261 @BASEBOARD_FAB2_LIB.BASEBOARD_FAB2(SCH_1):PAGE232
     2    GND @BASEBOARD_FAB2_LIB.BASEBOARD_FAB2(SCH_1):GND   I261 @BASEBOARD_FAB2_LIB.BASEBOARD_FAB2(SCH_1):PAGE232

C3M17 CAP_0603LF-10UF,4V,20%,X6S,E15A
     1 P1V05_PCH_STBY_VCCA_PLL1 @BASEBOARD_FAB2_LIB.BASEBOARD_FAB2(SCH_1):P1V05_PCH_STBY_VCCA_PLL1    I86 @BASEBOARD_FAB2_LIB.BASEBOARD_FAB2(SCH_1):PAGE127
     2    GND @BASEBOARD_FAB2_LIB.BASEBOARD_FAB2(SCH_1):GND    I86 @BASEBOARD_FAB2_LIB.BASEBOARD_FAB2(SCH_1):PAGE127

C3M18 CAP_0603LF-10UF,4V,20%,X6S,E15A
     1 P1V05_PCH_STBY_VCCA_PLL0 @BASEBOARD_FAB2_LIB.BASEBOARD_FAB2(SCH_1):P1V05_PCH_STBY_VCCA_PLL0    I85 @BASEBOARD_FAB2_LIB.BASEBOARD_FAB2(SCH_1):PAGE127
     2    GND @BASEBOARD_FAB2_LIB.BASEBOARD_FAB2(SCH_1):GND    I85 @BASEBOARD_FAB2_LIB.BASEBOARD_FAB2(SCH_1):PAGE127

C3M19 CAP_A_0402V-1.0UF,6.3V,10%,X6SA
     1 P1V05_PCH_STBY_VCCA_PLL1 @BASEBOARD_FAB2_LIB.BASEBOARD_FAB2(SCH_1):P1V05_PCH_STBY_VCCA_PLL1    I87 @BASEBOARD_FAB2_LIB.BASEBOARD_FAB2(SCH_1):PAGE127
     2    GND @BASEBOARD_FAB2_LIB.BASEBOARD_FAB2(SCH_1):GND    I87 @BASEBOARD_FAB2_LIB.BASEBOARD_FAB2(SCH_1):PAGE127

C3M20 CAP_A_0402V-1.0UF,6.3V,10%,X6SA
     1 P1V05_PCH_STBY_VCCA_PLL0 @BASEBOARD_FAB2_LIB.BASEBOARD_FAB2(SCH_1):P1V05_PCH_STBY_VCCA_PLL0    I84 @BASEBOARD_FAB2_LIB.BASEBOARD_FAB2(SCH_1):PAGE127
     2    GND @BASEBOARD_FAB2_LIB.BASEBOARD_FAB2(SCH_1):GND    I84 @BASEBOARD_FAB2_LIB.BASEBOARD_FAB2(SCH_1):PAGE127

C3M21 CAP_A_0402V-1.0UF,6.3V,10%,X6SA
     1 P1V05_PCH_STBY @BASEBOARD_FAB2_LIB.BASEBOARD_FAB2(SCH_1):P1V05_PCH_STBY     I9 @BASEBOARD_FAB2_LIB.BASEBOARD_FAB2(SCH_1):PAGE127
     2    GND @BASEBOARD_FAB2_LIB.BASEBOARD_FAB2(SCH_1):GND     I9 @BASEBOARD_FAB2_LIB.BASEBOARD_FAB2(SCH_1):PAGE127

C3M22 CAP_A_0402V-1.0UF,6.3V,10%,X6SA
     1 P1V05_PCH_STBY @BASEBOARD_FAB2_LIB.BASEBOARD_FAB2(SCH_1):P1V05_PCH_STBY    I18 @BASEBOARD_FAB2_LIB.BASEBOARD_FAB2(SCH_1):PAGE127
     2    GND @BASEBOARD_FAB2_LIB.BASEBOARD_FAB2(SCH_1):GND    I18 @BASEBOARD_FAB2_LIB.BASEBOARD_FAB2(SCH_1):PAGE127

C3M23 CAP_0603LF-10UF,4V,20%,X6S,E15A
     1 P1V05_PCH_STBY_VCCA_XTAL @BASEBOARD_FAB2_LIB.BASEBOARD_FAB2(SCH_1):P1V05_PCH_STBY_VCCA_XTAL    I82 @BASEBOARD_FAB2_LIB.BASEBOARD_FAB2(SCH_1):PAGE127
     2    GND @BASEBOARD_FAB2_LIB.BASEBOARD_FAB2(SCH_1):GND    I82 @BASEBOARD_FAB2_LIB.BASEBOARD_FAB2(SCH_1):PAGE127

C3M24 CAP_0603LF-10UF,4V,20%,X6S,E15A
     1 P1V05_PCH_STBY_ISCLK_PLL @BASEBOARD_FAB2_LIB.BASEBOARD_FAB2(SCH_1):P1V05_PCH_STBY_ISCLK_PLL    I81 @BASEBOARD_FAB2_LIB.BASEBOARD_FAB2(SCH_1):PAGE127
     2    GND @BASEBOARD_FAB2_LIB.BASEBOARD_FAB2(SCH_1):GND    I81 @BASEBOARD_FAB2_LIB.BASEBOARD_FAB2(SCH_1):PAGE127

C3M25 CAP_0402-0.22UF,16V,10%,X7R,A3A
     1 P3E_CPU0_PE1_PCH_R_RXP<11> @BASEBOARD_FAB2_LIB.BASEBOARD_FAB2(SCH_1):P3E_CPU0_PE1_PCH_R_RXP(11)   I205 @BASEBOARD_FAB2_LIB.BASEBOARD_FAB2(SCH_1):PAGE105
     2 P3E_CPU0_PE1_PCH_RXP<11> @BASEBOARD_FAB2_LIB.BASEBOARD_FAB2(SCH_1):P3E_CPU0_PE1_PCH_RXP(11)   I205 @BASEBOARD_FAB2_LIB.BASEBOARD_FAB2(SCH_1):PAGE105

C3M26 CAP_0402-0.22UF,16V,10%,X7R,A3A
     1 P3E_CPU0_PE1_PCH_R_RXN<11> @BASEBOARD_FAB2_LIB.BASEBOARD_FAB2(SCH_1):P3E_CPU0_PE1_PCH_R_RXN(11)   I229 @BASEBOARD_FAB2_LIB.BASEBOARD_FAB2(SCH_1):PAGE105
     2 P3E_CPU0_PE1_PCH_RXN<11> @BASEBOARD_FAB2_LIB.BASEBOARD_FAB2(SCH_1):P3E_CPU0_PE1_PCH_RXN(11)   I229 @BASEBOARD_FAB2_LIB.BASEBOARD_FAB2(SCH_1):PAGE105

C3M27 CAP_A_0402V-1.0UF,6.3V,10%,X6SA
     1 P1V05_PCH_STBY_VCCA_XTAL @BASEBOARD_FAB2_LIB.BASEBOARD_FAB2(SCH_1):P1V05_PCH_STBY_VCCA_XTAL    I83 @BASEBOARD_FAB2_LIB.BASEBOARD_FAB2(SCH_1):PAGE127
     2    GND @BASEBOARD_FAB2_LIB.BASEBOARD_FAB2(SCH_1):GND    I83 @BASEBOARD_FAB2_LIB.BASEBOARD_FAB2(SCH_1):PAGE127

C3M28 CAP_0402-0.22UF,16V,10%,X7R,A3A
     1 P3E_CPU0_PE1_PCH_R_RXP<10> @BASEBOARD_FAB2_LIB.BASEBOARD_FAB2(SCH_1):P3E_CPU0_PE1_PCH_R_RXP(10)   I212 @BASEBOARD_FAB2_LIB.BASEBOARD_FAB2(SCH_1):PAGE105
     2 P3E_CPU0_PE1_PCH_RXP<10> @BASEBOARD_FAB2_LIB.BASEBOARD_FAB2(SCH_1):P3E_CPU0_PE1_PCH_RXP(10)   I212 @BASEBOARD_FAB2_LIB.BASEBOARD_FAB2(SCH_1):PAGE105

C3M29 CAP_A_0402V-1.0UF,6.3V,10%,X6SA
     1 P1V05_PCH_STBY_ISCLK_PLL @BASEBOARD_FAB2_LIB.BASEBOARD_FAB2(SCH_1):P1V05_PCH_STBY_ISCLK_PLL    I80 @BASEBOARD_FAB2_LIB.BASEBOARD_FAB2(SCH_1):PAGE127
     2    GND @BASEBOARD_FAB2_LIB.BASEBOARD_FAB2(SCH_1):GND    I80 @BASEBOARD_FAB2_LIB.BASEBOARD_FAB2(SCH_1):PAGE127

C3M30 CAP_A_0402V-1.0UF,6.3V,10%,X6SA
     1 P1V05_PCH_STBY @BASEBOARD_FAB2_LIB.BASEBOARD_FAB2(SCH_1):P1V05_PCH_STBY    I27 @BASEBOARD_FAB2_LIB.BASEBOARD_FAB2(SCH_1):PAGE127
     2    GND @BASEBOARD_FAB2_LIB.BASEBOARD_FAB2(SCH_1):GND    I27 @BASEBOARD_FAB2_LIB.BASEBOARD_FAB2(SCH_1):PAGE127

C3M31 CAP_A_0402V-1.0UF,6.3V,10%,X6SA
     1 P1V05_PCH_STBY @BASEBOARD_FAB2_LIB.BASEBOARD_FAB2(SCH_1):P1V05_PCH_STBY    I57 @BASEBOARD_FAB2_LIB.BASEBOARD_FAB2(SCH_1):PAGE127
     2    GND @BASEBOARD_FAB2_LIB.BASEBOARD_FAB2(SCH_1):GND    I57 @BASEBOARD_FAB2_LIB.BASEBOARD_FAB2(SCH_1):PAGE127

C3M32 CAP_0402-0.22UF,16V,10%,X7R,A3A
     1 P3E_CPU0_PE1_PCH_R_RXN<10> @BASEBOARD_FAB2_LIB.BASEBOARD_FAB2(SCH_1):P3E_CPU0_PE1_PCH_R_RXN(10)   I223 @BASEBOARD_FAB2_LIB.BASEBOARD_FAB2(SCH_1):PAGE105
     2 P3E_CPU0_PE1_PCH_RXN<10> @BASEBOARD_FAB2_LIB.BASEBOARD_FAB2(SCH_1):P3E_CPU0_PE1_PCH_RXN(10)   I223 @BASEBOARD_FAB2_LIB.BASEBOARD_FAB2(SCH_1):PAGE105

C3M33 CAP_0402-0.22UF,16V,10%,X7R,A3A
     1 P3E_CPU0_PE1_PCH_R_RXN<8> @BASEBOARD_FAB2_LIB.BASEBOARD_FAB2(SCH_1):P3E_CPU0_PE1_PCH_R_RXN(8)   I217 @BASEBOARD_FAB2_LIB.BASEBOARD_FAB2(SCH_1):PAGE105
     2 P3E_CPU0_PE1_PCH_RXN<8> @BASEBOARD_FAB2_LIB.BASEBOARD_FAB2(SCH_1):P3E_CPU0_PE1_PCH_RXN(8)   I217 @BASEBOARD_FAB2_LIB.BASEBOARD_FAB2(SCH_1):PAGE105

C3M34 CAP_0402-0.22UF,16V,10%,X7R,A3A
     1 P3E_CPU0_PE1_PCH_R_RXP<8> @BASEBOARD_FAB2_LIB.BASEBOARD_FAB2(SCH_1):P3E_CPU0_PE1_PCH_R_RXP(8)   I206 @BASEBOARD_FAB2_LIB.BASEBOARD_FAB2(SCH_1):PAGE105
     2 P3E_CPU0_PE1_PCH_RXP<8> @BASEBOARD_FAB2_LIB.BASEBOARD_FAB2(SCH_1):P3E_CPU0_PE1_PCH_RXP(8)   I206 @BASEBOARD_FAB2_LIB.BASEBOARD_FAB2(SCH_1):PAGE105

C3M35 CAP_0402-0.22UF,16V,10%,X7R,A3A
     1 P3E_CPU0_PE1_PCH_R_RXN<9> @BASEBOARD_FAB2_LIB.BASEBOARD_FAB2(SCH_1):P3E_CPU0_PE1_PCH_R_RXN(9)   I225 @BASEBOARD_FAB2_LIB.BASEBOARD_FAB2(SCH_1):PAGE105
     2 P3E_CPU0_PE1_PCH_RXN<9> @BASEBOARD_FAB2_LIB.BASEBOARD_FAB2(SCH_1):P3E_CPU0_PE1_PCH_RXN(9)   I225 @BASEBOARD_FAB2_LIB.BASEBOARD_FAB2(SCH_1):PAGE105

C3M36 CAP_0402-0.22UF,16V,10%,X7R,A3A
     1 P3E_CPU0_PE1_PCH_R_RXP<9> @BASEBOARD_FAB2_LIB.BASEBOARD_FAB2(SCH_1):P3E_CPU0_PE1_PCH_R_RXP(9)   I218 @BASEBOARD_FAB2_LIB.BASEBOARD_FAB2(SCH_1):PAGE105
     2 P3E_CPU0_PE1_PCH_RXP<9> @BASEBOARD_FAB2_LIB.BASEBOARD_FAB2(SCH_1):P3E_CPU0_PE1_PCH_RXP(9)   I218 @BASEBOARD_FAB2_LIB.BASEBOARD_FAB2(SCH_1):PAGE105

C3M37 CAP_0402-0.22UF,16V,10%,X7R,A3A
     1 DMI_CPU0_PCH_RX_DP<1> @BASEBOARD_FAB2_LIB.BASEBOARD_FAB2(SCH_1):DMI_CPU0_PCH_RX_DP(1)    I73 @BASEBOARD_FAB2_LIB.BASEBOARD_FAB2(SCH_1):PAGE129
     2 DMI_CPU0_PCH_RX_C_DP<1> @BASEBOARD_FAB2_LIB.BASEBOARD_FAB2(SCH_1):DMI_CPU0_PCH_RX_C_DP(1)    I73 @BASEBOARD_FAB2_LIB.BASEBOARD_FAB2(SCH_1):PAGE129

C3M38 CAP_A_0402V-1.0UF,6.3V,10%,X6SA
     1 P1V05_PCH_STBY @BASEBOARD_FAB2_LIB.BASEBOARD_FAB2(SCH_1):P1V05_PCH_STBY    I32 @BASEBOARD_FAB2_LIB.BASEBOARD_FAB2(SCH_1):PAGE131
     2    GND @BASEBOARD_FAB2_LIB.BASEBOARD_FAB2(SCH_1):GND    I32 @BASEBOARD_FAB2_LIB.BASEBOARD_FAB2(SCH_1):PAGE131

C3M39 CAP_A_0402V-1.0UF,6.3V,10%,X6SA
     1 P1V05_PCH_STBY @BASEBOARD_FAB2_LIB.BASEBOARD_FAB2(SCH_1):P1V05_PCH_STBY    I44 @BASEBOARD_FAB2_LIB.BASEBOARD_FAB2(SCH_1):PAGE131
     2    GND @BASEBOARD_FAB2_LIB.BASEBOARD_FAB2(SCH_1):GND    I44 @BASEBOARD_FAB2_LIB.BASEBOARD_FAB2(SCH_1):PAGE131

C3M40 CAP_0402-0.22UF,16V,10%,X7R,A3A
     1 DMI_CPU0_PCH_RX_DP<0> @BASEBOARD_FAB2_LIB.BASEBOARD_FAB2(SCH_1):DMI_CPU0_PCH_RX_DP(0)    I72 @BASEBOARD_FAB2_LIB.BASEBOARD_FAB2(SCH_1):PAGE129
     2 DMI_CPU0_PCH_RX_C_DP<0> @BASEBOARD_FAB2_LIB.BASEBOARD_FAB2(SCH_1):DMI_CPU0_PCH_RX_C_DP(0)    I72 @BASEBOARD_FAB2_LIB.BASEBOARD_FAB2(SCH_1):PAGE129

C3M41 CAP_0402-0.22UF,16V,10%,X7R,A3A
     1 DMI_CPU0_PCH_RX_DN<1> @BASEBOARD_FAB2_LIB.BASEBOARD_FAB2(SCH_1):DMI_CPU0_PCH_RX_DN(1)    I81 @BASEBOARD_FAB2_LIB.BASEBOARD_FAB2(SCH_1):PAGE129
     2 DMI_CPU0_PCH_RX_C_DN<1> @BASEBOARD_FAB2_LIB.BASEBOARD_FAB2(SCH_1):DMI_CPU0_PCH_RX_C_DN(1)    I81 @BASEBOARD_FAB2_LIB.BASEBOARD_FAB2(SCH_1):PAGE129

C3M42 CAP_A_0402V-1.0UF,6.3V,10%,X6SA
     1 P1V05_PCH_STBY @BASEBOARD_FAB2_LIB.BASEBOARD_FAB2(SCH_1):P1V05_PCH_STBY    I45 @BASEBOARD_FAB2_LIB.BASEBOARD_FAB2(SCH_1):PAGE131
     2    GND @BASEBOARD_FAB2_LIB.BASEBOARD_FAB2(SCH_1):GND    I45 @BASEBOARD_FAB2_LIB.BASEBOARD_FAB2(SCH_1):PAGE131

C3M43 CAP_A_0402V-1.0UF,6.3V,10%,X6SA
     1 P1V05_PCH_STBY @BASEBOARD_FAB2_LIB.BASEBOARD_FAB2(SCH_1):P1V05_PCH_STBY    I42 @BASEBOARD_FAB2_LIB.BASEBOARD_FAB2(SCH_1):PAGE131
     2    GND @BASEBOARD_FAB2_LIB.BASEBOARD_FAB2(SCH_1):GND    I42 @BASEBOARD_FAB2_LIB.BASEBOARD_FAB2(SCH_1):PAGE131

C3M44 CAP_0402-0.22UF,16V,10%,X7R,A3A
     1 DMI_CPU0_PCH_RX_DN<0> @BASEBOARD_FAB2_LIB.BASEBOARD_FAB2(SCH_1):DMI_CPU0_PCH_RX_DN(0)    I80 @BASEBOARD_FAB2_LIB.BASEBOARD_FAB2(SCH_1):PAGE129
     2 DMI_CPU0_PCH_RX_C_DN<0> @BASEBOARD_FAB2_LIB.BASEBOARD_FAB2(SCH_1):DMI_CPU0_PCH_RX_C_DN(0)    I80 @BASEBOARD_FAB2_LIB.BASEBOARD_FAB2(SCH_1):PAGE129

C3M45 CAP_0402-0.22UF,16V,10%,X7R,A3A
     1 DMI_CPU0_PCH_RX_DN<2> @BASEBOARD_FAB2_LIB.BASEBOARD_FAB2(SCH_1):DMI_CPU0_PCH_RX_DN(2)    I82 @BASEBOARD_FAB2_LIB.BASEBOARD_FAB2(SCH_1):PAGE129
     2 DMI_CPU0_PCH_RX_C_DN<2> @BASEBOARD_FAB2_LIB.BASEBOARD_FAB2(SCH_1):DMI_CPU0_PCH_RX_C_DN(2)    I82 @BASEBOARD_FAB2_LIB.BASEBOARD_FAB2(SCH_1):PAGE129

C3M46 CAP_A_0402V-1.0UF,6.3V,10%,X6SA
     1 PVCCIOMCP_CPU0 @BASEBOARD_FAB2_LIB.BASEBOARD_FAB2(SCH_1):PVCCIOMCP_CPU0    I99 @BASEBOARD_FAB2_LIB.BASEBOARD_FAB2(SCH_1):PAGE194
     2    GND @BASEBOARD_FAB2_LIB.BASEBOARD_FAB2(SCH_1):GND    I99 @BASEBOARD_FAB2_LIB.BASEBOARD_FAB2(SCH_1):PAGE194

C3N1 CAP_A_0402V-1.0UF,6.3V,10%,X6SA
     1 PVNN_PCH_STBY @BASEBOARD_FAB2_LIB.BASEBOARD_FAB2(SCH_1):PVNN_PCH_STBY    I34 @BASEBOARD_FAB2_LIB.BASEBOARD_FAB2(SCH_1):PAGE132
     2    GND @BASEBOARD_FAB2_LIB.BASEBOARD_FAB2(SCH_1):GND    I34 @BASEBOARD_FAB2_LIB.BASEBOARD_FAB2(SCH_1):PAGE132

C3N2 CAP_A_0402V-1.0UF,6.3V,10%,X6SA
     1 PVNN_PCH_STBY @BASEBOARD_FAB2_LIB.BASEBOARD_FAB2(SCH_1):PVNN_PCH_STBY    I43 @BASEBOARD_FAB2_LIB.BASEBOARD_FAB2(SCH_1):PAGE132
     2    GND @BASEBOARD_FAB2_LIB.BASEBOARD_FAB2(SCH_1):GND    I43 @BASEBOARD_FAB2_LIB.BASEBOARD_FAB2(SCH_1):PAGE132

C3N3 CAP_A_0402V-1.0UF,6.3V,10%,X6SA
     1 PVNN_PCH_STBY @BASEBOARD_FAB2_LIB.BASEBOARD_FAB2(SCH_1):PVNN_PCH_STBY    I32 @BASEBOARD_FAB2_LIB.BASEBOARD_FAB2(SCH_1):PAGE132
     2    GND @BASEBOARD_FAB2_LIB.BASEBOARD_FAB2(SCH_1):GND    I32 @BASEBOARD_FAB2_LIB.BASEBOARD_FAB2(SCH_1):PAGE132

C3N4 CAP_A_0402V-1.0UF,6.3V,10%,X6SA
     1 PVNN_PCH_STBY @BASEBOARD_FAB2_LIB.BASEBOARD_FAB2(SCH_1):PVNN_PCH_STBY    I46 @BASEBOARD_FAB2_LIB.BASEBOARD_FAB2(SCH_1):PAGE132
     2    GND @BASEBOARD_FAB2_LIB.BASEBOARD_FAB2(SCH_1):GND    I46 @BASEBOARD_FAB2_LIB.BASEBOARD_FAB2(SCH_1):PAGE132

C3N5 CAP_A_0402V-1.0UF,6.3V,10%,X6SA
     1 PVNN_PCH_STBY @BASEBOARD_FAB2_LIB.BASEBOARD_FAB2(SCH_1):PVNN_PCH_STBY    I48 @BASEBOARD_FAB2_LIB.BASEBOARD_FAB2(SCH_1):PAGE132
     2    GND @BASEBOARD_FAB2_LIB.BASEBOARD_FAB2(SCH_1):GND    I48 @BASEBOARD_FAB2_LIB.BASEBOARD_FAB2(SCH_1):PAGE132

C3N6 CAP_A_0402V-1.0UF,6.3V,10%,X6SA
     1 PVNN_PCH_STBY @BASEBOARD_FAB2_LIB.BASEBOARD_FAB2(SCH_1):PVNN_PCH_STBY    I44 @BASEBOARD_FAB2_LIB.BASEBOARD_FAB2(SCH_1):PAGE132
     2    GND @BASEBOARD_FAB2_LIB.BASEBOARD_FAB2(SCH_1):GND    I44 @BASEBOARD_FAB2_LIB.BASEBOARD_FAB2(SCH_1):PAGE132

C3N7 CAP_A_0402V-1.0UF,6.3V,10%,X6SA
     1 PVNN_PCH_STBY @BASEBOARD_FAB2_LIB.BASEBOARD_FAB2(SCH_1):PVNN_PCH_STBY    I35 @BASEBOARD_FAB2_LIB.BASEBOARD_FAB2(SCH_1):PAGE132
     2    GND @BASEBOARD_FAB2_LIB.BASEBOARD_FAB2(SCH_1):GND    I35 @BASEBOARD_FAB2_LIB.BASEBOARD_FAB2(SCH_1):PAGE132

C3N8 CAP_0402-0.22UF,16V,10%,X7R,A3A
     1 DMI_CPU0_PCH_RX_DP<3> @BASEBOARD_FAB2_LIB.BASEBOARD_FAB2(SCH_1):DMI_CPU0_PCH_RX_DP(3)    I75 @BASEBOARD_FAB2_LIB.BASEBOARD_FAB2(SCH_1):PAGE129
     2 DMI_CPU0_PCH_RX_C_DP<3> @BASEBOARD_FAB2_LIB.BASEBOARD_FAB2(SCH_1):DMI_CPU0_PCH_RX_C_DP(3)    I75 @BASEBOARD_FAB2_LIB.BASEBOARD_FAB2(SCH_1):PAGE129

C3N9 CAP_0402-0.22UF,16V,10%,X7R,A3A
     1 DMI_CPU0_PCH_RX_DP<2> @BASEBOARD_FAB2_LIB.BASEBOARD_FAB2(SCH_1):DMI_CPU0_PCH_RX_DP(2)    I74 @BASEBOARD_FAB2_LIB.BASEBOARD_FAB2(SCH_1):PAGE129
     2 DMI_CPU0_PCH_RX_C_DP<2> @BASEBOARD_FAB2_LIB.BASEBOARD_FAB2(SCH_1):DMI_CPU0_PCH_RX_C_DP(2)    I74 @BASEBOARD_FAB2_LIB.BASEBOARD_FAB2(SCH_1):PAGE129

C3N10 CAP_A_0603V-22.0UF,4V,20%,X6S,A
     1 PVNN_PCH_STBY @BASEBOARD_FAB2_LIB.BASEBOARD_FAB2(SCH_1):PVNN_PCH_STBY    I13 @BASEBOARD_FAB2_LIB.BASEBOARD_FAB2(SCH_1):PAGE132
     2    GND @BASEBOARD_FAB2_LIB.BASEBOARD_FAB2(SCH_1):GND    I13 @BASEBOARD_FAB2_LIB.BASEBOARD_FAB2(SCH_1):PAGE132

C3N11 CAP_A_0603V-22.0UF,4V,20%,X6S,A
     1 PVNN_PCH_STBY @BASEBOARD_FAB2_LIB.BASEBOARD_FAB2(SCH_1):PVNN_PCH_STBY    I19 @BASEBOARD_FAB2_LIB.BASEBOARD_FAB2(SCH_1):PAGE132
     2    GND @BASEBOARD_FAB2_LIB.BASEBOARD_FAB2(SCH_1):GND    I19 @BASEBOARD_FAB2_LIB.BASEBOARD_FAB2(SCH_1):PAGE132

C3N12 CAP_A_0603V-22.0UF,4V,20%,X6S,A
     1 PVNN_PCH_STBY @BASEBOARD_FAB2_LIB.BASEBOARD_FAB2(SCH_1):PVNN_PCH_STBY    I12 @BASEBOARD_FAB2_LIB.BASEBOARD_FAB2(SCH_1):PAGE132
     2    GND @BASEBOARD_FAB2_LIB.BASEBOARD_FAB2(SCH_1):GND    I12 @BASEBOARD_FAB2_LIB.BASEBOARD_FAB2(SCH_1):PAGE132

C3N13 CAP_0402-0.22UF,16V,10%,X7R,A3A
     1 DMI_CPU0_PCH_RX_DN<3> @BASEBOARD_FAB2_LIB.BASEBOARD_FAB2(SCH_1):DMI_CPU0_PCH_RX_DN(3)    I83 @BASEBOARD_FAB2_LIB.BASEBOARD_FAB2(SCH_1):PAGE129
     2 DMI_CPU0_PCH_RX_C_DN<3> @BASEBOARD_FAB2_LIB.BASEBOARD_FAB2(SCH_1):DMI_CPU0_PCH_RX_C_DN(3)    I83 @BASEBOARD_FAB2_LIB.BASEBOARD_FAB2(SCH_1):PAGE129

C3N14 CAPP_3018-470UF,2.5V,20%,ALUM,A
     1 PVCCIOMCP_CPU0 @BASEBOARD_FAB2_LIB.BASEBOARD_FAB2(SCH_1):PVCCIOMCP_CPU0   I101 @BASEBOARD_FAB2_LIB.BASEBOARD_FAB2(SCH_1):PAGE194
     2    GND @BASEBOARD_FAB2_LIB.BASEBOARD_FAB2(SCH_1):GND   I101 @BASEBOARD_FAB2_LIB.BASEBOARD_FAB2(SCH_1):PAGE194

C3N15 CAP_A_0402V-1.0UF,6.3V,10%,X6SA
     1 PVNN_PCH_STBY @BASEBOARD_FAB2_LIB.BASEBOARD_FAB2(SCH_1):PVNN_PCH_STBY    I49 @BASEBOARD_FAB2_LIB.BASEBOARD_FAB2(SCH_1):PAGE132
     2    GND @BASEBOARD_FAB2_LIB.BASEBOARD_FAB2(SCH_1):GND    I49 @BASEBOARD_FAB2_LIB.BASEBOARD_FAB2(SCH_1):PAGE132

C3N16 CAP_A_0402V-1.0UF,6.3V,10%,X6SA
     1 PVNN_PCH_STBY @BASEBOARD_FAB2_LIB.BASEBOARD_FAB2(SCH_1):PVNN_PCH_STBY    I36 @BASEBOARD_FAB2_LIB.BASEBOARD_FAB2(SCH_1):PAGE132
     2    GND @BASEBOARD_FAB2_LIB.BASEBOARD_FAB2(SCH_1):GND    I36 @BASEBOARD_FAB2_LIB.BASEBOARD_FAB2(SCH_1):PAGE132

C3N17 CAP_A_0402V-1.0UF,6.3V,10%,X6SA
     1 PVNN_PCH_STBY @BASEBOARD_FAB2_LIB.BASEBOARD_FAB2(SCH_1):PVNN_PCH_STBY    I45 @BASEBOARD_FAB2_LIB.BASEBOARD_FAB2(SCH_1):PAGE132
     2    GND @BASEBOARD_FAB2_LIB.BASEBOARD_FAB2(SCH_1):GND    I45 @BASEBOARD_FAB2_LIB.BASEBOARD_FAB2(SCH_1):PAGE132

C3N18 CAP_A_0402V-1.0UF,6.3V,10%,X6SA
     1 PVNN_PCH_STBY @BASEBOARD_FAB2_LIB.BASEBOARD_FAB2(SCH_1):PVNN_PCH_STBY    I42 @BASEBOARD_FAB2_LIB.BASEBOARD_FAB2(SCH_1):PAGE132
     2    GND @BASEBOARD_FAB2_LIB.BASEBOARD_FAB2(SCH_1):GND    I42 @BASEBOARD_FAB2_LIB.BASEBOARD_FAB2(SCH_1):PAGE132

C3N19 CAP_A_0402V-1.0UF,6.3V,10%,X6SA
     1 PVNN_PCH_STBY @BASEBOARD_FAB2_LIB.BASEBOARD_FAB2(SCH_1):PVNN_PCH_STBY    I31 @BASEBOARD_FAB2_LIB.BASEBOARD_FAB2(SCH_1):PAGE132
     2    GND @BASEBOARD_FAB2_LIB.BASEBOARD_FAB2(SCH_1):GND    I31 @BASEBOARD_FAB2_LIB.BASEBOARD_FAB2(SCH_1):PAGE132

C3N20 CAP_A_0402V-1.0UF,6.3V,10%,X6SA
     1 PVNN_PCH_STBY @BASEBOARD_FAB2_LIB.BASEBOARD_FAB2(SCH_1):PVNN_PCH_STBY    I51 @BASEBOARD_FAB2_LIB.BASEBOARD_FAB2(SCH_1):PAGE132
     2    GND @BASEBOARD_FAB2_LIB.BASEBOARD_FAB2(SCH_1):GND    I51 @BASEBOARD_FAB2_LIB.BASEBOARD_FAB2(SCH_1):PAGE132

C3N21 CAP_A_0402V-1.0UF,6.3V,10%,X6SA
     1 P1V8_PCH_STBY @BASEBOARD_FAB2_LIB.BASEBOARD_FAB2(SCH_1):P1V8_PCH_STBY    I49 @BASEBOARD_FAB2_LIB.BASEBOARD_FAB2(SCH_1):PAGE130
     2    GND @BASEBOARD_FAB2_LIB.BASEBOARD_FAB2(SCH_1):GND    I49 @BASEBOARD_FAB2_LIB.BASEBOARD_FAB2(SCH_1):PAGE130

C3N22 CAP_A_0402V-1.0UF,6.3V,10%,X6SA
     1 P1V8_PCH_STBY @BASEBOARD_FAB2_LIB.BASEBOARD_FAB2(SCH_1):P1V8_PCH_STBY    I53 @BASEBOARD_FAB2_LIB.BASEBOARD_FAB2(SCH_1):PAGE130
     2    GND @BASEBOARD_FAB2_LIB.BASEBOARD_FAB2(SCH_1):GND    I53 @BASEBOARD_FAB2_LIB.BASEBOARD_FAB2(SCH_1):PAGE130

C3N23 CAP_A_0402V-1.0UF,6.3V,10%,X6SA
     1 P3V3_STBY @BASEBOARD_FAB2_LIB.BASEBOARD_FAB2(SCH_1):P3V3_STBY    I42 @BASEBOARD_FAB2_LIB.BASEBOARD_FAB2(SCH_1):PAGE130
     2    GND @BASEBOARD_FAB2_LIB.BASEBOARD_FAB2(SCH_1):GND    I42 @BASEBOARD_FAB2_LIB.BASEBOARD_FAB2(SCH_1):PAGE130

C3N24 CAP_A_0603V-22.0UF,4V,20%,X6S,A
     1 PVNN_PCH_STBY @BASEBOARD_FAB2_LIB.BASEBOARD_FAB2(SCH_1):PVNN_PCH_STBY    I16 @BASEBOARD_FAB2_LIB.BASEBOARD_FAB2(SCH_1):PAGE132
     2    GND @BASEBOARD_FAB2_LIB.BASEBOARD_FAB2(SCH_1):GND    I16 @BASEBOARD_FAB2_LIB.BASEBOARD_FAB2(SCH_1):PAGE132

C3N25 CAP_A_0402V-1.0UF,6.3V,10%,X6SA
     1 P1V8_PCH_STBY @BASEBOARD_FAB2_LIB.BASEBOARD_FAB2(SCH_1):P1V8_PCH_STBY    I50 @BASEBOARD_FAB2_LIB.BASEBOARD_FAB2(SCH_1):PAGE130
     2    GND @BASEBOARD_FAB2_LIB.BASEBOARD_FAB2(SCH_1):GND    I50 @BASEBOARD_FAB2_LIB.BASEBOARD_FAB2(SCH_1):PAGE130

C3N26 CAPP_3018-470UF,2.5V,20%,ALUM,A
     1 PVCCIO_CPU0 @BASEBOARD_FAB2_LIB.BASEBOARD_FAB2(SCH_1):PVCCIO_CPU0   I145 @BASEBOARD_FAB2_LIB.BASEBOARD_FAB2(SCH_1):PAGE212
     2    GND @BASEBOARD_FAB2_LIB.BASEBOARD_FAB2(SCH_1):GND   I145 @BASEBOARD_FAB2_LIB.BASEBOARD_FAB2(SCH_1):PAGE212

C3N27 CAP_A_0603V-22.0UF,4V,20%,X6S,A
     1 PVNN_PCH_STBY @BASEBOARD_FAB2_LIB.BASEBOARD_FAB2(SCH_1):PVNN_PCH_STBY     I8 @BASEBOARD_FAB2_LIB.BASEBOARD_FAB2(SCH_1):PAGE132
     2    GND @BASEBOARD_FAB2_LIB.BASEBOARD_FAB2(SCH_1):GND     I8 @BASEBOARD_FAB2_LIB.BASEBOARD_FAB2(SCH_1):PAGE132

C3N28 CAP_A_0603V-22.0UF,4V,20%,X6S,A
     1 PVNN_PCH_STBY @BASEBOARD_FAB2_LIB.BASEBOARD_FAB2(SCH_1):PVNN_PCH_STBY    I17 @BASEBOARD_FAB2_LIB.BASEBOARD_FAB2(SCH_1):PAGE132
     2    GND @BASEBOARD_FAB2_LIB.BASEBOARD_FAB2(SCH_1):GND    I17 @BASEBOARD_FAB2_LIB.BASEBOARD_FAB2(SCH_1):PAGE132

C3N29 CAP_A_0402V-0.1UF,16V,10%,X7R,A
     1 A_PVCCRTC_EXT_CAP @BASEBOARD_FAB2_LIB.BASEBOARD_FAB2(SCH_1):A_PVCCRTC_EXT_CAP    I16 @BASEBOARD_FAB2_LIB.BASEBOARD_FAB2(SCH_1):PAGE130
     2    GND @BASEBOARD_FAB2_LIB.BASEBOARD_FAB2(SCH_1):GND    I16 @BASEBOARD_FAB2_LIB.BASEBOARD_FAB2(SCH_1):PAGE130

C3N30 CAP_A_0603V-22.0UF,4V,20%,X6S,A
     1 PVNN_PCH_STBY @BASEBOARD_FAB2_LIB.BASEBOARD_FAB2(SCH_1):PVNN_PCH_STBY     I9 @BASEBOARD_FAB2_LIB.BASEBOARD_FAB2(SCH_1):PAGE132
     2    GND @BASEBOARD_FAB2_LIB.BASEBOARD_FAB2(SCH_1):GND     I9 @BASEBOARD_FAB2_LIB.BASEBOARD_FAB2(SCH_1):PAGE132

C3N31 CAP_A_0603V-22.0UF,4V,20%,X6S,A
     1 PVNN_PCH_STBY @BASEBOARD_FAB2_LIB.BASEBOARD_FAB2(SCH_1):PVNN_PCH_STBY    I20 @BASEBOARD_FAB2_LIB.BASEBOARD_FAB2(SCH_1):PAGE132
     2    GND @BASEBOARD_FAB2_LIB.BASEBOARD_FAB2(SCH_1):GND    I20 @BASEBOARD_FAB2_LIB.BASEBOARD_FAB2(SCH_1):PAGE132

C3N32 CAP_A_0402V-1.0UF,6.3V,10%,X6SA
     1 RST_SRTCRST_N @BASEBOARD_FAB2_LIB.BASEBOARD_FAB2(SCH_1):RST_SRTCRST_N    I20 @BASEBOARD_FAB2_LIB.BASEBOARD_FAB2(SCH_1):PAGE137
     2    GND @BASEBOARD_FAB2_LIB.BASEBOARD_FAB2(SCH_1):GND    I20 @BASEBOARD_FAB2_LIB.BASEBOARD_FAB2(SCH_1):PAGE137

C3N33 CAP_0805-10UF,16V,10%,X6S,C953A
     1 VR_FET_SW_P12V_STBY_PVCCIO_CPU0 @BASEBOARD_FAB2_LIB.BASEBOARD_FAB2(SCH_1):VR_FET_SW_P12V_STBY_PVCCIO_CPU0    I41 @BASEBOARD_FAB2_LIB.BASEBOARD_FAB2(SCH_1):PAGE212
     2    GND @BASEBOARD_FAB2_LIB.BASEBOARD_FAB2(SCH_1):GND    I41 @BASEBOARD_FAB2_LIB.BASEBOARD_FAB2(SCH_1):PAGE212

C3N34 CAP_0805-10UF,16V,10%,X6S,C953A
     1 VR_FET_SW_P12V_STBY_PVCCIO_CPU0 @BASEBOARD_FAB2_LIB.BASEBOARD_FAB2(SCH_1):VR_FET_SW_P12V_STBY_PVCCIO_CPU0    I43 @BASEBOARD_FAB2_LIB.BASEBOARD_FAB2(SCH_1):PAGE212
     2    GND @BASEBOARD_FAB2_LIB.BASEBOARD_FAB2(SCH_1):GND    I43 @BASEBOARD_FAB2_LIB.BASEBOARD_FAB2(SCH_1):PAGE212

C3N35 CAPP_3018-470UF,2.5V,20%,ALUM,A
     1 PVCCIO_CPU0 @BASEBOARD_FAB2_LIB.BASEBOARD_FAB2(SCH_1):PVCCIO_CPU0    I18 @BASEBOARD_FAB2_LIB.BASEBOARD_FAB2(SCH_1):PAGE212
     2    GND @BASEBOARD_FAB2_LIB.BASEBOARD_FAB2(SCH_1):GND    I18 @BASEBOARD_FAB2_LIB.BASEBOARD_FAB2(SCH_1):PAGE212

C3N36 CAP_0805-10UF,16V,10%,X6S,C953A
     1 VR_FET_SW_P12V_STBY_PVCCIO_CPU0 @BASEBOARD_FAB2_LIB.BASEBOARD_FAB2(SCH_1):VR_FET_SW_P12V_STBY_PVCCIO_CPU0    I40 @BASEBOARD_FAB2_LIB.BASEBOARD_FAB2(SCH_1):PAGE212
     2    GND @BASEBOARD_FAB2_LIB.BASEBOARD_FAB2(SCH_1):GND    I40 @BASEBOARD_FAB2_LIB.BASEBOARD_FAB2(SCH_1):PAGE212

C3N38 CAPP_3018-470UF,2.5V,20%,ALUM,A
     1 PVCCIO_CPU0 @BASEBOARD_FAB2_LIB.BASEBOARD_FAB2(SCH_1):PVCCIO_CPU0   I146 @BASEBOARD_FAB2_LIB.BASEBOARD_FAB2(SCH_1):PAGE212
     2    GND @BASEBOARD_FAB2_LIB.BASEBOARD_FAB2(SCH_1):GND   I146 @BASEBOARD_FAB2_LIB.BASEBOARD_FAB2(SCH_1):PAGE212

C3N39 CAP_0402LF-220PF,50V,10%,X7R,AA
     1 VR_PVCCIO_CPU0_AVSP @BASEBOARD_FAB2_LIB.BASEBOARD_FAB2(SCH_1):VR_PVCCIO_CPU0_AVSP    I83 @BASEBOARD_FAB2_LIB.BASEBOARD_FAB2(SCH_1):PAGE211
     2 VSENSE_PVCCIO_CPU0_AVSN @BASEBOARD_FAB2_LIB.BASEBOARD_FAB2(SCH_1):VSENSE_PVCCIO_CPU0_AVSN    I83 @BASEBOARD_FAB2_LIB.BASEBOARD_FAB2(SCH_1):PAGE211

C3N40 CAP_A_0402V-1.0UF,6.3V,10%,X6SA
     1 PVCCIOMCP_CPU0 @BASEBOARD_FAB2_LIB.BASEBOARD_FAB2(SCH_1):PVCCIOMCP_CPU0    I86 @BASEBOARD_FAB2_LIB.BASEBOARD_FAB2(SCH_1):PAGE194
     2    GND @BASEBOARD_FAB2_LIB.BASEBOARD_FAB2(SCH_1):GND    I86 @BASEBOARD_FAB2_LIB.BASEBOARD_FAB2(SCH_1):PAGE194

C3P1 CAP_A_0402V-0.1UF,16V,10%,EMPTA
     1 VSENSE_PVCCIO_CPU0_SKT_VSEN @BASEBOARD_FAB2_LIB.BASEBOARD_FAB2(SCH_1):VSENSE_PVCCIO_CPU0_SKT_VSEN    I60 @BASEBOARD_FAB2_LIB.BASEBOARD_FAB2(SCH_1):PAGE212
     2 VSENSE_PVCCIO_CPU0_SKT_VRTN @BASEBOARD_FAB2_LIB.BASEBOARD_FAB2(SCH_1):VSENSE_PVCCIO_CPU0_SKT_VRTN    I60 @BASEBOARD_FAB2_LIB.BASEBOARD_FAB2(SCH_1):PAGE212

C3P2 CAP_A_0402V-0.1UF,16V,10%,X7R,A
     1 VR_PVCCIO_CPU0_VINSEN @BASEBOARD_FAB2_LIB.BASEBOARD_FAB2(SCH_1):VR_PVCCIO_CPU0_VINSEN   I103 @BASEBOARD_FAB2_LIB.BASEBOARD_FAB2(SCH_1):PAGE211
     2    GND @BASEBOARD_FAB2_LIB.BASEBOARD_FAB2(SCH_1):GND   I103 @BASEBOARD_FAB2_LIB.BASEBOARD_FAB2(SCH_1):PAGE211

C3P3 CAP_A_0402V-1.0UF,6.3V,10%,X6SA
     1 VR_PVCCIO_CPU0_VDD @BASEBOARD_FAB2_LIB.BASEBOARD_FAB2(SCH_1):VR_PVCCIO_CPU0_VDD    I20 @BASEBOARD_FAB2_LIB.BASEBOARD_FAB2(SCH_1):PAGE211
     2    GND @BASEBOARD_FAB2_LIB.BASEBOARD_FAB2(SCH_1):GND    I20 @BASEBOARD_FAB2_LIB.BASEBOARD_FAB2(SCH_1):PAGE211

C3P4 CAP_A_0402V-1.0UF,6.3V,10%,X6SA
     1 VR_PVCCIO_CPU0_VD12 @BASEBOARD_FAB2_LIB.BASEBOARD_FAB2(SCH_1):VR_PVCCIO_CPU0_VD12    I11 @BASEBOARD_FAB2_LIB.BASEBOARD_FAB2(SCH_1):PAGE211
     2    GND @BASEBOARD_FAB2_LIB.BASEBOARD_FAB2(SCH_1):GND    I11 @BASEBOARD_FAB2_LIB.BASEBOARD_FAB2(SCH_1):PAGE211

C3P5 CAP_A_0402V-0.1UF,16V,10%,X7R,A
     1 VR_PVCCIO_CPU0_VD12 @BASEBOARD_FAB2_LIB.BASEBOARD_FAB2(SCH_1):VR_PVCCIO_CPU0_VD12    I13 @BASEBOARD_FAB2_LIB.BASEBOARD_FAB2(SCH_1):PAGE211
     2    GND @BASEBOARD_FAB2_LIB.BASEBOARD_FAB2(SCH_1):GND    I13 @BASEBOARD_FAB2_LIB.BASEBOARD_FAB2(SCH_1):PAGE211

C3P6 CAP_0402LF-1000PF,50V,10%,X7R,A
     1 PWRGD_PVCCIO_CPU0_R @BASEBOARD_FAB2_LIB.BASEBOARD_FAB2(SCH_1):PWRGD_PVCCIO_CPU0_R    I71 @BASEBOARD_FAB2_LIB.BASEBOARD_FAB2(SCH_1):PAGE211
     2    GND @BASEBOARD_FAB2_LIB.BASEBOARD_FAB2(SCH_1):GND    I71 @BASEBOARD_FAB2_LIB.BASEBOARD_FAB2(SCH_1):PAGE211

C3P7 CAP_A_0402V-0.1UF,16V,10%,X7R,A
     1 VR_PVCCIO_CPU0_VDD @BASEBOARD_FAB2_LIB.BASEBOARD_FAB2(SCH_1):VR_PVCCIO_CPU0_VDD    I22 @BASEBOARD_FAB2_LIB.BASEBOARD_FAB2(SCH_1):PAGE211
     2    GND @BASEBOARD_FAB2_LIB.BASEBOARD_FAB2(SCH_1):GND    I22 @BASEBOARD_FAB2_LIB.BASEBOARD_FAB2(SCH_1):PAGE211

C3P10 CAP_0402-0.22UF,16V,10%,X7R,A3A
     1 P3E_CPU0_PE1_SS_TXP<0> @BASEBOARD_FAB2_LIB.BASEBOARD_FAB2(SCH_1):P3E_CPU0_PE1_SS_TXP(0)   I482 @BASEBOARD_FAB2_LIB.BASEBOARD_FAB2(SCH_1):PAGE107
     2 P3E_CPU0_PE1_SS_C_TXP<0> @BASEBOARD_FAB2_LIB.BASEBOARD_FAB2(SCH_1):P3E_CPU0_PE1_SS_C_TXP(0)   I482 @BASEBOARD_FAB2_LIB.BASEBOARD_FAB2(SCH_1):PAGE107

C3P11 CAP_0402-0.22UF,16V,10%,X7R,A3A
     1 P3E_CPU0_PE1_SS_TXP<0> @BASEBOARD_FAB2_LIB.BASEBOARD_FAB2(SCH_1):P3E_CPU0_PE1_SS_TXP(0)   I212 @BASEBOARD_FAB2_LIB.BASEBOARD_FAB2(SCH_1):PAGE107
     2 P3E_CPU0_PE1_PCH_TXP<0> @BASEBOARD_FAB2_LIB.BASEBOARD_FAB2(SCH_1):P3E_CPU0_PE1_PCH_TXP(0)   I212 @BASEBOARD_FAB2_LIB.BASEBOARD_FAB2(SCH_1):PAGE107

C3P12 CAP_0402-0.22UF,16V,10%,X7R,A3A
     1 P3E_CPU0_PE1_SS_TXN<0> @BASEBOARD_FAB2_LIB.BASEBOARD_FAB2(SCH_1):P3E_CPU0_PE1_SS_TXN(0)   I481 @BASEBOARD_FAB2_LIB.BASEBOARD_FAB2(SCH_1):PAGE107
     2 P3E_CPU0_PE1_SS_C_TXN<0> @BASEBOARD_FAB2_LIB.BASEBOARD_FAB2(SCH_1):P3E_CPU0_PE1_SS_C_TXN(0)   I481 @BASEBOARD_FAB2_LIB.BASEBOARD_FAB2(SCH_1):PAGE107

C3P13 CAP_0402-0.22UF,16V,10%,X7R,A3A
     1 P3E_CPU0_PE1_SS_TXN<0> @BASEBOARD_FAB2_LIB.BASEBOARD_FAB2(SCH_1):P3E_CPU0_PE1_SS_TXN(0)   I207 @BASEBOARD_FAB2_LIB.BASEBOARD_FAB2(SCH_1):PAGE107
     2 P3E_CPU0_PE1_PCH_TXN<0> @BASEBOARD_FAB2_LIB.BASEBOARD_FAB2(SCH_1):P3E_CPU0_PE1_PCH_TXN(0)   I207 @BASEBOARD_FAB2_LIB.BASEBOARD_FAB2(SCH_1):PAGE107

C3P14 CAP_0402-0.22UF,16V,10%,X7R,A3A
     1 P3E_CPU0_PE1_SS_TXP<1> @BASEBOARD_FAB2_LIB.BASEBOARD_FAB2(SCH_1):P3E_CPU0_PE1_SS_TXP(1)   I483 @BASEBOARD_FAB2_LIB.BASEBOARD_FAB2(SCH_1):PAGE107
     2 P3E_CPU0_PE1_SS_C_TXP<1> @BASEBOARD_FAB2_LIB.BASEBOARD_FAB2(SCH_1):P3E_CPU0_PE1_SS_C_TXP(1)   I483 @BASEBOARD_FAB2_LIB.BASEBOARD_FAB2(SCH_1):PAGE107

C3P15 CAP_0402-0.22UF,16V,10%,X7R,A3A
     1 P3E_CPU0_PE1_SS_TXP<1> @BASEBOARD_FAB2_LIB.BASEBOARD_FAB2(SCH_1):P3E_CPU0_PE1_SS_TXP(1)   I226 @BASEBOARD_FAB2_LIB.BASEBOARD_FAB2(SCH_1):PAGE107
     2 P3E_CPU0_PE1_PCH_TXP<1> @BASEBOARD_FAB2_LIB.BASEBOARD_FAB2(SCH_1):P3E_CPU0_PE1_PCH_TXP(1)   I226 @BASEBOARD_FAB2_LIB.BASEBOARD_FAB2(SCH_1):PAGE107

C3P16 CAP_0402-0.22UF,16V,10%,X7R,A3A
     1 P3E_CPU0_PE1_SS_TXN<1> @BASEBOARD_FAB2_LIB.BASEBOARD_FAB2(SCH_1):P3E_CPU0_PE1_SS_TXN(1)   I476 @BASEBOARD_FAB2_LIB.BASEBOARD_FAB2(SCH_1):PAGE107
     2 P3E_CPU0_PE1_SS_C_TXN<1> @BASEBOARD_FAB2_LIB.BASEBOARD_FAB2(SCH_1):P3E_CPU0_PE1_SS_C_TXN(1)   I476 @BASEBOARD_FAB2_LIB.BASEBOARD_FAB2(SCH_1):PAGE107

C3P17 CAP_0402-0.22UF,16V,10%,X7R,A3A
     1 P3E_CPU0_PE1_SS_TXN<1> @BASEBOARD_FAB2_LIB.BASEBOARD_FAB2(SCH_1):P3E_CPU0_PE1_SS_TXN(1)   I208 @BASEBOARD_FAB2_LIB.BASEBOARD_FAB2(SCH_1):PAGE107
     2 P3E_CPU0_PE1_PCH_TXN<1> @BASEBOARD_FAB2_LIB.BASEBOARD_FAB2(SCH_1):P3E_CPU0_PE1_PCH_TXN(1)   I208 @BASEBOARD_FAB2_LIB.BASEBOARD_FAB2(SCH_1):PAGE107

C3P18 CAP_0402-0.22UF,16V,10%,X7R,A3A
     1 P3E_CPU0_PE1_SS_TXP<2> @BASEBOARD_FAB2_LIB.BASEBOARD_FAB2(SCH_1):P3E_CPU0_PE1_SS_TXP(2)   I219 @BASEBOARD_FAB2_LIB.BASEBOARD_FAB2(SCH_1):PAGE107
     2 P3E_CPU0_PE1_PCH_TXP<2> @BASEBOARD_FAB2_LIB.BASEBOARD_FAB2(SCH_1):P3E_CPU0_PE1_PCH_TXP(2)   I219 @BASEBOARD_FAB2_LIB.BASEBOARD_FAB2(SCH_1):PAGE107

C3P19 CAP_0402-0.22UF,16V,10%,X7R,A3A
     1 P3E_CPU0_PE1_SS_TXP<2> @BASEBOARD_FAB2_LIB.BASEBOARD_FAB2(SCH_1):P3E_CPU0_PE1_SS_TXP(2)   I485 @BASEBOARD_FAB2_LIB.BASEBOARD_FAB2(SCH_1):PAGE107
     2 P3E_CPU0_PE1_SS_C_TXP<2> @BASEBOARD_FAB2_LIB.BASEBOARD_FAB2(SCH_1):P3E_CPU0_PE1_SS_C_TXP(2)   I485 @BASEBOARD_FAB2_LIB.BASEBOARD_FAB2(SCH_1):PAGE107

C3P20 CAP_0402-0.22UF,16V,10%,X7R,A3A
     1 P3E_CPU0_PE1_SS_TXN<2> @BASEBOARD_FAB2_LIB.BASEBOARD_FAB2(SCH_1):P3E_CPU0_PE1_SS_TXN(2)   I215 @BASEBOARD_FAB2_LIB.BASEBOARD_FAB2(SCH_1):PAGE107
     2 P3E_CPU0_PE1_PCH_TXN<2> @BASEBOARD_FAB2_LIB.BASEBOARD_FAB2(SCH_1):P3E_CPU0_PE1_PCH_TXN(2)   I215 @BASEBOARD_FAB2_LIB.BASEBOARD_FAB2(SCH_1):PAGE107

C3P21 CAP_0402-0.22UF,16V,10%,X7R,A3A
     1 P3E_CPU0_PE1_SS_TXN<2> @BASEBOARD_FAB2_LIB.BASEBOARD_FAB2(SCH_1):P3E_CPU0_PE1_SS_TXN(2)   I480 @BASEBOARD_FAB2_LIB.BASEBOARD_FAB2(SCH_1):PAGE107
     2 P3E_CPU0_PE1_SS_C_TXN<2> @BASEBOARD_FAB2_LIB.BASEBOARD_FAB2(SCH_1):P3E_CPU0_PE1_SS_C_TXN(2)   I480 @BASEBOARD_FAB2_LIB.BASEBOARD_FAB2(SCH_1):PAGE107

C3P22 CAP_0402-0.22UF,16V,10%,X7R,A3A
     1 P3E_CPU0_PE1_SS_TXP<3> @BASEBOARD_FAB2_LIB.BASEBOARD_FAB2(SCH_1):P3E_CPU0_PE1_SS_TXP(3)   I484 @BASEBOARD_FAB2_LIB.BASEBOARD_FAB2(SCH_1):PAGE107
     2 P3E_CPU0_PE1_SS_C_TXP<3> @BASEBOARD_FAB2_LIB.BASEBOARD_FAB2(SCH_1):P3E_CPU0_PE1_SS_C_TXP(3)   I484 @BASEBOARD_FAB2_LIB.BASEBOARD_FAB2(SCH_1):PAGE107

C3P23 CAP_0402-0.22UF,16V,10%,X7R,A3A
     1 P3E_CPU0_PE1_SS_TXP<3> @BASEBOARD_FAB2_LIB.BASEBOARD_FAB2(SCH_1):P3E_CPU0_PE1_SS_TXP(3)   I229 @BASEBOARD_FAB2_LIB.BASEBOARD_FAB2(SCH_1):PAGE107
     2 P3E_CPU0_PE1_PCH_TXP<3> @BASEBOARD_FAB2_LIB.BASEBOARD_FAB2(SCH_1):P3E_CPU0_PE1_PCH_TXP(3)   I229 @BASEBOARD_FAB2_LIB.BASEBOARD_FAB2(SCH_1):PAGE107

C3P24 CAP_0402-0.22UF,16V,10%,X7R,A3A
     1 P3E_CPU0_PE1_SS_TXN<3> @BASEBOARD_FAB2_LIB.BASEBOARD_FAB2(SCH_1):P3E_CPU0_PE1_SS_TXN(3)   I479 @BASEBOARD_FAB2_LIB.BASEBOARD_FAB2(SCH_1):PAGE107
     2 P3E_CPU0_PE1_SS_C_TXN<3> @BASEBOARD_FAB2_LIB.BASEBOARD_FAB2(SCH_1):P3E_CPU0_PE1_SS_C_TXN(3)   I479 @BASEBOARD_FAB2_LIB.BASEBOARD_FAB2(SCH_1):PAGE107

C3P25 CAP_0402-0.22UF,16V,10%,X7R,A3A
     1 P3E_CPU0_PE1_SS_TXN<3> @BASEBOARD_FAB2_LIB.BASEBOARD_FAB2(SCH_1):P3E_CPU0_PE1_SS_TXN(3)   I216 @BASEBOARD_FAB2_LIB.BASEBOARD_FAB2(SCH_1):PAGE107
     2 P3E_CPU0_PE1_PCH_TXN<3> @BASEBOARD_FAB2_LIB.BASEBOARD_FAB2(SCH_1):P3E_CPU0_PE1_PCH_TXN(3)   I216 @BASEBOARD_FAB2_LIB.BASEBOARD_FAB2(SCH_1):PAGE107

C3P26 CAP_0402-0.22UF,16V,10%,X7R,A3A
     1 P3E_CPU0_PE1_SS_TXP<4> @BASEBOARD_FAB2_LIB.BASEBOARD_FAB2(SCH_1):P3E_CPU0_PE1_SS_TXP(4)   I487 @BASEBOARD_FAB2_LIB.BASEBOARD_FAB2(SCH_1):PAGE107
     2 P3E_CPU0_PE1_SS_C_TXP<4> @BASEBOARD_FAB2_LIB.BASEBOARD_FAB2(SCH_1):P3E_CPU0_PE1_SS_C_TXP(4)   I487 @BASEBOARD_FAB2_LIB.BASEBOARD_FAB2(SCH_1):PAGE107

C3P27 CAP_0402-0.22UF,16V,10%,X7R,A3A
     1 P3E_CPU0_PE1_SS_TXP<4> @BASEBOARD_FAB2_LIB.BASEBOARD_FAB2(SCH_1):P3E_CPU0_PE1_SS_TXP(4)   I223 @BASEBOARD_FAB2_LIB.BASEBOARD_FAB2(SCH_1):PAGE107
     2 P3E_CPU0_PE1_PCH_TXP<4> @BASEBOARD_FAB2_LIB.BASEBOARD_FAB2(SCH_1):P3E_CPU0_PE1_PCH_TXP(4)   I223 @BASEBOARD_FAB2_LIB.BASEBOARD_FAB2(SCH_1):PAGE107

C3P28 CAP_0402-0.22UF,16V,10%,X7R,A3A
     1 P3E_CPU0_PE1_SS_TXN<4> @BASEBOARD_FAB2_LIB.BASEBOARD_FAB2(SCH_1):P3E_CPU0_PE1_SS_TXN(4)   I232 @BASEBOARD_FAB2_LIB.BASEBOARD_FAB2(SCH_1):PAGE107
     2 P3E_CPU0_PE1_PCH_TXN<4> @BASEBOARD_FAB2_LIB.BASEBOARD_FAB2(SCH_1):P3E_CPU0_PE1_PCH_TXN(4)   I232 @BASEBOARD_FAB2_LIB.BASEBOARD_FAB2(SCH_1):PAGE107

C3P29 CAP_0402-0.22UF,16V,10%,X7R,A3A
     1 P3E_CPU0_PE1_SS_TXN<4> @BASEBOARD_FAB2_LIB.BASEBOARD_FAB2(SCH_1):P3E_CPU0_PE1_SS_TXN(4)   I478 @BASEBOARD_FAB2_LIB.BASEBOARD_FAB2(SCH_1):PAGE107
     2 P3E_CPU0_PE1_SS_C_TXN<4> @BASEBOARD_FAB2_LIB.BASEBOARD_FAB2(SCH_1):P3E_CPU0_PE1_SS_C_TXN(4)   I478 @BASEBOARD_FAB2_LIB.BASEBOARD_FAB2(SCH_1):PAGE107

C3P30 CAP_0402-0.22UF,16V,10%,X7R,A3A
     1 P3E_CPU0_PE1_SS_TXP<5> @BASEBOARD_FAB2_LIB.BASEBOARD_FAB2(SCH_1):P3E_CPU0_PE1_SS_TXP(5)   I245 @BASEBOARD_FAB2_LIB.BASEBOARD_FAB2(SCH_1):PAGE107
     2 P3E_CPU0_PE1_PCH_TXP<5> @BASEBOARD_FAB2_LIB.BASEBOARD_FAB2(SCH_1):P3E_CPU0_PE1_PCH_TXP(5)   I245 @BASEBOARD_FAB2_LIB.BASEBOARD_FAB2(SCH_1):PAGE107

C3P31 CAP_0402-0.22UF,16V,10%,X7R,A3A
     1 P3E_CPU0_PE1_SS_TXP<5> @BASEBOARD_FAB2_LIB.BASEBOARD_FAB2(SCH_1):P3E_CPU0_PE1_SS_TXP(5)   I488 @BASEBOARD_FAB2_LIB.BASEBOARD_FAB2(SCH_1):PAGE107
     2 P3E_CPU0_PE1_SS_C_TXP<5> @BASEBOARD_FAB2_LIB.BASEBOARD_FAB2(SCH_1):P3E_CPU0_PE1_SS_C_TXP(5)   I488 @BASEBOARD_FAB2_LIB.BASEBOARD_FAB2(SCH_1):PAGE107

C3P32 CAP_0402-0.22UF,16V,10%,X7R,A3A
     1 P3E_CPU0_PE1_SS_TXN<5> @BASEBOARD_FAB2_LIB.BASEBOARD_FAB2(SCH_1):P3E_CPU0_PE1_SS_TXN(5)   I234 @BASEBOARD_FAB2_LIB.BASEBOARD_FAB2(SCH_1):PAGE107
     2 P3E_CPU0_PE1_PCH_TXN<5> @BASEBOARD_FAB2_LIB.BASEBOARD_FAB2(SCH_1):P3E_CPU0_PE1_PCH_TXN(5)   I234 @BASEBOARD_FAB2_LIB.BASEBOARD_FAB2(SCH_1):PAGE107

C3P33 CAP_0402-0.22UF,16V,10%,X7R,A3A
     1 P3E_CPU0_PE1_SS_TXN<5> @BASEBOARD_FAB2_LIB.BASEBOARD_FAB2(SCH_1):P3E_CPU0_PE1_SS_TXN(5)   I477 @BASEBOARD_FAB2_LIB.BASEBOARD_FAB2(SCH_1):PAGE107
     2 P3E_CPU0_PE1_SS_C_TXN<5> @BASEBOARD_FAB2_LIB.BASEBOARD_FAB2(SCH_1):P3E_CPU0_PE1_SS_C_TXN(5)   I477 @BASEBOARD_FAB2_LIB.BASEBOARD_FAB2(SCH_1):PAGE107

C3P34 CAP_0402-0.22UF,16V,10%,X7R,A3A
     1 P3E_CPU0_PE1_SS_TXP<6> @BASEBOARD_FAB2_LIB.BASEBOARD_FAB2(SCH_1):P3E_CPU0_PE1_SS_TXP(6)   I489 @BASEBOARD_FAB2_LIB.BASEBOARD_FAB2(SCH_1):PAGE107
     2 P3E_CPU0_PE1_SS_C_TXP<6> @BASEBOARD_FAB2_LIB.BASEBOARD_FAB2(SCH_1):P3E_CPU0_PE1_SS_C_TXP(6)   I489 @BASEBOARD_FAB2_LIB.BASEBOARD_FAB2(SCH_1):PAGE107

C3P35 CAP_0402-0.22UF,16V,10%,X7R,A3A
     1 P3E_CPU0_PE1_SS_TXP<6> @BASEBOARD_FAB2_LIB.BASEBOARD_FAB2(SCH_1):P3E_CPU0_PE1_SS_TXP(6)   I240 @BASEBOARD_FAB2_LIB.BASEBOARD_FAB2(SCH_1):PAGE107
     2 P3E_CPU0_PE1_PCH_TXP<6> @BASEBOARD_FAB2_LIB.BASEBOARD_FAB2(SCH_1):P3E_CPU0_PE1_PCH_TXP(6)   I240 @BASEBOARD_FAB2_LIB.BASEBOARD_FAB2(SCH_1):PAGE107

C3P36 CAP_0402-0.22UF,16V,10%,X7R,A3A
     1 P3E_CPU0_PE1_SS_TXN<6> @BASEBOARD_FAB2_LIB.BASEBOARD_FAB2(SCH_1):P3E_CPU0_PE1_SS_TXN(6)   I475 @BASEBOARD_FAB2_LIB.BASEBOARD_FAB2(SCH_1):PAGE107
     2 P3E_CPU0_PE1_SS_C_TXN<6> @BASEBOARD_FAB2_LIB.BASEBOARD_FAB2(SCH_1):P3E_CPU0_PE1_SS_C_TXN(6)   I475 @BASEBOARD_FAB2_LIB.BASEBOARD_FAB2(SCH_1):PAGE107

C3P37 CAP_0402-0.22UF,16V,10%,X7R,A3A
     1 P3E_CPU0_PE1_SS_TXN<6> @BASEBOARD_FAB2_LIB.BASEBOARD_FAB2(SCH_1):P3E_CPU0_PE1_SS_TXN(6)   I235 @BASEBOARD_FAB2_LIB.BASEBOARD_FAB2(SCH_1):PAGE107
     2 P3E_CPU0_PE1_PCH_TXN<6> @BASEBOARD_FAB2_LIB.BASEBOARD_FAB2(SCH_1):P3E_CPU0_PE1_PCH_TXN(6)   I235 @BASEBOARD_FAB2_LIB.BASEBOARD_FAB2(SCH_1):PAGE107

C3P38 CAP_0402-0.22UF,16V,10%,X7R,A3A
     1 P3E_CPU0_PE1_SS_TXP<7> @BASEBOARD_FAB2_LIB.BASEBOARD_FAB2(SCH_1):P3E_CPU0_PE1_SS_TXP(7)   I486 @BASEBOARD_FAB2_LIB.BASEBOARD_FAB2(SCH_1):PAGE107
     2 P3E_CPU0_PE1_SS_C_TXP<7> @BASEBOARD_FAB2_LIB.BASEBOARD_FAB2(SCH_1):P3E_CPU0_PE1_SS_C_TXP(7)   I486 @BASEBOARD_FAB2_LIB.BASEBOARD_FAB2(SCH_1):PAGE107

C3P39 CAP_0402-0.22UF,16V,10%,X7R,A3A
     1 P3E_CPU0_PE1_SS_TXP<7> @BASEBOARD_FAB2_LIB.BASEBOARD_FAB2(SCH_1):P3E_CPU0_PE1_SS_TXP(7)   I248 @BASEBOARD_FAB2_LIB.BASEBOARD_FAB2(SCH_1):PAGE107
     2 P3E_CPU0_PE1_PCH_TXP<7> @BASEBOARD_FAB2_LIB.BASEBOARD_FAB2(SCH_1):P3E_CPU0_PE1_PCH_TXP(7)   I248 @BASEBOARD_FAB2_LIB.BASEBOARD_FAB2(SCH_1):PAGE107

C3P40 CAP_0402-0.22UF,16V,10%,X7R,A3A
     1 P3E_CPU0_PE1_SS_TXN<7> @BASEBOARD_FAB2_LIB.BASEBOARD_FAB2(SCH_1):P3E_CPU0_PE1_SS_TXN(7)   I241 @BASEBOARD_FAB2_LIB.BASEBOARD_FAB2(SCH_1):PAGE107
     2 P3E_CPU0_PE1_PCH_TXN<7> @BASEBOARD_FAB2_LIB.BASEBOARD_FAB2(SCH_1):P3E_CPU0_PE1_PCH_TXN(7)   I241 @BASEBOARD_FAB2_LIB.BASEBOARD_FAB2(SCH_1):PAGE107

C3P41 CAP_0402-0.22UF,16V,10%,X7R,A3A
     1 P3E_CPU0_PE1_SS_TXN<7> @BASEBOARD_FAB2_LIB.BASEBOARD_FAB2(SCH_1):P3E_CPU0_PE1_SS_TXN(7)   I474 @BASEBOARD_FAB2_LIB.BASEBOARD_FAB2(SCH_1):PAGE107
     2 P3E_CPU0_PE1_SS_C_TXN<7> @BASEBOARD_FAB2_LIB.BASEBOARD_FAB2(SCH_1):P3E_CPU0_PE1_SS_C_TXN(7)   I474 @BASEBOARD_FAB2_LIB.BASEBOARD_FAB2(SCH_1):PAGE107

C3P42 CAP_A_0402V-1.0UF,6.3V,10%,X6SA
     1 P3V3_STBY @BASEBOARD_FAB2_LIB.BASEBOARD_FAB2(SCH_1):P3V3_STBY    I73 @BASEBOARD_FAB2_LIB.BASEBOARD_FAB2(SCH_1):PAGE96
     2    GND @BASEBOARD_FAB2_LIB.BASEBOARD_FAB2(SCH_1):GND    I73 @BASEBOARD_FAB2_LIB.BASEBOARD_FAB2(SCH_1):PAGE96

C3P43 CAP_A_0402V-0.1UF,16V,10%,X7R,A
     1 P3V3_STBY @BASEBOARD_FAB2_LIB.BASEBOARD_FAB2(SCH_1):P3V3_STBY     I6 @BASEBOARD_FAB2_LIB.BASEBOARD_FAB2(SCH_1):PAGE192
     2    GND @BASEBOARD_FAB2_LIB.BASEBOARD_FAB2(SCH_1):GND     I6 @BASEBOARD_FAB2_LIB.BASEBOARD_FAB2(SCH_1):PAGE192

C3P44 CAP_A_0402V-0.1UF,16V,10%,X7R,A
     1 P3V3_STBY @BASEBOARD_FAB2_LIB.BASEBOARD_FAB2(SCH_1):P3V3_STBY    I23 @BASEBOARD_FAB2_LIB.BASEBOARD_FAB2(SCH_1):PAGE192
     2    GND @BASEBOARD_FAB2_LIB.BASEBOARD_FAB2(SCH_1):GND    I23 @BASEBOARD_FAB2_LIB.BASEBOARD_FAB2(SCH_1):PAGE192

C3P45 CAP_0402-0.047UF,25V,10%,X7R,AA
     1 A_ADM1085_CEXT @BASEBOARD_FAB2_LIB.BASEBOARD_FAB2(SCH_1):A_ADM1085_CEXT    I60 @BASEBOARD_FAB2_LIB.BASEBOARD_FAB2(SCH_1):PAGE196
     2    GND @BASEBOARD_FAB2_LIB.BASEBOARD_FAB2(SCH_1):GND    I60 @BASEBOARD_FAB2_LIB.BASEBOARD_FAB2(SCH_1):PAGE196

C3P46 CAP_A_0402V-0.1UF,16V,10%,X7R,A
     1 P3V3_STBY @BASEBOARD_FAB2_LIB.BASEBOARD_FAB2(SCH_1):P3V3_STBY    I72 @BASEBOARD_FAB2_LIB.BASEBOARD_FAB2(SCH_1):PAGE196
     2    GND @BASEBOARD_FAB2_LIB.BASEBOARD_FAB2(SCH_1):GND    I72 @BASEBOARD_FAB2_LIB.BASEBOARD_FAB2(SCH_1):PAGE196

C3P47 CAP_A_0402V-0.1UF,16V,10%,X7R,A
     1 P3V3_STBY @BASEBOARD_FAB2_LIB.BASEBOARD_FAB2(SCH_1):P3V3_STBY    I12 @BASEBOARD_FAB2_LIB.BASEBOARD_FAB2(SCH_1):PAGE192
     2    GND @BASEBOARD_FAB2_LIB.BASEBOARD_FAB2(SCH_1):GND    I12 @BASEBOARD_FAB2_LIB.BASEBOARD_FAB2(SCH_1):PAGE192

C3P48 CAP_A_0402V-0.1UF,16V,10%,X7R,A
     1 P3V3_STBY @BASEBOARD_FAB2_LIB.BASEBOARD_FAB2(SCH_1):P3V3_STBY    I25 @BASEBOARD_FAB2_LIB.BASEBOARD_FAB2(SCH_1):PAGE192
     2    GND @BASEBOARD_FAB2_LIB.BASEBOARD_FAB2(SCH_1):GND    I25 @BASEBOARD_FAB2_LIB.BASEBOARD_FAB2(SCH_1):PAGE192

C3P49 CAP_A_0402V-0.1UF,16V,10%,X7R,A
     1 P0V7_GTL2104_VREF_1 @BASEBOARD_FAB2_LIB.BASEBOARD_FAB2(SCH_1):P0V7_GTL2104_VREF_1    I37 @BASEBOARD_FAB2_LIB.BASEBOARD_FAB2(SCH_1):PAGE92
     2    GND @BASEBOARD_FAB2_LIB.BASEBOARD_FAB2(SCH_1):GND    I37 @BASEBOARD_FAB2_LIB.BASEBOARD_FAB2(SCH_1):PAGE92

C3P50 CAP_0402-1.0UF,16V,10%,X6S,D97A
     1   P3V3 @BASEBOARD_FAB2_LIB.BASEBOARD_FAB2(SCH_1):P3V3    I84 @BASEBOARD_FAB2_LIB.BASEBOARD_FAB2(SCH_1):PAGE92
     2    GND @BASEBOARD_FAB2_LIB.BASEBOARD_FAB2(SCH_1):GND    I84 @BASEBOARD_FAB2_LIB.BASEBOARD_FAB2(SCH_1):PAGE92

C3P51 CAP_A_0402V-0.1UF,16V,10%,X7R,A
     1 P3V3_STBY @BASEBOARD_FAB2_LIB.BASEBOARD_FAB2(SCH_1):P3V3_STBY    I11 @BASEBOARD_FAB2_LIB.BASEBOARD_FAB2(SCH_1):PAGE192
     2    GND @BASEBOARD_FAB2_LIB.BASEBOARD_FAB2(SCH_1):GND    I11 @BASEBOARD_FAB2_LIB.BASEBOARD_FAB2(SCH_1):PAGE192

C3P52 CAP_A_0402V-0.1UF,16V,10%,X7R,A
     1 P3V3_STBY @BASEBOARD_FAB2_LIB.BASEBOARD_FAB2(SCH_1):P3V3_STBY    I17 @BASEBOARD_FAB2_LIB.BASEBOARD_FAB2(SCH_1):PAGE192
     2    GND @BASEBOARD_FAB2_LIB.BASEBOARD_FAB2(SCH_1):GND    I17 @BASEBOARD_FAB2_LIB.BASEBOARD_FAB2(SCH_1):PAGE192

C3R1 CAP_A_0402V-0.1UF,16V,10%,X7R,A
     1 P3V3_STBY @BASEBOARD_FAB2_LIB.BASEBOARD_FAB2(SCH_1):P3V3_STBY     I4 @BASEBOARD_FAB2_LIB.BASEBOARD_FAB2(SCH_1):PAGE192
     2    GND @BASEBOARD_FAB2_LIB.BASEBOARD_FAB2(SCH_1):GND     I4 @BASEBOARD_FAB2_LIB.BASEBOARD_FAB2(SCH_1):PAGE192

C3R2 CAP_A_0402V-0.1UF,16V,10%,X7R,A
     1 P3V3_STBY @BASEBOARD_FAB2_LIB.BASEBOARD_FAB2(SCH_1):P3V3_STBY    I10 @BASEBOARD_FAB2_LIB.BASEBOARD_FAB2(SCH_1):PAGE192
     2    GND @BASEBOARD_FAB2_LIB.BASEBOARD_FAB2(SCH_1):GND    I10 @BASEBOARD_FAB2_LIB.BASEBOARD_FAB2(SCH_1):PAGE192

C3R3 CAP_A_0402V-0.1UF,16V,10%,X7R,A
     1 P3V3_STBY @BASEBOARD_FAB2_LIB.BASEBOARD_FAB2(SCH_1):P3V3_STBY     I7 @BASEBOARD_FAB2_LIB.BASEBOARD_FAB2(SCH_1):PAGE192
     2    GND @BASEBOARD_FAB2_LIB.BASEBOARD_FAB2(SCH_1):GND     I7 @BASEBOARD_FAB2_LIB.BASEBOARD_FAB2(SCH_1):PAGE192

C3R4 CAPP_3018-470UF,2.5V,20%,ALUM,A
     1 PVCCMCP_CPU0 @BASEBOARD_FAB2_LIB.BASEBOARD_FAB2(SCH_1):PVCCMCP_CPU0    I31 @BASEBOARD_FAB2_LIB.BASEBOARD_FAB2(SCH_1):PAGE194
     2    GND @BASEBOARD_FAB2_LIB.BASEBOARD_FAB2(SCH_1):GND    I31 @BASEBOARD_FAB2_LIB.BASEBOARD_FAB2(SCH_1):PAGE194

C3T1 CAP_A_0603V-47UF,4V,20%,X5R,60A
     1 P1V8_MCP_CPU0 @BASEBOARD_FAB2_LIB.BASEBOARD_FAB2(SCH_1):P1V8_MCP_CPU0   I149 @BASEBOARD_FAB2_LIB.BASEBOARD_FAB2(SCH_1):PAGE194
     2    GND @BASEBOARD_FAB2_LIB.BASEBOARD_FAB2(SCH_1):GND   I149 @BASEBOARD_FAB2_LIB.BASEBOARD_FAB2(SCH_1):PAGE194

C3T2 CAP_A_0603V-47UF,4V,20%,X5R,60A
     1 P1V8_MCP_CPU0 @BASEBOARD_FAB2_LIB.BASEBOARD_FAB2(SCH_1):P1V8_MCP_CPU0   I150 @BASEBOARD_FAB2_LIB.BASEBOARD_FAB2(SCH_1):PAGE194
     2    GND @BASEBOARD_FAB2_LIB.BASEBOARD_FAB2(SCH_1):GND   I150 @BASEBOARD_FAB2_LIB.BASEBOARD_FAB2(SCH_1):PAGE194

C3T3 CAPP_3018-68UF,16V,20%,TANT,72A
     1 P12V_STBY @BASEBOARD_FAB2_LIB.BASEBOARD_FAB2(SCH_1):P12V_STBY   I113 @BASEBOARD_FAB2_LIB.BASEBOARD_FAB2(SCH_1):PAGE195
     2    GND @BASEBOARD_FAB2_LIB.BASEBOARD_FAB2(SCH_1):GND   I113 @BASEBOARD_FAB2_LIB.BASEBOARD_FAB2(SCH_1):PAGE195

C3T4 CAP_A_0402V-1.0UF,6.3V,10%,X6SA
     1 P3V3_STBY @BASEBOARD_FAB2_LIB.BASEBOARD_FAB2(SCH_1):P3V3_STBY   I138 @BASEBOARD_FAB2_LIB.BASEBOARD_FAB2(SCH_1):PAGE153
     2    GND @BASEBOARD_FAB2_LIB.BASEBOARD_FAB2(SCH_1):GND   I138 @BASEBOARD_FAB2_LIB.BASEBOARD_FAB2(SCH_1):PAGE153

C3T5 CAP_A_0402V-0.01UF,25V,10%,X7RA
     1 P3V3_STBY @BASEBOARD_FAB2_LIB.BASEBOARD_FAB2(SCH_1):P3V3_STBY   I136 @BASEBOARD_FAB2_LIB.BASEBOARD_FAB2(SCH_1):PAGE153
     2    GND @BASEBOARD_FAB2_LIB.BASEBOARD_FAB2(SCH_1):GND   I136 @BASEBOARD_FAB2_LIB.BASEBOARD_FAB2(SCH_1):PAGE153

C3T6 CAPP_3018-68UF,16V,20%,TANT,72A
     1 P12V_STBY @BASEBOARD_FAB2_LIB.BASEBOARD_FAB2(SCH_1):P12V_STBY    I98 @BASEBOARD_FAB2_LIB.BASEBOARD_FAB2(SCH_1):PAGE195
     2    GND @BASEBOARD_FAB2_LIB.BASEBOARD_FAB2(SCH_1):GND    I98 @BASEBOARD_FAB2_LIB.BASEBOARD_FAB2(SCH_1):PAGE195

C3T7 CAP_0805-47UF,4V,20%,X6S,C9533A
     1 PVPP_ABC @BASEBOARD_FAB2_LIB.BASEBOARD_FAB2(SCH_1):PVPP_ABC   I184 @BASEBOARD_FAB2_LIB.BASEBOARD_FAB2(SCH_1):PAGE231
     2    GND @BASEBOARD_FAB2_LIB.BASEBOARD_FAB2(SCH_1):GND   I184 @BASEBOARD_FAB2_LIB.BASEBOARD_FAB2(SCH_1):PAGE231

C3T8 CAP_0805-10UF,16V,10%,X6S,C953A
     1 VR_FET_SW_P12V_STBY_PVPP_ABC @BASEBOARD_FAB2_LIB.BASEBOARD_FAB2(SCH_1):VR_FET_SW_P12V_STBY_PVPP_ABC   I210 @BASEBOARD_FAB2_LIB.BASEBOARD_FAB2(SCH_1):PAGE231
     2    GND @BASEBOARD_FAB2_LIB.BASEBOARD_FAB2(SCH_1):GND   I210 @BASEBOARD_FAB2_LIB.BASEBOARD_FAB2(SCH_1):PAGE231

C3T9 CAP_0805-47UF,4V,20%,X6S,C9533A
     1 PVPP_ABC @BASEBOARD_FAB2_LIB.BASEBOARD_FAB2(SCH_1):PVPP_ABC   I186 @BASEBOARD_FAB2_LIB.BASEBOARD_FAB2(SCH_1):PAGE231
     2    GND @BASEBOARD_FAB2_LIB.BASEBOARD_FAB2(SCH_1):GND   I186 @BASEBOARD_FAB2_LIB.BASEBOARD_FAB2(SCH_1):PAGE231

C3T10 CAP_0402-1.0UF,16V,10%,X6S,D97A
     1 VR_FET_SW_P12V_STBY_PVPP_ABC @BASEBOARD_FAB2_LIB.BASEBOARD_FAB2(SCH_1):VR_FET_SW_P12V_STBY_PVPP_ABC   I161 @BASEBOARD_FAB2_LIB.BASEBOARD_FAB2(SCH_1):PAGE231
     2    GND @BASEBOARD_FAB2_LIB.BASEBOARD_FAB2(SCH_1):GND   I161 @BASEBOARD_FAB2_LIB.BASEBOARD_FAB2(SCH_1):PAGE231

C3T11 CAP_0603-4.7UF,6.3V,10%,X6S,E1A
     1 VR_VB_PVPP_ABC @BASEBOARD_FAB2_LIB.BASEBOARD_FAB2(SCH_1):VR_VB_PVPP_ABC   I202 @BASEBOARD_FAB2_LIB.BASEBOARD_FAB2(SCH_1):PAGE231
     2 AGND_PVPP_ABC @BASEBOARD_FAB2_LIB.BASEBOARD_FAB2(SCH_1):AGND_PVPP_ABC   I202 @BASEBOARD_FAB2_LIB.BASEBOARD_FAB2(SCH_1):PAGE231

C3T12 CAP_0805-10UF,16V,10%,X6S,C953A
     1 VR_FET_SW_P12V_STBY_PVPP_ABC @BASEBOARD_FAB2_LIB.BASEBOARD_FAB2(SCH_1):VR_FET_SW_P12V_STBY_PVPP_ABC   I215 @BASEBOARD_FAB2_LIB.BASEBOARD_FAB2(SCH_1):PAGE231
     2    GND @BASEBOARD_FAB2_LIB.BASEBOARD_FAB2(SCH_1):GND   I215 @BASEBOARD_FAB2_LIB.BASEBOARD_FAB2(SCH_1):PAGE231

C3T13 CAPP_3018-68UF,16V,20%,TANT,72A
     1 P12V_STBY @BASEBOARD_FAB2_LIB.BASEBOARD_FAB2(SCH_1):P12V_STBY   I104 @BASEBOARD_FAB2_LIB.BASEBOARD_FAB2(SCH_1):PAGE195
     2    GND @BASEBOARD_FAB2_LIB.BASEBOARD_FAB2(SCH_1):GND   I104 @BASEBOARD_FAB2_LIB.BASEBOARD_FAB2(SCH_1):PAGE195

C3T14 CAP_0805-10UF,16V,10%,X6S,C953A
     1 VR_FET_SW_P12V_STBY_PVPP_ABC @BASEBOARD_FAB2_LIB.BASEBOARD_FAB2(SCH_1):VR_FET_SW_P12V_STBY_PVPP_ABC   I211 @BASEBOARD_FAB2_LIB.BASEBOARD_FAB2(SCH_1):PAGE231
     2    GND @BASEBOARD_FAB2_LIB.BASEBOARD_FAB2(SCH_1):GND   I211 @BASEBOARD_FAB2_LIB.BASEBOARD_FAB2(SCH_1):PAGE231

C3T15 CAPP_3018-68UF,16V,20%,TANT,72A
     1 P12V_STBY @BASEBOARD_FAB2_LIB.BASEBOARD_FAB2(SCH_1):P12V_STBY   I106 @BASEBOARD_FAB2_LIB.BASEBOARD_FAB2(SCH_1):PAGE195
     2    GND @BASEBOARD_FAB2_LIB.BASEBOARD_FAB2(SCH_1):GND   I106 @BASEBOARD_FAB2_LIB.BASEBOARD_FAB2(SCH_1):PAGE195

C3U1 CAPP_3018-470UF,2.5V,20%,ALUM,A
     1 PVDDQ_ABC @BASEBOARD_FAB2_LIB.BASEBOARD_FAB2(SCH_1):PVDDQ_ABC    I76 @BASEBOARD_FAB2_LIB.BASEBOARD_FAB2(SCH_1):PAGE217
     2    GND @BASEBOARD_FAB2_LIB.BASEBOARD_FAB2(SCH_1):GND    I76 @BASEBOARD_FAB2_LIB.BASEBOARD_FAB2(SCH_1):PAGE217

C3U2 CAP_0805-10UF,16V,10%,X6S,C953A
     1 VR_FET_SW_P12V_STBY_PVDDQ_ABC @BASEBOARD_FAB2_LIB.BASEBOARD_FAB2(SCH_1):VR_FET_SW_P12V_STBY_PVDDQ_ABC    I45 @BASEBOARD_FAB2_LIB.BASEBOARD_FAB2(SCH_1):PAGE216
     2    GND @BASEBOARD_FAB2_LIB.BASEBOARD_FAB2(SCH_1):GND    I45 @BASEBOARD_FAB2_LIB.BASEBOARD_FAB2(SCH_1):PAGE216

C3U3 CAP_0805-10UF,16V,10%,X6S,C953A
     1 VR_FET_SW_P12V_STBY_PVDDQ_ABC @BASEBOARD_FAB2_LIB.BASEBOARD_FAB2(SCH_1):VR_FET_SW_P12V_STBY_PVDDQ_ABC    I46 @BASEBOARD_FAB2_LIB.BASEBOARD_FAB2(SCH_1):PAGE216
     2    GND @BASEBOARD_FAB2_LIB.BASEBOARD_FAB2(SCH_1):GND    I46 @BASEBOARD_FAB2_LIB.BASEBOARD_FAB2(SCH_1):PAGE216

C3U4 CAP_0805-10UF,16V,10%,X6S,C953A
     1 VR_FET_SW_P12V_STBY_PVDDQ_ABC @BASEBOARD_FAB2_LIB.BASEBOARD_FAB2(SCH_1):VR_FET_SW_P12V_STBY_PVDDQ_ABC    I47 @BASEBOARD_FAB2_LIB.BASEBOARD_FAB2(SCH_1):PAGE216
     2    GND @BASEBOARD_FAB2_LIB.BASEBOARD_FAB2(SCH_1):GND    I47 @BASEBOARD_FAB2_LIB.BASEBOARD_FAB2(SCH_1):PAGE216

C3U5 CAPP_3018-470UF,2.5V,20%,ALUM,A
     1 PVDDQ_ABC @BASEBOARD_FAB2_LIB.BASEBOARD_FAB2(SCH_1):PVDDQ_ABC    I77 @BASEBOARD_FAB2_LIB.BASEBOARD_FAB2(SCH_1):PAGE217
     2    GND @BASEBOARD_FAB2_LIB.BASEBOARD_FAB2(SCH_1):GND    I77 @BASEBOARD_FAB2_LIB.BASEBOARD_FAB2(SCH_1):PAGE217

C3U6 CAP_0805-10UF,16V,10%,X6S,C953A
     1 VR_FET_SW_P12V_STBY_PVDDQ_ABC @BASEBOARD_FAB2_LIB.BASEBOARD_FAB2(SCH_1):VR_FET_SW_P12V_STBY_PVDDQ_ABC    I84 @BASEBOARD_FAB2_LIB.BASEBOARD_FAB2(SCH_1):PAGE216
     2    GND @BASEBOARD_FAB2_LIB.BASEBOARD_FAB2(SCH_1):GND    I84 @BASEBOARD_FAB2_LIB.BASEBOARD_FAB2(SCH_1):PAGE216

C3U7 CAP_0805-10UF,16V,10%,X6S,C953A
     1 VR_FET_SW_P12V_STBY_PVDDQ_ABC @BASEBOARD_FAB2_LIB.BASEBOARD_FAB2(SCH_1):VR_FET_SW_P12V_STBY_PVDDQ_ABC    I81 @BASEBOARD_FAB2_LIB.BASEBOARD_FAB2(SCH_1):PAGE216
     2    GND @BASEBOARD_FAB2_LIB.BASEBOARD_FAB2(SCH_1):GND    I81 @BASEBOARD_FAB2_LIB.BASEBOARD_FAB2(SCH_1):PAGE216

C3U8 CAPP_3018-470UF,2.5V,20%,ALUM,A
     1 PVDDQ_ABC @BASEBOARD_FAB2_LIB.BASEBOARD_FAB2(SCH_1):PVDDQ_ABC    I78 @BASEBOARD_FAB2_LIB.BASEBOARD_FAB2(SCH_1):PAGE217
     2    GND @BASEBOARD_FAB2_LIB.BASEBOARD_FAB2(SCH_1):GND    I78 @BASEBOARD_FAB2_LIB.BASEBOARD_FAB2(SCH_1):PAGE217

C3U9 CAP_0805-10UF,16V,10%,X6S,C953A
     1 VR_FET_SW_P12V_STBY_PVDDQ_ABC @BASEBOARD_FAB2_LIB.BASEBOARD_FAB2(SCH_1):VR_FET_SW_P12V_STBY_PVDDQ_ABC    I80 @BASEBOARD_FAB2_LIB.BASEBOARD_FAB2(SCH_1):PAGE216
     2    GND @BASEBOARD_FAB2_LIB.BASEBOARD_FAB2(SCH_1):GND    I80 @BASEBOARD_FAB2_LIB.BASEBOARD_FAB2(SCH_1):PAGE216

C3W1 CAP_0402-1.0UF,6.3V,10%,EMPTY,A
     1 A_PCH_XCLK_BIASREF @BASEBOARD_FAB2_LIB.BASEBOARD_FAB2(SCH_1):A_PCH_XCLK_BIASREF   I193 @BASEBOARD_FAB2_LIB.BASEBOARD_FAB2(SCH_1):PAGE114
     2    GND @BASEBOARD_FAB2_LIB.BASEBOARD_FAB2(SCH_1):GND   I193 @BASEBOARD_FAB2_LIB.BASEBOARD_FAB2(SCH_1):PAGE114

C3W2 CAP_A_0402V-0.1UF,16V,10%,X7R,A
     1 BMC_TPM_HW_C_RST @BASEBOARD_FAB2_LIB.BASEBOARD_FAB2(SCH_1):BMC_TPM_HW_C_RST    I57 @BASEBOARD_FAB2_LIB.BASEBOARD_FAB2(SCH_1):PAGE249
     2    GND @BASEBOARD_FAB2_LIB.BASEBOARD_FAB2(SCH_1):GND    I57 @BASEBOARD_FAB2_LIB.BASEBOARD_FAB2(SCH_1):PAGE249

C3W3 CAP_A_0603V-22.0UF,4V,20%,X6S,A
     1 PVCCMCP_CPU1 @BASEBOARD_FAB2_LIB.BASEBOARD_FAB2(SCH_1):PVCCMCP_CPU1   I256 @BASEBOARD_FAB2_LIB.BASEBOARD_FAB2(SCH_1):PAGE76
     2    GND @BASEBOARD_FAB2_LIB.BASEBOARD_FAB2(SCH_1):GND   I256 @BASEBOARD_FAB2_LIB.BASEBOARD_FAB2(SCH_1):PAGE76

C3W4 CAP_A_0603V-22.0UF,4V,20%,X6S,A
     1 PVCCMCP_CPU1 @BASEBOARD_FAB2_LIB.BASEBOARD_FAB2(SCH_1):PVCCMCP_CPU1   I254 @BASEBOARD_FAB2_LIB.BASEBOARD_FAB2(SCH_1):PAGE76
     2    GND @BASEBOARD_FAB2_LIB.BASEBOARD_FAB2(SCH_1):GND   I254 @BASEBOARD_FAB2_LIB.BASEBOARD_FAB2(SCH_1):PAGE76

C4A1 CAP_0805LF-22UF,4V,20%,X6S,C95A
     1 PVTT_DEF @BASEBOARD_FAB2_LIB.BASEBOARD_FAB2(SCH_1):PVTT_DEF    I28 @BASEBOARD_FAB2_LIB.BASEBOARD_FAB2(SCH_1):PAGE222
     2    GND @BASEBOARD_FAB2_LIB.BASEBOARD_FAB2(SCH_1):GND    I28 @BASEBOARD_FAB2_LIB.BASEBOARD_FAB2(SCH_1):PAGE222

C4A2 CAP_0402LF-1000PF,50V,10%,EMPTA
     1 FM_PVTT_DEF_EN_R @BASEBOARD_FAB2_LIB.BASEBOARD_FAB2(SCH_1):FM_PVTT_DEF_EN_R     I2 @BASEBOARD_FAB2_LIB.BASEBOARD_FAB2(SCH_1):PAGE222
     2    GND @BASEBOARD_FAB2_LIB.BASEBOARD_FAB2(SCH_1):GND     I2 @BASEBOARD_FAB2_LIB.BASEBOARD_FAB2(SCH_1):PAGE222

C4A3 CAP_0402LF-1000PF,50V,10%,X7R,A
     1 PWRGD_PVTT_KLM_CPU1_R @BASEBOARD_FAB2_LIB.BASEBOARD_FAB2(SCH_1):PWRGD_PVTT_KLM_CPU1_R    I23 @BASEBOARD_FAB2_LIB.BASEBOARD_FAB2(SCH_1):PAGE230
     2    GND @BASEBOARD_FAB2_LIB.BASEBOARD_FAB2(SCH_1):GND    I23 @BASEBOARD_FAB2_LIB.BASEBOARD_FAB2(SCH_1):PAGE230

C4A4 CAP_0805-10UF,16V,10%,X7R,G106A
     1 P12V_NVDIMM_DEF @BASEBOARD_FAB2_LIB.BASEBOARD_FAB2(SCH_1):P12V_NVDIMM_DEF    I81 @BASEBOARD_FAB2_LIB.BASEBOARD_FAB2(SCH_1):PAGE197
     2    GND @BASEBOARD_FAB2_LIB.BASEBOARD_FAB2(SCH_1):GND    I81 @BASEBOARD_FAB2_LIB.BASEBOARD_FAB2(SCH_1):PAGE197

C4A5 CAP_A_0402V-0.01UF,25V,10%,X7RA
     1 M_F_VREF @BASEBOARD_FAB2_LIB.BASEBOARD_FAB2(SCH_1):M_F_VREF   I179 @BASEBOARD_FAB2_LIB.BASEBOARD_FAB2(SCH_1):PAGE54
     2    GND @BASEBOARD_FAB2_LIB.BASEBOARD_FAB2(SCH_1):GND   I179 @BASEBOARD_FAB2_LIB.BASEBOARD_FAB2(SCH_1):PAGE54

C4A6 CAP_0402LF-1000PF,50V,10%,EMPTA
     1 FM_PVTT_KLM_EN_R @BASEBOARD_FAB2_LIB.BASEBOARD_FAB2(SCH_1):FM_PVTT_KLM_EN_R     I2 @BASEBOARD_FAB2_LIB.BASEBOARD_FAB2(SCH_1):PAGE230
     2    GND @BASEBOARD_FAB2_LIB.BASEBOARD_FAB2(SCH_1):GND     I2 @BASEBOARD_FAB2_LIB.BASEBOARD_FAB2(SCH_1):PAGE230

C4A7 CAP_0603-4.7UF,6.3V,10%,X6S,E1A
     1 VSENSE_PVDDQ_KLM_VTT @BASEBOARD_FAB2_LIB.BASEBOARD_FAB2(SCH_1):VSENSE_PVDDQ_KLM_VTT    I10 @BASEBOARD_FAB2_LIB.BASEBOARD_FAB2(SCH_1):PAGE230
     2    GND @BASEBOARD_FAB2_LIB.BASEBOARD_FAB2(SCH_1):GND    I10 @BASEBOARD_FAB2_LIB.BASEBOARD_FAB2(SCH_1):PAGE230

C4A8 CAP_0402-1.0UF,16V,10%,X6S,D97A
     1 VR_PVTT_KLM_BIAS @BASEBOARD_FAB2_LIB.BASEBOARD_FAB2(SCH_1):VR_PVTT_KLM_BIAS    I12 @BASEBOARD_FAB2_LIB.BASEBOARD_FAB2(SCH_1):PAGE230
     2    GND @BASEBOARD_FAB2_LIB.BASEBOARD_FAB2(SCH_1):GND    I12 @BASEBOARD_FAB2_LIB.BASEBOARD_FAB2(SCH_1):PAGE230

C4A9 CAP_0402-1.0UF,16V,10%,X6S,D97A
     1 VR_PVTT_DEF_VREF @BASEBOARD_FAB2_LIB.BASEBOARD_FAB2(SCH_1):VR_PVTT_DEF_VREF    I20 @BASEBOARD_FAB2_LIB.BASEBOARD_FAB2(SCH_1):PAGE222
     2    GND @BASEBOARD_FAB2_LIB.BASEBOARD_FAB2(SCH_1):GND    I20 @BASEBOARD_FAB2_LIB.BASEBOARD_FAB2(SCH_1):PAGE222

C4A10 CAP_0402-1.0UF,16V,10%,X6S,D97A
     1 VR_PVTT_DEF_BIAS @BASEBOARD_FAB2_LIB.BASEBOARD_FAB2(SCH_1):VR_PVTT_DEF_BIAS    I12 @BASEBOARD_FAB2_LIB.BASEBOARD_FAB2(SCH_1):PAGE222
     2    GND @BASEBOARD_FAB2_LIB.BASEBOARD_FAB2(SCH_1):GND    I12 @BASEBOARD_FAB2_LIB.BASEBOARD_FAB2(SCH_1):PAGE222

C4A11 CAP_0603-4.7UF,6.3V,10%,X6S,E1A
     1 VSENSE_PVDDQ_DEF_VTT @BASEBOARD_FAB2_LIB.BASEBOARD_FAB2(SCH_1):VSENSE_PVDDQ_DEF_VTT     I9 @BASEBOARD_FAB2_LIB.BASEBOARD_FAB2(SCH_1):PAGE222
     2    GND @BASEBOARD_FAB2_LIB.BASEBOARD_FAB2(SCH_1):GND     I9 @BASEBOARD_FAB2_LIB.BASEBOARD_FAB2(SCH_1):PAGE222

C4A12 CAP_0402LF-1000PF,50V,10%,X7R,A
     1 PWRGD_PVTT_DEF_CPU0_R @BASEBOARD_FAB2_LIB.BASEBOARD_FAB2(SCH_1):PWRGD_PVTT_DEF_CPU0_R    I22 @BASEBOARD_FAB2_LIB.BASEBOARD_FAB2(SCH_1):PAGE222
     2    GND @BASEBOARD_FAB2_LIB.BASEBOARD_FAB2(SCH_1):GND    I22 @BASEBOARD_FAB2_LIB.BASEBOARD_FAB2(SCH_1):PAGE222

C4A13 CAP_0805LF-22UF,4V,20%,X6S,C95A
     1 PVTT_KLM @BASEBOARD_FAB2_LIB.BASEBOARD_FAB2(SCH_1):PVTT_KLM    I20 @BASEBOARD_FAB2_LIB.BASEBOARD_FAB2(SCH_1):PAGE230
     2    GND @BASEBOARD_FAB2_LIB.BASEBOARD_FAB2(SCH_1):GND    I20 @BASEBOARD_FAB2_LIB.BASEBOARD_FAB2(SCH_1):PAGE230

C4A14 CAP_0402-1.0UF,16V,10%,X6S,D97A
     1 VR_PVTT_KLM_VREF @BASEBOARD_FAB2_LIB.BASEBOARD_FAB2(SCH_1):VR_PVTT_KLM_VREF    I36 @BASEBOARD_FAB2_LIB.BASEBOARD_FAB2(SCH_1):PAGE230
     2    GND @BASEBOARD_FAB2_LIB.BASEBOARD_FAB2(SCH_1):GND    I36 @BASEBOARD_FAB2_LIB.BASEBOARD_FAB2(SCH_1):PAGE230

C4A15 CAP_0603LF-10UF,4V,20%,X6S,E15A
     1 PVDDQ_KLM @BASEBOARD_FAB2_LIB.BASEBOARD_FAB2(SCH_1):PVDDQ_KLM    I17 @BASEBOARD_FAB2_LIB.BASEBOARD_FAB2(SCH_1):PAGE230
     2    GND @BASEBOARD_FAB2_LIB.BASEBOARD_FAB2(SCH_1):GND    I17 @BASEBOARD_FAB2_LIB.BASEBOARD_FAB2(SCH_1):PAGE230

C4A16 CAP_0402LF-3300PF,50V,10%,EMPTA
     1 VR_PVPP_KLM_PHASE @BASEBOARD_FAB2_LIB.BASEBOARD_FAB2(SCH_1):VR_PVPP_KLM_PHASE   I163 @BASEBOARD_FAB2_LIB.BASEBOARD_FAB2(SCH_1):PAGE234
     2 VR_PVPP_KLM_SNUB @BASEBOARD_FAB2_LIB.BASEBOARD_FAB2(SCH_1):VR_PVPP_KLM_SNUB   I163 @BASEBOARD_FAB2_LIB.BASEBOARD_FAB2(SCH_1):PAGE234

C4A17 CAP_0805-10UF,16V,10%,X7R,G106A
     1 P12V_NVDIMM_DEF @BASEBOARD_FAB2_LIB.BASEBOARD_FAB2(SCH_1):P12V_NVDIMM_DEF    I88 @BASEBOARD_FAB2_LIB.BASEBOARD_FAB2(SCH_1):PAGE197
     2    GND @BASEBOARD_FAB2_LIB.BASEBOARD_FAB2(SCH_1):GND    I88 @BASEBOARD_FAB2_LIB.BASEBOARD_FAB2(SCH_1):PAGE197

C4A18 CAP_A_0402V-0.01UF,25V,10%,X7RA
     1 M_E_VREF @BASEBOARD_FAB2_LIB.BASEBOARD_FAB2(SCH_1):M_E_VREF     I3 @BASEBOARD_FAB2_LIB.BASEBOARD_FAB2(SCH_1):PAGE52
     2    GND @BASEBOARD_FAB2_LIB.BASEBOARD_FAB2(SCH_1):GND     I3 @BASEBOARD_FAB2_LIB.BASEBOARD_FAB2(SCH_1):PAGE52

C4A19 CAP_0805-10UF,16V,10%,X6S,C953A
     1 VR_FET_SW_P12V_STBY_PVPP_KLM @BASEBOARD_FAB2_LIB.BASEBOARD_FAB2(SCH_1):VR_FET_SW_P12V_STBY_PVPP_KLM   I205 @BASEBOARD_FAB2_LIB.BASEBOARD_FAB2(SCH_1):PAGE234
     2    GND @BASEBOARD_FAB2_LIB.BASEBOARD_FAB2(SCH_1):GND   I205 @BASEBOARD_FAB2_LIB.BASEBOARD_FAB2(SCH_1):PAGE234

C4A20 CAP_A_0402V-0.1UF,16V,10%,X7R,A
     1 VR_FET_SW_P12V_STBY_PVPP_KLM @BASEBOARD_FAB2_LIB.BASEBOARD_FAB2(SCH_1):VR_FET_SW_P12V_STBY_PVPP_KLM   I199 @BASEBOARD_FAB2_LIB.BASEBOARD_FAB2(SCH_1):PAGE234
     2    GND @BASEBOARD_FAB2_LIB.BASEBOARD_FAB2(SCH_1):GND   I199 @BASEBOARD_FAB2_LIB.BASEBOARD_FAB2(SCH_1):PAGE234

C4B1 SC22U16V5MX-4-GP_SMD-BCG5-SC22A
     1 VR_FET_SW_P12V_STBY_PVPP_KLM @BASEBOARD_FAB2_LIB.BASEBOARD_FAB2(SCH_1):VR_FET_SW_P12V_STBY_PVPP_KLM   I223 @BASEBOARD_FAB2_LIB.BASEBOARD_FAB2(SCH_1):PAGE234
     2    GND @BASEBOARD_FAB2_LIB.BASEBOARD_FAB2(SCH_1):GND   I223 @BASEBOARD_FAB2_LIB.BASEBOARD_FAB2(SCH_1):PAGE234

C4B2 CAP_0805-47UF,4V,20%,X6S,C9533A
     1 PVPP_KLM @BASEBOARD_FAB2_LIB.BASEBOARD_FAB2(SCH_1):PVPP_KLM   I180 @BASEBOARD_FAB2_LIB.BASEBOARD_FAB2(SCH_1):PAGE234
     2    GND @BASEBOARD_FAB2_LIB.BASEBOARD_FAB2(SCH_1):GND   I180 @BASEBOARD_FAB2_LIB.BASEBOARD_FAB2(SCH_1):PAGE234

C4B3 CAP_0805-47UF,4V,20%,X6S,C9533A
     1 PVPP_KLM @BASEBOARD_FAB2_LIB.BASEBOARD_FAB2(SCH_1):PVPP_KLM   I177 @BASEBOARD_FAB2_LIB.BASEBOARD_FAB2(SCH_1):PAGE234
     2    GND @BASEBOARD_FAB2_LIB.BASEBOARD_FAB2(SCH_1):GND   I177 @BASEBOARD_FAB2_LIB.BASEBOARD_FAB2(SCH_1):PAGE234

C4B4 CAP_0402LF-100.0PF,50V,5%,COG,A
     1 VR_FB_PVPP_KLM @BASEBOARD_FAB2_LIB.BASEBOARD_FAB2(SCH_1):VR_FB_PVPP_KLM   I212 @BASEBOARD_FAB2_LIB.BASEBOARD_FAB2(SCH_1):PAGE234
     2 VR_COMP_PVPP_KLM_3 @BASEBOARD_FAB2_LIB.BASEBOARD_FAB2(SCH_1):VR_COMP_PVPP_KLM_3   I212 @BASEBOARD_FAB2_LIB.BASEBOARD_FAB2(SCH_1):PAGE234

C4B5 CAP_0402LF-1000PF,50V,10%,EMPTA
     1 FM_PVPP_CPU1_EN @BASEBOARD_FAB2_LIB.BASEBOARD_FAB2(SCH_1):FM_PVPP_CPU1_EN   I129 @BASEBOARD_FAB2_LIB.BASEBOARD_FAB2(SCH_1):PAGE234
     2 AGND_PVPP_KLM @BASEBOARD_FAB2_LIB.BASEBOARD_FAB2(SCH_1):AGND_PVPP_KLM   I129 @BASEBOARD_FAB2_LIB.BASEBOARD_FAB2(SCH_1):PAGE234

C4B6 CAP_0402-0.027UF,16V,10%,X7R,AA
     1 VR_PVPP_KLM_SS @BASEBOARD_FAB2_LIB.BASEBOARD_FAB2(SCH_1):VR_PVPP_KLM_SS   I146 @BASEBOARD_FAB2_LIB.BASEBOARD_FAB2(SCH_1):PAGE234
     2 AGND_PVPP_KLM @BASEBOARD_FAB2_LIB.BASEBOARD_FAB2(SCH_1):AGND_PVPP_KLM   I146 @BASEBOARD_FAB2_LIB.BASEBOARD_FAB2(SCH_1):PAGE234

C4B7 CAP_0402LF-2200PF,50V,10%,X7R,A
     1 VR_COMP_PVPP_KLM @BASEBOARD_FAB2_LIB.BASEBOARD_FAB2(SCH_1):VR_COMP_PVPP_KLM   I218 @BASEBOARD_FAB2_LIB.BASEBOARD_FAB2(SCH_1):PAGE234
     2 VR_FB_PVPP_KLM @BASEBOARD_FAB2_LIB.BASEBOARD_FAB2(SCH_1):VR_FB_PVPP_KLM   I218 @BASEBOARD_FAB2_LIB.BASEBOARD_FAB2(SCH_1):PAGE234

C4B8 CAP_0402LF-1000PF,50V,10%,X7R,A
     1 PWRGD_PVPP_KLM_R @BASEBOARD_FAB2_LIB.BASEBOARD_FAB2(SCH_1):PWRGD_PVPP_KLM_R   I139 @BASEBOARD_FAB2_LIB.BASEBOARD_FAB2(SCH_1):PAGE234
     2    GND @BASEBOARD_FAB2_LIB.BASEBOARD_FAB2(SCH_1):GND   I139 @BASEBOARD_FAB2_LIB.BASEBOARD_FAB2(SCH_1):PAGE234

C4B9 CAP_0402LF-2200PF,50V,10%,X7R,A
     1 VR_COMP_RC_PVPP_KLM @BASEBOARD_FAB2_LIB.BASEBOARD_FAB2(SCH_1):VR_COMP_RC_PVPP_KLM   I211 @BASEBOARD_FAB2_LIB.BASEBOARD_FAB2(SCH_1):PAGE234
     2 VR_COMP_PVPP_KLM_3 @BASEBOARD_FAB2_LIB.BASEBOARD_FAB2(SCH_1):VR_COMP_PVPP_KLM_3   I211 @BASEBOARD_FAB2_LIB.BASEBOARD_FAB2(SCH_1):PAGE234

C4B11 CAP_0805-10UF,16V,10%,X7R,G106A
     1 P12V_NVDIMM_DEF @BASEBOARD_FAB2_LIB.BASEBOARD_FAB2(SCH_1):P12V_NVDIMM_DEF    I78 @BASEBOARD_FAB2_LIB.BASEBOARD_FAB2(SCH_1):PAGE197
     2    GND @BASEBOARD_FAB2_LIB.BASEBOARD_FAB2(SCH_1):GND    I78 @BASEBOARD_FAB2_LIB.BASEBOARD_FAB2(SCH_1):PAGE197

C4B12 CAP_A_0402V-0.01UF,25V,10%,X7RA
     1 M_D_VREF @BASEBOARD_FAB2_LIB.BASEBOARD_FAB2(SCH_1):M_D_VREF   I179 @BASEBOARD_FAB2_LIB.BASEBOARD_FAB2(SCH_1):PAGE49
     2    GND @BASEBOARD_FAB2_LIB.BASEBOARD_FAB2(SCH_1):GND   I179 @BASEBOARD_FAB2_LIB.BASEBOARD_FAB2(SCH_1):PAGE49

C4B13 CAPP_4040LF-470UF,16V,20%,ALUMA
     1 P12V_STBY @BASEBOARD_FAB2_LIB.BASEBOARD_FAB2(SCH_1):P12V_STBY    I83 @BASEBOARD_FAB2_LIB.BASEBOARD_FAB2(SCH_1):PAGE195
     2    GND @BASEBOARD_FAB2_LIB.BASEBOARD_FAB2(SCH_1):GND    I83 @BASEBOARD_FAB2_LIB.BASEBOARD_FAB2(SCH_1):PAGE195

C4B14 CAPP_3018-68UF,16V,20%,TANT,72A
     1 P12V_STBY @BASEBOARD_FAB2_LIB.BASEBOARD_FAB2(SCH_1):P12V_STBY    I97 @BASEBOARD_FAB2_LIB.BASEBOARD_FAB2(SCH_1):PAGE195
     2    GND @BASEBOARD_FAB2_LIB.BASEBOARD_FAB2(SCH_1):GND    I97 @BASEBOARD_FAB2_LIB.BASEBOARD_FAB2(SCH_1):PAGE195

C4B15 CAP_0603LF-0.1UF,25V,10%,X7R,6A
     1 VR_PVPP_KLM_PHASE @BASEBOARD_FAB2_LIB.BASEBOARD_FAB2(SCH_1):VR_PVPP_KLM_PHASE   I182 @BASEBOARD_FAB2_LIB.BASEBOARD_FAB2(SCH_1):PAGE234
     2 VR_PVPP_KLM_BOOT_R @BASEBOARD_FAB2_LIB.BASEBOARD_FAB2(SCH_1):VR_PVPP_KLM_BOOT_R   I182 @BASEBOARD_FAB2_LIB.BASEBOARD_FAB2(SCH_1):PAGE234

C4C1 CAPP_3018-470UF,2.5V,20%,ALUM,A
     1 PVCCIOMCP_CPU1 @BASEBOARD_FAB2_LIB.BASEBOARD_FAB2(SCH_1):PVCCIOMCP_CPU1    I29 @BASEBOARD_FAB2_LIB.BASEBOARD_FAB2(SCH_1):PAGE193
     2    GND @BASEBOARD_FAB2_LIB.BASEBOARD_FAB2(SCH_1):GND    I29 @BASEBOARD_FAB2_LIB.BASEBOARD_FAB2(SCH_1):PAGE193

C4C3 CAP_A_0402V-1.0UF,6.3V,10%,X6SA
     1 P3V3_STBY @BASEBOARD_FAB2_LIB.BASEBOARD_FAB2(SCH_1):P3V3_STBY    I75 @BASEBOARD_FAB2_LIB.BASEBOARD_FAB2(SCH_1):PAGE96
     2    GND @BASEBOARD_FAB2_LIB.BASEBOARD_FAB2(SCH_1):GND    I75 @BASEBOARD_FAB2_LIB.BASEBOARD_FAB2(SCH_1):PAGE96

C4C4 SC1U10V2KX-4-GP_SMD-BCG6-SC1U1A
     1 P5V_STBY @BASEBOARD_FAB2_LIB.BASEBOARD_FAB2(SCH_1):P5V_STBY    I83 @BASEBOARD_FAB2_LIB.BASEBOARD_FAB2(SCH_1):PAGE205
     2    GND @BASEBOARD_FAB2_LIB.BASEBOARD_FAB2(SCH_1):GND    I83 @BASEBOARD_FAB2_LIB.BASEBOARD_FAB2(SCH_1):PAGE205

C4C5 CAP_0402-0.22UF,16V,10%,X7R,A3A
     1 P5V_STBY @BASEBOARD_FAB2_LIB.BASEBOARD_FAB2(SCH_1):P5V_STBY    I16 @BASEBOARD_FAB2_LIB.BASEBOARD_FAB2(SCH_1):PAGE205
     2    GND @BASEBOARD_FAB2_LIB.BASEBOARD_FAB2(SCH_1):GND    I16 @BASEBOARD_FAB2_LIB.BASEBOARD_FAB2(SCH_1):PAGE205

C4C6 CAP_0402-1.0UF,16V,10%,X6S,D97A
     1 VR_PVSA_CPU0_VCIN @BASEBOARD_FAB2_LIB.BASEBOARD_FAB2(SCH_1):VR_PVSA_CPU0_VCIN    I20 @BASEBOARD_FAB2_LIB.BASEBOARD_FAB2(SCH_1):PAGE205
     2    GND @BASEBOARD_FAB2_LIB.BASEBOARD_FAB2(SCH_1):GND    I20 @BASEBOARD_FAB2_LIB.BASEBOARD_FAB2(SCH_1):PAGE205

C4C8 CAP_0402-0.220UF,16V,10%,X7R,AA
     1 VR_PVSA_CPU0_BOOT @BASEBOARD_FAB2_LIB.BASEBOARD_FAB2(SCH_1):VR_PVSA_CPU0_BOOT    I25 @BASEBOARD_FAB2_LIB.BASEBOARD_FAB2(SCH_1):PAGE205
     2 VR_PVSA_CPU0_PHASE @BASEBOARD_FAB2_LIB.BASEBOARD_FAB2(SCH_1):VR_PVSA_CPU0_PHASE    I25 @BASEBOARD_FAB2_LIB.BASEBOARD_FAB2(SCH_1):PAGE205

C4C9 CAP_0402-1.0UF,16V,10%,X6S,D97A
     1 VR_FET_SW_P12V_STBY_PVCCIN_CPU0 @BASEBOARD_FAB2_LIB.BASEBOARD_FAB2(SCH_1):VR_FET_SW_P12V_STBY_PVCCIN_CPU0    I32 @BASEBOARD_FAB2_LIB.BASEBOARD_FAB2(SCH_1):PAGE205
     2    GND @BASEBOARD_FAB2_LIB.BASEBOARD_FAB2(SCH_1):GND    I32 @BASEBOARD_FAB2_LIB.BASEBOARD_FAB2(SCH_1):PAGE205

C4C10 CAP_A_0402V-0.1UF,16V,10%,X7R,A
     1 VR_FET_SW_P12V_STBY_PVCCIN_CPU0 @BASEBOARD_FAB2_LIB.BASEBOARD_FAB2(SCH_1):VR_FET_SW_P12V_STBY_PVCCIN_CPU0    I31 @BASEBOARD_FAB2_LIB.BASEBOARD_FAB2(SCH_1):PAGE205
     2    GND @BASEBOARD_FAB2_LIB.BASEBOARD_FAB2(SCH_1):GND    I31 @BASEBOARD_FAB2_LIB.BASEBOARD_FAB2(SCH_1):PAGE205

C4C11 CAP_A_0603V-22.0UF,4V,20%,X6S,A
     1 PVSA_CPU0 @BASEBOARD_FAB2_LIB.BASEBOARD_FAB2(SCH_1):PVSA_CPU0    I43 @BASEBOARD_FAB2_LIB.BASEBOARD_FAB2(SCH_1):PAGE205
     2    GND @BASEBOARD_FAB2_LIB.BASEBOARD_FAB2(SCH_1):GND    I43 @BASEBOARD_FAB2_LIB.BASEBOARD_FAB2(SCH_1):PAGE205

C4C12 CAPP_2626-270UF,16V,20%,OSCON,A
     1 VR_FET_SW_P12V_STBY_PVCCIN_CPU0 @BASEBOARD_FAB2_LIB.BASEBOARD_FAB2(SCH_1):VR_FET_SW_P12V_STBY_PVCCIN_CPU0    I67 @BASEBOARD_FAB2_LIB.BASEBOARD_FAB2(SCH_1):PAGE204
     2    GND @BASEBOARD_FAB2_LIB.BASEBOARD_FAB2(SCH_1):GND    I67 @BASEBOARD_FAB2_LIB.BASEBOARD_FAB2(SCH_1):PAGE204

C4C14 SC1U10V2KX-4-GP_SMD-BCG6-SC1U1A
     1 P5V_STBY @BASEBOARD_FAB2_LIB.BASEBOARD_FAB2(SCH_1):P5V_STBY   I113 @BASEBOARD_FAB2_LIB.BASEBOARD_FAB2(SCH_1):PAGE204
     2    GND @BASEBOARD_FAB2_LIB.BASEBOARD_FAB2(SCH_1):GND   I113 @BASEBOARD_FAB2_LIB.BASEBOARD_FAB2(SCH_1):PAGE204

C4C17 CAP_0402-0.220UF,16V,10%,X7R,AA
     1 VR_PVCCIN_CPU0_PH5_BOOT @BASEBOARD_FAB2_LIB.BASEBOARD_FAB2(SCH_1):VR_PVCCIN_CPU0_PH5_BOOT    I22 @BASEBOARD_FAB2_LIB.BASEBOARD_FAB2(SCH_1):PAGE204
     2 VR_PVCCIN_CPU0_PH5_PHASE @BASEBOARD_FAB2_LIB.BASEBOARD_FAB2(SCH_1):VR_PVCCIN_CPU0_PH5_PHASE    I22 @BASEBOARD_FAB2_LIB.BASEBOARD_FAB2(SCH_1):PAGE204

C4C18 CAP_0402-1.0UF,16V,10%,X6S,D97A
     1 VR_FET_SW_P12V_STBY_PVCCIN_CPU0 @BASEBOARD_FAB2_LIB.BASEBOARD_FAB2(SCH_1):VR_FET_SW_P12V_STBY_PVCCIN_CPU0    I36 @BASEBOARD_FAB2_LIB.BASEBOARD_FAB2(SCH_1):PAGE204
     2    GND @BASEBOARD_FAB2_LIB.BASEBOARD_FAB2(SCH_1):GND    I36 @BASEBOARD_FAB2_LIB.BASEBOARD_FAB2(SCH_1):PAGE204

C4C19 CAP_A_0402V-0.1UF,16V,10%,X7R,A
     1 VR_FET_SW_P12V_STBY_PVCCIN_CPU0 @BASEBOARD_FAB2_LIB.BASEBOARD_FAB2(SCH_1):VR_FET_SW_P12V_STBY_PVCCIN_CPU0    I35 @BASEBOARD_FAB2_LIB.BASEBOARD_FAB2(SCH_1):PAGE204
     2    GND @BASEBOARD_FAB2_LIB.BASEBOARD_FAB2(SCH_1):GND    I35 @BASEBOARD_FAB2_LIB.BASEBOARD_FAB2(SCH_1):PAGE204

C4D2 CAPP_2626-270UF,16V,20%,OSCON,A
     1 VR_FET_SW_P12V_STBY_PVCCIN_CPU0 @BASEBOARD_FAB2_LIB.BASEBOARD_FAB2(SCH_1):VR_FET_SW_P12V_STBY_PVCCIN_CPU0    I48 @BASEBOARD_FAB2_LIB.BASEBOARD_FAB2(SCH_1):PAGE204
     2    GND @BASEBOARD_FAB2_LIB.BASEBOARD_FAB2(SCH_1):GND    I48 @BASEBOARD_FAB2_LIB.BASEBOARD_FAB2(SCH_1):PAGE204

C4D4 CAP_A_0603V-22.0UF,4V,20%,X6S,A
     1 PVCCIN_CPU0 @BASEBOARD_FAB2_LIB.BASEBOARD_FAB2(SCH_1):PVCCIN_CPU0    I69 @BASEBOARD_FAB2_LIB.BASEBOARD_FAB2(SCH_1):PAGE203
     2    GND @BASEBOARD_FAB2_LIB.BASEBOARD_FAB2(SCH_1):GND    I69 @BASEBOARD_FAB2_LIB.BASEBOARD_FAB2(SCH_1):PAGE203

C4D5 CAP_0402-0.22UF,16V,10%,X7R,A3A
     1 P5V_STBY @BASEBOARD_FAB2_LIB.BASEBOARD_FAB2(SCH_1):P5V_STBY    I48 @BASEBOARD_FAB2_LIB.BASEBOARD_FAB2(SCH_1):PAGE203
     2    GND @BASEBOARD_FAB2_LIB.BASEBOARD_FAB2(SCH_1):GND    I48 @BASEBOARD_FAB2_LIB.BASEBOARD_FAB2(SCH_1):PAGE203

C4D6 SC1U10V2KX-4-GP_SMD-BCG6-SC1U1A
     1 P5V_STBY @BASEBOARD_FAB2_LIB.BASEBOARD_FAB2(SCH_1):P5V_STBY   I133 @BASEBOARD_FAB2_LIB.BASEBOARD_FAB2(SCH_1):PAGE203
     2    GND @BASEBOARD_FAB2_LIB.BASEBOARD_FAB2(SCH_1):GND   I133 @BASEBOARD_FAB2_LIB.BASEBOARD_FAB2(SCH_1):PAGE203

C4D7 CAP_0402-1.0UF,16V,10%,X6S,D97A
     1 VR_PVCCIN_CPU0_PH4_VCIN @BASEBOARD_FAB2_LIB.BASEBOARD_FAB2(SCH_1):VR_PVCCIN_CPU0_PH4_VCIN    I51 @BASEBOARD_FAB2_LIB.BASEBOARD_FAB2(SCH_1):PAGE203
     2    GND @BASEBOARD_FAB2_LIB.BASEBOARD_FAB2(SCH_1):GND    I51 @BASEBOARD_FAB2_LIB.BASEBOARD_FAB2(SCH_1):PAGE203

C4D9 CAP_0402-0.220UF,16V,10%,X7R,AA
     1 VR_PVCCIN_CPU0_PH4_BOOT @BASEBOARD_FAB2_LIB.BASEBOARD_FAB2(SCH_1):VR_PVCCIN_CPU0_PH4_BOOT     I3 @BASEBOARD_FAB2_LIB.BASEBOARD_FAB2(SCH_1):PAGE203
     2 VR_PVCCIN_CPU0_PH4_PHASE @BASEBOARD_FAB2_LIB.BASEBOARD_FAB2(SCH_1):VR_PVCCIN_CPU0_PH4_PHASE     I3 @BASEBOARD_FAB2_LIB.BASEBOARD_FAB2(SCH_1):PAGE203

C4D10 CAP_0402-1.0UF,16V,10%,X6S,D97A
     1 VR_FET_SW_P12V_STBY_PVCCIN_CPU0 @BASEBOARD_FAB2_LIB.BASEBOARD_FAB2(SCH_1):VR_FET_SW_P12V_STBY_PVCCIN_CPU0    I53 @BASEBOARD_FAB2_LIB.BASEBOARD_FAB2(SCH_1):PAGE203
     2    GND @BASEBOARD_FAB2_LIB.BASEBOARD_FAB2(SCH_1):GND    I53 @BASEBOARD_FAB2_LIB.BASEBOARD_FAB2(SCH_1):PAGE203

C4D11 CAP_A_0402V-0.1UF,16V,10%,X7R,A
     1 VR_FET_SW_P12V_STBY_PVCCIN_CPU0 @BASEBOARD_FAB2_LIB.BASEBOARD_FAB2(SCH_1):VR_FET_SW_P12V_STBY_PVCCIN_CPU0    I52 @BASEBOARD_FAB2_LIB.BASEBOARD_FAB2(SCH_1):PAGE203
     2    GND @BASEBOARD_FAB2_LIB.BASEBOARD_FAB2(SCH_1):GND    I52 @BASEBOARD_FAB2_LIB.BASEBOARD_FAB2(SCH_1):PAGE203

C4D12 CAP_A_0603V-22.0UF,4V,20%,X6S,A
     1 PVCCIN_CPU0 @BASEBOARD_FAB2_LIB.BASEBOARD_FAB2(SCH_1):PVCCIN_CPU0     I9 @BASEBOARD_FAB2_LIB.BASEBOARD_FAB2(SCH_1):PAGE204
     2    GND @BASEBOARD_FAB2_LIB.BASEBOARD_FAB2(SCH_1):GND     I9 @BASEBOARD_FAB2_LIB.BASEBOARD_FAB2(SCH_1):PAGE204

C4D13 CAP_0402-0.22UF,16V,10%,X7R,A3A
     1 P5V_STBY @BASEBOARD_FAB2_LIB.BASEBOARD_FAB2(SCH_1):P5V_STBY    I40 @BASEBOARD_FAB2_LIB.BASEBOARD_FAB2(SCH_1):PAGE203
     2    GND @BASEBOARD_FAB2_LIB.BASEBOARD_FAB2(SCH_1):GND    I40 @BASEBOARD_FAB2_LIB.BASEBOARD_FAB2(SCH_1):PAGE203

C4D14 SC1U10V2KX-4-GP_SMD-BCG6-SC1U1A
     1 P5V_STBY @BASEBOARD_FAB2_LIB.BASEBOARD_FAB2(SCH_1):P5V_STBY   I132 @BASEBOARD_FAB2_LIB.BASEBOARD_FAB2(SCH_1):PAGE203
     2    GND @BASEBOARD_FAB2_LIB.BASEBOARD_FAB2(SCH_1):GND   I132 @BASEBOARD_FAB2_LIB.BASEBOARD_FAB2(SCH_1):PAGE203

C4D15 CAP_A_0402V-1.0UF,6.3V,10%,X6SA
     1 VR_PVCCIN_CPU0_VDD @BASEBOARD_FAB2_LIB.BASEBOARD_FAB2(SCH_1):VR_PVCCIN_CPU0_VDD    I37 @BASEBOARD_FAB2_LIB.BASEBOARD_FAB2(SCH_1):PAGE201
     2    GND @BASEBOARD_FAB2_LIB.BASEBOARD_FAB2(SCH_1):GND    I37 @BASEBOARD_FAB2_LIB.BASEBOARD_FAB2(SCH_1):PAGE201

C4D16 CAP_0402-1.0UF,16V,10%,X6S,D97A
     1 VR_PVCCIN_CPU0_PH3_VCIN @BASEBOARD_FAB2_LIB.BASEBOARD_FAB2(SCH_1):VR_PVCCIN_CPU0_PH3_VCIN    I45 @BASEBOARD_FAB2_LIB.BASEBOARD_FAB2(SCH_1):PAGE203
     2    GND @BASEBOARD_FAB2_LIB.BASEBOARD_FAB2(SCH_1):GND    I45 @BASEBOARD_FAB2_LIB.BASEBOARD_FAB2(SCH_1):PAGE203

C4D17 CAP_0402LF-220PF,50V,10%,X7R,AA
     1 A_TSENSE_PVCCIN_CPU0 @BASEBOARD_FAB2_LIB.BASEBOARD_FAB2(SCH_1):A_TSENSE_PVCCIN_CPU0    I66 @BASEBOARD_FAB2_LIB.BASEBOARD_FAB2(SCH_1):PAGE201
     2    GND @BASEBOARD_FAB2_LIB.BASEBOARD_FAB2(SCH_1):GND    I66 @BASEBOARD_FAB2_LIB.BASEBOARD_FAB2(SCH_1):PAGE201

C4D18 CAP_0402LF-220PF,50V,10%,X7R,AA
     1 A_TSENSE_PVSA_CPU0 @BASEBOARD_FAB2_LIB.BASEBOARD_FAB2(SCH_1):A_TSENSE_PVSA_CPU0    I68 @BASEBOARD_FAB2_LIB.BASEBOARD_FAB2(SCH_1):PAGE201
     2    GND @BASEBOARD_FAB2_LIB.BASEBOARD_FAB2(SCH_1):GND    I68 @BASEBOARD_FAB2_LIB.BASEBOARD_FAB2(SCH_1):PAGE201

C4D19 CAP_A_0402V-0.1UF,16V,10%,X7R,A
     1 VR_PVCCIN_CPU0_VDD @BASEBOARD_FAB2_LIB.BASEBOARD_FAB2(SCH_1):VR_PVCCIN_CPU0_VDD    I39 @BASEBOARD_FAB2_LIB.BASEBOARD_FAB2(SCH_1):PAGE201
     2    GND @BASEBOARD_FAB2_LIB.BASEBOARD_FAB2(SCH_1):GND    I39 @BASEBOARD_FAB2_LIB.BASEBOARD_FAB2(SCH_1):PAGE201

C4D20 CAP_A_0402V-0.1UF,16V,10%,X7R,A
     1 VR_PVCCIN_CPU0_AVINSEN @BASEBOARD_FAB2_LIB.BASEBOARD_FAB2(SCH_1):VR_PVCCIN_CPU0_AVINSEN   I192 @BASEBOARD_FAB2_LIB.BASEBOARD_FAB2(SCH_1):PAGE201
     2    GND @BASEBOARD_FAB2_LIB.BASEBOARD_FAB2(SCH_1):GND   I192 @BASEBOARD_FAB2_LIB.BASEBOARD_FAB2(SCH_1):PAGE201

C4D22 CAP_A_0402V-0.1UF,16V,10%,X7R,A
     1 P3V3_DB1200_R @BASEBOARD_FAB2_LIB.BASEBOARD_FAB2(SCH_1):P3V3_DB1200_R    I28 @BASEBOARD_FAB2_LIB.BASEBOARD_FAB2(SCH_1):PAGE102
     2    GND @BASEBOARD_FAB2_LIB.BASEBOARD_FAB2(SCH_1):GND    I28 @BASEBOARD_FAB2_LIB.BASEBOARD_FAB2(SCH_1):PAGE102

C4D23 CAP_A_0402V-1.0UF,6.3V,10%,X6SA
     1 P3V3_DB1200_A @BASEBOARD_FAB2_LIB.BASEBOARD_FAB2(SCH_1):P3V3_DB1200_A    I19 @BASEBOARD_FAB2_LIB.BASEBOARD_FAB2(SCH_1):PAGE102
     2    GND @BASEBOARD_FAB2_LIB.BASEBOARD_FAB2(SCH_1):GND    I19 @BASEBOARD_FAB2_LIB.BASEBOARD_FAB2(SCH_1):PAGE102

C4D24 CAP_A_0402V-0.1UF,16V,10%,X7R,A
     1 P3V3_DB1200_A @BASEBOARD_FAB2_LIB.BASEBOARD_FAB2(SCH_1):P3V3_DB1200_A    I18 @BASEBOARD_FAB2_LIB.BASEBOARD_FAB2(SCH_1):PAGE102
     2    GND @BASEBOARD_FAB2_LIB.BASEBOARD_FAB2(SCH_1):GND    I18 @BASEBOARD_FAB2_LIB.BASEBOARD_FAB2(SCH_1):PAGE102

C4D25 CAP_A_0402V-1.0UF,6.3V,10%,X6SA
     1 VR_PVCCIN_CPU0_VD12 @BASEBOARD_FAB2_LIB.BASEBOARD_FAB2(SCH_1):VR_PVCCIN_CPU0_VD12    I30 @BASEBOARD_FAB2_LIB.BASEBOARD_FAB2(SCH_1):PAGE201
     2    GND @BASEBOARD_FAB2_LIB.BASEBOARD_FAB2(SCH_1):GND    I30 @BASEBOARD_FAB2_LIB.BASEBOARD_FAB2(SCH_1):PAGE201

C4D26 CAP_A_0402V-0.1UF,16V,10%,X7R,A
     1 VR_PVCCIN_CPU0_VD12 @BASEBOARD_FAB2_LIB.BASEBOARD_FAB2(SCH_1):VR_PVCCIN_CPU0_VD12    I32 @BASEBOARD_FAB2_LIB.BASEBOARD_FAB2(SCH_1):PAGE201
     2    GND @BASEBOARD_FAB2_LIB.BASEBOARD_FAB2(SCH_1):GND    I32 @BASEBOARD_FAB2_LIB.BASEBOARD_FAB2(SCH_1):PAGE201

C4D27 CAP_A_0402V-1.0UF,6.3V,10%,X6SA
     1 P3V3_DB1200_R @BASEBOARD_FAB2_LIB.BASEBOARD_FAB2(SCH_1):P3V3_DB1200_R    I30 @BASEBOARD_FAB2_LIB.BASEBOARD_FAB2(SCH_1):PAGE102
     2    GND @BASEBOARD_FAB2_LIB.BASEBOARD_FAB2(SCH_1):GND    I30 @BASEBOARD_FAB2_LIB.BASEBOARD_FAB2(SCH_1):PAGE102

C4D28 CAP_0402-0.220UF,16V,10%,X7R,AA
     1 VR_PVCCIN_CPU0_PH3_BOOT @BASEBOARD_FAB2_LIB.BASEBOARD_FAB2(SCH_1):VR_PVCCIN_CPU0_PH3_BOOT    I42 @BASEBOARD_FAB2_LIB.BASEBOARD_FAB2(SCH_1):PAGE203
     2 VR_PVCCIN_CPU0_PH3_PHASE @BASEBOARD_FAB2_LIB.BASEBOARD_FAB2(SCH_1):VR_PVCCIN_CPU0_PH3_PHASE    I42 @BASEBOARD_FAB2_LIB.BASEBOARD_FAB2(SCH_1):PAGE203

C4D29 CAP_0402LF-220PF,50V,10%,X7R,AA
     1 VSENSE_PVSA_CPU0_BVSP @BASEBOARD_FAB2_LIB.BASEBOARD_FAB2(SCH_1):VSENSE_PVSA_CPU0_BVSP    I64 @BASEBOARD_FAB2_LIB.BASEBOARD_FAB2(SCH_1):PAGE201
     2 VSENSE_PVSA_CPU0_N @BASEBOARD_FAB2_LIB.BASEBOARD_FAB2(SCH_1):VSENSE_PVSA_CPU0_N    I64 @BASEBOARD_FAB2_LIB.BASEBOARD_FAB2(SCH_1):PAGE201

C4D30 CAP_0402-1.0UF,16V,10%,X6S,D97A
     1 VR_FET_SW_P12V_STBY_PVCCIN_CPU0 @BASEBOARD_FAB2_LIB.BASEBOARD_FAB2(SCH_1):VR_FET_SW_P12V_STBY_PVCCIN_CPU0    I47 @BASEBOARD_FAB2_LIB.BASEBOARD_FAB2(SCH_1):PAGE203
     2    GND @BASEBOARD_FAB2_LIB.BASEBOARD_FAB2(SCH_1):GND    I47 @BASEBOARD_FAB2_LIB.BASEBOARD_FAB2(SCH_1):PAGE203

C4D31 CAP_A_0402V-1.0UF,6.3V,10%,X6SA
     1 VR_PVCCIO_CPU1_VD12 @BASEBOARD_FAB2_LIB.BASEBOARD_FAB2(SCH_1):VR_PVCCIO_CPU1_VD12     I9 @BASEBOARD_FAB2_LIB.BASEBOARD_FAB2(SCH_1):PAGE213
     2    GND @BASEBOARD_FAB2_LIB.BASEBOARD_FAB2(SCH_1):GND     I9 @BASEBOARD_FAB2_LIB.BASEBOARD_FAB2(SCH_1):PAGE213

C4D32 CAP_A_0402V-0.1UF,16V,10%,X7R,A
     1 VR_PVCCIO_CPU1_VD12 @BASEBOARD_FAB2_LIB.BASEBOARD_FAB2(SCH_1):VR_PVCCIO_CPU1_VD12    I11 @BASEBOARD_FAB2_LIB.BASEBOARD_FAB2(SCH_1):PAGE213
     2    GND @BASEBOARD_FAB2_LIB.BASEBOARD_FAB2(SCH_1):GND    I11 @BASEBOARD_FAB2_LIB.BASEBOARD_FAB2(SCH_1):PAGE213

C4D33 CAP_0402LF-1000PF,50V,10%,X7R,A
     1 PWRGD_PVCCIO_CPU1_R @BASEBOARD_FAB2_LIB.BASEBOARD_FAB2(SCH_1):PWRGD_PVCCIO_CPU1_R    I73 @BASEBOARD_FAB2_LIB.BASEBOARD_FAB2(SCH_1):PAGE213
     2    GND @BASEBOARD_FAB2_LIB.BASEBOARD_FAB2(SCH_1):GND    I73 @BASEBOARD_FAB2_LIB.BASEBOARD_FAB2(SCH_1):PAGE213

C4D34 CAP_A_0603V-22.0UF,4V,20%,X6S,A
     1 PVCCIN_CPU0 @BASEBOARD_FAB2_LIB.BASEBOARD_FAB2(SCH_1):PVCCIN_CPU0    I68 @BASEBOARD_FAB2_LIB.BASEBOARD_FAB2(SCH_1):PAGE203
     2    GND @BASEBOARD_FAB2_LIB.BASEBOARD_FAB2(SCH_1):GND    I68 @BASEBOARD_FAB2_LIB.BASEBOARD_FAB2(SCH_1):PAGE203

C4D35 CAP_A_0402V-0.1UF,16V,10%,X7R,A
     1 VR_FET_SW_P12V_STBY_PVCCIN_CPU0 @BASEBOARD_FAB2_LIB.BASEBOARD_FAB2(SCH_1):VR_FET_SW_P12V_STBY_PVCCIN_CPU0    I46 @BASEBOARD_FAB2_LIB.BASEBOARD_FAB2(SCH_1):PAGE203
     2    GND @BASEBOARD_FAB2_LIB.BASEBOARD_FAB2(SCH_1):GND    I46 @BASEBOARD_FAB2_LIB.BASEBOARD_FAB2(SCH_1):PAGE203

C4D36 CAP_A_0402V-1.0UF,6.3V,10%,X6SA
     1 VR_PVCCIO_CPU1_VDD @BASEBOARD_FAB2_LIB.BASEBOARD_FAB2(SCH_1):VR_PVCCIO_CPU1_VDD    I17 @BASEBOARD_FAB2_LIB.BASEBOARD_FAB2(SCH_1):PAGE213
     2    GND @BASEBOARD_FAB2_LIB.BASEBOARD_FAB2(SCH_1):GND    I17 @BASEBOARD_FAB2_LIB.BASEBOARD_FAB2(SCH_1):PAGE213

C4D38 CAP_A_0402V-0.1UF,16V,10%,X7R,A
     1 VR_PVCCIO_CPU1_VDD @BASEBOARD_FAB2_LIB.BASEBOARD_FAB2(SCH_1):VR_PVCCIO_CPU1_VDD    I35 @BASEBOARD_FAB2_LIB.BASEBOARD_FAB2(SCH_1):PAGE213
     2    GND @BASEBOARD_FAB2_LIB.BASEBOARD_FAB2(SCH_1):GND    I35 @BASEBOARD_FAB2_LIB.BASEBOARD_FAB2(SCH_1):PAGE213

C4D40 CAP_A_0402V-0.1UF,16V,10%,X7R,A
     1 VR_PVCCIO_CPU1_VINSEN @BASEBOARD_FAB2_LIB.BASEBOARD_FAB2(SCH_1):VR_PVCCIO_CPU1_VINSEN   I105 @BASEBOARD_FAB2_LIB.BASEBOARD_FAB2(SCH_1):PAGE213
     2    GND @BASEBOARD_FAB2_LIB.BASEBOARD_FAB2(SCH_1):GND   I105 @BASEBOARD_FAB2_LIB.BASEBOARD_FAB2(SCH_1):PAGE213

C4D42 CAP_0402LF-1000PF,50V,10%,X7R,A
     1 VR_VRRDY_PVCCIN_CPU0 @BASEBOARD_FAB2_LIB.BASEBOARD_FAB2(SCH_1):VR_VRRDY_PVCCIN_CPU0   I125 @BASEBOARD_FAB2_LIB.BASEBOARD_FAB2(SCH_1):PAGE201
     2    GND @BASEBOARD_FAB2_LIB.BASEBOARD_FAB2(SCH_1):GND   I125 @BASEBOARD_FAB2_LIB.BASEBOARD_FAB2(SCH_1):PAGE201

C4D44 CAP_0402LF-220PF,50V,10%,X7R,AA
     1 VR_PVCCIO_CPU1_AVSP @BASEBOARD_FAB2_LIB.BASEBOARD_FAB2(SCH_1):VR_PVCCIO_CPU1_AVSP    I83 @BASEBOARD_FAB2_LIB.BASEBOARD_FAB2(SCH_1):PAGE213
     2 VSENSE_PVCCIO_CPU1_AVSN @BASEBOARD_FAB2_LIB.BASEBOARD_FAB2(SCH_1):VSENSE_PVCCIO_CPU1_AVSN    I83 @BASEBOARD_FAB2_LIB.BASEBOARD_FAB2(SCH_1):PAGE213

C4D45 CAP_0402LF-220PF,50V,10%,X7R,AA
     1 VSENSE_PVCCIN_CPU0_AVSP @BASEBOARD_FAB2_LIB.BASEBOARD_FAB2(SCH_1):VSENSE_PVCCIN_CPU0_AVSP    I70 @BASEBOARD_FAB2_LIB.BASEBOARD_FAB2(SCH_1):PAGE201
     2 VSENSE_PVCCIN_CPU0_N @BASEBOARD_FAB2_LIB.BASEBOARD_FAB2(SCH_1):VSENSE_PVCCIN_CPU0_N    I70 @BASEBOARD_FAB2_LIB.BASEBOARD_FAB2(SCH_1):PAGE201

C4D46 CAP_0402-1.0UF,16V,10%,X6S,D97A
     1 VR_PVCCIN_CPU0_PH5_VCIN @BASEBOARD_FAB2_LIB.BASEBOARD_FAB2(SCH_1):VR_PVCCIN_CPU0_PH5_VCIN    I34 @BASEBOARD_FAB2_LIB.BASEBOARD_FAB2(SCH_1):PAGE204
     2    GND @BASEBOARD_FAB2_LIB.BASEBOARD_FAB2(SCH_1):GND    I34 @BASEBOARD_FAB2_LIB.BASEBOARD_FAB2(SCH_1):PAGE204

C4D47 CAP_0402-0.22UF,16V,10%,X7R,A3A
     1 P5V_STBY @BASEBOARD_FAB2_LIB.BASEBOARD_FAB2(SCH_1):P5V_STBY    I18 @BASEBOARD_FAB2_LIB.BASEBOARD_FAB2(SCH_1):PAGE204
     2    GND @BASEBOARD_FAB2_LIB.BASEBOARD_FAB2(SCH_1):GND    I18 @BASEBOARD_FAB2_LIB.BASEBOARD_FAB2(SCH_1):PAGE204

C4D48 CAP_0402-1.0UF,16V,10%,X6S,D97A
     1 VR_FET_SW_P12V_STBY_PVCCIN_CPU0 @BASEBOARD_FAB2_LIB.BASEBOARD_FAB2(SCH_1):VR_FET_SW_P12V_STBY_PVCCIN_CPU0    I47 @BASEBOARD_FAB2_LIB.BASEBOARD_FAB2(SCH_1):PAGE202
     2    GND @BASEBOARD_FAB2_LIB.BASEBOARD_FAB2(SCH_1):GND    I47 @BASEBOARD_FAB2_LIB.BASEBOARD_FAB2(SCH_1):PAGE202

C4D49 CAP_A_0402V-0.1UF,16V,10%,X7R,A
     1 VR_FET_SW_P12V_STBY_PVCCIN_CPU0 @BASEBOARD_FAB2_LIB.BASEBOARD_FAB2(SCH_1):VR_FET_SW_P12V_STBY_PVCCIN_CPU0    I46 @BASEBOARD_FAB2_LIB.BASEBOARD_FAB2(SCH_1):PAGE202
     2    GND @BASEBOARD_FAB2_LIB.BASEBOARD_FAB2(SCH_1):GND    I46 @BASEBOARD_FAB2_LIB.BASEBOARD_FAB2(SCH_1):PAGE202

C4D50 CAP_0402-0.220UF,16V,10%,X7R,AA
     1 VR_PVCCIN_CPU0_PH2_BOOT @BASEBOARD_FAB2_LIB.BASEBOARD_FAB2(SCH_1):VR_PVCCIN_CPU0_PH2_BOOT    I32 @BASEBOARD_FAB2_LIB.BASEBOARD_FAB2(SCH_1):PAGE202
     2 VR_PVCCIN_CPU0_PH2_PHASE @BASEBOARD_FAB2_LIB.BASEBOARD_FAB2(SCH_1):VR_PVCCIN_CPU0_PH2_PHASE    I32 @BASEBOARD_FAB2_LIB.BASEBOARD_FAB2(SCH_1):PAGE202

C4E3 CAP_A_0603V-22.0UF,4V,20%,X6S,A
     1 PVCCIN_CPU0 @BASEBOARD_FAB2_LIB.BASEBOARD_FAB2(SCH_1):PVCCIN_CPU0    I61 @BASEBOARD_FAB2_LIB.BASEBOARD_FAB2(SCH_1):PAGE202
     2    GND @BASEBOARD_FAB2_LIB.BASEBOARD_FAB2(SCH_1):GND    I61 @BASEBOARD_FAB2_LIB.BASEBOARD_FAB2(SCH_1):PAGE202

C4E5 CAP_0402-0.22UF,16V,10%,X7R,A3A
     1 P5V_STBY @BASEBOARD_FAB2_LIB.BASEBOARD_FAB2(SCH_1):P5V_STBY    I18 @BASEBOARD_FAB2_LIB.BASEBOARD_FAB2(SCH_1):PAGE202
     2    GND @BASEBOARD_FAB2_LIB.BASEBOARD_FAB2(SCH_1):GND    I18 @BASEBOARD_FAB2_LIB.BASEBOARD_FAB2(SCH_1):PAGE202

C4E6 SC1U10V2KX-4-GP_SMD-BCG6-SC1U1A
     1 P5V_STBY @BASEBOARD_FAB2_LIB.BASEBOARD_FAB2(SCH_1):P5V_STBY   I112 @BASEBOARD_FAB2_LIB.BASEBOARD_FAB2(SCH_1):PAGE202
     2    GND @BASEBOARD_FAB2_LIB.BASEBOARD_FAB2(SCH_1):GND   I112 @BASEBOARD_FAB2_LIB.BASEBOARD_FAB2(SCH_1):PAGE202

C4E7 CAPP_3018-470UF,2.5V,20%,ALUM,A
     1 PVCCIO_CPU1 @BASEBOARD_FAB2_LIB.BASEBOARD_FAB2(SCH_1):PVCCIO_CPU1   I178 @BASEBOARD_FAB2_LIB.BASEBOARD_FAB2(SCH_1):PAGE214
     2    GND @BASEBOARD_FAB2_LIB.BASEBOARD_FAB2(SCH_1):GND   I178 @BASEBOARD_FAB2_LIB.BASEBOARD_FAB2(SCH_1):PAGE214

C4E8 SC22U16V5MX-4-GP_SMD-BCG5-SC22A
     1 VR_FET_SW_P12V_STBY_PVCCIN_CPU0 @BASEBOARD_FAB2_LIB.BASEBOARD_FAB2(SCH_1):VR_FET_SW_P12V_STBY_PVCCIN_CPU0   I161 @BASEBOARD_FAB2_LIB.BASEBOARD_FAB2(SCH_1):PAGE214
     2    GND @BASEBOARD_FAB2_LIB.BASEBOARD_FAB2(SCH_1):GND   I161 @BASEBOARD_FAB2_LIB.BASEBOARD_FAB2(SCH_1):PAGE214

C4E9 SC22U16V5MX-4-GP_SMD-BCG5-SC22A
     1 VR_FET_SW_P12V_STBY_PVCCIN_CPU0 @BASEBOARD_FAB2_LIB.BASEBOARD_FAB2(SCH_1):VR_FET_SW_P12V_STBY_PVCCIN_CPU0   I164 @BASEBOARD_FAB2_LIB.BASEBOARD_FAB2(SCH_1):PAGE214
     2    GND @BASEBOARD_FAB2_LIB.BASEBOARD_FAB2(SCH_1):GND   I164 @BASEBOARD_FAB2_LIB.BASEBOARD_FAB2(SCH_1):PAGE214

C4E10 CAP_0402-1.0UF,16V,10%,X6S,D97A
     1 VR_PVCCIN_CPU0_PH1_VCIN @BASEBOARD_FAB2_LIB.BASEBOARD_FAB2(SCH_1):VR_PVCCIN_CPU0_PH1_VCIN    I34 @BASEBOARD_FAB2_LIB.BASEBOARD_FAB2(SCH_1):PAGE202
     2    GND @BASEBOARD_FAB2_LIB.BASEBOARD_FAB2(SCH_1):GND    I34 @BASEBOARD_FAB2_LIB.BASEBOARD_FAB2(SCH_1):PAGE202

C4E11 CAP_A_0603V-22.0UF,4V,20%,X6S,A
     1 PVCCIN_CPU0 @BASEBOARD_FAB2_LIB.BASEBOARD_FAB2(SCH_1):PVCCIN_CPU0    I27 @BASEBOARD_FAB2_LIB.BASEBOARD_FAB2(SCH_1):PAGE202
     2    GND @BASEBOARD_FAB2_LIB.BASEBOARD_FAB2(SCH_1):GND    I27 @BASEBOARD_FAB2_LIB.BASEBOARD_FAB2(SCH_1):PAGE202

C4E13 CAP_A_0402V-0.1UF,16V,10%,X7R,A
     1 VR_FET_SW_P12V_STBY_PVCCIN_CPU0 @BASEBOARD_FAB2_LIB.BASEBOARD_FAB2(SCH_1):VR_FET_SW_P12V_STBY_PVCCIN_CPU0    I77 @BASEBOARD_FAB2_LIB.BASEBOARD_FAB2(SCH_1):PAGE214
     2    GND @BASEBOARD_FAB2_LIB.BASEBOARD_FAB2(SCH_1):GND    I77 @BASEBOARD_FAB2_LIB.BASEBOARD_FAB2(SCH_1):PAGE214

C4E14 SC22U16V5MX-4-GP_SMD-BCG5-SC22A
     1 VR_FET_SW_P12V_STBY_PVCCIN_CPU0 @BASEBOARD_FAB2_LIB.BASEBOARD_FAB2(SCH_1):VR_FET_SW_P12V_STBY_PVCCIN_CPU0   I148 @BASEBOARD_FAB2_LIB.BASEBOARD_FAB2(SCH_1):PAGE214
     2    GND @BASEBOARD_FAB2_LIB.BASEBOARD_FAB2(SCH_1):GND   I148 @BASEBOARD_FAB2_LIB.BASEBOARD_FAB2(SCH_1):PAGE214

C4E15 CAP_0402-1.0UF,16V,10%,X6S,D97A
     1 VR_FET_SW_P12V_STBY_PVCCIN_CPU0 @BASEBOARD_FAB2_LIB.BASEBOARD_FAB2(SCH_1):VR_FET_SW_P12V_STBY_PVCCIN_CPU0    I79 @BASEBOARD_FAB2_LIB.BASEBOARD_FAB2(SCH_1):PAGE214
     2    GND @BASEBOARD_FAB2_LIB.BASEBOARD_FAB2(SCH_1):GND    I79 @BASEBOARD_FAB2_LIB.BASEBOARD_FAB2(SCH_1):PAGE214

C4E16 CAPP_2626-270UF,16V,20%,OSCON,A
     1 VR_FET_SW_P12V_STBY_PVCCIN_CPU0 @BASEBOARD_FAB2_LIB.BASEBOARD_FAB2(SCH_1):VR_FET_SW_P12V_STBY_PVCCIN_CPU0    I50 @BASEBOARD_FAB2_LIB.BASEBOARD_FAB2(SCH_1):PAGE204
     2    GND @BASEBOARD_FAB2_LIB.BASEBOARD_FAB2(SCH_1):GND    I50 @BASEBOARD_FAB2_LIB.BASEBOARD_FAB2(SCH_1):PAGE204

C4E17 CAP_0402-0.220UF,16V,10%,X7R,AA
     1 VR_PVCCIN_CPU0_PH1_BOOT @BASEBOARD_FAB2_LIB.BASEBOARD_FAB2(SCH_1):VR_PVCCIN_CPU0_PH1_BOOT    I22 @BASEBOARD_FAB2_LIB.BASEBOARD_FAB2(SCH_1):PAGE202
     2 VR_PVCCIN_CPU0_PH1_PHASE @BASEBOARD_FAB2_LIB.BASEBOARD_FAB2(SCH_1):VR_PVCCIN_CPU0_PH1_PHASE    I22 @BASEBOARD_FAB2_LIB.BASEBOARD_FAB2(SCH_1):PAGE202

C4E18 CAP_0402-0.220UF,16V,10%,X7R,AA
     1 VR_PVCCIO_CPU1_PH1_BOOT @BASEBOARD_FAB2_LIB.BASEBOARD_FAB2(SCH_1):VR_PVCCIO_CPU1_PH1_BOOT    I78 @BASEBOARD_FAB2_LIB.BASEBOARD_FAB2(SCH_1):PAGE214
     2 VR_PVCCIO_CPU1_PH1_PHASE @BASEBOARD_FAB2_LIB.BASEBOARD_FAB2(SCH_1):VR_PVCCIO_CPU1_PH1_PHASE    I78 @BASEBOARD_FAB2_LIB.BASEBOARD_FAB2(SCH_1):PAGE214

C4E19 CAP_0402-1.0UF,16V,10%,X6S,D97A
     1 VR_FET_SW_P12V_STBY_PVCCIN_CPU0 @BASEBOARD_FAB2_LIB.BASEBOARD_FAB2(SCH_1):VR_FET_SW_P12V_STBY_PVCCIN_CPU0    I36 @BASEBOARD_FAB2_LIB.BASEBOARD_FAB2(SCH_1):PAGE202
     2    GND @BASEBOARD_FAB2_LIB.BASEBOARD_FAB2(SCH_1):GND    I36 @BASEBOARD_FAB2_LIB.BASEBOARD_FAB2(SCH_1):PAGE202

C4E20 CAP_A_0402V-0.1UF,16V,10%,X7R,A
     1 VR_FET_SW_P12V_STBY_PVCCIN_CPU0 @BASEBOARD_FAB2_LIB.BASEBOARD_FAB2(SCH_1):VR_FET_SW_P12V_STBY_PVCCIN_CPU0    I35 @BASEBOARD_FAB2_LIB.BASEBOARD_FAB2(SCH_1):PAGE202
     2    GND @BASEBOARD_FAB2_LIB.BASEBOARD_FAB2(SCH_1):GND    I35 @BASEBOARD_FAB2_LIB.BASEBOARD_FAB2(SCH_1):PAGE202

C4E22 CAP_0402-1.0UF,16V,10%,X6S,D97A
     1 VR_PVCCIO_CPU1_PH1_VCIN @BASEBOARD_FAB2_LIB.BASEBOARD_FAB2(SCH_1):VR_PVCCIO_CPU1_PH1_VCIN    I76 @BASEBOARD_FAB2_LIB.BASEBOARD_FAB2(SCH_1):PAGE214
     2    GND @BASEBOARD_FAB2_LIB.BASEBOARD_FAB2(SCH_1):GND    I76 @BASEBOARD_FAB2_LIB.BASEBOARD_FAB2(SCH_1):PAGE214

C4E23 CAP_0402-0.22UF,16V,10%,X7R,A3A
     1 P5V_STBY @BASEBOARD_FAB2_LIB.BASEBOARD_FAB2(SCH_1):P5V_STBY    I73 @BASEBOARD_FAB2_LIB.BASEBOARD_FAB2(SCH_1):PAGE214
     2    GND @BASEBOARD_FAB2_LIB.BASEBOARD_FAB2(SCH_1):GND    I73 @BASEBOARD_FAB2_LIB.BASEBOARD_FAB2(SCH_1):PAGE214

C4E24 CAPP_3018-470UF,2.5V,20%,ALUM,A
     1 PVCCMCP_CPU1 @BASEBOARD_FAB2_LIB.BASEBOARD_FAB2(SCH_1):PVCCMCP_CPU1    I61 @BASEBOARD_FAB2_LIB.BASEBOARD_FAB2(SCH_1):PAGE193
     2    GND @BASEBOARD_FAB2_LIB.BASEBOARD_FAB2(SCH_1):GND    I61 @BASEBOARD_FAB2_LIB.BASEBOARD_FAB2(SCH_1):PAGE193

C4E25 SC1U10V2KX-4-GP_SMD-BCG6-SC1U1A
     1 P5V_STBY @BASEBOARD_FAB2_LIB.BASEBOARD_FAB2(SCH_1):P5V_STBY   I111 @BASEBOARD_FAB2_LIB.BASEBOARD_FAB2(SCH_1):PAGE202
     2    GND @BASEBOARD_FAB2_LIB.BASEBOARD_FAB2(SCH_1):GND   I111 @BASEBOARD_FAB2_LIB.BASEBOARD_FAB2(SCH_1):PAGE202

C4E26 CAP_0402-1.0UF,16V,10%,X6S,D97A
     1 VR_PVCCIN_CPU0_PH2_VCIN @BASEBOARD_FAB2_LIB.BASEBOARD_FAB2(SCH_1):VR_PVCCIN_CPU0_PH2_VCIN    I45 @BASEBOARD_FAB2_LIB.BASEBOARD_FAB2(SCH_1):PAGE202
     2    GND @BASEBOARD_FAB2_LIB.BASEBOARD_FAB2(SCH_1):GND    I45 @BASEBOARD_FAB2_LIB.BASEBOARD_FAB2(SCH_1):PAGE202

C4E27 CAP_0402-0.22UF,16V,10%,X7R,A3A
     1 P5V_STBY @BASEBOARD_FAB2_LIB.BASEBOARD_FAB2(SCH_1):P5V_STBY    I24 @BASEBOARD_FAB2_LIB.BASEBOARD_FAB2(SCH_1):PAGE202
     2    GND @BASEBOARD_FAB2_LIB.BASEBOARD_FAB2(SCH_1):GND    I24 @BASEBOARD_FAB2_LIB.BASEBOARD_FAB2(SCH_1):PAGE202

C4E28 SC1U10V2KX-4-GP_SMD-BCG6-SC1U1A
     1 P5V_STBY @BASEBOARD_FAB2_LIB.BASEBOARD_FAB2(SCH_1):P5V_STBY   I175 @BASEBOARD_FAB2_LIB.BASEBOARD_FAB2(SCH_1):PAGE214
     2    GND @BASEBOARD_FAB2_LIB.BASEBOARD_FAB2(SCH_1):GND   I175 @BASEBOARD_FAB2_LIB.BASEBOARD_FAB2(SCH_1):PAGE214

C4E29 CAPP_3018-470UF,2.5V,20%,ALUM,A
     1 PVCCMCP_CPU1 @BASEBOARD_FAB2_LIB.BASEBOARD_FAB2(SCH_1):PVCCMCP_CPU1   I175 @BASEBOARD_FAB2_LIB.BASEBOARD_FAB2(SCH_1):PAGE193
     2    GND @BASEBOARD_FAB2_LIB.BASEBOARD_FAB2(SCH_1):GND   I175 @BASEBOARD_FAB2_LIB.BASEBOARD_FAB2(SCH_1):PAGE193

C4F1 CAP_A_0402V-1.0UF,6.3V,10%,X6SA
     1 P1V8_MCP_CPU1 @BASEBOARD_FAB2_LIB.BASEBOARD_FAB2(SCH_1):P1V8_MCP_CPU1    I68 @BASEBOARD_FAB2_LIB.BASEBOARD_FAB2(SCH_1):PAGE193
     2    GND @BASEBOARD_FAB2_LIB.BASEBOARD_FAB2(SCH_1):GND    I68 @BASEBOARD_FAB2_LIB.BASEBOARD_FAB2(SCH_1):PAGE193

C4F2 CAP_A_0603V-47UF,4V,20%,X5R,60A
     1 P1V8_MCP_CPU1 @BASEBOARD_FAB2_LIB.BASEBOARD_FAB2(SCH_1):P1V8_MCP_CPU1   I141 @BASEBOARD_FAB2_LIB.BASEBOARD_FAB2(SCH_1):PAGE193
     2    GND @BASEBOARD_FAB2_LIB.BASEBOARD_FAB2(SCH_1):GND   I141 @BASEBOARD_FAB2_LIB.BASEBOARD_FAB2(SCH_1):PAGE193

C4F3 CAP_A_0402V-1.0UF,6.3V,10%,X6SA
     1 P1V8_MCP_CPU1 @BASEBOARD_FAB2_LIB.BASEBOARD_FAB2(SCH_1):P1V8_MCP_CPU1    I70 @BASEBOARD_FAB2_LIB.BASEBOARD_FAB2(SCH_1):PAGE193
     2    GND @BASEBOARD_FAB2_LIB.BASEBOARD_FAB2(SCH_1):GND    I70 @BASEBOARD_FAB2_LIB.BASEBOARD_FAB2(SCH_1):PAGE193

C4F4 CAPP_3018-68UF,16V,20%,TANT,72A
     1 P12V_STBY @BASEBOARD_FAB2_LIB.BASEBOARD_FAB2(SCH_1):P12V_STBY   I112 @BASEBOARD_FAB2_LIB.BASEBOARD_FAB2(SCH_1):PAGE195
     2    GND @BASEBOARD_FAB2_LIB.BASEBOARD_FAB2(SCH_1):GND   I112 @BASEBOARD_FAB2_LIB.BASEBOARD_FAB2(SCH_1):PAGE195

C4F5 CAPP_3018-68UF,16V,20%,TANT,72A
     1 P12V_STBY @BASEBOARD_FAB2_LIB.BASEBOARD_FAB2(SCH_1):P12V_STBY    I96 @BASEBOARD_FAB2_LIB.BASEBOARD_FAB2(SCH_1):PAGE195
     2    GND @BASEBOARD_FAB2_LIB.BASEBOARD_FAB2(SCH_1):GND    I96 @BASEBOARD_FAB2_LIB.BASEBOARD_FAB2(SCH_1):PAGE195

C4F6 CAPP_4040LF-470UF,16V,20%,ALUMA
     1 P12V_STBY @BASEBOARD_FAB2_LIB.BASEBOARD_FAB2(SCH_1):P12V_STBY    I82 @BASEBOARD_FAB2_LIB.BASEBOARD_FAB2(SCH_1):PAGE195
     2    GND @BASEBOARD_FAB2_LIB.BASEBOARD_FAB2(SCH_1):GND    I82 @BASEBOARD_FAB2_LIB.BASEBOARD_FAB2(SCH_1):PAGE195

C4F7 CAPP_7343LF-330UF,6.3V,20%,POSA
     1 PVPP_GHJ @BASEBOARD_FAB2_LIB.BASEBOARD_FAB2(SCH_1):PVPP_GHJ   I217 @BASEBOARD_FAB2_LIB.BASEBOARD_FAB2(SCH_1):PAGE233
     2    GND @BASEBOARD_FAB2_LIB.BASEBOARD_FAB2(SCH_1):GND   I217 @BASEBOARD_FAB2_LIB.BASEBOARD_FAB2(SCH_1):PAGE233

C4F9 CAP_A_0402V-0.01UF,25V,10%,X7RA
     1 M_A_CPU_VREF @BASEBOARD_FAB2_LIB.BASEBOARD_FAB2(SCH_1):M_A_CPU_VREF     I7 @BASEBOARD_FAB2_LIB.BASEBOARD_FAB2(SCH_1):PAGE98
     2    GND @BASEBOARD_FAB2_LIB.BASEBOARD_FAB2(SCH_1):GND     I7 @BASEBOARD_FAB2_LIB.BASEBOARD_FAB2(SCH_1):PAGE98

C4F10 CAP_A_0402V-0.01UF,25V,10%,X7RA
     1 M_A_VREF @BASEBOARD_FAB2_LIB.BASEBOARD_FAB2(SCH_1):M_A_VREF   I272 @BASEBOARD_FAB2_LIB.BASEBOARD_FAB2(SCH_1):PAGE43
     2    GND @BASEBOARD_FAB2_LIB.BASEBOARD_FAB2(SCH_1):GND   I272 @BASEBOARD_FAB2_LIB.BASEBOARD_FAB2(SCH_1):PAGE43

C4F11 CAPP_7343-220UF,4V,20%,POSCAP,A
     1 PVPP_GHJ @BASEBOARD_FAB2_LIB.BASEBOARD_FAB2(SCH_1):PVPP_GHJ   I256 @BASEBOARD_FAB2_LIB.BASEBOARD_FAB2(SCH_1):PAGE233
     2    GND @BASEBOARD_FAB2_LIB.BASEBOARD_FAB2(SCH_1):GND   I256 @BASEBOARD_FAB2_LIB.BASEBOARD_FAB2(SCH_1):PAGE233

C4F12 CAP_0402LF-3300PF,50V,10%,EMPTA
     1 VR_PVPP_GHJ_PHASE @BASEBOARD_FAB2_LIB.BASEBOARD_FAB2(SCH_1):VR_PVPP_GHJ_PHASE   I209 @BASEBOARD_FAB2_LIB.BASEBOARD_FAB2(SCH_1):PAGE233
     2 VR_PVPP_GHJ_SNUB @BASEBOARD_FAB2_LIB.BASEBOARD_FAB2(SCH_1):VR_PVPP_GHJ_SNUB   I209 @BASEBOARD_FAB2_LIB.BASEBOARD_FAB2(SCH_1):PAGE233

C4G1 CAP_A_0402V-0.01UF,25V,10%,X7RA
     1 M_B_CPU_VREF @BASEBOARD_FAB2_LIB.BASEBOARD_FAB2(SCH_1):M_B_CPU_VREF    I43 @BASEBOARD_FAB2_LIB.BASEBOARD_FAB2(SCH_1):PAGE98
     2    GND @BASEBOARD_FAB2_LIB.BASEBOARD_FAB2(SCH_1):GND    I43 @BASEBOARD_FAB2_LIB.BASEBOARD_FAB2(SCH_1):PAGE98

C4G2 CAP_0805-10UF,16V,10%,X6S,C953A
     1 VR_FET_SW_P12V_STBY_PVPP_GHJ @BASEBOARD_FAB2_LIB.BASEBOARD_FAB2(SCH_1):VR_FET_SW_P12V_STBY_PVPP_GHJ   I253 @BASEBOARD_FAB2_LIB.BASEBOARD_FAB2(SCH_1):PAGE233
     2    GND @BASEBOARD_FAB2_LIB.BASEBOARD_FAB2(SCH_1):GND   I253 @BASEBOARD_FAB2_LIB.BASEBOARD_FAB2(SCH_1):PAGE233

C4G3 CAP_A_0402V-0.01UF,25V,10%,X7RA
     1 M_B_VREF @BASEBOARD_FAB2_LIB.BASEBOARD_FAB2(SCH_1):M_B_VREF   I179 @BASEBOARD_FAB2_LIB.BASEBOARD_FAB2(SCH_1):PAGE45
     2    GND @BASEBOARD_FAB2_LIB.BASEBOARD_FAB2(SCH_1):GND   I179 @BASEBOARD_FAB2_LIB.BASEBOARD_FAB2(SCH_1):PAGE45

C4G4 CAP_0402-1.0UF,16V,10%,X6S,D97A
     1 VR_FET_SW_P12V_STBY_PVPP_GHJ @BASEBOARD_FAB2_LIB.BASEBOARD_FAB2(SCH_1):VR_FET_SW_P12V_STBY_PVPP_GHJ   I196 @BASEBOARD_FAB2_LIB.BASEBOARD_FAB2(SCH_1):PAGE233
     2    GND @BASEBOARD_FAB2_LIB.BASEBOARD_FAB2(SCH_1):GND   I196 @BASEBOARD_FAB2_LIB.BASEBOARD_FAB2(SCH_1):PAGE233

C4G5 SC22U16V5MX-4-GP_SMD-BCG5-SC22A
     1 VR_FET_SW_P12V_STBY_PVPP_GHJ @BASEBOARD_FAB2_LIB.BASEBOARD_FAB2(SCH_1):VR_FET_SW_P12V_STBY_PVPP_GHJ   I280 @BASEBOARD_FAB2_LIB.BASEBOARD_FAB2(SCH_1):PAGE233
     2    GND @BASEBOARD_FAB2_LIB.BASEBOARD_FAB2(SCH_1):GND   I280 @BASEBOARD_FAB2_LIB.BASEBOARD_FAB2(SCH_1):PAGE233

C4G6 CAP_0402LF-100.0PF,50V,5%,COG,A
     1 VR_FB_PVPP_GHJ @BASEBOARD_FAB2_LIB.BASEBOARD_FAB2(SCH_1):VR_FB_PVPP_GHJ   I273 @BASEBOARD_FAB2_LIB.BASEBOARD_FAB2(SCH_1):PAGE233
     2 VR_COMP_PVPP_GHJ_3 @BASEBOARD_FAB2_LIB.BASEBOARD_FAB2(SCH_1):VR_COMP_PVPP_GHJ_3   I273 @BASEBOARD_FAB2_LIB.BASEBOARD_FAB2(SCH_1):PAGE233

C4G7 CAP_0402LF-1000PF,50V,10%,EMPTA
     1 FM_PVPP_CPU1_EN @BASEBOARD_FAB2_LIB.BASEBOARD_FAB2(SCH_1):FM_PVPP_CPU1_EN   I183 @BASEBOARD_FAB2_LIB.BASEBOARD_FAB2(SCH_1):PAGE233
     2 AGND_PVPP_GHJ @BASEBOARD_FAB2_LIB.BASEBOARD_FAB2(SCH_1):AGND_PVPP_GHJ   I183 @BASEBOARD_FAB2_LIB.BASEBOARD_FAB2(SCH_1):PAGE233

C4G8 CAP_0402-0.027UF,16V,10%,X7R,AA
     1 VR_PVPP_GHJ_SS @BASEBOARD_FAB2_LIB.BASEBOARD_FAB2(SCH_1):VR_PVPP_GHJ_SS   I194 @BASEBOARD_FAB2_LIB.BASEBOARD_FAB2(SCH_1):PAGE233
     2 AGND_PVPP_GHJ @BASEBOARD_FAB2_LIB.BASEBOARD_FAB2(SCH_1):AGND_PVPP_GHJ   I194 @BASEBOARD_FAB2_LIB.BASEBOARD_FAB2(SCH_1):PAGE233

C4G9 CAP_0402LF-1000PF,50V,10%,X7R,A
     1 PWRGD_PVPP_GHJ_R @BASEBOARD_FAB2_LIB.BASEBOARD_FAB2(SCH_1):PWRGD_PVPP_GHJ_R   I201 @BASEBOARD_FAB2_LIB.BASEBOARD_FAB2(SCH_1):PAGE233
     2    GND @BASEBOARD_FAB2_LIB.BASEBOARD_FAB2(SCH_1):GND   I201 @BASEBOARD_FAB2_LIB.BASEBOARD_FAB2(SCH_1):PAGE233

C4G10 CAP_0402LF-2200PF,50V,10%,X7R,A
     1 VR_COMP_RC_PVPP_GHJ @BASEBOARD_FAB2_LIB.BASEBOARD_FAB2(SCH_1):VR_COMP_RC_PVPP_GHJ   I274 @BASEBOARD_FAB2_LIB.BASEBOARD_FAB2(SCH_1):PAGE233
     2 VR_COMP_PVPP_GHJ_3 @BASEBOARD_FAB2_LIB.BASEBOARD_FAB2(SCH_1):VR_COMP_PVPP_GHJ_3   I274 @BASEBOARD_FAB2_LIB.BASEBOARD_FAB2(SCH_1):PAGE233

C4G11 CAP_0402LF-2200PF,50V,10%,X7R,A
     1 VR_COMP_PVPP_GHJ @BASEBOARD_FAB2_LIB.BASEBOARD_FAB2(SCH_1):VR_COMP_PVPP_GHJ   I267 @BASEBOARD_FAB2_LIB.BASEBOARD_FAB2(SCH_1):PAGE233
     2 VR_FB_PVPP_GHJ @BASEBOARD_FAB2_LIB.BASEBOARD_FAB2(SCH_1):VR_FB_PVPP_GHJ   I267 @BASEBOARD_FAB2_LIB.BASEBOARD_FAB2(SCH_1):PAGE233

C4G12 CAP_0402LF-1000PF,50V,10%,EMPTA
     1 FM_PVTT_GHJ_EN_R @BASEBOARD_FAB2_LIB.BASEBOARD_FAB2(SCH_1):FM_PVTT_GHJ_EN_R     I2 @BASEBOARD_FAB2_LIB.BASEBOARD_FAB2(SCH_1):PAGE229
     2    GND @BASEBOARD_FAB2_LIB.BASEBOARD_FAB2(SCH_1):GND     I2 @BASEBOARD_FAB2_LIB.BASEBOARD_FAB2(SCH_1):PAGE229

C4G13 CAP_0402LF-1000PF,50V,10%,X7R,A
     1 PWRGD_PVTT_GHJ_CPU1_R @BASEBOARD_FAB2_LIB.BASEBOARD_FAB2(SCH_1):PWRGD_PVTT_GHJ_CPU1_R    I26 @BASEBOARD_FAB2_LIB.BASEBOARD_FAB2(SCH_1):PAGE229
     2    GND @BASEBOARD_FAB2_LIB.BASEBOARD_FAB2(SCH_1):GND    I26 @BASEBOARD_FAB2_LIB.BASEBOARD_FAB2(SCH_1):PAGE229

C4G14 CAP_0402LF-1000PF,50V,10%,X7R,A
     1 PWRGD_PVTT_ABC_CPU0_R @BASEBOARD_FAB2_LIB.BASEBOARD_FAB2(SCH_1):PWRGD_PVTT_ABC_CPU0_R    I30 @BASEBOARD_FAB2_LIB.BASEBOARD_FAB2(SCH_1):PAGE221
     2    GND @BASEBOARD_FAB2_LIB.BASEBOARD_FAB2(SCH_1):GND    I30 @BASEBOARD_FAB2_LIB.BASEBOARD_FAB2(SCH_1):PAGE221

C4G15 CAP_0402-1.0UF,16V,10%,X6S,D97A
     1 VR_PVTT_ABC_BIAS @BASEBOARD_FAB2_LIB.BASEBOARD_FAB2(SCH_1):VR_PVTT_ABC_BIAS    I13 @BASEBOARD_FAB2_LIB.BASEBOARD_FAB2(SCH_1):PAGE221
     2    GND @BASEBOARD_FAB2_LIB.BASEBOARD_FAB2(SCH_1):GND    I13 @BASEBOARD_FAB2_LIB.BASEBOARD_FAB2(SCH_1):PAGE221

C4G16 CAP_0402-1.0UF,16V,10%,X6S,D97A
     1 VR_PVTT_ABC_VREF @BASEBOARD_FAB2_LIB.BASEBOARD_FAB2(SCH_1):VR_PVTT_ABC_VREF    I22 @BASEBOARD_FAB2_LIB.BASEBOARD_FAB2(SCH_1):PAGE221
     2    GND @BASEBOARD_FAB2_LIB.BASEBOARD_FAB2(SCH_1):GND    I22 @BASEBOARD_FAB2_LIB.BASEBOARD_FAB2(SCH_1):PAGE221

C4G17 CAP_A_0402V-0.01UF,25V,10%,X7RA
     1 M_C_CPU_VREF @BASEBOARD_FAB2_LIB.BASEBOARD_FAB2(SCH_1):M_C_CPU_VREF    I51 @BASEBOARD_FAB2_LIB.BASEBOARD_FAB2(SCH_1):PAGE98
     2    GND @BASEBOARD_FAB2_LIB.BASEBOARD_FAB2(SCH_1):GND    I51 @BASEBOARD_FAB2_LIB.BASEBOARD_FAB2(SCH_1):PAGE98

C4G18 CAP_0402-1.0UF,16V,10%,X6S,D97A
     1 VR_PVTT_GHJ_BIAS @BASEBOARD_FAB2_LIB.BASEBOARD_FAB2(SCH_1):VR_PVTT_GHJ_BIAS    I16 @BASEBOARD_FAB2_LIB.BASEBOARD_FAB2(SCH_1):PAGE229
     2    GND @BASEBOARD_FAB2_LIB.BASEBOARD_FAB2(SCH_1):GND    I16 @BASEBOARD_FAB2_LIB.BASEBOARD_FAB2(SCH_1):PAGE229

C4G19 CAP_A_0402V-0.01UF,25V,10%,X7RA
     1 M_C_VREF @BASEBOARD_FAB2_LIB.BASEBOARD_FAB2(SCH_1):M_C_VREF   I188 @BASEBOARD_FAB2_LIB.BASEBOARD_FAB2(SCH_1):PAGE47
     2    GND @BASEBOARD_FAB2_LIB.BASEBOARD_FAB2(SCH_1):GND   I188 @BASEBOARD_FAB2_LIB.BASEBOARD_FAB2(SCH_1):PAGE47

C4G20 CAP_0805LF-22UF,4V,20%,X6S,C95A
     1 PVTT_GHJ @BASEBOARD_FAB2_LIB.BASEBOARD_FAB2(SCH_1):PVTT_GHJ    I23 @BASEBOARD_FAB2_LIB.BASEBOARD_FAB2(SCH_1):PAGE229
     2    GND @BASEBOARD_FAB2_LIB.BASEBOARD_FAB2(SCH_1):GND    I23 @BASEBOARD_FAB2_LIB.BASEBOARD_FAB2(SCH_1):PAGE229

C4G21 CAP_0402-1.0UF,16V,10%,X6S,D97A
     1 VR_PVTT_GHJ_VREF @BASEBOARD_FAB2_LIB.BASEBOARD_FAB2(SCH_1):VR_PVTT_GHJ_VREF    I21 @BASEBOARD_FAB2_LIB.BASEBOARD_FAB2(SCH_1):PAGE229
     2    GND @BASEBOARD_FAB2_LIB.BASEBOARD_FAB2(SCH_1):GND    I21 @BASEBOARD_FAB2_LIB.BASEBOARD_FAB2(SCH_1):PAGE229

C4G22 CAP_A_0402V-0.1UF,16V,10%,X7R,A
     1 PVCCIO_CPU1 @BASEBOARD_FAB2_LIB.BASEBOARD_FAB2(SCH_1):PVCCIO_CPU1    I27 @BASEBOARD_FAB2_LIB.BASEBOARD_FAB2(SCH_1):PAGE99
     2    GND @BASEBOARD_FAB2_LIB.BASEBOARD_FAB2(SCH_1):GND    I27 @BASEBOARD_FAB2_LIB.BASEBOARD_FAB2(SCH_1):PAGE99

C4G23 CAP_0402LF-1000PF,50V,10%,EMPTA
     1 FM_PVTT_ABC_EN_R @BASEBOARD_FAB2_LIB.BASEBOARD_FAB2(SCH_1):FM_PVTT_ABC_EN_R     I2 @BASEBOARD_FAB2_LIB.BASEBOARD_FAB2(SCH_1):PAGE221
     2    GND @BASEBOARD_FAB2_LIB.BASEBOARD_FAB2(SCH_1):GND     I2 @BASEBOARD_FAB2_LIB.BASEBOARD_FAB2(SCH_1):PAGE221

C4G24 CAP_0805LF-22UF,4V,20%,X6S,C95A
     1 PVTT_ABC @BASEBOARD_FAB2_LIB.BASEBOARD_FAB2(SCH_1):PVTT_ABC    I24 @BASEBOARD_FAB2_LIB.BASEBOARD_FAB2(SCH_1):PAGE221
     2    GND @BASEBOARD_FAB2_LIB.BASEBOARD_FAB2(SCH_1):GND    I24 @BASEBOARD_FAB2_LIB.BASEBOARD_FAB2(SCH_1):PAGE221

C4G25 CAP_A_0402V-0.1UF,16V,10%,X7R,A
     1 PVPP_GHJ @BASEBOARD_FAB2_LIB.BASEBOARD_FAB2(SCH_1):PVPP_GHJ    I41 @BASEBOARD_FAB2_LIB.BASEBOARD_FAB2(SCH_1):PAGE99
     2    GND @BASEBOARD_FAB2_LIB.BASEBOARD_FAB2(SCH_1):GND    I41 @BASEBOARD_FAB2_LIB.BASEBOARD_FAB2(SCH_1):PAGE99

C4G26 CAP_0603LF-0.1UF,25V,10%,X7R,6A
     1 VR_PVPP_GHJ_PHASE @BASEBOARD_FAB2_LIB.BASEBOARD_FAB2(SCH_1):VR_PVPP_GHJ_PHASE   I224 @BASEBOARD_FAB2_LIB.BASEBOARD_FAB2(SCH_1):PAGE233
     2 VR_PVPP_GHJ_BOOT_R @BASEBOARD_FAB2_LIB.BASEBOARD_FAB2(SCH_1):VR_PVPP_GHJ_BOOT_R   I224 @BASEBOARD_FAB2_LIB.BASEBOARD_FAB2(SCH_1):PAGE233

C4L1 CAP_0603LF-10UF,4V,20%,X6S,E15A
     1 PVPP_DEF @BASEBOARD_FAB2_LIB.BASEBOARD_FAB2(SCH_1):PVPP_DEF   I129 @BASEBOARD_FAB2_LIB.BASEBOARD_FAB2(SCH_1):PAGE232
     2    GND @BASEBOARD_FAB2_LIB.BASEBOARD_FAB2(SCH_1):GND   I129 @BASEBOARD_FAB2_LIB.BASEBOARD_FAB2(SCH_1):PAGE232

C4L2 CAP_0603LF-10UF,4V,20%,X6S,E15A
     1 PVPP_DEF @BASEBOARD_FAB2_LIB.BASEBOARD_FAB2(SCH_1):PVPP_DEF   I102 @BASEBOARD_FAB2_LIB.BASEBOARD_FAB2(SCH_1):PAGE232
     2    GND @BASEBOARD_FAB2_LIB.BASEBOARD_FAB2(SCH_1):GND   I102 @BASEBOARD_FAB2_LIB.BASEBOARD_FAB2(SCH_1):PAGE232

C4L3 CAP_0603LF-10UF,4V,20%,X6S,E15A
     1 PVPP_DEF @BASEBOARD_FAB2_LIB.BASEBOARD_FAB2(SCH_1):PVPP_DEF   I106 @BASEBOARD_FAB2_LIB.BASEBOARD_FAB2(SCH_1):PAGE232
     2    GND @BASEBOARD_FAB2_LIB.BASEBOARD_FAB2(SCH_1):GND   I106 @BASEBOARD_FAB2_LIB.BASEBOARD_FAB2(SCH_1):PAGE232

C4L4 CAP_0603LF-10UF,4V,20%,X6S,E15A
     1 PVPP_DEF @BASEBOARD_FAB2_LIB.BASEBOARD_FAB2(SCH_1):PVPP_DEF   I108 @BASEBOARD_FAB2_LIB.BASEBOARD_FAB2(SCH_1):PAGE232
     2    GND @BASEBOARD_FAB2_LIB.BASEBOARD_FAB2(SCH_1):GND   I108 @BASEBOARD_FAB2_LIB.BASEBOARD_FAB2(SCH_1):PAGE232

C4L5 CAPP_3018-470UF,2.5V,20%,ALUM,A
     1 PVDDQ_DEF @BASEBOARD_FAB2_LIB.BASEBOARD_FAB2(SCH_1):PVDDQ_DEF    I78 @BASEBOARD_FAB2_LIB.BASEBOARD_FAB2(SCH_1):PAGE220
     2    GND @BASEBOARD_FAB2_LIB.BASEBOARD_FAB2(SCH_1):GND    I78 @BASEBOARD_FAB2_LIB.BASEBOARD_FAB2(SCH_1):PAGE220

C4M1 CAPP_7343-220UF,4V,20%,POSCAP,A
     1 PVPP_DEF @BASEBOARD_FAB2_LIB.BASEBOARD_FAB2(SCH_1):PVPP_DEF   I267 @BASEBOARD_FAB2_LIB.BASEBOARD_FAB2(SCH_1):PAGE232
     2    GND @BASEBOARD_FAB2_LIB.BASEBOARD_FAB2(SCH_1):GND   I267 @BASEBOARD_FAB2_LIB.BASEBOARD_FAB2(SCH_1):PAGE232

C4M2 CAP_A_0603V-47UF,4V,20%,X5R,60A
     1 PVDDQ_DEF @BASEBOARD_FAB2_LIB.BASEBOARD_FAB2(SCH_1):PVDDQ_DEF   I292 @BASEBOARD_FAB2_LIB.BASEBOARD_FAB2(SCH_1):PAGE220
     2    GND @BASEBOARD_FAB2_LIB.BASEBOARD_FAB2(SCH_1):GND   I292 @BASEBOARD_FAB2_LIB.BASEBOARD_FAB2(SCH_1):PAGE220

C4M3 CAP_0603LF-10UF,4V,20%,X6S,E15A
     1 PVPP_DEF @BASEBOARD_FAB2_LIB.BASEBOARD_FAB2(SCH_1):PVPP_DEF   I111 @BASEBOARD_FAB2_LIB.BASEBOARD_FAB2(SCH_1):PAGE232
     2    GND @BASEBOARD_FAB2_LIB.BASEBOARD_FAB2(SCH_1):GND   I111 @BASEBOARD_FAB2_LIB.BASEBOARD_FAB2(SCH_1):PAGE232

C4M4 CAP_0603LF-10UF,4V,20%,X6S,E15A
     1 PVPP_DEF @BASEBOARD_FAB2_LIB.BASEBOARD_FAB2(SCH_1):PVPP_DEF   I125 @BASEBOARD_FAB2_LIB.BASEBOARD_FAB2(SCH_1):PAGE232
     2    GND @BASEBOARD_FAB2_LIB.BASEBOARD_FAB2(SCH_1):GND   I125 @BASEBOARD_FAB2_LIB.BASEBOARD_FAB2(SCH_1):PAGE232

C4M5 CAP_A_0603V-47UF,4V,20%,X5R,60A
     1 PVDDQ_DEF @BASEBOARD_FAB2_LIB.BASEBOARD_FAB2(SCH_1):PVDDQ_DEF   I196 @BASEBOARD_FAB2_LIB.BASEBOARD_FAB2(SCH_1):PAGE220
     2    GND @BASEBOARD_FAB2_LIB.BASEBOARD_FAB2(SCH_1):GND   I196 @BASEBOARD_FAB2_LIB.BASEBOARD_FAB2(SCH_1):PAGE220

C4M6 CAPP_3018-68UF,16V,20%,TANT,72A
     1 P12V_STBY @BASEBOARD_FAB2_LIB.BASEBOARD_FAB2(SCH_1):P12V_STBY   I102 @BASEBOARD_FAB2_LIB.BASEBOARD_FAB2(SCH_1):PAGE195
     2    GND @BASEBOARD_FAB2_LIB.BASEBOARD_FAB2(SCH_1):GND   I102 @BASEBOARD_FAB2_LIB.BASEBOARD_FAB2(SCH_1):PAGE195

C4M7 CAPP_3018-68UF,16V,20%,TANT,72A
     1 P12V_STBY @BASEBOARD_FAB2_LIB.BASEBOARD_FAB2(SCH_1):P12V_STBY   I105 @BASEBOARD_FAB2_LIB.BASEBOARD_FAB2(SCH_1):PAGE195
     2    GND @BASEBOARD_FAB2_LIB.BASEBOARD_FAB2(SCH_1):GND   I105 @BASEBOARD_FAB2_LIB.BASEBOARD_FAB2(SCH_1):PAGE195

C4P1 CAP_0805-47UF,4V,20%,X6S,C9533A
     1 PVCCIO_CPU0 @BASEBOARD_FAB2_LIB.BASEBOARD_FAB2(SCH_1):PVCCIO_CPU0    I10 @BASEBOARD_FAB2_LIB.BASEBOARD_FAB2(SCH_1):PAGE42
     2    GND @BASEBOARD_FAB2_LIB.BASEBOARD_FAB2(SCH_1):GND    I10 @BASEBOARD_FAB2_LIB.BASEBOARD_FAB2(SCH_1):PAGE42

C4P2 CAP_0805-100UF,4V,20%,X5R,6024A
     1 PVCCMCP_CPU0 @BASEBOARD_FAB2_LIB.BASEBOARD_FAB2(SCH_1):PVCCMCP_CPU0   I230 @BASEBOARD_FAB2_LIB.BASEBOARD_FAB2(SCH_1):PAGE42
     2    GND @BASEBOARD_FAB2_LIB.BASEBOARD_FAB2(SCH_1):GND   I230 @BASEBOARD_FAB2_LIB.BASEBOARD_FAB2(SCH_1):PAGE42

C4P3 CAP_0805-100UF,4V,20%,X5R,6024A
     1 PVCCMCP_CPU0 @BASEBOARD_FAB2_LIB.BASEBOARD_FAB2(SCH_1):PVCCMCP_CPU0   I225 @BASEBOARD_FAB2_LIB.BASEBOARD_FAB2(SCH_1):PAGE42
     2    GND @BASEBOARD_FAB2_LIB.BASEBOARD_FAB2(SCH_1):GND   I225 @BASEBOARD_FAB2_LIB.BASEBOARD_FAB2(SCH_1):PAGE42

C4P4 CAP_0805-100UF,4V,20%,X5R,6024A
     1 PVCCMCP_CPU0 @BASEBOARD_FAB2_LIB.BASEBOARD_FAB2(SCH_1):PVCCMCP_CPU0   I223 @BASEBOARD_FAB2_LIB.BASEBOARD_FAB2(SCH_1):PAGE42
     2    GND @BASEBOARD_FAB2_LIB.BASEBOARD_FAB2(SCH_1):GND   I223 @BASEBOARD_FAB2_LIB.BASEBOARD_FAB2(SCH_1):PAGE42

C4P5 CAP_0805-100UF,4V,20%,X5R,6024A
     1 PVCCMCP_CPU0 @BASEBOARD_FAB2_LIB.BASEBOARD_FAB2(SCH_1):PVCCMCP_CPU0   I233 @BASEBOARD_FAB2_LIB.BASEBOARD_FAB2(SCH_1):PAGE42
     2    GND @BASEBOARD_FAB2_LIB.BASEBOARD_FAB2(SCH_1):GND   I233 @BASEBOARD_FAB2_LIB.BASEBOARD_FAB2(SCH_1):PAGE42

C4P6 CAP_A_0603V-22.0UF,4V,20%,X6S,A
     1 PVCCIO_CPU0 @BASEBOARD_FAB2_LIB.BASEBOARD_FAB2(SCH_1):PVCCIO_CPU0   I164 @BASEBOARD_FAB2_LIB.BASEBOARD_FAB2(SCH_1):PAGE42
     2    GND @BASEBOARD_FAB2_LIB.BASEBOARD_FAB2(SCH_1):GND   I164 @BASEBOARD_FAB2_LIB.BASEBOARD_FAB2(SCH_1):PAGE42

C4P7 CAP_0805-100UF,4V,20%,X5R,6024A
     1 PVCCMCP_CPU0 @BASEBOARD_FAB2_LIB.BASEBOARD_FAB2(SCH_1):PVCCMCP_CPU0   I224 @BASEBOARD_FAB2_LIB.BASEBOARD_FAB2(SCH_1):PAGE42
     2    GND @BASEBOARD_FAB2_LIB.BASEBOARD_FAB2(SCH_1):GND   I224 @BASEBOARD_FAB2_LIB.BASEBOARD_FAB2(SCH_1):PAGE42

C4P8 CAP_A_0603V-22.0UF,4V,20%,X6S,A
     1 PVCCIO_CPU0 @BASEBOARD_FAB2_LIB.BASEBOARD_FAB2(SCH_1):PVCCIO_CPU0   I178 @BASEBOARD_FAB2_LIB.BASEBOARD_FAB2(SCH_1):PAGE42
     2    GND @BASEBOARD_FAB2_LIB.BASEBOARD_FAB2(SCH_1):GND   I178 @BASEBOARD_FAB2_LIB.BASEBOARD_FAB2(SCH_1):PAGE42

C4P9 CAP_0805-47UF,4V,20%,X6S,C9533A
     1 PVCCIO_CPU0 @BASEBOARD_FAB2_LIB.BASEBOARD_FAB2(SCH_1):PVCCIO_CPU0    I12 @BASEBOARD_FAB2_LIB.BASEBOARD_FAB2(SCH_1):PAGE42
     2    GND @BASEBOARD_FAB2_LIB.BASEBOARD_FAB2(SCH_1):GND    I12 @BASEBOARD_FAB2_LIB.BASEBOARD_FAB2(SCH_1):PAGE42

C4P10 CAP_0805-47UF,4V,20%,X6S,C9533A
     1 PVCCIO_CPU0 @BASEBOARD_FAB2_LIB.BASEBOARD_FAB2(SCH_1):PVCCIO_CPU0    I17 @BASEBOARD_FAB2_LIB.BASEBOARD_FAB2(SCH_1):PAGE42
     2    GND @BASEBOARD_FAB2_LIB.BASEBOARD_FAB2(SCH_1):GND    I17 @BASEBOARD_FAB2_LIB.BASEBOARD_FAB2(SCH_1):PAGE42

C4R1 CAPP_3018-470UF,2.5V,20%,ALUM,A
     1 PVCCMCP_CPU0 @BASEBOARD_FAB2_LIB.BASEBOARD_FAB2(SCH_1):PVCCMCP_CPU0    I29 @BASEBOARD_FAB2_LIB.BASEBOARD_FAB2(SCH_1):PAGE194
     2    GND @BASEBOARD_FAB2_LIB.BASEBOARD_FAB2(SCH_1):GND    I29 @BASEBOARD_FAB2_LIB.BASEBOARD_FAB2(SCH_1):PAGE194

C4R2 CAP_A_0402V-0.1UF,16V,10%,X7R,A
     1 JTAG_MCP_CPU0_TDI_R @BASEBOARD_FAB2_LIB.BASEBOARD_FAB2(SCH_1):JTAG_MCP_CPU0_TDI_R   I246 @BASEBOARD_FAB2_LIB.BASEBOARD_FAB2(SCH_1):PAGE113
     2    GND @BASEBOARD_FAB2_LIB.BASEBOARD_FAB2(SCH_1):GND   I246 @BASEBOARD_FAB2_LIB.BASEBOARD_FAB2(SCH_1):PAGE113

C4T1 CAP_A_0402V-1.0UF,6.3V,10%,X6SA
     1 P1V8_MCP_CPU0 @BASEBOARD_FAB2_LIB.BASEBOARD_FAB2(SCH_1):P1V8_MCP_CPU0    I16 @BASEBOARD_FAB2_LIB.BASEBOARD_FAB2(SCH_1):PAGE194
     2    GND @BASEBOARD_FAB2_LIB.BASEBOARD_FAB2(SCH_1):GND    I16 @BASEBOARD_FAB2_LIB.BASEBOARD_FAB2(SCH_1):PAGE194

C4T2 CAP_A_0402V-1.0UF,6.3V,10%,X6SA
     1 P1V8_MCP_CPU0 @BASEBOARD_FAB2_LIB.BASEBOARD_FAB2(SCH_1):P1V8_MCP_CPU0     I9 @BASEBOARD_FAB2_LIB.BASEBOARD_FAB2(SCH_1):PAGE194
     2    GND @BASEBOARD_FAB2_LIB.BASEBOARD_FAB2(SCH_1):GND     I9 @BASEBOARD_FAB2_LIB.BASEBOARD_FAB2(SCH_1):PAGE194

C4T3 CAPP_7343-220UF,4V,20%,POSCAP,A
     1 PVPP_ABC @BASEBOARD_FAB2_LIB.BASEBOARD_FAB2(SCH_1):PVPP_ABC   I217 @BASEBOARD_FAB2_LIB.BASEBOARD_FAB2(SCH_1):PAGE231
     2    GND @BASEBOARD_FAB2_LIB.BASEBOARD_FAB2(SCH_1):GND   I217 @BASEBOARD_FAB2_LIB.BASEBOARD_FAB2(SCH_1):PAGE231

C4T4 CAP_0805-100UF,4V,20%,X5R,6024A
     1 PVDDQ_ABC @BASEBOARD_FAB2_LIB.BASEBOARD_FAB2(SCH_1):PVDDQ_ABC   I319 @BASEBOARD_FAB2_LIB.BASEBOARD_FAB2(SCH_1):PAGE217
     2    GND @BASEBOARD_FAB2_LIB.BASEBOARD_FAB2(SCH_1):GND   I319 @BASEBOARD_FAB2_LIB.BASEBOARD_FAB2(SCH_1):PAGE217

C4T5 CAP_0603LF-10UF,4V,20%,X6S,E15A
     1 PVPP_ABC @BASEBOARD_FAB2_LIB.BASEBOARD_FAB2(SCH_1):PVPP_ABC   I125 @BASEBOARD_FAB2_LIB.BASEBOARD_FAB2(SCH_1):PAGE231
     2    GND @BASEBOARD_FAB2_LIB.BASEBOARD_FAB2(SCH_1):GND   I125 @BASEBOARD_FAB2_LIB.BASEBOARD_FAB2(SCH_1):PAGE231

C4T6 CAP_0603LF-10UF,4V,20%,X6S,E15A
     1 PVPP_ABC @BASEBOARD_FAB2_LIB.BASEBOARD_FAB2(SCH_1):PVPP_ABC   I124 @BASEBOARD_FAB2_LIB.BASEBOARD_FAB2(SCH_1):PAGE231
     2    GND @BASEBOARD_FAB2_LIB.BASEBOARD_FAB2(SCH_1):GND   I124 @BASEBOARD_FAB2_LIB.BASEBOARD_FAB2(SCH_1):PAGE231

C4U1 CAP_0603LF-10UF,4V,20%,X6S,E15A
     1 PVPP_ABC @BASEBOARD_FAB2_LIB.BASEBOARD_FAB2(SCH_1):PVPP_ABC   I130 @BASEBOARD_FAB2_LIB.BASEBOARD_FAB2(SCH_1):PAGE231
     2    GND @BASEBOARD_FAB2_LIB.BASEBOARD_FAB2(SCH_1):GND   I130 @BASEBOARD_FAB2_LIB.BASEBOARD_FAB2(SCH_1):PAGE231

C4U2 CAP_0603LF-10UF,4V,20%,X6S,E15A
     1 PVPP_ABC @BASEBOARD_FAB2_LIB.BASEBOARD_FAB2(SCH_1):PVPP_ABC   I129 @BASEBOARD_FAB2_LIB.BASEBOARD_FAB2(SCH_1):PAGE231
     2    GND @BASEBOARD_FAB2_LIB.BASEBOARD_FAB2(SCH_1):GND   I129 @BASEBOARD_FAB2_LIB.BASEBOARD_FAB2(SCH_1):PAGE231

C4U3 CAP_0603LF-10UF,4V,20%,X6S,E15A
     1 PVPP_ABC @BASEBOARD_FAB2_LIB.BASEBOARD_FAB2(SCH_1):PVPP_ABC   I148 @BASEBOARD_FAB2_LIB.BASEBOARD_FAB2(SCH_1):PAGE231
     2    GND @BASEBOARD_FAB2_LIB.BASEBOARD_FAB2(SCH_1):GND   I148 @BASEBOARD_FAB2_LIB.BASEBOARD_FAB2(SCH_1):PAGE231

C4U4 CAP_0603LF-10UF,4V,20%,X6S,E15A
     1 PVPP_ABC @BASEBOARD_FAB2_LIB.BASEBOARD_FAB2(SCH_1):PVPP_ABC   I146 @BASEBOARD_FAB2_LIB.BASEBOARD_FAB2(SCH_1):PAGE231
     2    GND @BASEBOARD_FAB2_LIB.BASEBOARD_FAB2(SCH_1):GND   I146 @BASEBOARD_FAB2_LIB.BASEBOARD_FAB2(SCH_1):PAGE231

C4W1 CAP_0402LF-220PF,50V,10%,X7R,AA
     1 A_TSENSE_PVCCIO_CPU0 @BASEBOARD_FAB2_LIB.BASEBOARD_FAB2(SCH_1):A_TSENSE_PVCCIO_CPU0    I97 @BASEBOARD_FAB2_LIB.BASEBOARD_FAB2(SCH_1):PAGE211
     2    GND @BASEBOARD_FAB2_LIB.BASEBOARD_FAB2(SCH_1):GND    I97 @BASEBOARD_FAB2_LIB.BASEBOARD_FAB2(SCH_1):PAGE211

C4W2 CAP_0402LF-220PF,50V,10%,X7R,AA
     1 A_TSENSE_PVCCIO_CPU1 @BASEBOARD_FAB2_LIB.BASEBOARD_FAB2(SCH_1):A_TSENSE_PVCCIO_CPU1   I101 @BASEBOARD_FAB2_LIB.BASEBOARD_FAB2(SCH_1):PAGE213
     2    GND @BASEBOARD_FAB2_LIB.BASEBOARD_FAB2(SCH_1):GND   I101 @BASEBOARD_FAB2_LIB.BASEBOARD_FAB2(SCH_1):PAGE213

C4W3 CAP_0402LF-220PF,50V,10%,X7R,AA
     1 A_TSENSE_PVNN_PCH_TMON @BASEBOARD_FAB2_LIB.BASEBOARD_FAB2(SCH_1):A_TSENSE_PVNN_PCH_TMON   I244 @BASEBOARD_FAB2_LIB.BASEBOARD_FAB2(SCH_1):PAGE235
     2    GND @BASEBOARD_FAB2_LIB.BASEBOARD_FAB2(SCH_1):GND   I244 @BASEBOARD_FAB2_LIB.BASEBOARD_FAB2(SCH_1):PAGE235

C4W4 CAP_0402LF-220PF,50V,10%,X7R,AA
     1 A_TSENSE_P1V05_PCH_STBY_TMON @BASEBOARD_FAB2_LIB.BASEBOARD_FAB2(SCH_1):A_TSENSE_P1V05_PCH_STBY_TMON   I246 @BASEBOARD_FAB2_LIB.BASEBOARD_FAB2(SCH_1):PAGE235
     2    GND @BASEBOARD_FAB2_LIB.BASEBOARD_FAB2(SCH_1):GND   I246 @BASEBOARD_FAB2_LIB.BASEBOARD_FAB2(SCH_1):PAGE235

C4W5 CAP_0805-100UF,4V,20%,X5R,6024A
     1 PVTT_DEF @BASEBOARD_FAB2_LIB.BASEBOARD_FAB2(SCH_1):PVTT_DEF    I46 @BASEBOARD_FAB2_LIB.BASEBOARD_FAB2(SCH_1):PAGE222
     2    GND @BASEBOARD_FAB2_LIB.BASEBOARD_FAB2(SCH_1):GND    I46 @BASEBOARD_FAB2_LIB.BASEBOARD_FAB2(SCH_1):PAGE222

C5A1 CAP_A_0603V-47UF,4V,20%,X5R,60A
     1 PVDDQ_DEF @BASEBOARD_FAB2_LIB.BASEBOARD_FAB2(SCH_1):PVDDQ_DEF   I262 @BASEBOARD_FAB2_LIB.BASEBOARD_FAB2(SCH_1):PAGE220
     2    GND @BASEBOARD_FAB2_LIB.BASEBOARD_FAB2(SCH_1):GND   I262 @BASEBOARD_FAB2_LIB.BASEBOARD_FAB2(SCH_1):PAGE220

C5A2 CAP_A_0603V-47UF,4V,20%,X5R,60A
     1 PVDDQ_DEF @BASEBOARD_FAB2_LIB.BASEBOARD_FAB2(SCH_1):PVDDQ_DEF   I266 @BASEBOARD_FAB2_LIB.BASEBOARD_FAB2(SCH_1):PAGE220
     2    GND @BASEBOARD_FAB2_LIB.BASEBOARD_FAB2(SCH_1):GND   I266 @BASEBOARD_FAB2_LIB.BASEBOARD_FAB2(SCH_1):PAGE220

C5A3 CAP_A_0603V-47UF,4V,20%,X5R,60A
     1 PVDDQ_DEF @BASEBOARD_FAB2_LIB.BASEBOARD_FAB2(SCH_1):PVDDQ_DEF   I270 @BASEBOARD_FAB2_LIB.BASEBOARD_FAB2(SCH_1):PAGE220
     2    GND @BASEBOARD_FAB2_LIB.BASEBOARD_FAB2(SCH_1):GND   I270 @BASEBOARD_FAB2_LIB.BASEBOARD_FAB2(SCH_1):PAGE220

C5A4 CAP_A_0603V-47UF,4V,20%,X5R,60A
     1 PVDDQ_DEF @BASEBOARD_FAB2_LIB.BASEBOARD_FAB2(SCH_1):PVDDQ_DEF   I274 @BASEBOARD_FAB2_LIB.BASEBOARD_FAB2(SCH_1):PAGE220
     2    GND @BASEBOARD_FAB2_LIB.BASEBOARD_FAB2(SCH_1):GND   I274 @BASEBOARD_FAB2_LIB.BASEBOARD_FAB2(SCH_1):PAGE220

C5A5 CAP_A_0603V-47UF,4V,20%,X5R,60A
     1 PVDDQ_DEF @BASEBOARD_FAB2_LIB.BASEBOARD_FAB2(SCH_1):PVDDQ_DEF   I193 @BASEBOARD_FAB2_LIB.BASEBOARD_FAB2(SCH_1):PAGE220
     2    GND @BASEBOARD_FAB2_LIB.BASEBOARD_FAB2(SCH_1):GND   I193 @BASEBOARD_FAB2_LIB.BASEBOARD_FAB2(SCH_1):PAGE220

C5A6 CAP_A_0603V-47UF,4V,20%,X5R,60A
     1 PVDDQ_DEF @BASEBOARD_FAB2_LIB.BASEBOARD_FAB2(SCH_1):PVDDQ_DEF   I268 @BASEBOARD_FAB2_LIB.BASEBOARD_FAB2(SCH_1):PAGE220
     2    GND @BASEBOARD_FAB2_LIB.BASEBOARD_FAB2(SCH_1):GND   I268 @BASEBOARD_FAB2_LIB.BASEBOARD_FAB2(SCH_1):PAGE220

C5A7 CAP_A_0603V-47UF,4V,20%,X5R,60A
     1 PVDDQ_DEF @BASEBOARD_FAB2_LIB.BASEBOARD_FAB2(SCH_1):PVDDQ_DEF   I269 @BASEBOARD_FAB2_LIB.BASEBOARD_FAB2(SCH_1):PAGE220
     2    GND @BASEBOARD_FAB2_LIB.BASEBOARD_FAB2(SCH_1):GND   I269 @BASEBOARD_FAB2_LIB.BASEBOARD_FAB2(SCH_1):PAGE220

C5A8 CAP_A_0603V-47UF,4V,20%,X5R,60A
     1 PVDDQ_DEF @BASEBOARD_FAB2_LIB.BASEBOARD_FAB2(SCH_1):PVDDQ_DEF   I271 @BASEBOARD_FAB2_LIB.BASEBOARD_FAB2(SCH_1):PAGE220
     2    GND @BASEBOARD_FAB2_LIB.BASEBOARD_FAB2(SCH_1):GND   I271 @BASEBOARD_FAB2_LIB.BASEBOARD_FAB2(SCH_1):PAGE220

C5A9 CAP_A_0603V-47UF,4V,20%,X5R,60A
     1 PVDDQ_DEF @BASEBOARD_FAB2_LIB.BASEBOARD_FAB2(SCH_1):PVDDQ_DEF   I272 @BASEBOARD_FAB2_LIB.BASEBOARD_FAB2(SCH_1):PAGE220
     2    GND @BASEBOARD_FAB2_LIB.BASEBOARD_FAB2(SCH_1):GND   I272 @BASEBOARD_FAB2_LIB.BASEBOARD_FAB2(SCH_1):PAGE220

C5A10 CAP_0805-100UF,4V,20%,X5R,6024A
     1 PVDDQ_DEF @BASEBOARD_FAB2_LIB.BASEBOARD_FAB2(SCH_1):PVDDQ_DEF   I321 @BASEBOARD_FAB2_LIB.BASEBOARD_FAB2(SCH_1):PAGE220
     2    GND @BASEBOARD_FAB2_LIB.BASEBOARD_FAB2(SCH_1):GND   I321 @BASEBOARD_FAB2_LIB.BASEBOARD_FAB2(SCH_1):PAGE220

C5A11 CAP_A_0603V-47UF,4V,20%,X5R,60A
     1 PVDDQ_DEF @BASEBOARD_FAB2_LIB.BASEBOARD_FAB2(SCH_1):PVDDQ_DEF   I293 @BASEBOARD_FAB2_LIB.BASEBOARD_FAB2(SCH_1):PAGE220
     2    GND @BASEBOARD_FAB2_LIB.BASEBOARD_FAB2(SCH_1):GND   I293 @BASEBOARD_FAB2_LIB.BASEBOARD_FAB2(SCH_1):PAGE220

C5A12 CAP_A_0603V-47UF,4V,20%,X5R,60A
     1 PVDDQ_DEF @BASEBOARD_FAB2_LIB.BASEBOARD_FAB2(SCH_1):PVDDQ_DEF   I264 @BASEBOARD_FAB2_LIB.BASEBOARD_FAB2(SCH_1):PAGE220
     2    GND @BASEBOARD_FAB2_LIB.BASEBOARD_FAB2(SCH_1):GND   I264 @BASEBOARD_FAB2_LIB.BASEBOARD_FAB2(SCH_1):PAGE220

C5A13 CAP_A_0603V-47UF,4V,20%,X5R,60A
     1 PVDDQ_DEF @BASEBOARD_FAB2_LIB.BASEBOARD_FAB2(SCH_1):PVDDQ_DEF   I265 @BASEBOARD_FAB2_LIB.BASEBOARD_FAB2(SCH_1):PAGE220
     2    GND @BASEBOARD_FAB2_LIB.BASEBOARD_FAB2(SCH_1):GND   I265 @BASEBOARD_FAB2_LIB.BASEBOARD_FAB2(SCH_1):PAGE220

C5A14 CAP_A_0603V-47UF,4V,20%,X5R,60A
     1 PVDDQ_DEF @BASEBOARD_FAB2_LIB.BASEBOARD_FAB2(SCH_1):PVDDQ_DEF   I267 @BASEBOARD_FAB2_LIB.BASEBOARD_FAB2(SCH_1):PAGE220
     2    GND @BASEBOARD_FAB2_LIB.BASEBOARD_FAB2(SCH_1):GND   I267 @BASEBOARD_FAB2_LIB.BASEBOARD_FAB2(SCH_1):PAGE220

C5A15 CAP_A_0603V-47UF,4V,20%,X5R,60A
     1 PVDDQ_DEF @BASEBOARD_FAB2_LIB.BASEBOARD_FAB2(SCH_1):PVDDQ_DEF   I263 @BASEBOARD_FAB2_LIB.BASEBOARD_FAB2(SCH_1):PAGE220
     2    GND @BASEBOARD_FAB2_LIB.BASEBOARD_FAB2(SCH_1):GND   I263 @BASEBOARD_FAB2_LIB.BASEBOARD_FAB2(SCH_1):PAGE220

C5A16 CAP_A_0603V-47UF,4V,20%,X5R,60A
     1 PVDDQ_DEF @BASEBOARD_FAB2_LIB.BASEBOARD_FAB2(SCH_1):PVDDQ_DEF   I273 @BASEBOARD_FAB2_LIB.BASEBOARD_FAB2(SCH_1):PAGE220
     2    GND @BASEBOARD_FAB2_LIB.BASEBOARD_FAB2(SCH_1):GND   I273 @BASEBOARD_FAB2_LIB.BASEBOARD_FAB2(SCH_1):PAGE220

C5A17 CAP_A_0603V-47UF,4V,20%,X5R,60A
     1 PVDDQ_DEF @BASEBOARD_FAB2_LIB.BASEBOARD_FAB2(SCH_1):PVDDQ_DEF   I275 @BASEBOARD_FAB2_LIB.BASEBOARD_FAB2(SCH_1):PAGE220
     2    GND @BASEBOARD_FAB2_LIB.BASEBOARD_FAB2(SCH_1):GND   I275 @BASEBOARD_FAB2_LIB.BASEBOARD_FAB2(SCH_1):PAGE220

C5A18 CAP_A_0603V-47UF,4V,20%,X5R,60A
     1 PVDDQ_DEF @BASEBOARD_FAB2_LIB.BASEBOARD_FAB2(SCH_1):PVDDQ_DEF   I276 @BASEBOARD_FAB2_LIB.BASEBOARD_FAB2(SCH_1):PAGE220
     2    GND @BASEBOARD_FAB2_LIB.BASEBOARD_FAB2(SCH_1):GND   I276 @BASEBOARD_FAB2_LIB.BASEBOARD_FAB2(SCH_1):PAGE220

C5A19 CAP_A_0603V-47UF,4V,20%,X5R,60A
     1 PVDDQ_DEF @BASEBOARD_FAB2_LIB.BASEBOARD_FAB2(SCH_1):PVDDQ_DEF   I277 @BASEBOARD_FAB2_LIB.BASEBOARD_FAB2(SCH_1):PAGE220
     2    GND @BASEBOARD_FAB2_LIB.BASEBOARD_FAB2(SCH_1):GND   I277 @BASEBOARD_FAB2_LIB.BASEBOARD_FAB2(SCH_1):PAGE220

C5A20 CAP_0805-100UF,4V,20%,X5R,6024A
     1 PVDDQ_DEF @BASEBOARD_FAB2_LIB.BASEBOARD_FAB2(SCH_1):PVDDQ_DEF   I308 @BASEBOARD_FAB2_LIB.BASEBOARD_FAB2(SCH_1):PAGE220
     2    GND @BASEBOARD_FAB2_LIB.BASEBOARD_FAB2(SCH_1):GND   I308 @BASEBOARD_FAB2_LIB.BASEBOARD_FAB2(SCH_1):PAGE220

C5B1 CAP_A_0603V-47UF,4V,20%,X5R,60A
     1 PVDDQ_DEF @BASEBOARD_FAB2_LIB.BASEBOARD_FAB2(SCH_1):PVDDQ_DEF   I194 @BASEBOARD_FAB2_LIB.BASEBOARD_FAB2(SCH_1):PAGE220
     2    GND @BASEBOARD_FAB2_LIB.BASEBOARD_FAB2(SCH_1):GND   I194 @BASEBOARD_FAB2_LIB.BASEBOARD_FAB2(SCH_1):PAGE220

C5B2 CAP_A_0603V-47UF,4V,20%,X5R,60A
     1 PVDDQ_DEF @BASEBOARD_FAB2_LIB.BASEBOARD_FAB2(SCH_1):PVDDQ_DEF   I197 @BASEBOARD_FAB2_LIB.BASEBOARD_FAB2(SCH_1):PAGE220
     2    GND @BASEBOARD_FAB2_LIB.BASEBOARD_FAB2(SCH_1):GND   I197 @BASEBOARD_FAB2_LIB.BASEBOARD_FAB2(SCH_1):PAGE220

C5D1 CAP_A_0603V-22.0UF,4V,20%,X6S,A
     1 PVDDQ_DEF @BASEBOARD_FAB2_LIB.BASEBOARD_FAB2(SCH_1):PVDDQ_DEF   I252 @BASEBOARD_FAB2_LIB.BASEBOARD_FAB2(SCH_1):PAGE220
     2    GND @BASEBOARD_FAB2_LIB.BASEBOARD_FAB2(SCH_1):GND   I252 @BASEBOARD_FAB2_LIB.BASEBOARD_FAB2(SCH_1):PAGE220

C5D2 CAP_A_0603V-22.0UF,4V,20%,X6S,A
     1 PVDDQ_DEF @BASEBOARD_FAB2_LIB.BASEBOARD_FAB2(SCH_1):PVDDQ_DEF   I251 @BASEBOARD_FAB2_LIB.BASEBOARD_FAB2(SCH_1):PAGE220
     2    GND @BASEBOARD_FAB2_LIB.BASEBOARD_FAB2(SCH_1):GND   I251 @BASEBOARD_FAB2_LIB.BASEBOARD_FAB2(SCH_1):PAGE220

C5D3 CAP_A_0603V-22.0UF,4V,20%,X6S,A
     1 PVDDQ_DEF @BASEBOARD_FAB2_LIB.BASEBOARD_FAB2(SCH_1):PVDDQ_DEF   I250 @BASEBOARD_FAB2_LIB.BASEBOARD_FAB2(SCH_1):PAGE220
     2    GND @BASEBOARD_FAB2_LIB.BASEBOARD_FAB2(SCH_1):GND   I250 @BASEBOARD_FAB2_LIB.BASEBOARD_FAB2(SCH_1):PAGE220

C5D4 CAP_A_0603V-22.0UF,4V,20%,X6S,A
     1 PVDDQ_DEF @BASEBOARD_FAB2_LIB.BASEBOARD_FAB2(SCH_1):PVDDQ_DEF   I249 @BASEBOARD_FAB2_LIB.BASEBOARD_FAB2(SCH_1):PAGE220
     2    GND @BASEBOARD_FAB2_LIB.BASEBOARD_FAB2(SCH_1):GND   I249 @BASEBOARD_FAB2_LIB.BASEBOARD_FAB2(SCH_1):PAGE220

C5D5 CAP_A_0603V-22.0UF,4V,20%,X6S,A
     1 PVCCIN_CPU0 @BASEBOARD_FAB2_LIB.BASEBOARD_FAB2(SCH_1):PVCCIN_CPU0   I125 @BASEBOARD_FAB2_LIB.BASEBOARD_FAB2(SCH_1):PAGE42
     2    GND @BASEBOARD_FAB2_LIB.BASEBOARD_FAB2(SCH_1):GND   I125 @BASEBOARD_FAB2_LIB.BASEBOARD_FAB2(SCH_1):PAGE42

C5D6 CAP_A_0603V-22.0UF,4V,20%,X6S,A
     1 PVDDQ_DEF @BASEBOARD_FAB2_LIB.BASEBOARD_FAB2(SCH_1):PVDDQ_DEF   I259 @BASEBOARD_FAB2_LIB.BASEBOARD_FAB2(SCH_1):PAGE220
     2    GND @BASEBOARD_FAB2_LIB.BASEBOARD_FAB2(SCH_1):GND   I259 @BASEBOARD_FAB2_LIB.BASEBOARD_FAB2(SCH_1):PAGE220

C5D7 CAP_A_0603V-22.0UF,4V,20%,X6S,A
     1 PVDDQ_DEF @BASEBOARD_FAB2_LIB.BASEBOARD_FAB2(SCH_1):PVDDQ_DEF   I260 @BASEBOARD_FAB2_LIB.BASEBOARD_FAB2(SCH_1):PAGE220
     2    GND @BASEBOARD_FAB2_LIB.BASEBOARD_FAB2(SCH_1):GND   I260 @BASEBOARD_FAB2_LIB.BASEBOARD_FAB2(SCH_1):PAGE220

C5D8 CAP_A_0603V-22.0UF,4V,20%,X6S,A
     1 PVDDQ_DEF @BASEBOARD_FAB2_LIB.BASEBOARD_FAB2(SCH_1):PVDDQ_DEF   I261 @BASEBOARD_FAB2_LIB.BASEBOARD_FAB2(SCH_1):PAGE220
     2    GND @BASEBOARD_FAB2_LIB.BASEBOARD_FAB2(SCH_1):GND   I261 @BASEBOARD_FAB2_LIB.BASEBOARD_FAB2(SCH_1):PAGE220

C5D9 CAP_A_0603V-22.0UF,4V,20%,X6S,A
     1 PVDDQ_DEF @BASEBOARD_FAB2_LIB.BASEBOARD_FAB2(SCH_1):PVDDQ_DEF   I258 @BASEBOARD_FAB2_LIB.BASEBOARD_FAB2(SCH_1):PAGE220
     2    GND @BASEBOARD_FAB2_LIB.BASEBOARD_FAB2(SCH_1):GND   I258 @BASEBOARD_FAB2_LIB.BASEBOARD_FAB2(SCH_1):PAGE220

C5D10 CAP_0603LF-10UF,4V,20%,X6S,E15A
     1 PVSA_CPU0 @BASEBOARD_FAB2_LIB.BASEBOARD_FAB2(SCH_1):PVSA_CPU0   I108 @BASEBOARD_FAB2_LIB.BASEBOARD_FAB2(SCH_1):PAGE42
     2    GND @BASEBOARD_FAB2_LIB.BASEBOARD_FAB2(SCH_1):GND   I108 @BASEBOARD_FAB2_LIB.BASEBOARD_FAB2(SCH_1):PAGE42

C5D11 CAP_0603LF-10UF,4V,20%,X6S,E15A
     1 PVSA_CPU0 @BASEBOARD_FAB2_LIB.BASEBOARD_FAB2(SCH_1):PVSA_CPU0    I93 @BASEBOARD_FAB2_LIB.BASEBOARD_FAB2(SCH_1):PAGE42
     2    GND @BASEBOARD_FAB2_LIB.BASEBOARD_FAB2(SCH_1):GND    I93 @BASEBOARD_FAB2_LIB.BASEBOARD_FAB2(SCH_1):PAGE42

C5D12 CAP_0603LF-10UF,4V,20%,X6S,E15A
     1 PVSA_CPU0 @BASEBOARD_FAB2_LIB.BASEBOARD_FAB2(SCH_1):PVSA_CPU0    I94 @BASEBOARD_FAB2_LIB.BASEBOARD_FAB2(SCH_1):PAGE42
     2    GND @BASEBOARD_FAB2_LIB.BASEBOARD_FAB2(SCH_1):GND    I94 @BASEBOARD_FAB2_LIB.BASEBOARD_FAB2(SCH_1):PAGE42

C5D13 CAP_0603LF-10UF,4V,20%,X6S,E15A
     1 PVSA_CPU0 @BASEBOARD_FAB2_LIB.BASEBOARD_FAB2(SCH_1):PVSA_CPU0    I91 @BASEBOARD_FAB2_LIB.BASEBOARD_FAB2(SCH_1):PAGE42
     2    GND @BASEBOARD_FAB2_LIB.BASEBOARD_FAB2(SCH_1):GND    I91 @BASEBOARD_FAB2_LIB.BASEBOARD_FAB2(SCH_1):PAGE42

C5D14 CAP_A_0603V-22.0UF,4V,20%,X6S,A
     1 PVCCIN_CPU0 @BASEBOARD_FAB2_LIB.BASEBOARD_FAB2(SCH_1):PVCCIN_CPU0   I117 @BASEBOARD_FAB2_LIB.BASEBOARD_FAB2(SCH_1):PAGE42
     2    GND @BASEBOARD_FAB2_LIB.BASEBOARD_FAB2(SCH_1):GND   I117 @BASEBOARD_FAB2_LIB.BASEBOARD_FAB2(SCH_1):PAGE42

C5D15 CAP_A_0603V-22.0UF,4V,20%,X6S,A
     1 PVCCIN_CPU0 @BASEBOARD_FAB2_LIB.BASEBOARD_FAB2(SCH_1):PVCCIN_CPU0   I132 @BASEBOARD_FAB2_LIB.BASEBOARD_FAB2(SCH_1):PAGE42
     2    GND @BASEBOARD_FAB2_LIB.BASEBOARD_FAB2(SCH_1):GND   I132 @BASEBOARD_FAB2_LIB.BASEBOARD_FAB2(SCH_1):PAGE42

C5D16 CAP_A_0603V-22.0UF,4V,20%,X6S,A
     1 PVCCIN_CPU0 @BASEBOARD_FAB2_LIB.BASEBOARD_FAB2(SCH_1):PVCCIN_CPU0   I123 @BASEBOARD_FAB2_LIB.BASEBOARD_FAB2(SCH_1):PAGE42
     2    GND @BASEBOARD_FAB2_LIB.BASEBOARD_FAB2(SCH_1):GND   I123 @BASEBOARD_FAB2_LIB.BASEBOARD_FAB2(SCH_1):PAGE42

C5D17 CAP_A_0603V-22.0UF,4V,20%,X6S,A
     1 PVCCIN_CPU0 @BASEBOARD_FAB2_LIB.BASEBOARD_FAB2(SCH_1):PVCCIN_CPU0   I118 @BASEBOARD_FAB2_LIB.BASEBOARD_FAB2(SCH_1):PAGE42
     2    GND @BASEBOARD_FAB2_LIB.BASEBOARD_FAB2(SCH_1):GND   I118 @BASEBOARD_FAB2_LIB.BASEBOARD_FAB2(SCH_1):PAGE42

C5D18 CAP_A_0603V-22.0UF,4V,20%,X6S,A
     1 PVCCIN_CPU0 @BASEBOARD_FAB2_LIB.BASEBOARD_FAB2(SCH_1):PVCCIN_CPU0   I134 @BASEBOARD_FAB2_LIB.BASEBOARD_FAB2(SCH_1):PAGE42
     2    GND @BASEBOARD_FAB2_LIB.BASEBOARD_FAB2(SCH_1):GND   I134 @BASEBOARD_FAB2_LIB.BASEBOARD_FAB2(SCH_1):PAGE42

C5D19 CAP_A_0603V-22.0UF,4V,20%,X6S,A
     1 PVCCIN_CPU0 @BASEBOARD_FAB2_LIB.BASEBOARD_FAB2(SCH_1):PVCCIN_CPU0   I128 @BASEBOARD_FAB2_LIB.BASEBOARD_FAB2(SCH_1):PAGE42
     2    GND @BASEBOARD_FAB2_LIB.BASEBOARD_FAB2(SCH_1):GND   I128 @BASEBOARD_FAB2_LIB.BASEBOARD_FAB2(SCH_1):PAGE42

C5D20 CAP_A_0603V-22.0UF,4V,20%,X6S,A
     1 PVCCMCP_CPU0 @BASEBOARD_FAB2_LIB.BASEBOARD_FAB2(SCH_1):PVCCMCP_CPU0   I173 @BASEBOARD_FAB2_LIB.BASEBOARD_FAB2(SCH_1):PAGE42
     2    GND @BASEBOARD_FAB2_LIB.BASEBOARD_FAB2(SCH_1):GND   I173 @BASEBOARD_FAB2_LIB.BASEBOARD_FAB2(SCH_1):PAGE42

C5D21 CAP_A_0603V-22.0UF,4V,20%,X6S,A
     1 PVCCMCP_CPU0 @BASEBOARD_FAB2_LIB.BASEBOARD_FAB2(SCH_1):PVCCMCP_CPU0    I88 @BASEBOARD_FAB2_LIB.BASEBOARD_FAB2(SCH_1):PAGE42
     2    GND @BASEBOARD_FAB2_LIB.BASEBOARD_FAB2(SCH_1):GND    I88 @BASEBOARD_FAB2_LIB.BASEBOARD_FAB2(SCH_1):PAGE42

C5D22 CAP_A_0603V-22.0UF,4V,20%,X6S,A
     1 PVCCMCP_CPU0 @BASEBOARD_FAB2_LIB.BASEBOARD_FAB2(SCH_1):PVCCMCP_CPU0   I153 @BASEBOARD_FAB2_LIB.BASEBOARD_FAB2(SCH_1):PAGE42
     2    GND @BASEBOARD_FAB2_LIB.BASEBOARD_FAB2(SCH_1):GND   I153 @BASEBOARD_FAB2_LIB.BASEBOARD_FAB2(SCH_1):PAGE42

C5D23 CAP_A_0603V-22.0UF,4V,20%,X6S,A
     1 PVCCMCP_CPU0 @BASEBOARD_FAB2_LIB.BASEBOARD_FAB2(SCH_1):PVCCMCP_CPU0    I98 @BASEBOARD_FAB2_LIB.BASEBOARD_FAB2(SCH_1):PAGE42
     2    GND @BASEBOARD_FAB2_LIB.BASEBOARD_FAB2(SCH_1):GND    I98 @BASEBOARD_FAB2_LIB.BASEBOARD_FAB2(SCH_1):PAGE42

C5D24 CAP_A_0603V-22.0UF,4V,20%,X6S,A
     1 PVCCIN_CPU0 @BASEBOARD_FAB2_LIB.BASEBOARD_FAB2(SCH_1):PVCCIN_CPU0   I138 @BASEBOARD_FAB2_LIB.BASEBOARD_FAB2(SCH_1):PAGE42
     2    GND @BASEBOARD_FAB2_LIB.BASEBOARD_FAB2(SCH_1):GND   I138 @BASEBOARD_FAB2_LIB.BASEBOARD_FAB2(SCH_1):PAGE42

C5D25 CAP_A_0603V-22.0UF,4V,20%,X6S,A
     1 PVCCIN_CPU0 @BASEBOARD_FAB2_LIB.BASEBOARD_FAB2(SCH_1):PVCCIN_CPU0   I155 @BASEBOARD_FAB2_LIB.BASEBOARD_FAB2(SCH_1):PAGE42
     2    GND @BASEBOARD_FAB2_LIB.BASEBOARD_FAB2(SCH_1):GND   I155 @BASEBOARD_FAB2_LIB.BASEBOARD_FAB2(SCH_1):PAGE42

C5D26 CAP_A_0603V-22.0UF,4V,20%,X6S,A
     1 PVCCIN_CPU0 @BASEBOARD_FAB2_LIB.BASEBOARD_FAB2(SCH_1):PVCCIN_CPU0   I154 @BASEBOARD_FAB2_LIB.BASEBOARD_FAB2(SCH_1):PAGE42
     2    GND @BASEBOARD_FAB2_LIB.BASEBOARD_FAB2(SCH_1):GND   I154 @BASEBOARD_FAB2_LIB.BASEBOARD_FAB2(SCH_1):PAGE42

C5D27 CAP_A_0603V-22.0UF,4V,20%,X6S,A
     1 PVCCIN_CPU0 @BASEBOARD_FAB2_LIB.BASEBOARD_FAB2(SCH_1):PVCCIN_CPU0   I109 @BASEBOARD_FAB2_LIB.BASEBOARD_FAB2(SCH_1):PAGE42
     2    GND @BASEBOARD_FAB2_LIB.BASEBOARD_FAB2(SCH_1):GND   I109 @BASEBOARD_FAB2_LIB.BASEBOARD_FAB2(SCH_1):PAGE42

C5D28 CAP_A_0603V-22.0UF,4V,20%,X6S,A
     1 PVCCIN_CPU0 @BASEBOARD_FAB2_LIB.BASEBOARD_FAB2(SCH_1):PVCCIN_CPU0   I100 @BASEBOARD_FAB2_LIB.BASEBOARD_FAB2(SCH_1):PAGE42
     2    GND @BASEBOARD_FAB2_LIB.BASEBOARD_FAB2(SCH_1):GND   I100 @BASEBOARD_FAB2_LIB.BASEBOARD_FAB2(SCH_1):PAGE42

C5D29 CAP_A_0603V-22.0UF,4V,20%,X6S,A
     1 PVCCIN_CPU0 @BASEBOARD_FAB2_LIB.BASEBOARD_FAB2(SCH_1):PVCCIN_CPU0   I102 @BASEBOARD_FAB2_LIB.BASEBOARD_FAB2(SCH_1):PAGE42
     2    GND @BASEBOARD_FAB2_LIB.BASEBOARD_FAB2(SCH_1):GND   I102 @BASEBOARD_FAB2_LIB.BASEBOARD_FAB2(SCH_1):PAGE42

C5D30 CAP_A_0603V-22.0UF,4V,20%,X6S,A
     1 PVCCIN_CPU0 @BASEBOARD_FAB2_LIB.BASEBOARD_FAB2(SCH_1):PVCCIN_CPU0   I111 @BASEBOARD_FAB2_LIB.BASEBOARD_FAB2(SCH_1):PAGE42
     2    GND @BASEBOARD_FAB2_LIB.BASEBOARD_FAB2(SCH_1):GND   I111 @BASEBOARD_FAB2_LIB.BASEBOARD_FAB2(SCH_1):PAGE42

C5D31 CAP_A_0603V-22.0UF,4V,20%,X6S,A
     1 PVCCIN_CPU0 @BASEBOARD_FAB2_LIB.BASEBOARD_FAB2(SCH_1):PVCCIN_CPU0   I106 @BASEBOARD_FAB2_LIB.BASEBOARD_FAB2(SCH_1):PAGE42
     2    GND @BASEBOARD_FAB2_LIB.BASEBOARD_FAB2(SCH_1):GND   I106 @BASEBOARD_FAB2_LIB.BASEBOARD_FAB2(SCH_1):PAGE42

C5D32 CAP_A_0603V-22.0UF,4V,20%,X6S,A
     1 PVCCIN_CPU0 @BASEBOARD_FAB2_LIB.BASEBOARD_FAB2(SCH_1):PVCCIN_CPU0   I103 @BASEBOARD_FAB2_LIB.BASEBOARD_FAB2(SCH_1):PAGE42
     2    GND @BASEBOARD_FAB2_LIB.BASEBOARD_FAB2(SCH_1):GND   I103 @BASEBOARD_FAB2_LIB.BASEBOARD_FAB2(SCH_1):PAGE42

C5D33 CAP_A_0603V-22.0UF,4V,20%,X6S,A
     1 PVCCMCP_CPU0 @BASEBOARD_FAB2_LIB.BASEBOARD_FAB2(SCH_1):PVCCMCP_CPU0   I174 @BASEBOARD_FAB2_LIB.BASEBOARD_FAB2(SCH_1):PAGE42
     2    GND @BASEBOARD_FAB2_LIB.BASEBOARD_FAB2(SCH_1):GND   I174 @BASEBOARD_FAB2_LIB.BASEBOARD_FAB2(SCH_1):PAGE42

C5D34 CAP_A_0603V-22.0UF,4V,20%,X6S,A
     1 PVCCMCP_CPU0 @BASEBOARD_FAB2_LIB.BASEBOARD_FAB2(SCH_1):PVCCMCP_CPU0   I175 @BASEBOARD_FAB2_LIB.BASEBOARD_FAB2(SCH_1):PAGE42
     2    GND @BASEBOARD_FAB2_LIB.BASEBOARD_FAB2(SCH_1):GND   I175 @BASEBOARD_FAB2_LIB.BASEBOARD_FAB2(SCH_1):PAGE42

C5D35 CAP_A_0603V-22.0UF,4V,20%,X6S,A
     1 PVCCMCP_CPU0 @BASEBOARD_FAB2_LIB.BASEBOARD_FAB2(SCH_1):PVCCMCP_CPU0   I176 @BASEBOARD_FAB2_LIB.BASEBOARD_FAB2(SCH_1):PAGE42
     2    GND @BASEBOARD_FAB2_LIB.BASEBOARD_FAB2(SCH_1):GND   I176 @BASEBOARD_FAB2_LIB.BASEBOARD_FAB2(SCH_1):PAGE42

C5D36 CAP_A_0603V-22.0UF,4V,20%,X6S,A
     1 PVCCMCP_CPU0 @BASEBOARD_FAB2_LIB.BASEBOARD_FAB2(SCH_1):PVCCMCP_CPU0   I151 @BASEBOARD_FAB2_LIB.BASEBOARD_FAB2(SCH_1):PAGE42
     2    GND @BASEBOARD_FAB2_LIB.BASEBOARD_FAB2(SCH_1):GND   I151 @BASEBOARD_FAB2_LIB.BASEBOARD_FAB2(SCH_1):PAGE42

C5D37 CAP_A_0603V-22.0UF,4V,20%,X6S,A
     1 PVCCMCP_CPU0 @BASEBOARD_FAB2_LIB.BASEBOARD_FAB2(SCH_1):PVCCMCP_CPU0    I70 @BASEBOARD_FAB2_LIB.BASEBOARD_FAB2(SCH_1):PAGE42
     2    GND @BASEBOARD_FAB2_LIB.BASEBOARD_FAB2(SCH_1):GND    I70 @BASEBOARD_FAB2_LIB.BASEBOARD_FAB2(SCH_1):PAGE42

C5D38 CAP_A_0603V-22.0UF,4V,20%,X6S,A
     1 PVCCMCP_CPU0 @BASEBOARD_FAB2_LIB.BASEBOARD_FAB2(SCH_1):PVCCMCP_CPU0    I69 @BASEBOARD_FAB2_LIB.BASEBOARD_FAB2(SCH_1):PAGE42
     2    GND @BASEBOARD_FAB2_LIB.BASEBOARD_FAB2(SCH_1):GND    I69 @BASEBOARD_FAB2_LIB.BASEBOARD_FAB2(SCH_1):PAGE42

C5D39 CAP_A_0603V-22.0UF,4V,20%,X6S,A
     1 PVCCIN_CPU0 @BASEBOARD_FAB2_LIB.BASEBOARD_FAB2(SCH_1):PVCCIN_CPU0   I140 @BASEBOARD_FAB2_LIB.BASEBOARD_FAB2(SCH_1):PAGE42
     2    GND @BASEBOARD_FAB2_LIB.BASEBOARD_FAB2(SCH_1):GND   I140 @BASEBOARD_FAB2_LIB.BASEBOARD_FAB2(SCH_1):PAGE42

C5D40 CAP_A_0603V-22.0UF,4V,20%,X6S,A
     1 PVCCIN_CPU0 @BASEBOARD_FAB2_LIB.BASEBOARD_FAB2(SCH_1):PVCCIN_CPU0   I115 @BASEBOARD_FAB2_LIB.BASEBOARD_FAB2(SCH_1):PAGE42
     2    GND @BASEBOARD_FAB2_LIB.BASEBOARD_FAB2(SCH_1):GND   I115 @BASEBOARD_FAB2_LIB.BASEBOARD_FAB2(SCH_1):PAGE42

C5D41 CAP_A_0603V-22.0UF,4V,20%,X6S,A
     1 PVCCIN_CPU0 @BASEBOARD_FAB2_LIB.BASEBOARD_FAB2(SCH_1):PVCCIN_CPU0   I114 @BASEBOARD_FAB2_LIB.BASEBOARD_FAB2(SCH_1):PAGE42
     2    GND @BASEBOARD_FAB2_LIB.BASEBOARD_FAB2(SCH_1):GND   I114 @BASEBOARD_FAB2_LIB.BASEBOARD_FAB2(SCH_1):PAGE42

C5D42 CAP_A_0603V-22.0UF,4V,20%,X6S,A
     1 PVCCIN_CPU0 @BASEBOARD_FAB2_LIB.BASEBOARD_FAB2(SCH_1):PVCCIN_CPU0   I135 @BASEBOARD_FAB2_LIB.BASEBOARD_FAB2(SCH_1):PAGE42
     2    GND @BASEBOARD_FAB2_LIB.BASEBOARD_FAB2(SCH_1):GND   I135 @BASEBOARD_FAB2_LIB.BASEBOARD_FAB2(SCH_1):PAGE42

C5D43 CAP_A_0603V-22.0UF,4V,20%,X6S,A
     1 PVCCIN_CPU0 @BASEBOARD_FAB2_LIB.BASEBOARD_FAB2(SCH_1):PVCCIN_CPU0   I131 @BASEBOARD_FAB2_LIB.BASEBOARD_FAB2(SCH_1):PAGE42
     2    GND @BASEBOARD_FAB2_LIB.BASEBOARD_FAB2(SCH_1):GND   I131 @BASEBOARD_FAB2_LIB.BASEBOARD_FAB2(SCH_1):PAGE42

C5D44 CAP_A_0603V-22.0UF,4V,20%,X6S,A
     1 PVCCIN_CPU0 @BASEBOARD_FAB2_LIB.BASEBOARD_FAB2(SCH_1):PVCCIN_CPU0   I142 @BASEBOARD_FAB2_LIB.BASEBOARD_FAB2(SCH_1):PAGE42
     2    GND @BASEBOARD_FAB2_LIB.BASEBOARD_FAB2(SCH_1):GND   I142 @BASEBOARD_FAB2_LIB.BASEBOARD_FAB2(SCH_1):PAGE42

C5D45 CAP_A_0603V-22.0UF,4V,20%,X6S,A
     1 PVCCIN_CPU0 @BASEBOARD_FAB2_LIB.BASEBOARD_FAB2(SCH_1):PVCCIN_CPU0   I156 @BASEBOARD_FAB2_LIB.BASEBOARD_FAB2(SCH_1):PAGE42
     2    GND @BASEBOARD_FAB2_LIB.BASEBOARD_FAB2(SCH_1):GND   I156 @BASEBOARD_FAB2_LIB.BASEBOARD_FAB2(SCH_1):PAGE42

C5D46 CAP_A_0603V-22.0UF,4V,20%,X6S,A
     1 PVCCIN_CPU0 @BASEBOARD_FAB2_LIB.BASEBOARD_FAB2(SCH_1):PVCCIN_CPU0   I107 @BASEBOARD_FAB2_LIB.BASEBOARD_FAB2(SCH_1):PAGE42
     2    GND @BASEBOARD_FAB2_LIB.BASEBOARD_FAB2(SCH_1):GND   I107 @BASEBOARD_FAB2_LIB.BASEBOARD_FAB2(SCH_1):PAGE42

C5D47 CAP_A_0603V-22.0UF,4V,20%,X6S,A
     1 PVCCIN_CPU0 @BASEBOARD_FAB2_LIB.BASEBOARD_FAB2(SCH_1):PVCCIN_CPU0   I104 @BASEBOARD_FAB2_LIB.BASEBOARD_FAB2(SCH_1):PAGE42
     2    GND @BASEBOARD_FAB2_LIB.BASEBOARD_FAB2(SCH_1):GND   I104 @BASEBOARD_FAB2_LIB.BASEBOARD_FAB2(SCH_1):PAGE42

C5D48 CAP_A_0603V-22.0UF,4V,20%,X6S,A
     1 PVCCMCP_CPU0 @BASEBOARD_FAB2_LIB.BASEBOARD_FAB2(SCH_1):PVCCMCP_CPU0    I90 @BASEBOARD_FAB2_LIB.BASEBOARD_FAB2(SCH_1):PAGE42
     2    GND @BASEBOARD_FAB2_LIB.BASEBOARD_FAB2(SCH_1):GND    I90 @BASEBOARD_FAB2_LIB.BASEBOARD_FAB2(SCH_1):PAGE42

C5D49 CAP_A_0603V-22.0UF,4V,20%,X6S,A
     1 PVCCMCP_CPU0 @BASEBOARD_FAB2_LIB.BASEBOARD_FAB2(SCH_1):PVCCMCP_CPU0   I152 @BASEBOARD_FAB2_LIB.BASEBOARD_FAB2(SCH_1):PAGE42
     2    GND @BASEBOARD_FAB2_LIB.BASEBOARD_FAB2(SCH_1):GND   I152 @BASEBOARD_FAB2_LIB.BASEBOARD_FAB2(SCH_1):PAGE42

C5D50 CAP_A_0603V-22.0UF,4V,20%,X6S,A
     1 PVCCMCP_CPU0 @BASEBOARD_FAB2_LIB.BASEBOARD_FAB2(SCH_1):PVCCMCP_CPU0    I89 @BASEBOARD_FAB2_LIB.BASEBOARD_FAB2(SCH_1):PAGE42
     2    GND @BASEBOARD_FAB2_LIB.BASEBOARD_FAB2(SCH_1):GND    I89 @BASEBOARD_FAB2_LIB.BASEBOARD_FAB2(SCH_1):PAGE42

C5D51 CAP_A_0603V-22.0UF,4V,20%,X6S,A
     1 PVCCMCP_CPU0 @BASEBOARD_FAB2_LIB.BASEBOARD_FAB2(SCH_1):PVCCMCP_CPU0    I83 @BASEBOARD_FAB2_LIB.BASEBOARD_FAB2(SCH_1):PAGE42
     2    GND @BASEBOARD_FAB2_LIB.BASEBOARD_FAB2(SCH_1):GND    I83 @BASEBOARD_FAB2_LIB.BASEBOARD_FAB2(SCH_1):PAGE42

C5D52 CAP_A_0603V-22.0UF,4V,20%,X6S,A
     1 PVCCMCP_CPU0 @BASEBOARD_FAB2_LIB.BASEBOARD_FAB2(SCH_1):PVCCMCP_CPU0   I180 @BASEBOARD_FAB2_LIB.BASEBOARD_FAB2(SCH_1):PAGE42
     2    GND @BASEBOARD_FAB2_LIB.BASEBOARD_FAB2(SCH_1):GND   I180 @BASEBOARD_FAB2_LIB.BASEBOARD_FAB2(SCH_1):PAGE42

C5D53 CAP_A_0603V-22.0UF,4V,20%,X6S,A
     1 PVCCMCP_CPU0 @BASEBOARD_FAB2_LIB.BASEBOARD_FAB2(SCH_1):PVCCMCP_CPU0   I179 @BASEBOARD_FAB2_LIB.BASEBOARD_FAB2(SCH_1):PAGE42
     2    GND @BASEBOARD_FAB2_LIB.BASEBOARD_FAB2(SCH_1):GND   I179 @BASEBOARD_FAB2_LIB.BASEBOARD_FAB2(SCH_1):PAGE42

C5D54 CAP_A_0603V-22.0UF,4V,20%,X6S,A
     1 PVDDQ_ABC @BASEBOARD_FAB2_LIB.BASEBOARD_FAB2(SCH_1):PVDDQ_ABC   I279 @BASEBOARD_FAB2_LIB.BASEBOARD_FAB2(SCH_1):PAGE217
     2    GND @BASEBOARD_FAB2_LIB.BASEBOARD_FAB2(SCH_1):GND   I279 @BASEBOARD_FAB2_LIB.BASEBOARD_FAB2(SCH_1):PAGE217

C5D55 CAP_A_0603V-22.0UF,4V,20%,X6S,A
     1 PVDDQ_ABC @BASEBOARD_FAB2_LIB.BASEBOARD_FAB2(SCH_1):PVDDQ_ABC   I280 @BASEBOARD_FAB2_LIB.BASEBOARD_FAB2(SCH_1):PAGE217
     2    GND @BASEBOARD_FAB2_LIB.BASEBOARD_FAB2(SCH_1):GND   I280 @BASEBOARD_FAB2_LIB.BASEBOARD_FAB2(SCH_1):PAGE217

C5D56 CAP_A_0603V-22.0UF,4V,20%,X6S,A
     1 PVDDQ_ABC @BASEBOARD_FAB2_LIB.BASEBOARD_FAB2(SCH_1):PVDDQ_ABC   I281 @BASEBOARD_FAB2_LIB.BASEBOARD_FAB2(SCH_1):PAGE217
     2    GND @BASEBOARD_FAB2_LIB.BASEBOARD_FAB2(SCH_1):GND   I281 @BASEBOARD_FAB2_LIB.BASEBOARD_FAB2(SCH_1):PAGE217

C5D57 CAP_A_0603V-22.0UF,4V,20%,X6S,A
     1 PVDDQ_ABC @BASEBOARD_FAB2_LIB.BASEBOARD_FAB2(SCH_1):PVDDQ_ABC   I282 @BASEBOARD_FAB2_LIB.BASEBOARD_FAB2(SCH_1):PAGE217
     2    GND @BASEBOARD_FAB2_LIB.BASEBOARD_FAB2(SCH_1):GND   I282 @BASEBOARD_FAB2_LIB.BASEBOARD_FAB2(SCH_1):PAGE217

C5D58 CAP_A_0603V-22.0UF,4V,20%,X6S,A
     1 PVDDQ_ABC @BASEBOARD_FAB2_LIB.BASEBOARD_FAB2(SCH_1):PVDDQ_ABC   I269 @BASEBOARD_FAB2_LIB.BASEBOARD_FAB2(SCH_1):PAGE217
     2    GND @BASEBOARD_FAB2_LIB.BASEBOARD_FAB2(SCH_1):GND   I269 @BASEBOARD_FAB2_LIB.BASEBOARD_FAB2(SCH_1):PAGE217

C5D59 CAP_A_0603V-22.0UF,4V,20%,X6S,A
     1 PVDDQ_ABC @BASEBOARD_FAB2_LIB.BASEBOARD_FAB2(SCH_1):PVDDQ_ABC   I271 @BASEBOARD_FAB2_LIB.BASEBOARD_FAB2(SCH_1):PAGE217
     2    GND @BASEBOARD_FAB2_LIB.BASEBOARD_FAB2(SCH_1):GND   I271 @BASEBOARD_FAB2_LIB.BASEBOARD_FAB2(SCH_1):PAGE217

C5D60 CAP_A_0603V-22.0UF,4V,20%,X6S,A
     1 PVDDQ_ABC @BASEBOARD_FAB2_LIB.BASEBOARD_FAB2(SCH_1):PVDDQ_ABC   I272 @BASEBOARD_FAB2_LIB.BASEBOARD_FAB2(SCH_1):PAGE217
     2    GND @BASEBOARD_FAB2_LIB.BASEBOARD_FAB2(SCH_1):GND   I272 @BASEBOARD_FAB2_LIB.BASEBOARD_FAB2(SCH_1):PAGE217

C5D61 CAP_A_0603V-22.0UF,4V,20%,X6S,A
     1 PVDDQ_ABC @BASEBOARD_FAB2_LIB.BASEBOARD_FAB2(SCH_1):PVDDQ_ABC   I270 @BASEBOARD_FAB2_LIB.BASEBOARD_FAB2(SCH_1):PAGE217
     2    GND @BASEBOARD_FAB2_LIB.BASEBOARD_FAB2(SCH_1):GND   I270 @BASEBOARD_FAB2_LIB.BASEBOARD_FAB2(SCH_1):PAGE217

C5F1 CAP_A_0603V-47UF,4V,20%,X5R,60A
     1 PVDDQ_ABC @BASEBOARD_FAB2_LIB.BASEBOARD_FAB2(SCH_1):PVDDQ_ABC   I206 @BASEBOARD_FAB2_LIB.BASEBOARD_FAB2(SCH_1):PAGE217
     2    GND @BASEBOARD_FAB2_LIB.BASEBOARD_FAB2(SCH_1):GND   I206 @BASEBOARD_FAB2_LIB.BASEBOARD_FAB2(SCH_1):PAGE217

C5F2 CAP_A_0603V-47UF,4V,20%,X5R,60A
     1 PVDDQ_ABC @BASEBOARD_FAB2_LIB.BASEBOARD_FAB2(SCH_1):PVDDQ_ABC   I205 @BASEBOARD_FAB2_LIB.BASEBOARD_FAB2(SCH_1):PAGE217
     2    GND @BASEBOARD_FAB2_LIB.BASEBOARD_FAB2(SCH_1):GND   I205 @BASEBOARD_FAB2_LIB.BASEBOARD_FAB2(SCH_1):PAGE217

C5G1 CAP_A_0603V-47UF,4V,20%,X5R,60A
     1 PVDDQ_ABC @BASEBOARD_FAB2_LIB.BASEBOARD_FAB2(SCH_1):PVDDQ_ABC   I307 @BASEBOARD_FAB2_LIB.BASEBOARD_FAB2(SCH_1):PAGE217
     2    GND @BASEBOARD_FAB2_LIB.BASEBOARD_FAB2(SCH_1):GND   I307 @BASEBOARD_FAB2_LIB.BASEBOARD_FAB2(SCH_1):PAGE217

C5G2 CAP_A_0603V-47UF,4V,20%,X5R,60A
     1 PVDDQ_ABC @BASEBOARD_FAB2_LIB.BASEBOARD_FAB2(SCH_1):PVDDQ_ABC   I301 @BASEBOARD_FAB2_LIB.BASEBOARD_FAB2(SCH_1):PAGE217
     2    GND @BASEBOARD_FAB2_LIB.BASEBOARD_FAB2(SCH_1):GND   I301 @BASEBOARD_FAB2_LIB.BASEBOARD_FAB2(SCH_1):PAGE217

C5G3 CAP_A_0603V-47UF,4V,20%,X5R,60A
     1 PVDDQ_ABC @BASEBOARD_FAB2_LIB.BASEBOARD_FAB2(SCH_1):PVDDQ_ABC   I314 @BASEBOARD_FAB2_LIB.BASEBOARD_FAB2(SCH_1):PAGE217
     2    GND @BASEBOARD_FAB2_LIB.BASEBOARD_FAB2(SCH_1):GND   I314 @BASEBOARD_FAB2_LIB.BASEBOARD_FAB2(SCH_1):PAGE217

C5G4 CAP_A_0603V-47UF,4V,20%,X5R,60A
     1 PVDDQ_ABC @BASEBOARD_FAB2_LIB.BASEBOARD_FAB2(SCH_1):PVDDQ_ABC   I302 @BASEBOARD_FAB2_LIB.BASEBOARD_FAB2(SCH_1):PAGE217
     2    GND @BASEBOARD_FAB2_LIB.BASEBOARD_FAB2(SCH_1):GND   I302 @BASEBOARD_FAB2_LIB.BASEBOARD_FAB2(SCH_1):PAGE217

C5G5 CAP_A_0603V-47UF,4V,20%,X5R,60A
     1 PVDDQ_ABC @BASEBOARD_FAB2_LIB.BASEBOARD_FAB2(SCH_1):PVDDQ_ABC   I305 @BASEBOARD_FAB2_LIB.BASEBOARD_FAB2(SCH_1):PAGE217
     2    GND @BASEBOARD_FAB2_LIB.BASEBOARD_FAB2(SCH_1):GND   I305 @BASEBOARD_FAB2_LIB.BASEBOARD_FAB2(SCH_1):PAGE217

C5G6 CAP_A_0603V-47UF,4V,20%,X5R,60A
     1 PVDDQ_ABC @BASEBOARD_FAB2_LIB.BASEBOARD_FAB2(SCH_1):PVDDQ_ABC   I304 @BASEBOARD_FAB2_LIB.BASEBOARD_FAB2(SCH_1):PAGE217
     2    GND @BASEBOARD_FAB2_LIB.BASEBOARD_FAB2(SCH_1):GND   I304 @BASEBOARD_FAB2_LIB.BASEBOARD_FAB2(SCH_1):PAGE217

C5G7 CAP_A_0603V-47UF,4V,20%,X5R,60A
     1 PVDDQ_ABC @BASEBOARD_FAB2_LIB.BASEBOARD_FAB2(SCH_1):PVDDQ_ABC   I306 @BASEBOARD_FAB2_LIB.BASEBOARD_FAB2(SCH_1):PAGE217
     2    GND @BASEBOARD_FAB2_LIB.BASEBOARD_FAB2(SCH_1):GND   I306 @BASEBOARD_FAB2_LIB.BASEBOARD_FAB2(SCH_1):PAGE217

C5G8 CAP_A_0603V-47UF,4V,20%,X5R,60A
     1 PVDDQ_ABC @BASEBOARD_FAB2_LIB.BASEBOARD_FAB2(SCH_1):PVDDQ_ABC   I308 @BASEBOARD_FAB2_LIB.BASEBOARD_FAB2(SCH_1):PAGE217
     2    GND @BASEBOARD_FAB2_LIB.BASEBOARD_FAB2(SCH_1):GND   I308 @BASEBOARD_FAB2_LIB.BASEBOARD_FAB2(SCH_1):PAGE217

C5G9 CAP_0805-100UF,4V,20%,X5R,6024A
     1 PVDDQ_ABC @BASEBOARD_FAB2_LIB.BASEBOARD_FAB2(SCH_1):PVDDQ_ABC   I318 @BASEBOARD_FAB2_LIB.BASEBOARD_FAB2(SCH_1):PAGE217
     2    GND @BASEBOARD_FAB2_LIB.BASEBOARD_FAB2(SCH_1):GND   I318 @BASEBOARD_FAB2_LIB.BASEBOARD_FAB2(SCH_1):PAGE217

C5G10 CAP_A_0603V-47UF,4V,20%,X5R,60A
     1 PVDDQ_ABC @BASEBOARD_FAB2_LIB.BASEBOARD_FAB2(SCH_1):PVDDQ_ABC   I207 @BASEBOARD_FAB2_LIB.BASEBOARD_FAB2(SCH_1):PAGE217
     2    GND @BASEBOARD_FAB2_LIB.BASEBOARD_FAB2(SCH_1):GND   I207 @BASEBOARD_FAB2_LIB.BASEBOARD_FAB2(SCH_1):PAGE217

C5G11 CAP_A_0603V-47UF,4V,20%,X5R,60A
     1 PVDDQ_ABC @BASEBOARD_FAB2_LIB.BASEBOARD_FAB2(SCH_1):PVDDQ_ABC   I299 @BASEBOARD_FAB2_LIB.BASEBOARD_FAB2(SCH_1):PAGE217
     2    GND @BASEBOARD_FAB2_LIB.BASEBOARD_FAB2(SCH_1):GND   I299 @BASEBOARD_FAB2_LIB.BASEBOARD_FAB2(SCH_1):PAGE217

C5G12 CAP_A_0603V-47UF,4V,20%,X5R,60A
     1 PVDDQ_ABC @BASEBOARD_FAB2_LIB.BASEBOARD_FAB2(SCH_1):PVDDQ_ABC   I300 @BASEBOARD_FAB2_LIB.BASEBOARD_FAB2(SCH_1):PAGE217
     2    GND @BASEBOARD_FAB2_LIB.BASEBOARD_FAB2(SCH_1):GND   I300 @BASEBOARD_FAB2_LIB.BASEBOARD_FAB2(SCH_1):PAGE217

C5G13 CAP_A_0603V-47UF,4V,20%,X5R,60A
     1 PVDDQ_ABC @BASEBOARD_FAB2_LIB.BASEBOARD_FAB2(SCH_1):PVDDQ_ABC   I303 @BASEBOARD_FAB2_LIB.BASEBOARD_FAB2(SCH_1):PAGE217
     2    GND @BASEBOARD_FAB2_LIB.BASEBOARD_FAB2(SCH_1):GND   I303 @BASEBOARD_FAB2_LIB.BASEBOARD_FAB2(SCH_1):PAGE217

C5G14 CAP_A_0603V-47UF,4V,20%,X5R,60A
     1 PVDDQ_ABC @BASEBOARD_FAB2_LIB.BASEBOARD_FAB2(SCH_1):PVDDQ_ABC   I311 @BASEBOARD_FAB2_LIB.BASEBOARD_FAB2(SCH_1):PAGE217
     2    GND @BASEBOARD_FAB2_LIB.BASEBOARD_FAB2(SCH_1):GND   I311 @BASEBOARD_FAB2_LIB.BASEBOARD_FAB2(SCH_1):PAGE217

C5G15 CAP_A_0603V-47UF,4V,20%,X5R,60A
     1 PVDDQ_ABC @BASEBOARD_FAB2_LIB.BASEBOARD_FAB2(SCH_1):PVDDQ_ABC   I313 @BASEBOARD_FAB2_LIB.BASEBOARD_FAB2(SCH_1):PAGE217
     2    GND @BASEBOARD_FAB2_LIB.BASEBOARD_FAB2(SCH_1):GND   I313 @BASEBOARD_FAB2_LIB.BASEBOARD_FAB2(SCH_1):PAGE217

C5G16 CAP_A_0603V-47UF,4V,20%,X5R,60A
     1 PVDDQ_ABC @BASEBOARD_FAB2_LIB.BASEBOARD_FAB2(SCH_1):PVDDQ_ABC   I312 @BASEBOARD_FAB2_LIB.BASEBOARD_FAB2(SCH_1):PAGE217
     2    GND @BASEBOARD_FAB2_LIB.BASEBOARD_FAB2(SCH_1):GND   I312 @BASEBOARD_FAB2_LIB.BASEBOARD_FAB2(SCH_1):PAGE217

C5G17 CAP_A_0603V-47UF,4V,20%,X5R,60A
     1 PVDDQ_ABC @BASEBOARD_FAB2_LIB.BASEBOARD_FAB2(SCH_1):PVDDQ_ABC   I310 @BASEBOARD_FAB2_LIB.BASEBOARD_FAB2(SCH_1):PAGE217
     2    GND @BASEBOARD_FAB2_LIB.BASEBOARD_FAB2(SCH_1):GND   I310 @BASEBOARD_FAB2_LIB.BASEBOARD_FAB2(SCH_1):PAGE217

C5G18 CAP_A_0603V-47UF,4V,20%,X5R,60A
     1 PVDDQ_ABC @BASEBOARD_FAB2_LIB.BASEBOARD_FAB2(SCH_1):PVDDQ_ABC   I309 @BASEBOARD_FAB2_LIB.BASEBOARD_FAB2(SCH_1):PAGE217
     2    GND @BASEBOARD_FAB2_LIB.BASEBOARD_FAB2(SCH_1):GND   I309 @BASEBOARD_FAB2_LIB.BASEBOARD_FAB2(SCH_1):PAGE217

C5G19 CAP_A_0603V-47UF,4V,20%,X5R,60A
     1 PVDDQ_ABC @BASEBOARD_FAB2_LIB.BASEBOARD_FAB2(SCH_1):PVDDQ_ABC   I213 @BASEBOARD_FAB2_LIB.BASEBOARD_FAB2(SCH_1):PAGE217
     2    GND @BASEBOARD_FAB2_LIB.BASEBOARD_FAB2(SCH_1):GND   I213 @BASEBOARD_FAB2_LIB.BASEBOARD_FAB2(SCH_1):PAGE217

C5G20 CAP_0805-100UF,4V,20%,X5R,6024A
     1 PVDDQ_ABC @BASEBOARD_FAB2_LIB.BASEBOARD_FAB2(SCH_1):PVDDQ_ABC   I329 @BASEBOARD_FAB2_LIB.BASEBOARD_FAB2(SCH_1):PAGE217
     2    GND @BASEBOARD_FAB2_LIB.BASEBOARD_FAB2(SCH_1):GND   I329 @BASEBOARD_FAB2_LIB.BASEBOARD_FAB2(SCH_1):PAGE217

C5G21 CAP_0805-47UF,4V,20%,X6S,C9533A
     1 PVDDQ_ABC @BASEBOARD_FAB2_LIB.BASEBOARD_FAB2(SCH_1):PVDDQ_ABC    I92 @BASEBOARD_FAB2_LIB.BASEBOARD_FAB2(SCH_1):PAGE242
     2    GND @BASEBOARD_FAB2_LIB.BASEBOARD_FAB2(SCH_1):GND    I92 @BASEBOARD_FAB2_LIB.BASEBOARD_FAB2(SCH_1):PAGE242

C5G22 CAP_0805-47UF,4V,20%,X6S,C9533A
     1 PVDDQ_ABC @BASEBOARD_FAB2_LIB.BASEBOARD_FAB2(SCH_1):PVDDQ_ABC    I90 @BASEBOARD_FAB2_LIB.BASEBOARD_FAB2(SCH_1):PAGE242
     2    GND @BASEBOARD_FAB2_LIB.BASEBOARD_FAB2(SCH_1):GND    I90 @BASEBOARD_FAB2_LIB.BASEBOARD_FAB2(SCH_1):PAGE242

C5G41 CAP_A_0603V-22.0UF,4V,20%,X6S,A
     1 PVDDQ_ABC @BASEBOARD_FAB2_LIB.BASEBOARD_FAB2(SCH_1):PVDDQ_ABC    I53 @BASEBOARD_FAB2_LIB.BASEBOARD_FAB2(SCH_1):PAGE242
     2    GND @BASEBOARD_FAB2_LIB.BASEBOARD_FAB2(SCH_1):GND    I53 @BASEBOARD_FAB2_LIB.BASEBOARD_FAB2(SCH_1):PAGE242

C5G42 CAP_A_0603V-22.0UF,4V,20%,X6S,A
     1 PVDDQ_ABC @BASEBOARD_FAB2_LIB.BASEBOARD_FAB2(SCH_1):PVDDQ_ABC    I54 @BASEBOARD_FAB2_LIB.BASEBOARD_FAB2(SCH_1):PAGE242
     2    GND @BASEBOARD_FAB2_LIB.BASEBOARD_FAB2(SCH_1):GND    I54 @BASEBOARD_FAB2_LIB.BASEBOARD_FAB2(SCH_1):PAGE242

C5G43 CAP_A_0603V-22.0UF,4V,20%,X6S,A
     1 PVDDQ_ABC @BASEBOARD_FAB2_LIB.BASEBOARD_FAB2(SCH_1):PVDDQ_ABC    I56 @BASEBOARD_FAB2_LIB.BASEBOARD_FAB2(SCH_1):PAGE242
     2    GND @BASEBOARD_FAB2_LIB.BASEBOARD_FAB2(SCH_1):GND    I56 @BASEBOARD_FAB2_LIB.BASEBOARD_FAB2(SCH_1):PAGE242

C5G44 CAP_A_0603V-22.0UF,4V,20%,X6S,A
     1 PVDDQ_ABC @BASEBOARD_FAB2_LIB.BASEBOARD_FAB2(SCH_1):PVDDQ_ABC    I55 @BASEBOARD_FAB2_LIB.BASEBOARD_FAB2(SCH_1):PAGE242
     2    GND @BASEBOARD_FAB2_LIB.BASEBOARD_FAB2(SCH_1):GND    I55 @BASEBOARD_FAB2_LIB.BASEBOARD_FAB2(SCH_1):PAGE242

C5G45 CAP_A_0603V-22.0UF,4V,20%,X6S,A
     1 PVDDQ_ABC @BASEBOARD_FAB2_LIB.BASEBOARD_FAB2(SCH_1):PVDDQ_ABC    I60 @BASEBOARD_FAB2_LIB.BASEBOARD_FAB2(SCH_1):PAGE242
     2    GND @BASEBOARD_FAB2_LIB.BASEBOARD_FAB2(SCH_1):GND    I60 @BASEBOARD_FAB2_LIB.BASEBOARD_FAB2(SCH_1):PAGE242

C5G46 CAP_A_0603V-22.0UF,4V,20%,X6S,A
     1 PVDDQ_ABC @BASEBOARD_FAB2_LIB.BASEBOARD_FAB2(SCH_1):PVDDQ_ABC    I59 @BASEBOARD_FAB2_LIB.BASEBOARD_FAB2(SCH_1):PAGE242
     2    GND @BASEBOARD_FAB2_LIB.BASEBOARD_FAB2(SCH_1):GND    I59 @BASEBOARD_FAB2_LIB.BASEBOARD_FAB2(SCH_1):PAGE242

C5G47 CAP_A_0603V-22.0UF,4V,20%,X6S,A
     1 PVDDQ_ABC @BASEBOARD_FAB2_LIB.BASEBOARD_FAB2(SCH_1):PVDDQ_ABC    I58 @BASEBOARD_FAB2_LIB.BASEBOARD_FAB2(SCH_1):PAGE242
     2    GND @BASEBOARD_FAB2_LIB.BASEBOARD_FAB2(SCH_1):GND    I58 @BASEBOARD_FAB2_LIB.BASEBOARD_FAB2(SCH_1):PAGE242

C5G48 CAP_A_0603V-22.0UF,4V,20%,X6S,A
     1 PVDDQ_ABC @BASEBOARD_FAB2_LIB.BASEBOARD_FAB2(SCH_1):PVDDQ_ABC    I57 @BASEBOARD_FAB2_LIB.BASEBOARD_FAB2(SCH_1):PAGE242
     2    GND @BASEBOARD_FAB2_LIB.BASEBOARD_FAB2(SCH_1):GND    I57 @BASEBOARD_FAB2_LIB.BASEBOARD_FAB2(SCH_1):PAGE242

C5G49 CAP_A_0603V-22.0UF,4V,20%,X6S,A
     1 PVDDQ_ABC @BASEBOARD_FAB2_LIB.BASEBOARD_FAB2(SCH_1):PVDDQ_ABC    I61 @BASEBOARD_FAB2_LIB.BASEBOARD_FAB2(SCH_1):PAGE242
     2    GND @BASEBOARD_FAB2_LIB.BASEBOARD_FAB2(SCH_1):GND    I61 @BASEBOARD_FAB2_LIB.BASEBOARD_FAB2(SCH_1):PAGE242

C5G50 CAP_A_0603V-22.0UF,4V,20%,X6S,A
     1 PVDDQ_ABC @BASEBOARD_FAB2_LIB.BASEBOARD_FAB2(SCH_1):PVDDQ_ABC    I70 @BASEBOARD_FAB2_LIB.BASEBOARD_FAB2(SCH_1):PAGE242
     2    GND @BASEBOARD_FAB2_LIB.BASEBOARD_FAB2(SCH_1):GND    I70 @BASEBOARD_FAB2_LIB.BASEBOARD_FAB2(SCH_1):PAGE242

C5G51 CAP_A_0603V-22.0UF,4V,20%,X6S,A
     1 PVDDQ_ABC @BASEBOARD_FAB2_LIB.BASEBOARD_FAB2(SCH_1):PVDDQ_ABC    I69 @BASEBOARD_FAB2_LIB.BASEBOARD_FAB2(SCH_1):PAGE242
     2    GND @BASEBOARD_FAB2_LIB.BASEBOARD_FAB2(SCH_1):GND    I69 @BASEBOARD_FAB2_LIB.BASEBOARD_FAB2(SCH_1):PAGE242

C5G52 CAP_A_0603V-22.0UF,4V,20%,X6S,A
     1 PVDDQ_ABC @BASEBOARD_FAB2_LIB.BASEBOARD_FAB2(SCH_1):PVDDQ_ABC    I68 @BASEBOARD_FAB2_LIB.BASEBOARD_FAB2(SCH_1):PAGE242
     2    GND @BASEBOARD_FAB2_LIB.BASEBOARD_FAB2(SCH_1):GND    I68 @BASEBOARD_FAB2_LIB.BASEBOARD_FAB2(SCH_1):PAGE242

C5G53 CAP_A_0603V-22.0UF,4V,20%,X6S,A
     1 PVDDQ_ABC @BASEBOARD_FAB2_LIB.BASEBOARD_FAB2(SCH_1):PVDDQ_ABC    I67 @BASEBOARD_FAB2_LIB.BASEBOARD_FAB2(SCH_1):PAGE242
     2    GND @BASEBOARD_FAB2_LIB.BASEBOARD_FAB2(SCH_1):GND    I67 @BASEBOARD_FAB2_LIB.BASEBOARD_FAB2(SCH_1):PAGE242

C5G54 CAP_A_0603V-22.0UF,4V,20%,X6S,A
     1 PVDDQ_ABC @BASEBOARD_FAB2_LIB.BASEBOARD_FAB2(SCH_1):PVDDQ_ABC    I62 @BASEBOARD_FAB2_LIB.BASEBOARD_FAB2(SCH_1):PAGE242
     2    GND @BASEBOARD_FAB2_LIB.BASEBOARD_FAB2(SCH_1):GND    I62 @BASEBOARD_FAB2_LIB.BASEBOARD_FAB2(SCH_1):PAGE242

C5G55 CAP_A_0603V-22.0UF,4V,20%,X6S,A
     1 PVDDQ_ABC @BASEBOARD_FAB2_LIB.BASEBOARD_FAB2(SCH_1):PVDDQ_ABC    I66 @BASEBOARD_FAB2_LIB.BASEBOARD_FAB2(SCH_1):PAGE242
     2    GND @BASEBOARD_FAB2_LIB.BASEBOARD_FAB2(SCH_1):GND    I66 @BASEBOARD_FAB2_LIB.BASEBOARD_FAB2(SCH_1):PAGE242

C5G56 CAP_A_0603V-22.0UF,4V,20%,X6S,A
     1 PVDDQ_ABC @BASEBOARD_FAB2_LIB.BASEBOARD_FAB2(SCH_1):PVDDQ_ABC    I65 @BASEBOARD_FAB2_LIB.BASEBOARD_FAB2(SCH_1):PAGE242
     2    GND @BASEBOARD_FAB2_LIB.BASEBOARD_FAB2(SCH_1):GND    I65 @BASEBOARD_FAB2_LIB.BASEBOARD_FAB2(SCH_1):PAGE242

C5G57 CAP_A_0603V-22.0UF,4V,20%,X6S,A
     1 PVDDQ_ABC @BASEBOARD_FAB2_LIB.BASEBOARD_FAB2(SCH_1):PVDDQ_ABC    I64 @BASEBOARD_FAB2_LIB.BASEBOARD_FAB2(SCH_1):PAGE242
     2    GND @BASEBOARD_FAB2_LIB.BASEBOARD_FAB2(SCH_1):GND    I64 @BASEBOARD_FAB2_LIB.BASEBOARD_FAB2(SCH_1):PAGE242

C5G58 CAP_A_0603V-22.0UF,4V,20%,X6S,A
     1 PVDDQ_ABC @BASEBOARD_FAB2_LIB.BASEBOARD_FAB2(SCH_1):PVDDQ_ABC    I63 @BASEBOARD_FAB2_LIB.BASEBOARD_FAB2(SCH_1):PAGE242
     2    GND @BASEBOARD_FAB2_LIB.BASEBOARD_FAB2(SCH_1):GND    I63 @BASEBOARD_FAB2_LIB.BASEBOARD_FAB2(SCH_1):PAGE242

C5G59 CAP_A_0603V-22.0UF,4V,20%,X6S,A
     1 PVDDQ_DEF @BASEBOARD_FAB2_LIB.BASEBOARD_FAB2(SCH_1):PVDDQ_DEF    I79 @BASEBOARD_FAB2_LIB.BASEBOARD_FAB2(SCH_1):PAGE242
     2    GND @BASEBOARD_FAB2_LIB.BASEBOARD_FAB2(SCH_1):GND    I79 @BASEBOARD_FAB2_LIB.BASEBOARD_FAB2(SCH_1):PAGE242

C5G60 CAP_A_0603V-22.0UF,4V,20%,X6S,A
     1 PVDDQ_DEF @BASEBOARD_FAB2_LIB.BASEBOARD_FAB2(SCH_1):PVDDQ_DEF    I78 @BASEBOARD_FAB2_LIB.BASEBOARD_FAB2(SCH_1):PAGE242
     2    GND @BASEBOARD_FAB2_LIB.BASEBOARD_FAB2(SCH_1):GND    I78 @BASEBOARD_FAB2_LIB.BASEBOARD_FAB2(SCH_1):PAGE242

C5G61 CAP_A_0603V-22.0UF,4V,20%,X6S,A
     1 PVDDQ_DEF @BASEBOARD_FAB2_LIB.BASEBOARD_FAB2(SCH_1):PVDDQ_DEF    I77 @BASEBOARD_FAB2_LIB.BASEBOARD_FAB2(SCH_1):PAGE242
     2    GND @BASEBOARD_FAB2_LIB.BASEBOARD_FAB2(SCH_1):GND    I77 @BASEBOARD_FAB2_LIB.BASEBOARD_FAB2(SCH_1):PAGE242

C5G62 CAP_A_0603V-22.0UF,4V,20%,X6S,A
     1 PVDDQ_DEF @BASEBOARD_FAB2_LIB.BASEBOARD_FAB2(SCH_1):PVDDQ_DEF    I76 @BASEBOARD_FAB2_LIB.BASEBOARD_FAB2(SCH_1):PAGE242
     2    GND @BASEBOARD_FAB2_LIB.BASEBOARD_FAB2(SCH_1):GND    I76 @BASEBOARD_FAB2_LIB.BASEBOARD_FAB2(SCH_1):PAGE242

C5G63 CAP_A_0603V-22.0UF,4V,20%,X6S,A
     1 PVDDQ_DEF @BASEBOARD_FAB2_LIB.BASEBOARD_FAB2(SCH_1):PVDDQ_DEF    I75 @BASEBOARD_FAB2_LIB.BASEBOARD_FAB2(SCH_1):PAGE242
     2    GND @BASEBOARD_FAB2_LIB.BASEBOARD_FAB2(SCH_1):GND    I75 @BASEBOARD_FAB2_LIB.BASEBOARD_FAB2(SCH_1):PAGE242

C5G64 CAP_A_0603V-22.0UF,4V,20%,X6S,A
     1 PVDDQ_DEF @BASEBOARD_FAB2_LIB.BASEBOARD_FAB2(SCH_1):PVDDQ_DEF    I74 @BASEBOARD_FAB2_LIB.BASEBOARD_FAB2(SCH_1):PAGE242
     2    GND @BASEBOARD_FAB2_LIB.BASEBOARD_FAB2(SCH_1):GND    I74 @BASEBOARD_FAB2_LIB.BASEBOARD_FAB2(SCH_1):PAGE242

C5G65 CAP_A_0603V-22.0UF,4V,20%,X6S,A
     1 PVDDQ_DEF @BASEBOARD_FAB2_LIB.BASEBOARD_FAB2(SCH_1):PVDDQ_DEF    I73 @BASEBOARD_FAB2_LIB.BASEBOARD_FAB2(SCH_1):PAGE242
     2    GND @BASEBOARD_FAB2_LIB.BASEBOARD_FAB2(SCH_1):GND    I73 @BASEBOARD_FAB2_LIB.BASEBOARD_FAB2(SCH_1):PAGE242

C5G66 CAP_A_0603V-22.0UF,4V,20%,X6S,A
     1 PVDDQ_DEF @BASEBOARD_FAB2_LIB.BASEBOARD_FAB2(SCH_1):PVDDQ_DEF    I72 @BASEBOARD_FAB2_LIB.BASEBOARD_FAB2(SCH_1):PAGE242
     2    GND @BASEBOARD_FAB2_LIB.BASEBOARD_FAB2(SCH_1):GND    I72 @BASEBOARD_FAB2_LIB.BASEBOARD_FAB2(SCH_1):PAGE242

C5G67 CAP_A_0603V-22.0UF,4V,20%,X6S,A
     1 PVDDQ_DEF @BASEBOARD_FAB2_LIB.BASEBOARD_FAB2(SCH_1):PVDDQ_DEF    I71 @BASEBOARD_FAB2_LIB.BASEBOARD_FAB2(SCH_1):PAGE242
     2    GND @BASEBOARD_FAB2_LIB.BASEBOARD_FAB2(SCH_1):GND    I71 @BASEBOARD_FAB2_LIB.BASEBOARD_FAB2(SCH_1):PAGE242

C5G68 CAP_A_0603V-22.0UF,4V,20%,X6S,A
     1 PVDDQ_DEF @BASEBOARD_FAB2_LIB.BASEBOARD_FAB2(SCH_1):PVDDQ_DEF    I88 @BASEBOARD_FAB2_LIB.BASEBOARD_FAB2(SCH_1):PAGE242
     2    GND @BASEBOARD_FAB2_LIB.BASEBOARD_FAB2(SCH_1):GND    I88 @BASEBOARD_FAB2_LIB.BASEBOARD_FAB2(SCH_1):PAGE242

C5G69 CAP_A_0603V-22.0UF,4V,20%,X6S,A
     1 PVDDQ_DEF @BASEBOARD_FAB2_LIB.BASEBOARD_FAB2(SCH_1):PVDDQ_DEF    I87 @BASEBOARD_FAB2_LIB.BASEBOARD_FAB2(SCH_1):PAGE242
     2    GND @BASEBOARD_FAB2_LIB.BASEBOARD_FAB2(SCH_1):GND    I87 @BASEBOARD_FAB2_LIB.BASEBOARD_FAB2(SCH_1):PAGE242

C5G70 CAP_A_0603V-22.0UF,4V,20%,X6S,A
     1 PVDDQ_DEF @BASEBOARD_FAB2_LIB.BASEBOARD_FAB2(SCH_1):PVDDQ_DEF    I86 @BASEBOARD_FAB2_LIB.BASEBOARD_FAB2(SCH_1):PAGE242
     2    GND @BASEBOARD_FAB2_LIB.BASEBOARD_FAB2(SCH_1):GND    I86 @BASEBOARD_FAB2_LIB.BASEBOARD_FAB2(SCH_1):PAGE242

C5G71 CAP_A_0603V-22.0UF,4V,20%,X6S,A
     1 PVDDQ_DEF @BASEBOARD_FAB2_LIB.BASEBOARD_FAB2(SCH_1):PVDDQ_DEF    I85 @BASEBOARD_FAB2_LIB.BASEBOARD_FAB2(SCH_1):PAGE242
     2    GND @BASEBOARD_FAB2_LIB.BASEBOARD_FAB2(SCH_1):GND    I85 @BASEBOARD_FAB2_LIB.BASEBOARD_FAB2(SCH_1):PAGE242

C5G72 CAP_A_0603V-22.0UF,4V,20%,X6S,A
     1 PVDDQ_DEF @BASEBOARD_FAB2_LIB.BASEBOARD_FAB2(SCH_1):PVDDQ_DEF    I84 @BASEBOARD_FAB2_LIB.BASEBOARD_FAB2(SCH_1):PAGE242
     2    GND @BASEBOARD_FAB2_LIB.BASEBOARD_FAB2(SCH_1):GND    I84 @BASEBOARD_FAB2_LIB.BASEBOARD_FAB2(SCH_1):PAGE242

C5G73 CAP_A_0603V-22.0UF,4V,20%,X6S,A
     1 PVDDQ_DEF @BASEBOARD_FAB2_LIB.BASEBOARD_FAB2(SCH_1):PVDDQ_DEF    I83 @BASEBOARD_FAB2_LIB.BASEBOARD_FAB2(SCH_1):PAGE242
     2    GND @BASEBOARD_FAB2_LIB.BASEBOARD_FAB2(SCH_1):GND    I83 @BASEBOARD_FAB2_LIB.BASEBOARD_FAB2(SCH_1):PAGE242

C5G74 CAP_A_0603V-22.0UF,4V,20%,X6S,A
     1 PVDDQ_DEF @BASEBOARD_FAB2_LIB.BASEBOARD_FAB2(SCH_1):PVDDQ_DEF    I82 @BASEBOARD_FAB2_LIB.BASEBOARD_FAB2(SCH_1):PAGE242
     2    GND @BASEBOARD_FAB2_LIB.BASEBOARD_FAB2(SCH_1):GND    I82 @BASEBOARD_FAB2_LIB.BASEBOARD_FAB2(SCH_1):PAGE242

C5G75 CAP_A_0603V-22.0UF,4V,20%,X6S,A
     1 PVDDQ_DEF @BASEBOARD_FAB2_LIB.BASEBOARD_FAB2(SCH_1):PVDDQ_DEF    I81 @BASEBOARD_FAB2_LIB.BASEBOARD_FAB2(SCH_1):PAGE242
     2    GND @BASEBOARD_FAB2_LIB.BASEBOARD_FAB2(SCH_1):GND    I81 @BASEBOARD_FAB2_LIB.BASEBOARD_FAB2(SCH_1):PAGE242

C5G76 CAP_A_0603V-22.0UF,4V,20%,X6S,A
     1 PVDDQ_DEF @BASEBOARD_FAB2_LIB.BASEBOARD_FAB2(SCH_1):PVDDQ_DEF    I80 @BASEBOARD_FAB2_LIB.BASEBOARD_FAB2(SCH_1):PAGE242
     2    GND @BASEBOARD_FAB2_LIB.BASEBOARD_FAB2(SCH_1):GND    I80 @BASEBOARD_FAB2_LIB.BASEBOARD_FAB2(SCH_1):PAGE242

C5G77 CAP_0805-47UF,4V,20%,X6S,C9533A
     1 PVDDQ_DEF @BASEBOARD_FAB2_LIB.BASEBOARD_FAB2(SCH_1):PVDDQ_DEF    I89 @BASEBOARD_FAB2_LIB.BASEBOARD_FAB2(SCH_1):PAGE242
     2    GND @BASEBOARD_FAB2_LIB.BASEBOARD_FAB2(SCH_1):GND    I89 @BASEBOARD_FAB2_LIB.BASEBOARD_FAB2(SCH_1):PAGE242

C5G78 CAP_0805-47UF,4V,20%,X6S,C9533A
     1 PVDDQ_DEF @BASEBOARD_FAB2_LIB.BASEBOARD_FAB2(SCH_1):PVDDQ_DEF    I91 @BASEBOARD_FAB2_LIB.BASEBOARD_FAB2(SCH_1):PAGE242
     2    GND @BASEBOARD_FAB2_LIB.BASEBOARD_FAB2(SCH_1):GND    I91 @BASEBOARD_FAB2_LIB.BASEBOARD_FAB2(SCH_1):PAGE242

C5G79 CAP_A_0603V-22.0UF,4V,20%,X6S,A
     1 PVDDQ_GHJ @BASEBOARD_FAB2_LIB.BASEBOARD_FAB2(SCH_1):PVDDQ_GHJ    I53 @BASEBOARD_FAB2_LIB.BASEBOARD_FAB2(SCH_1):PAGE243
     2    GND @BASEBOARD_FAB2_LIB.BASEBOARD_FAB2(SCH_1):GND    I53 @BASEBOARD_FAB2_LIB.BASEBOARD_FAB2(SCH_1):PAGE243

C5G80 CAP_A_0603V-22.0UF,4V,20%,X6S,A
     1 PVDDQ_GHJ @BASEBOARD_FAB2_LIB.BASEBOARD_FAB2(SCH_1):PVDDQ_GHJ    I61 @BASEBOARD_FAB2_LIB.BASEBOARD_FAB2(SCH_1):PAGE243
     2    GND @BASEBOARD_FAB2_LIB.BASEBOARD_FAB2(SCH_1):GND    I61 @BASEBOARD_FAB2_LIB.BASEBOARD_FAB2(SCH_1):PAGE243

C5G81 CAP_A_0603V-22.0UF,4V,20%,X6S,A
     1 PVDDQ_GHJ @BASEBOARD_FAB2_LIB.BASEBOARD_FAB2(SCH_1):PVDDQ_GHJ    I60 @BASEBOARD_FAB2_LIB.BASEBOARD_FAB2(SCH_1):PAGE243
     2    GND @BASEBOARD_FAB2_LIB.BASEBOARD_FAB2(SCH_1):GND    I60 @BASEBOARD_FAB2_LIB.BASEBOARD_FAB2(SCH_1):PAGE243

C5G82 CAP_A_0603V-22.0UF,4V,20%,X6S,A
     1 PVDDQ_GHJ @BASEBOARD_FAB2_LIB.BASEBOARD_FAB2(SCH_1):PVDDQ_GHJ    I59 @BASEBOARD_FAB2_LIB.BASEBOARD_FAB2(SCH_1):PAGE243
     2    GND @BASEBOARD_FAB2_LIB.BASEBOARD_FAB2(SCH_1):GND    I59 @BASEBOARD_FAB2_LIB.BASEBOARD_FAB2(SCH_1):PAGE243

C5G83 CAP_A_0603V-22.0UF,4V,20%,X6S,A
     1 PVDDQ_GHJ @BASEBOARD_FAB2_LIB.BASEBOARD_FAB2(SCH_1):PVDDQ_GHJ    I58 @BASEBOARD_FAB2_LIB.BASEBOARD_FAB2(SCH_1):PAGE243
     2    GND @BASEBOARD_FAB2_LIB.BASEBOARD_FAB2(SCH_1):GND    I58 @BASEBOARD_FAB2_LIB.BASEBOARD_FAB2(SCH_1):PAGE243

C5G84 CAP_A_0603V-22.0UF,4V,20%,X6S,A
     1 PVDDQ_GHJ @BASEBOARD_FAB2_LIB.BASEBOARD_FAB2(SCH_1):PVDDQ_GHJ    I57 @BASEBOARD_FAB2_LIB.BASEBOARD_FAB2(SCH_1):PAGE243
     2    GND @BASEBOARD_FAB2_LIB.BASEBOARD_FAB2(SCH_1):GND    I57 @BASEBOARD_FAB2_LIB.BASEBOARD_FAB2(SCH_1):PAGE243

C5G85 CAP_A_0603V-22.0UF,4V,20%,X6S,A
     1 PVDDQ_GHJ @BASEBOARD_FAB2_LIB.BASEBOARD_FAB2(SCH_1):PVDDQ_GHJ    I56 @BASEBOARD_FAB2_LIB.BASEBOARD_FAB2(SCH_1):PAGE243
     2    GND @BASEBOARD_FAB2_LIB.BASEBOARD_FAB2(SCH_1):GND    I56 @BASEBOARD_FAB2_LIB.BASEBOARD_FAB2(SCH_1):PAGE243

C5G86 CAP_A_0603V-22.0UF,4V,20%,X6S,A
     1 PVDDQ_GHJ @BASEBOARD_FAB2_LIB.BASEBOARD_FAB2(SCH_1):PVDDQ_GHJ    I55 @BASEBOARD_FAB2_LIB.BASEBOARD_FAB2(SCH_1):PAGE243
     2    GND @BASEBOARD_FAB2_LIB.BASEBOARD_FAB2(SCH_1):GND    I55 @BASEBOARD_FAB2_LIB.BASEBOARD_FAB2(SCH_1):PAGE243

C5G87 CAP_A_0603V-22.0UF,4V,20%,X6S,A
     1 PVDDQ_GHJ @BASEBOARD_FAB2_LIB.BASEBOARD_FAB2(SCH_1):PVDDQ_GHJ    I54 @BASEBOARD_FAB2_LIB.BASEBOARD_FAB2(SCH_1):PAGE243
     2    GND @BASEBOARD_FAB2_LIB.BASEBOARD_FAB2(SCH_1):GND    I54 @BASEBOARD_FAB2_LIB.BASEBOARD_FAB2(SCH_1):PAGE243

C5G88 CAP_A_0603V-22.0UF,4V,20%,X6S,A
     1 PVDDQ_GHJ @BASEBOARD_FAB2_LIB.BASEBOARD_FAB2(SCH_1):PVDDQ_GHJ    I70 @BASEBOARD_FAB2_LIB.BASEBOARD_FAB2(SCH_1):PAGE243
     2    GND @BASEBOARD_FAB2_LIB.BASEBOARD_FAB2(SCH_1):GND    I70 @BASEBOARD_FAB2_LIB.BASEBOARD_FAB2(SCH_1):PAGE243

C5G89 CAP_A_0603V-22.0UF,4V,20%,X6S,A
     1 PVDDQ_GHJ @BASEBOARD_FAB2_LIB.BASEBOARD_FAB2(SCH_1):PVDDQ_GHJ    I69 @BASEBOARD_FAB2_LIB.BASEBOARD_FAB2(SCH_1):PAGE243
     2    GND @BASEBOARD_FAB2_LIB.BASEBOARD_FAB2(SCH_1):GND    I69 @BASEBOARD_FAB2_LIB.BASEBOARD_FAB2(SCH_1):PAGE243

C5G90 CAP_A_0603V-22.0UF,4V,20%,X6S,A
     1 PVDDQ_GHJ @BASEBOARD_FAB2_LIB.BASEBOARD_FAB2(SCH_1):PVDDQ_GHJ    I68 @BASEBOARD_FAB2_LIB.BASEBOARD_FAB2(SCH_1):PAGE243
     2    GND @BASEBOARD_FAB2_LIB.BASEBOARD_FAB2(SCH_1):GND    I68 @BASEBOARD_FAB2_LIB.BASEBOARD_FAB2(SCH_1):PAGE243

C5G91 CAP_A_0603V-22.0UF,4V,20%,X6S,A
     1 PVDDQ_GHJ @BASEBOARD_FAB2_LIB.BASEBOARD_FAB2(SCH_1):PVDDQ_GHJ    I67 @BASEBOARD_FAB2_LIB.BASEBOARD_FAB2(SCH_1):PAGE243
     2    GND @BASEBOARD_FAB2_LIB.BASEBOARD_FAB2(SCH_1):GND    I67 @BASEBOARD_FAB2_LIB.BASEBOARD_FAB2(SCH_1):PAGE243

C5G92 CAP_A_0603V-22.0UF,4V,20%,X6S,A
     1 PVDDQ_GHJ @BASEBOARD_FAB2_LIB.BASEBOARD_FAB2(SCH_1):PVDDQ_GHJ    I66 @BASEBOARD_FAB2_LIB.BASEBOARD_FAB2(SCH_1):PAGE243
     2    GND @BASEBOARD_FAB2_LIB.BASEBOARD_FAB2(SCH_1):GND    I66 @BASEBOARD_FAB2_LIB.BASEBOARD_FAB2(SCH_1):PAGE243

C5G93 CAP_A_0603V-22.0UF,4V,20%,X6S,A
     1 PVDDQ_GHJ @BASEBOARD_FAB2_LIB.BASEBOARD_FAB2(SCH_1):PVDDQ_GHJ    I65 @BASEBOARD_FAB2_LIB.BASEBOARD_FAB2(SCH_1):PAGE243
     2    GND @BASEBOARD_FAB2_LIB.BASEBOARD_FAB2(SCH_1):GND    I65 @BASEBOARD_FAB2_LIB.BASEBOARD_FAB2(SCH_1):PAGE243

C5G94 CAP_A_0603V-22.0UF,4V,20%,X6S,A
     1 PVDDQ_GHJ @BASEBOARD_FAB2_LIB.BASEBOARD_FAB2(SCH_1):PVDDQ_GHJ    I64 @BASEBOARD_FAB2_LIB.BASEBOARD_FAB2(SCH_1):PAGE243
     2    GND @BASEBOARD_FAB2_LIB.BASEBOARD_FAB2(SCH_1):GND    I64 @BASEBOARD_FAB2_LIB.BASEBOARD_FAB2(SCH_1):PAGE243

C5G95 CAP_A_0603V-22.0UF,4V,20%,X6S,A
     1 PVDDQ_GHJ @BASEBOARD_FAB2_LIB.BASEBOARD_FAB2(SCH_1):PVDDQ_GHJ    I63 @BASEBOARD_FAB2_LIB.BASEBOARD_FAB2(SCH_1):PAGE243
     2    GND @BASEBOARD_FAB2_LIB.BASEBOARD_FAB2(SCH_1):GND    I63 @BASEBOARD_FAB2_LIB.BASEBOARD_FAB2(SCH_1):PAGE243

C5G96 CAP_A_0603V-22.0UF,4V,20%,X6S,A
     1 PVDDQ_GHJ @BASEBOARD_FAB2_LIB.BASEBOARD_FAB2(SCH_1):PVDDQ_GHJ    I62 @BASEBOARD_FAB2_LIB.BASEBOARD_FAB2(SCH_1):PAGE243
     2    GND @BASEBOARD_FAB2_LIB.BASEBOARD_FAB2(SCH_1):GND    I62 @BASEBOARD_FAB2_LIB.BASEBOARD_FAB2(SCH_1):PAGE243

C5G97 CAP_A_0603V-22.0UF,4V,20%,X6S,A
     1 PVDDQ_KLM @BASEBOARD_FAB2_LIB.BASEBOARD_FAB2(SCH_1):PVDDQ_KLM    I79 @BASEBOARD_FAB2_LIB.BASEBOARD_FAB2(SCH_1):PAGE243
     2    GND @BASEBOARD_FAB2_LIB.BASEBOARD_FAB2(SCH_1):GND    I79 @BASEBOARD_FAB2_LIB.BASEBOARD_FAB2(SCH_1):PAGE243

C5G98 CAP_A_0603V-22.0UF,4V,20%,X6S,A
     1 PVDDQ_KLM @BASEBOARD_FAB2_LIB.BASEBOARD_FAB2(SCH_1):PVDDQ_KLM    I78 @BASEBOARD_FAB2_LIB.BASEBOARD_FAB2(SCH_1):PAGE243
     2    GND @BASEBOARD_FAB2_LIB.BASEBOARD_FAB2(SCH_1):GND    I78 @BASEBOARD_FAB2_LIB.BASEBOARD_FAB2(SCH_1):PAGE243

C5G99 CAP_A_0603V-22.0UF,4V,20%,X6S,A
     1 PVDDQ_KLM @BASEBOARD_FAB2_LIB.BASEBOARD_FAB2(SCH_1):PVDDQ_KLM    I77 @BASEBOARD_FAB2_LIB.BASEBOARD_FAB2(SCH_1):PAGE243
     2    GND @BASEBOARD_FAB2_LIB.BASEBOARD_FAB2(SCH_1):GND    I77 @BASEBOARD_FAB2_LIB.BASEBOARD_FAB2(SCH_1):PAGE243

C5G100 CAP_A_0603V-22.0UF,4V,20%,X6S,A
     1 PVDDQ_KLM @BASEBOARD_FAB2_LIB.BASEBOARD_FAB2(SCH_1):PVDDQ_KLM    I76 @BASEBOARD_FAB2_LIB.BASEBOARD_FAB2(SCH_1):PAGE243
     2    GND @BASEBOARD_FAB2_LIB.BASEBOARD_FAB2(SCH_1):GND    I76 @BASEBOARD_FAB2_LIB.BASEBOARD_FAB2(SCH_1):PAGE243

C5G101 CAP_A_0603V-22.0UF,4V,20%,X6S,A
     1 PVDDQ_KLM @BASEBOARD_FAB2_LIB.BASEBOARD_FAB2(SCH_1):PVDDQ_KLM    I75 @BASEBOARD_FAB2_LIB.BASEBOARD_FAB2(SCH_1):PAGE243
     2    GND @BASEBOARD_FAB2_LIB.BASEBOARD_FAB2(SCH_1):GND    I75 @BASEBOARD_FAB2_LIB.BASEBOARD_FAB2(SCH_1):PAGE243

C5G102 CAP_A_0603V-22.0UF,4V,20%,X6S,A
     1 PVDDQ_KLM @BASEBOARD_FAB2_LIB.BASEBOARD_FAB2(SCH_1):PVDDQ_KLM    I74 @BASEBOARD_FAB2_LIB.BASEBOARD_FAB2(SCH_1):PAGE243
     2    GND @BASEBOARD_FAB2_LIB.BASEBOARD_FAB2(SCH_1):GND    I74 @BASEBOARD_FAB2_LIB.BASEBOARD_FAB2(SCH_1):PAGE243

C5G103 CAP_A_0603V-22.0UF,4V,20%,X6S,A
     1 PVDDQ_KLM @BASEBOARD_FAB2_LIB.BASEBOARD_FAB2(SCH_1):PVDDQ_KLM    I71 @BASEBOARD_FAB2_LIB.BASEBOARD_FAB2(SCH_1):PAGE243
     2    GND @BASEBOARD_FAB2_LIB.BASEBOARD_FAB2(SCH_1):GND    I71 @BASEBOARD_FAB2_LIB.BASEBOARD_FAB2(SCH_1):PAGE243

C5G104 CAP_A_0603V-22.0UF,4V,20%,X6S,A
     1 PVDDQ_KLM @BASEBOARD_FAB2_LIB.BASEBOARD_FAB2(SCH_1):PVDDQ_KLM    I72 @BASEBOARD_FAB2_LIB.BASEBOARD_FAB2(SCH_1):PAGE243
     2    GND @BASEBOARD_FAB2_LIB.BASEBOARD_FAB2(SCH_1):GND    I72 @BASEBOARD_FAB2_LIB.BASEBOARD_FAB2(SCH_1):PAGE243

C5G105 CAP_A_0603V-22.0UF,4V,20%,X6S,A
     1 PVDDQ_KLM @BASEBOARD_FAB2_LIB.BASEBOARD_FAB2(SCH_1):PVDDQ_KLM    I73 @BASEBOARD_FAB2_LIB.BASEBOARD_FAB2(SCH_1):PAGE243
     2    GND @BASEBOARD_FAB2_LIB.BASEBOARD_FAB2(SCH_1):GND    I73 @BASEBOARD_FAB2_LIB.BASEBOARD_FAB2(SCH_1):PAGE243

C5G106 CAP_A_0603V-22.0UF,4V,20%,X6S,A
     1 PVDDQ_KLM @BASEBOARD_FAB2_LIB.BASEBOARD_FAB2(SCH_1):PVDDQ_KLM    I88 @BASEBOARD_FAB2_LIB.BASEBOARD_FAB2(SCH_1):PAGE243
     2    GND @BASEBOARD_FAB2_LIB.BASEBOARD_FAB2(SCH_1):GND    I88 @BASEBOARD_FAB2_LIB.BASEBOARD_FAB2(SCH_1):PAGE243

C5G107 CAP_A_0603V-22.0UF,4V,20%,X6S,A
     1 PVDDQ_KLM @BASEBOARD_FAB2_LIB.BASEBOARD_FAB2(SCH_1):PVDDQ_KLM    I87 @BASEBOARD_FAB2_LIB.BASEBOARD_FAB2(SCH_1):PAGE243
     2    GND @BASEBOARD_FAB2_LIB.BASEBOARD_FAB2(SCH_1):GND    I87 @BASEBOARD_FAB2_LIB.BASEBOARD_FAB2(SCH_1):PAGE243

C5G108 CAP_A_0603V-22.0UF,4V,20%,X6S,A
     1 PVDDQ_KLM @BASEBOARD_FAB2_LIB.BASEBOARD_FAB2(SCH_1):PVDDQ_KLM    I86 @BASEBOARD_FAB2_LIB.BASEBOARD_FAB2(SCH_1):PAGE243
     2    GND @BASEBOARD_FAB2_LIB.BASEBOARD_FAB2(SCH_1):GND    I86 @BASEBOARD_FAB2_LIB.BASEBOARD_FAB2(SCH_1):PAGE243

C5G109 CAP_A_0603V-22.0UF,4V,20%,X6S,A
     1 PVDDQ_KLM @BASEBOARD_FAB2_LIB.BASEBOARD_FAB2(SCH_1):PVDDQ_KLM    I85 @BASEBOARD_FAB2_LIB.BASEBOARD_FAB2(SCH_1):PAGE243
     2    GND @BASEBOARD_FAB2_LIB.BASEBOARD_FAB2(SCH_1):GND    I85 @BASEBOARD_FAB2_LIB.BASEBOARD_FAB2(SCH_1):PAGE243

C5G110 CAP_A_0603V-22.0UF,4V,20%,X6S,A
     1 PVDDQ_KLM @BASEBOARD_FAB2_LIB.BASEBOARD_FAB2(SCH_1):PVDDQ_KLM    I84 @BASEBOARD_FAB2_LIB.BASEBOARD_FAB2(SCH_1):PAGE243
     2    GND @BASEBOARD_FAB2_LIB.BASEBOARD_FAB2(SCH_1):GND    I84 @BASEBOARD_FAB2_LIB.BASEBOARD_FAB2(SCH_1):PAGE243

C5G111 CAP_A_0603V-22.0UF,4V,20%,X6S,A
     1 PVDDQ_KLM @BASEBOARD_FAB2_LIB.BASEBOARD_FAB2(SCH_1):PVDDQ_KLM    I83 @BASEBOARD_FAB2_LIB.BASEBOARD_FAB2(SCH_1):PAGE243
     2    GND @BASEBOARD_FAB2_LIB.BASEBOARD_FAB2(SCH_1):GND    I83 @BASEBOARD_FAB2_LIB.BASEBOARD_FAB2(SCH_1):PAGE243

C5G112 CAP_A_0603V-22.0UF,4V,20%,X6S,A
     1 PVDDQ_KLM @BASEBOARD_FAB2_LIB.BASEBOARD_FAB2(SCH_1):PVDDQ_KLM    I82 @BASEBOARD_FAB2_LIB.BASEBOARD_FAB2(SCH_1):PAGE243
     2    GND @BASEBOARD_FAB2_LIB.BASEBOARD_FAB2(SCH_1):GND    I82 @BASEBOARD_FAB2_LIB.BASEBOARD_FAB2(SCH_1):PAGE243

C5G113 CAP_A_0603V-22.0UF,4V,20%,X6S,A
     1 PVDDQ_KLM @BASEBOARD_FAB2_LIB.BASEBOARD_FAB2(SCH_1):PVDDQ_KLM    I81 @BASEBOARD_FAB2_LIB.BASEBOARD_FAB2(SCH_1):PAGE243
     2    GND @BASEBOARD_FAB2_LIB.BASEBOARD_FAB2(SCH_1):GND    I81 @BASEBOARD_FAB2_LIB.BASEBOARD_FAB2(SCH_1):PAGE243

C5G114 CAP_A_0603V-22.0UF,4V,20%,X6S,A
     1 PVDDQ_KLM @BASEBOARD_FAB2_LIB.BASEBOARD_FAB2(SCH_1):PVDDQ_KLM    I80 @BASEBOARD_FAB2_LIB.BASEBOARD_FAB2(SCH_1):PAGE243
     2    GND @BASEBOARD_FAB2_LIB.BASEBOARD_FAB2(SCH_1):GND    I80 @BASEBOARD_FAB2_LIB.BASEBOARD_FAB2(SCH_1):PAGE243

C5G115 CAP_0805-47UF,4V,20%,X6S,C9533A
     1 PVDDQ_KLM @BASEBOARD_FAB2_LIB.BASEBOARD_FAB2(SCH_1):PVDDQ_KLM    I89 @BASEBOARD_FAB2_LIB.BASEBOARD_FAB2(SCH_1):PAGE243
     2    GND @BASEBOARD_FAB2_LIB.BASEBOARD_FAB2(SCH_1):GND    I89 @BASEBOARD_FAB2_LIB.BASEBOARD_FAB2(SCH_1):PAGE243

C5G116 CAP_0805-47UF,4V,20%,X6S,C9533A
     1 PVDDQ_KLM @BASEBOARD_FAB2_LIB.BASEBOARD_FAB2(SCH_1):PVDDQ_KLM    I90 @BASEBOARD_FAB2_LIB.BASEBOARD_FAB2(SCH_1):PAGE243
     2    GND @BASEBOARD_FAB2_LIB.BASEBOARD_FAB2(SCH_1):GND    I90 @BASEBOARD_FAB2_LIB.BASEBOARD_FAB2(SCH_1):PAGE243

C5G117 CAP_0805-47UF,4V,20%,X6S,C9533A
     1 PVDDQ_GHJ @BASEBOARD_FAB2_LIB.BASEBOARD_FAB2(SCH_1):PVDDQ_GHJ    I92 @BASEBOARD_FAB2_LIB.BASEBOARD_FAB2(SCH_1):PAGE243
     2    GND @BASEBOARD_FAB2_LIB.BASEBOARD_FAB2(SCH_1):GND    I92 @BASEBOARD_FAB2_LIB.BASEBOARD_FAB2(SCH_1):PAGE243

C5G118 CAP_0805-47UF,4V,20%,X6S,C9533A
     1 PVDDQ_GHJ @BASEBOARD_FAB2_LIB.BASEBOARD_FAB2(SCH_1):PVDDQ_GHJ    I91 @BASEBOARD_FAB2_LIB.BASEBOARD_FAB2(SCH_1):PAGE243
     2    GND @BASEBOARD_FAB2_LIB.BASEBOARD_FAB2(SCH_1):GND    I91 @BASEBOARD_FAB2_LIB.BASEBOARD_FAB2(SCH_1):PAGE243

C5L1 CAP_0805-100UF,4V,20%,X5R,6024A
     1 PVDDQ_DEF @BASEBOARD_FAB2_LIB.BASEBOARD_FAB2(SCH_1):PVDDQ_DEF   I309 @BASEBOARD_FAB2_LIB.BASEBOARD_FAB2(SCH_1):PAGE220
     2    GND @BASEBOARD_FAB2_LIB.BASEBOARD_FAB2(SCH_1):GND   I309 @BASEBOARD_FAB2_LIB.BASEBOARD_FAB2(SCH_1):PAGE220

C5L2 CAP_0805-100UF,4V,20%,X5R,6024A
     1 PVDDQ_DEF @BASEBOARD_FAB2_LIB.BASEBOARD_FAB2(SCH_1):PVDDQ_DEF   I311 @BASEBOARD_FAB2_LIB.BASEBOARD_FAB2(SCH_1):PAGE220
     2    GND @BASEBOARD_FAB2_LIB.BASEBOARD_FAB2(SCH_1):GND   I311 @BASEBOARD_FAB2_LIB.BASEBOARD_FAB2(SCH_1):PAGE220

C5L3 CAP_0805-100UF,4V,20%,X5R,6024A
     1 PVDDQ_DEF @BASEBOARD_FAB2_LIB.BASEBOARD_FAB2(SCH_1):PVDDQ_DEF   I310 @BASEBOARD_FAB2_LIB.BASEBOARD_FAB2(SCH_1):PAGE220
     2    GND @BASEBOARD_FAB2_LIB.BASEBOARD_FAB2(SCH_1):GND   I310 @BASEBOARD_FAB2_LIB.BASEBOARD_FAB2(SCH_1):PAGE220

C5L4 CAP_0805-100UF,4V,20%,X5R,6024A
     1 PVTT_DEF @BASEBOARD_FAB2_LIB.BASEBOARD_FAB2(SCH_1):PVTT_DEF    I45 @BASEBOARD_FAB2_LIB.BASEBOARD_FAB2(SCH_1):PAGE222
     2    GND @BASEBOARD_FAB2_LIB.BASEBOARD_FAB2(SCH_1):GND    I45 @BASEBOARD_FAB2_LIB.BASEBOARD_FAB2(SCH_1):PAGE222

C5L5 CAP_0805-100UF,4V,20%,X5R,6024A
     1 PVTT_DEF @BASEBOARD_FAB2_LIB.BASEBOARD_FAB2(SCH_1):PVTT_DEF    I44 @BASEBOARD_FAB2_LIB.BASEBOARD_FAB2(SCH_1):PAGE222
     2    GND @BASEBOARD_FAB2_LIB.BASEBOARD_FAB2(SCH_1):GND    I44 @BASEBOARD_FAB2_LIB.BASEBOARD_FAB2(SCH_1):PAGE222

C5L6 CAP_A_0603V-47UF,4V,20%,X5R,60A
     1 PVDDQ_DEF @BASEBOARD_FAB2_LIB.BASEBOARD_FAB2(SCH_1):PVDDQ_DEF   I278 @BASEBOARD_FAB2_LIB.BASEBOARD_FAB2(SCH_1):PAGE220
     2    GND @BASEBOARD_FAB2_LIB.BASEBOARD_FAB2(SCH_1):GND   I278 @BASEBOARD_FAB2_LIB.BASEBOARD_FAB2(SCH_1):PAGE220

C5L7 CAP_A_0603V-47UF,4V,20%,X5R,60A
     1 PVDDQ_DEF @BASEBOARD_FAB2_LIB.BASEBOARD_FAB2(SCH_1):PVDDQ_DEF   I279 @BASEBOARD_FAB2_LIB.BASEBOARD_FAB2(SCH_1):PAGE220
     2    GND @BASEBOARD_FAB2_LIB.BASEBOARD_FAB2(SCH_1):GND   I279 @BASEBOARD_FAB2_LIB.BASEBOARD_FAB2(SCH_1):PAGE220

C5L8 CAP_A_0603V-47UF,4V,20%,X5R,60A
     1 PVDDQ_DEF @BASEBOARD_FAB2_LIB.BASEBOARD_FAB2(SCH_1):PVDDQ_DEF   I280 @BASEBOARD_FAB2_LIB.BASEBOARD_FAB2(SCH_1):PAGE220
     2    GND @BASEBOARD_FAB2_LIB.BASEBOARD_FAB2(SCH_1):GND   I280 @BASEBOARD_FAB2_LIB.BASEBOARD_FAB2(SCH_1):PAGE220

C5L9 CAP_A_0603V-47UF,4V,20%,X5R,60A
     1 PVDDQ_DEF @BASEBOARD_FAB2_LIB.BASEBOARD_FAB2(SCH_1):PVDDQ_DEF   I281 @BASEBOARD_FAB2_LIB.BASEBOARD_FAB2(SCH_1):PAGE220
     2    GND @BASEBOARD_FAB2_LIB.BASEBOARD_FAB2(SCH_1):GND   I281 @BASEBOARD_FAB2_LIB.BASEBOARD_FAB2(SCH_1):PAGE220

C5L10 CAP_A_0603V-47UF,4V,20%,X5R,60A
     1 PVDDQ_DEF @BASEBOARD_FAB2_LIB.BASEBOARD_FAB2(SCH_1):PVDDQ_DEF   I282 @BASEBOARD_FAB2_LIB.BASEBOARD_FAB2(SCH_1):PAGE220
     2    GND @BASEBOARD_FAB2_LIB.BASEBOARD_FAB2(SCH_1):GND   I282 @BASEBOARD_FAB2_LIB.BASEBOARD_FAB2(SCH_1):PAGE220

C5L11 CAP_A_0603V-47UF,4V,20%,X5R,60A
     1 PVDDQ_DEF @BASEBOARD_FAB2_LIB.BASEBOARD_FAB2(SCH_1):PVDDQ_DEF   I283 @BASEBOARD_FAB2_LIB.BASEBOARD_FAB2(SCH_1):PAGE220
     2    GND @BASEBOARD_FAB2_LIB.BASEBOARD_FAB2(SCH_1):GND   I283 @BASEBOARD_FAB2_LIB.BASEBOARD_FAB2(SCH_1):PAGE220

C5L12 CAP_A_0603V-47UF,4V,20%,X5R,60A
     1 PVDDQ_DEF @BASEBOARD_FAB2_LIB.BASEBOARD_FAB2(SCH_1):PVDDQ_DEF   I284 @BASEBOARD_FAB2_LIB.BASEBOARD_FAB2(SCH_1):PAGE220
     2    GND @BASEBOARD_FAB2_LIB.BASEBOARD_FAB2(SCH_1):GND   I284 @BASEBOARD_FAB2_LIB.BASEBOARD_FAB2(SCH_1):PAGE220

C5L13 CAP_A_0603V-47UF,4V,20%,X5R,60A
     1 PVDDQ_DEF @BASEBOARD_FAB2_LIB.BASEBOARD_FAB2(SCH_1):PVDDQ_DEF   I285 @BASEBOARD_FAB2_LIB.BASEBOARD_FAB2(SCH_1):PAGE220
     2    GND @BASEBOARD_FAB2_LIB.BASEBOARD_FAB2(SCH_1):GND   I285 @BASEBOARD_FAB2_LIB.BASEBOARD_FAB2(SCH_1):PAGE220

C5L14 CAP_0805-100UF,4V,20%,X5R,6024A
     1 PVDDQ_DEF @BASEBOARD_FAB2_LIB.BASEBOARD_FAB2(SCH_1):PVDDQ_DEF   I313 @BASEBOARD_FAB2_LIB.BASEBOARD_FAB2(SCH_1):PAGE220
     2    GND @BASEBOARD_FAB2_LIB.BASEBOARD_FAB2(SCH_1):GND   I313 @BASEBOARD_FAB2_LIB.BASEBOARD_FAB2(SCH_1):PAGE220

C5L15 CAP_A_0603V-47UF,4V,20%,X5R,60A
     1 PVDDQ_DEF @BASEBOARD_FAB2_LIB.BASEBOARD_FAB2(SCH_1):PVDDQ_DEF   I192 @BASEBOARD_FAB2_LIB.BASEBOARD_FAB2(SCH_1):PAGE220
     2    GND @BASEBOARD_FAB2_LIB.BASEBOARD_FAB2(SCH_1):GND   I192 @BASEBOARD_FAB2_LIB.BASEBOARD_FAB2(SCH_1):PAGE220

C5M1 CAP_A_0603V-47UF,4V,20%,X5R,60A
     1 PVDDQ_DEF @BASEBOARD_FAB2_LIB.BASEBOARD_FAB2(SCH_1):PVDDQ_DEF   I291 @BASEBOARD_FAB2_LIB.BASEBOARD_FAB2(SCH_1):PAGE220
     2    GND @BASEBOARD_FAB2_LIB.BASEBOARD_FAB2(SCH_1):GND   I291 @BASEBOARD_FAB2_LIB.BASEBOARD_FAB2(SCH_1):PAGE220

C5M2 CAP_A_0603V-47UF,4V,20%,X5R,60A
     1 PVDDQ_DEF @BASEBOARD_FAB2_LIB.BASEBOARD_FAB2(SCH_1):PVDDQ_DEF   I290 @BASEBOARD_FAB2_LIB.BASEBOARD_FAB2(SCH_1):PAGE220
     2    GND @BASEBOARD_FAB2_LIB.BASEBOARD_FAB2(SCH_1):GND   I290 @BASEBOARD_FAB2_LIB.BASEBOARD_FAB2(SCH_1):PAGE220

C5M3 CAP_A_0603V-47UF,4V,20%,X5R,60A
     1 PVDDQ_DEF @BASEBOARD_FAB2_LIB.BASEBOARD_FAB2(SCH_1):PVDDQ_DEF   I199 @BASEBOARD_FAB2_LIB.BASEBOARD_FAB2(SCH_1):PAGE220
     2    GND @BASEBOARD_FAB2_LIB.BASEBOARD_FAB2(SCH_1):GND   I199 @BASEBOARD_FAB2_LIB.BASEBOARD_FAB2(SCH_1):PAGE220

C5M4 CAP_A_0603V-47UF,4V,20%,X5R,60A
     1 PVDDQ_DEF @BASEBOARD_FAB2_LIB.BASEBOARD_FAB2(SCH_1):PVDDQ_DEF   I289 @BASEBOARD_FAB2_LIB.BASEBOARD_FAB2(SCH_1):PAGE220
     2    GND @BASEBOARD_FAB2_LIB.BASEBOARD_FAB2(SCH_1):GND   I289 @BASEBOARD_FAB2_LIB.BASEBOARD_FAB2(SCH_1):PAGE220

C5M5 CAP_A_0603V-47UF,4V,20%,X5R,60A
     1 PVDDQ_DEF @BASEBOARD_FAB2_LIB.BASEBOARD_FAB2(SCH_1):PVDDQ_DEF   I288 @BASEBOARD_FAB2_LIB.BASEBOARD_FAB2(SCH_1):PAGE220
     2    GND @BASEBOARD_FAB2_LIB.BASEBOARD_FAB2(SCH_1):GND   I288 @BASEBOARD_FAB2_LIB.BASEBOARD_FAB2(SCH_1):PAGE220

C5M6 CAP_A_0603V-47UF,4V,20%,X5R,60A
     1 PVDDQ_DEF @BASEBOARD_FAB2_LIB.BASEBOARD_FAB2(SCH_1):PVDDQ_DEF   I287 @BASEBOARD_FAB2_LIB.BASEBOARD_FAB2(SCH_1):PAGE220
     2    GND @BASEBOARD_FAB2_LIB.BASEBOARD_FAB2(SCH_1):GND   I287 @BASEBOARD_FAB2_LIB.BASEBOARD_FAB2(SCH_1):PAGE220

C5M7 CAP_A_0603V-47UF,4V,20%,X5R,60A
     1 PVDDQ_DEF @BASEBOARD_FAB2_LIB.BASEBOARD_FAB2(SCH_1):PVDDQ_DEF   I286 @BASEBOARD_FAB2_LIB.BASEBOARD_FAB2(SCH_1):PAGE220
     2    GND @BASEBOARD_FAB2_LIB.BASEBOARD_FAB2(SCH_1):GND   I286 @BASEBOARD_FAB2_LIB.BASEBOARD_FAB2(SCH_1):PAGE220

C5M8 CAP_0805-100UF,4V,20%,X5R,6024A
     1 PVDDQ_DEF @BASEBOARD_FAB2_LIB.BASEBOARD_FAB2(SCH_1):PVDDQ_DEF   I314 @BASEBOARD_FAB2_LIB.BASEBOARD_FAB2(SCH_1):PAGE220
     2    GND @BASEBOARD_FAB2_LIB.BASEBOARD_FAB2(SCH_1):GND   I314 @BASEBOARD_FAB2_LIB.BASEBOARD_FAB2(SCH_1):PAGE220

C5M9 CAP_A_0603V-47UF,4V,20%,X5R,60A
     1 PVDDQ_DEF @BASEBOARD_FAB2_LIB.BASEBOARD_FAB2(SCH_1):PVDDQ_DEF   I195 @BASEBOARD_FAB2_LIB.BASEBOARD_FAB2(SCH_1):PAGE220
     2    GND @BASEBOARD_FAB2_LIB.BASEBOARD_FAB2(SCH_1):GND   I195 @BASEBOARD_FAB2_LIB.BASEBOARD_FAB2(SCH_1):PAGE220

C5M10 CAP_A_0603V-47UF,4V,20%,X5R,60A
     1 PVDDQ_DEF @BASEBOARD_FAB2_LIB.BASEBOARD_FAB2(SCH_1):PVDDQ_DEF   I198 @BASEBOARD_FAB2_LIB.BASEBOARD_FAB2(SCH_1):PAGE220
     2    GND @BASEBOARD_FAB2_LIB.BASEBOARD_FAB2(SCH_1):GND   I198 @BASEBOARD_FAB2_LIB.BASEBOARD_FAB2(SCH_1):PAGE220

C5M11 CAP_A_0603V-47UF,4V,20%,X5R,60A
     1 PVDDQ_DEF @BASEBOARD_FAB2_LIB.BASEBOARD_FAB2(SCH_1):PVDDQ_DEF   I200 @BASEBOARD_FAB2_LIB.BASEBOARD_FAB2(SCH_1):PAGE220
     2    GND @BASEBOARD_FAB2_LIB.BASEBOARD_FAB2(SCH_1):GND   I200 @BASEBOARD_FAB2_LIB.BASEBOARD_FAB2(SCH_1):PAGE220

C5M12 CAP_0805-100UF,4V,20%,X5R,6024A
     1 PVDDQ_DEF @BASEBOARD_FAB2_LIB.BASEBOARD_FAB2(SCH_1):PVDDQ_DEF   I312 @BASEBOARD_FAB2_LIB.BASEBOARD_FAB2(SCH_1):PAGE220
     2    GND @BASEBOARD_FAB2_LIB.BASEBOARD_FAB2(SCH_1):GND   I312 @BASEBOARD_FAB2_LIB.BASEBOARD_FAB2(SCH_1):PAGE220

C5M13 CAP_A_0603V-47UF,4V,20%,X5R,60A
     1 PVTT_DEF @BASEBOARD_FAB2_LIB.BASEBOARD_FAB2(SCH_1):PVTT_DEF    I41 @BASEBOARD_FAB2_LIB.BASEBOARD_FAB2(SCH_1):PAGE222
     2    GND @BASEBOARD_FAB2_LIB.BASEBOARD_FAB2(SCH_1):GND    I41 @BASEBOARD_FAB2_LIB.BASEBOARD_FAB2(SCH_1):PAGE222

C5P1 CAP_0805-100UF,4V,20%,X5R,6024A
     1 PVDDQ_DEF @BASEBOARD_FAB2_LIB.BASEBOARD_FAB2(SCH_1):PVDDQ_DEF   I320 @BASEBOARD_FAB2_LIB.BASEBOARD_FAB2(SCH_1):PAGE220
     2    GND @BASEBOARD_FAB2_LIB.BASEBOARD_FAB2(SCH_1):GND   I320 @BASEBOARD_FAB2_LIB.BASEBOARD_FAB2(SCH_1):PAGE220

C5P2 CAP_0805-100UF,4V,20%,X5R,6024A
     1 PVDDQ_DEF @BASEBOARD_FAB2_LIB.BASEBOARD_FAB2(SCH_1):PVDDQ_DEF   I319 @BASEBOARD_FAB2_LIB.BASEBOARD_FAB2(SCH_1):PAGE220
     2    GND @BASEBOARD_FAB2_LIB.BASEBOARD_FAB2(SCH_1):GND   I319 @BASEBOARD_FAB2_LIB.BASEBOARD_FAB2(SCH_1):PAGE220

C5P3 CAP_0805-100UF,4V,20%,X5R,6024A
     1 PVDDQ_DEF @BASEBOARD_FAB2_LIB.BASEBOARD_FAB2(SCH_1):PVDDQ_DEF   I315 @BASEBOARD_FAB2_LIB.BASEBOARD_FAB2(SCH_1):PAGE220
     2    GND @BASEBOARD_FAB2_LIB.BASEBOARD_FAB2(SCH_1):GND   I315 @BASEBOARD_FAB2_LIB.BASEBOARD_FAB2(SCH_1):PAGE220

C5P4 CAP_0805-100UF,4V,20%,X5R,6024A
     1 PVDDQ_DEF @BASEBOARD_FAB2_LIB.BASEBOARD_FAB2(SCH_1):PVDDQ_DEF   I318 @BASEBOARD_FAB2_LIB.BASEBOARD_FAB2(SCH_1):PAGE220
     2    GND @BASEBOARD_FAB2_LIB.BASEBOARD_FAB2(SCH_1):GND   I318 @BASEBOARD_FAB2_LIB.BASEBOARD_FAB2(SCH_1):PAGE220

C5P5 CAP_0805-100UF,4V,20%,X5R,6024A
     1 PVDDQ_DEF @BASEBOARD_FAB2_LIB.BASEBOARD_FAB2(SCH_1):PVDDQ_DEF   I317 @BASEBOARD_FAB2_LIB.BASEBOARD_FAB2(SCH_1):PAGE220
     2    GND @BASEBOARD_FAB2_LIB.BASEBOARD_FAB2(SCH_1):GND   I317 @BASEBOARD_FAB2_LIB.BASEBOARD_FAB2(SCH_1):PAGE220

C5P6 CAP_0805-100UF,4V,20%,X5R,6024A
     1 PVDDQ_DEF @BASEBOARD_FAB2_LIB.BASEBOARD_FAB2(SCH_1):PVDDQ_DEF   I316 @BASEBOARD_FAB2_LIB.BASEBOARD_FAB2(SCH_1):PAGE220
     2    GND @BASEBOARD_FAB2_LIB.BASEBOARD_FAB2(SCH_1):GND   I316 @BASEBOARD_FAB2_LIB.BASEBOARD_FAB2(SCH_1):PAGE220

C5P7 CAP_0805LF-22UF,4V,20%,X6S,C95A
     1 PVSA_CPU0 @BASEBOARD_FAB2_LIB.BASEBOARD_FAB2(SCH_1):PVSA_CPU0    I25 @BASEBOARD_FAB2_LIB.BASEBOARD_FAB2(SCH_1):PAGE42
     2    GND @BASEBOARD_FAB2_LIB.BASEBOARD_FAB2(SCH_1):GND    I25 @BASEBOARD_FAB2_LIB.BASEBOARD_FAB2(SCH_1):PAGE42

C5P8 CAP_0805LF-22UF,4V,20%,X6S,C95A
     1 PVSA_CPU0 @BASEBOARD_FAB2_LIB.BASEBOARD_FAB2(SCH_1):PVSA_CPU0   I214 @BASEBOARD_FAB2_LIB.BASEBOARD_FAB2(SCH_1):PAGE42
     2    GND @BASEBOARD_FAB2_LIB.BASEBOARD_FAB2(SCH_1):GND   I214 @BASEBOARD_FAB2_LIB.BASEBOARD_FAB2(SCH_1):PAGE42

C5P9 CAP_0805LF-22UF,4V,20%,X6S,C95A
     1 PVSA_CPU0 @BASEBOARD_FAB2_LIB.BASEBOARD_FAB2(SCH_1):PVSA_CPU0   I215 @BASEBOARD_FAB2_LIB.BASEBOARD_FAB2(SCH_1):PAGE42
     2    GND @BASEBOARD_FAB2_LIB.BASEBOARD_FAB2(SCH_1):GND   I215 @BASEBOARD_FAB2_LIB.BASEBOARD_FAB2(SCH_1):PAGE42

C5P10 CAP_0805-100UF,4V,20%,X5R,6024A
     1 PVCCMCP_CPU0 @BASEBOARD_FAB2_LIB.BASEBOARD_FAB2(SCH_1):PVCCMCP_CPU0   I226 @BASEBOARD_FAB2_LIB.BASEBOARD_FAB2(SCH_1):PAGE42
     2    GND @BASEBOARD_FAB2_LIB.BASEBOARD_FAB2(SCH_1):GND   I226 @BASEBOARD_FAB2_LIB.BASEBOARD_FAB2(SCH_1):PAGE42

C5P11 CAP_0805-100UF,4V,20%,X5R,6024A
     1 PVCCMCP_CPU0 @BASEBOARD_FAB2_LIB.BASEBOARD_FAB2(SCH_1):PVCCMCP_CPU0   I227 @BASEBOARD_FAB2_LIB.BASEBOARD_FAB2(SCH_1):PAGE42
     2    GND @BASEBOARD_FAB2_LIB.BASEBOARD_FAB2(SCH_1):GND   I227 @BASEBOARD_FAB2_LIB.BASEBOARD_FAB2(SCH_1):PAGE42

C5P12 CAP_0805-100UF,4V,20%,X5R,6024A
     1 PVCCMCP_CPU0 @BASEBOARD_FAB2_LIB.BASEBOARD_FAB2(SCH_1):PVCCMCP_CPU0   I236 @BASEBOARD_FAB2_LIB.BASEBOARD_FAB2(SCH_1):PAGE42
     2    GND @BASEBOARD_FAB2_LIB.BASEBOARD_FAB2(SCH_1):GND   I236 @BASEBOARD_FAB2_LIB.BASEBOARD_FAB2(SCH_1):PAGE42

C5P13 CAP_0805-100UF,4V,20%,X5R,6024A
     1 PVCCMCP_CPU0 @BASEBOARD_FAB2_LIB.BASEBOARD_FAB2(SCH_1):PVCCMCP_CPU0   I232 @BASEBOARD_FAB2_LIB.BASEBOARD_FAB2(SCH_1):PAGE42
     2    GND @BASEBOARD_FAB2_LIB.BASEBOARD_FAB2(SCH_1):GND   I232 @BASEBOARD_FAB2_LIB.BASEBOARD_FAB2(SCH_1):PAGE42

C5P14 CAP_0805-47UF,4V,20%,X6S,C9533A
     1 PVCCIN_CPU0 @BASEBOARD_FAB2_LIB.BASEBOARD_FAB2(SCH_1):PVCCIN_CPU0    I41 @BASEBOARD_FAB2_LIB.BASEBOARD_FAB2(SCH_1):PAGE42
     2    GND @BASEBOARD_FAB2_LIB.BASEBOARD_FAB2(SCH_1):GND    I41 @BASEBOARD_FAB2_LIB.BASEBOARD_FAB2(SCH_1):PAGE42

C5P15 CAP_0805-47UF,4V,20%,X6S,C9533A
     1 PVCCIN_CPU0 @BASEBOARD_FAB2_LIB.BASEBOARD_FAB2(SCH_1):PVCCIN_CPU0   I187 @BASEBOARD_FAB2_LIB.BASEBOARD_FAB2(SCH_1):PAGE42
     2    GND @BASEBOARD_FAB2_LIB.BASEBOARD_FAB2(SCH_1):GND   I187 @BASEBOARD_FAB2_LIB.BASEBOARD_FAB2(SCH_1):PAGE42

C5P16 CAP_0805-47UF,4V,20%,X6S,C9533A
     1 PVCCIN_CPU0 @BASEBOARD_FAB2_LIB.BASEBOARD_FAB2(SCH_1):PVCCIN_CPU0   I188 @BASEBOARD_FAB2_LIB.BASEBOARD_FAB2(SCH_1):PAGE42
     2    GND @BASEBOARD_FAB2_LIB.BASEBOARD_FAB2(SCH_1):GND   I188 @BASEBOARD_FAB2_LIB.BASEBOARD_FAB2(SCH_1):PAGE42

C5P17 CAP_0805-47UF,4V,20%,X6S,C9533A
     1 PVCCIN_CPU0 @BASEBOARD_FAB2_LIB.BASEBOARD_FAB2(SCH_1):PVCCIN_CPU0   I190 @BASEBOARD_FAB2_LIB.BASEBOARD_FAB2(SCH_1):PAGE42
     2    GND @BASEBOARD_FAB2_LIB.BASEBOARD_FAB2(SCH_1):GND   I190 @BASEBOARD_FAB2_LIB.BASEBOARD_FAB2(SCH_1):PAGE42

C5P18 CAP_0805-100UF,4V,20%,X5R,6024A
     1 PVCCMCP_CPU0 @BASEBOARD_FAB2_LIB.BASEBOARD_FAB2(SCH_1):PVCCMCP_CPU0   I228 @BASEBOARD_FAB2_LIB.BASEBOARD_FAB2(SCH_1):PAGE42
     2    GND @BASEBOARD_FAB2_LIB.BASEBOARD_FAB2(SCH_1):GND   I228 @BASEBOARD_FAB2_LIB.BASEBOARD_FAB2(SCH_1):PAGE42

C5P19 CAP_0805-100UF,4V,20%,X5R,6024A
     1 PVCCMCP_CPU0 @BASEBOARD_FAB2_LIB.BASEBOARD_FAB2(SCH_1):PVCCMCP_CPU0   I222 @BASEBOARD_FAB2_LIB.BASEBOARD_FAB2(SCH_1):PAGE42
     2    GND @BASEBOARD_FAB2_LIB.BASEBOARD_FAB2(SCH_1):GND   I222 @BASEBOARD_FAB2_LIB.BASEBOARD_FAB2(SCH_1):PAGE42

C5P20 CAP_0805-100UF,4V,20%,X5R,6024A
     1 PVCCMCP_CPU0 @BASEBOARD_FAB2_LIB.BASEBOARD_FAB2(SCH_1):PVCCMCP_CPU0   I234 @BASEBOARD_FAB2_LIB.BASEBOARD_FAB2(SCH_1):PAGE42
     2    GND @BASEBOARD_FAB2_LIB.BASEBOARD_FAB2(SCH_1):GND   I234 @BASEBOARD_FAB2_LIB.BASEBOARD_FAB2(SCH_1):PAGE42

C5P21 CAP_0805-100UF,4V,20%,X5R,6024A
     1 PVCCMCP_CPU0 @BASEBOARD_FAB2_LIB.BASEBOARD_FAB2(SCH_1):PVCCMCP_CPU0   I235 @BASEBOARD_FAB2_LIB.BASEBOARD_FAB2(SCH_1):PAGE42
     2    GND @BASEBOARD_FAB2_LIB.BASEBOARD_FAB2(SCH_1):GND   I235 @BASEBOARD_FAB2_LIB.BASEBOARD_FAB2(SCH_1):PAGE42

C5P22 CAP_0805-47UF,4V,20%,X6S,C9533A
     1 PVCCIN_CPU0 @BASEBOARD_FAB2_LIB.BASEBOARD_FAB2(SCH_1):PVCCIN_CPU0    I55 @BASEBOARD_FAB2_LIB.BASEBOARD_FAB2(SCH_1):PAGE42
     2    GND @BASEBOARD_FAB2_LIB.BASEBOARD_FAB2(SCH_1):GND    I55 @BASEBOARD_FAB2_LIB.BASEBOARD_FAB2(SCH_1):PAGE42

C5P23 CAP_0805-47UF,4V,20%,X6S,C9533A
     1 PVCCIN_CPU0 @BASEBOARD_FAB2_LIB.BASEBOARD_FAB2(SCH_1):PVCCIN_CPU0    I28 @BASEBOARD_FAB2_LIB.BASEBOARD_FAB2(SCH_1):PAGE42
     2    GND @BASEBOARD_FAB2_LIB.BASEBOARD_FAB2(SCH_1):GND    I28 @BASEBOARD_FAB2_LIB.BASEBOARD_FAB2(SCH_1):PAGE42

C5P24 CAP_0805-47UF,4V,20%,X6S,C9533A
     1 PVCCIN_CPU0 @BASEBOARD_FAB2_LIB.BASEBOARD_FAB2(SCH_1):PVCCIN_CPU0    I33 @BASEBOARD_FAB2_LIB.BASEBOARD_FAB2(SCH_1):PAGE42
     2    GND @BASEBOARD_FAB2_LIB.BASEBOARD_FAB2(SCH_1):GND    I33 @BASEBOARD_FAB2_LIB.BASEBOARD_FAB2(SCH_1):PAGE42

C5P25 CAP_0805-47UF,4V,20%,X6S,C9533A
     1 PVCCIN_CPU0 @BASEBOARD_FAB2_LIB.BASEBOARD_FAB2(SCH_1):PVCCIN_CPU0    I37 @BASEBOARD_FAB2_LIB.BASEBOARD_FAB2(SCH_1):PAGE42
     2    GND @BASEBOARD_FAB2_LIB.BASEBOARD_FAB2(SCH_1):GND    I37 @BASEBOARD_FAB2_LIB.BASEBOARD_FAB2(SCH_1):PAGE42

C5P26 CAP_0805-47UF,4V,20%,X6S,C9533A
     1 PVCCIN_CPU0 @BASEBOARD_FAB2_LIB.BASEBOARD_FAB2(SCH_1):PVCCIN_CPU0    I56 @BASEBOARD_FAB2_LIB.BASEBOARD_FAB2(SCH_1):PAGE42
     2    GND @BASEBOARD_FAB2_LIB.BASEBOARD_FAB2(SCH_1):GND    I56 @BASEBOARD_FAB2_LIB.BASEBOARD_FAB2(SCH_1):PAGE42

C5P27 CAP_0805-47UF,4V,20%,X6S,C9533A
     1 PVCCIN_CPU0 @BASEBOARD_FAB2_LIB.BASEBOARD_FAB2(SCH_1):PVCCIN_CPU0    I44 @BASEBOARD_FAB2_LIB.BASEBOARD_FAB2(SCH_1):PAGE42
     2    GND @BASEBOARD_FAB2_LIB.BASEBOARD_FAB2(SCH_1):GND    I44 @BASEBOARD_FAB2_LIB.BASEBOARD_FAB2(SCH_1):PAGE42

C5P28 CAP_0805-100UF,4V,20%,X5R,6024A
     1 PVCCMCP_CPU0 @BASEBOARD_FAB2_LIB.BASEBOARD_FAB2(SCH_1):PVCCMCP_CPU0   I229 @BASEBOARD_FAB2_LIB.BASEBOARD_FAB2(SCH_1):PAGE42
     2    GND @BASEBOARD_FAB2_LIB.BASEBOARD_FAB2(SCH_1):GND   I229 @BASEBOARD_FAB2_LIB.BASEBOARD_FAB2(SCH_1):PAGE42

C5P29 CAP_0805-100UF,4V,20%,X5R,6024A
     1 PVCCMCP_CPU0 @BASEBOARD_FAB2_LIB.BASEBOARD_FAB2(SCH_1):PVCCMCP_CPU0   I220 @BASEBOARD_FAB2_LIB.BASEBOARD_FAB2(SCH_1):PAGE42
     2    GND @BASEBOARD_FAB2_LIB.BASEBOARD_FAB2(SCH_1):GND   I220 @BASEBOARD_FAB2_LIB.BASEBOARD_FAB2(SCH_1):PAGE42

C5P30 CAP_0805-100UF,4V,20%,X5R,6024A
     1 PVCCMCP_CPU0 @BASEBOARD_FAB2_LIB.BASEBOARD_FAB2(SCH_1):PVCCMCP_CPU0   I221 @BASEBOARD_FAB2_LIB.BASEBOARD_FAB2(SCH_1):PAGE42
     2    GND @BASEBOARD_FAB2_LIB.BASEBOARD_FAB2(SCH_1):GND   I221 @BASEBOARD_FAB2_LIB.BASEBOARD_FAB2(SCH_1):PAGE42

C5P31 CAP_0805-100UF,4V,20%,X5R,6024A
     1 PVCCMCP_CPU0 @BASEBOARD_FAB2_LIB.BASEBOARD_FAB2(SCH_1):PVCCMCP_CPU0   I231 @BASEBOARD_FAB2_LIB.BASEBOARD_FAB2(SCH_1):PAGE42
     2    GND @BASEBOARD_FAB2_LIB.BASEBOARD_FAB2(SCH_1):GND   I231 @BASEBOARD_FAB2_LIB.BASEBOARD_FAB2(SCH_1):PAGE42

C5P32 CAP_0805-47UF,4V,20%,X6S,C9533A
     1 PVCCIN_CPU0 @BASEBOARD_FAB2_LIB.BASEBOARD_FAB2(SCH_1):PVCCIN_CPU0    I53 @BASEBOARD_FAB2_LIB.BASEBOARD_FAB2(SCH_1):PAGE42
     2    GND @BASEBOARD_FAB2_LIB.BASEBOARD_FAB2(SCH_1):GND    I53 @BASEBOARD_FAB2_LIB.BASEBOARD_FAB2(SCH_1):PAGE42

C5P33 CAP_0805-47UF,4V,20%,X6S,C9533A
     1 PVCCIN_CPU0 @BASEBOARD_FAB2_LIB.BASEBOARD_FAB2(SCH_1):PVCCIN_CPU0    I50 @BASEBOARD_FAB2_LIB.BASEBOARD_FAB2(SCH_1):PAGE42
     2    GND @BASEBOARD_FAB2_LIB.BASEBOARD_FAB2(SCH_1):GND    I50 @BASEBOARD_FAB2_LIB.BASEBOARD_FAB2(SCH_1):PAGE42

C5P34 CAP_0805-47UF,4V,20%,X6S,C9533A
     1 PVCCIN_CPU0 @BASEBOARD_FAB2_LIB.BASEBOARD_FAB2(SCH_1):PVCCIN_CPU0    I54 @BASEBOARD_FAB2_LIB.BASEBOARD_FAB2(SCH_1):PAGE42
     2    GND @BASEBOARD_FAB2_LIB.BASEBOARD_FAB2(SCH_1):GND    I54 @BASEBOARD_FAB2_LIB.BASEBOARD_FAB2(SCH_1):PAGE42

C5P35 CAP_0805-47UF,4V,20%,X6S,C9533A
     1 PVCCIN_CPU0 @BASEBOARD_FAB2_LIB.BASEBOARD_FAB2(SCH_1):PVCCIN_CPU0    I51 @BASEBOARD_FAB2_LIB.BASEBOARD_FAB2(SCH_1):PAGE42
     2    GND @BASEBOARD_FAB2_LIB.BASEBOARD_FAB2(SCH_1):GND    I51 @BASEBOARD_FAB2_LIB.BASEBOARD_FAB2(SCH_1):PAGE42

C5P36 CAP_0805-47UF,4V,20%,X6S,C9533A
     1 PVCCIN_CPU0 @BASEBOARD_FAB2_LIB.BASEBOARD_FAB2(SCH_1):PVCCIN_CPU0    I65 @BASEBOARD_FAB2_LIB.BASEBOARD_FAB2(SCH_1):PAGE42
     2    GND @BASEBOARD_FAB2_LIB.BASEBOARD_FAB2(SCH_1):GND    I65 @BASEBOARD_FAB2_LIB.BASEBOARD_FAB2(SCH_1):PAGE42

C5P37 CAP_0805-47UF,4V,20%,X6S,C9533A
     1 PVCCIN_CPU0 @BASEBOARD_FAB2_LIB.BASEBOARD_FAB2(SCH_1):PVCCIN_CPU0    I63 @BASEBOARD_FAB2_LIB.BASEBOARD_FAB2(SCH_1):PAGE42
     2    GND @BASEBOARD_FAB2_LIB.BASEBOARD_FAB2(SCH_1):GND    I63 @BASEBOARD_FAB2_LIB.BASEBOARD_FAB2(SCH_1):PAGE42

C5P38 CAP_0805-100UF,4V,20%,X5R,6024A
     1 PVDDQ_ABC @BASEBOARD_FAB2_LIB.BASEBOARD_FAB2(SCH_1):PVDDQ_ABC   I327 @BASEBOARD_FAB2_LIB.BASEBOARD_FAB2(SCH_1):PAGE217
     2    GND @BASEBOARD_FAB2_LIB.BASEBOARD_FAB2(SCH_1):GND   I327 @BASEBOARD_FAB2_LIB.BASEBOARD_FAB2(SCH_1):PAGE217

C5P39 CAP_0805-100UF,4V,20%,X5R,6024A
     1 PVDDQ_ABC @BASEBOARD_FAB2_LIB.BASEBOARD_FAB2(SCH_1):PVDDQ_ABC   I328 @BASEBOARD_FAB2_LIB.BASEBOARD_FAB2(SCH_1):PAGE217
     2    GND @BASEBOARD_FAB2_LIB.BASEBOARD_FAB2(SCH_1):GND   I328 @BASEBOARD_FAB2_LIB.BASEBOARD_FAB2(SCH_1):PAGE217

C5P40 CAP_0805-47UF,4V,20%,X6S,C9533A
     1 PVCCIN_CPU0 @BASEBOARD_FAB2_LIB.BASEBOARD_FAB2(SCH_1):PVCCIN_CPU0    I57 @BASEBOARD_FAB2_LIB.BASEBOARD_FAB2(SCH_1):PAGE42
     2    GND @BASEBOARD_FAB2_LIB.BASEBOARD_FAB2(SCH_1):GND    I57 @BASEBOARD_FAB2_LIB.BASEBOARD_FAB2(SCH_1):PAGE42

C5P41 CAP_0805-100UF,4V,20%,X5R,6024A
     1 PVDDQ_ABC @BASEBOARD_FAB2_LIB.BASEBOARD_FAB2(SCH_1):PVDDQ_ABC   I323 @BASEBOARD_FAB2_LIB.BASEBOARD_FAB2(SCH_1):PAGE217
     2    GND @BASEBOARD_FAB2_LIB.BASEBOARD_FAB2(SCH_1):GND   I323 @BASEBOARD_FAB2_LIB.BASEBOARD_FAB2(SCH_1):PAGE217

C5P42 CAP_0805-100UF,4V,20%,X5R,6024A
     1 PVDDQ_ABC @BASEBOARD_FAB2_LIB.BASEBOARD_FAB2(SCH_1):PVDDQ_ABC   I325 @BASEBOARD_FAB2_LIB.BASEBOARD_FAB2(SCH_1):PAGE217
     2    GND @BASEBOARD_FAB2_LIB.BASEBOARD_FAB2(SCH_1):GND   I325 @BASEBOARD_FAB2_LIB.BASEBOARD_FAB2(SCH_1):PAGE217

C5P43 CAP_0805-100UF,4V,20%,X5R,6024A
     1 PVDDQ_ABC @BASEBOARD_FAB2_LIB.BASEBOARD_FAB2(SCH_1):PVDDQ_ABC   I326 @BASEBOARD_FAB2_LIB.BASEBOARD_FAB2(SCH_1):PAGE217
     2    GND @BASEBOARD_FAB2_LIB.BASEBOARD_FAB2(SCH_1):GND   I326 @BASEBOARD_FAB2_LIB.BASEBOARD_FAB2(SCH_1):PAGE217

C5P44 CAP_0805-100UF,4V,20%,X5R,6024A
     1 PVDDQ_ABC @BASEBOARD_FAB2_LIB.BASEBOARD_FAB2(SCH_1):PVDDQ_ABC   I324 @BASEBOARD_FAB2_LIB.BASEBOARD_FAB2(SCH_1):PAGE217
     2    GND @BASEBOARD_FAB2_LIB.BASEBOARD_FAB2(SCH_1):GND   I324 @BASEBOARD_FAB2_LIB.BASEBOARD_FAB2(SCH_1):PAGE217

C5T1 CAP_A_0603V-47UF,4V,20%,X5R,60A
     1 PVDDQ_ABC @BASEBOARD_FAB2_LIB.BASEBOARD_FAB2(SCH_1):PVDDQ_ABC   I212 @BASEBOARD_FAB2_LIB.BASEBOARD_FAB2(SCH_1):PAGE217
     2    GND @BASEBOARD_FAB2_LIB.BASEBOARD_FAB2(SCH_1):GND   I212 @BASEBOARD_FAB2_LIB.BASEBOARD_FAB2(SCH_1):PAGE217

C5T2 CAP_A_0603V-47UF,4V,20%,X5R,60A
     1 PVDDQ_ABC @BASEBOARD_FAB2_LIB.BASEBOARD_FAB2(SCH_1):PVDDQ_ABC   I208 @BASEBOARD_FAB2_LIB.BASEBOARD_FAB2(SCH_1):PAGE217
     2    GND @BASEBOARD_FAB2_LIB.BASEBOARD_FAB2(SCH_1):GND   I208 @BASEBOARD_FAB2_LIB.BASEBOARD_FAB2(SCH_1):PAGE217

C5T3 CAP_A_0603V-47UF,4V,20%,X5R,60A
     1 PVTT_ABC @BASEBOARD_FAB2_LIB.BASEBOARD_FAB2(SCH_1):PVTT_ABC    I40 @BASEBOARD_FAB2_LIB.BASEBOARD_FAB2(SCH_1):PAGE221
     2    GND @BASEBOARD_FAB2_LIB.BASEBOARD_FAB2(SCH_1):GND    I40 @BASEBOARD_FAB2_LIB.BASEBOARD_FAB2(SCH_1):PAGE221

C5T4 CAP_A_0603V-47UF,4V,20%,X5R,60A
     1 PVDDQ_ABC @BASEBOARD_FAB2_LIB.BASEBOARD_FAB2(SCH_1):PVDDQ_ABC   I211 @BASEBOARD_FAB2_LIB.BASEBOARD_FAB2(SCH_1):PAGE217
     2    GND @BASEBOARD_FAB2_LIB.BASEBOARD_FAB2(SCH_1):GND   I211 @BASEBOARD_FAB2_LIB.BASEBOARD_FAB2(SCH_1):PAGE217

C5T5 CAP_A_0603V-47UF,4V,20%,X5R,60A
     1 PVDDQ_ABC @BASEBOARD_FAB2_LIB.BASEBOARD_FAB2(SCH_1):PVDDQ_ABC   I298 @BASEBOARD_FAB2_LIB.BASEBOARD_FAB2(SCH_1):PAGE217
     2    GND @BASEBOARD_FAB2_LIB.BASEBOARD_FAB2(SCH_1):GND   I298 @BASEBOARD_FAB2_LIB.BASEBOARD_FAB2(SCH_1):PAGE217

C5T6 CAP_A_0603V-47UF,4V,20%,X5R,60A
     1 PVDDQ_ABC @BASEBOARD_FAB2_LIB.BASEBOARD_FAB2(SCH_1):PVDDQ_ABC   I297 @BASEBOARD_FAB2_LIB.BASEBOARD_FAB2(SCH_1):PAGE217
     2    GND @BASEBOARD_FAB2_LIB.BASEBOARD_FAB2(SCH_1):GND   I297 @BASEBOARD_FAB2_LIB.BASEBOARD_FAB2(SCH_1):PAGE217

C5T7 CAP_A_0603V-47UF,4V,20%,X5R,60A
     1 PVDDQ_ABC @BASEBOARD_FAB2_LIB.BASEBOARD_FAB2(SCH_1):PVDDQ_ABC   I296 @BASEBOARD_FAB2_LIB.BASEBOARD_FAB2(SCH_1):PAGE217
     2    GND @BASEBOARD_FAB2_LIB.BASEBOARD_FAB2(SCH_1):GND   I296 @BASEBOARD_FAB2_LIB.BASEBOARD_FAB2(SCH_1):PAGE217

C5T8 CAP_A_0603V-47UF,4V,20%,X5R,60A
     1 PVDDQ_ABC @BASEBOARD_FAB2_LIB.BASEBOARD_FAB2(SCH_1):PVDDQ_ABC   I295 @BASEBOARD_FAB2_LIB.BASEBOARD_FAB2(SCH_1):PAGE217
     2    GND @BASEBOARD_FAB2_LIB.BASEBOARD_FAB2(SCH_1):GND   I295 @BASEBOARD_FAB2_LIB.BASEBOARD_FAB2(SCH_1):PAGE217

C5T9 CAP_A_0603V-47UF,4V,20%,X5R,60A
     1 PVDDQ_ABC @BASEBOARD_FAB2_LIB.BASEBOARD_FAB2(SCH_1):PVDDQ_ABC   I294 @BASEBOARD_FAB2_LIB.BASEBOARD_FAB2(SCH_1):PAGE217
     2    GND @BASEBOARD_FAB2_LIB.BASEBOARD_FAB2(SCH_1):GND   I294 @BASEBOARD_FAB2_LIB.BASEBOARD_FAB2(SCH_1):PAGE217

C5T10 CAP_A_0603V-47UF,4V,20%,X5R,60A
     1 PVDDQ_ABC @BASEBOARD_FAB2_LIB.BASEBOARD_FAB2(SCH_1):PVDDQ_ABC   I293 @BASEBOARD_FAB2_LIB.BASEBOARD_FAB2(SCH_1):PAGE217
     2    GND @BASEBOARD_FAB2_LIB.BASEBOARD_FAB2(SCH_1):GND   I293 @BASEBOARD_FAB2_LIB.BASEBOARD_FAB2(SCH_1):PAGE217

C5T11 CAP_A_0603V-47UF,4V,20%,X5R,60A
     1 PVDDQ_ABC @BASEBOARD_FAB2_LIB.BASEBOARD_FAB2(SCH_1):PVDDQ_ABC   I292 @BASEBOARD_FAB2_LIB.BASEBOARD_FAB2(SCH_1):PAGE217
     2    GND @BASEBOARD_FAB2_LIB.BASEBOARD_FAB2(SCH_1):GND   I292 @BASEBOARD_FAB2_LIB.BASEBOARD_FAB2(SCH_1):PAGE217

C5T12 CAP_A_0603V-47UF,4V,20%,X5R,60A
     1 PVDDQ_ABC @BASEBOARD_FAB2_LIB.BASEBOARD_FAB2(SCH_1):PVDDQ_ABC   I291 @BASEBOARD_FAB2_LIB.BASEBOARD_FAB2(SCH_1):PAGE217
     2    GND @BASEBOARD_FAB2_LIB.BASEBOARD_FAB2(SCH_1):GND   I291 @BASEBOARD_FAB2_LIB.BASEBOARD_FAB2(SCH_1):PAGE217

C5T13 CAP_A_0603V-47UF,4V,20%,X5R,60A
     1 PVDDQ_ABC @BASEBOARD_FAB2_LIB.BASEBOARD_FAB2(SCH_1):PVDDQ_ABC   I210 @BASEBOARD_FAB2_LIB.BASEBOARD_FAB2(SCH_1):PAGE217
     2    GND @BASEBOARD_FAB2_LIB.BASEBOARD_FAB2(SCH_1):GND   I210 @BASEBOARD_FAB2_LIB.BASEBOARD_FAB2(SCH_1):PAGE217

C5U1 CAP_0805-100UF,4V,20%,X5R,6024A
     1 PVDDQ_ABC @BASEBOARD_FAB2_LIB.BASEBOARD_FAB2(SCH_1):PVDDQ_ABC   I316 @BASEBOARD_FAB2_LIB.BASEBOARD_FAB2(SCH_1):PAGE217
     2    GND @BASEBOARD_FAB2_LIB.BASEBOARD_FAB2(SCH_1):GND   I316 @BASEBOARD_FAB2_LIB.BASEBOARD_FAB2(SCH_1):PAGE217

C5U2 CAP_A_0603V-47UF,4V,20%,X5R,60A
     1 PVDDQ_ABC @BASEBOARD_FAB2_LIB.BASEBOARD_FAB2(SCH_1):PVDDQ_ABC   I283 @BASEBOARD_FAB2_LIB.BASEBOARD_FAB2(SCH_1):PAGE217
     2    GND @BASEBOARD_FAB2_LIB.BASEBOARD_FAB2(SCH_1):GND   I283 @BASEBOARD_FAB2_LIB.BASEBOARD_FAB2(SCH_1):PAGE217

C5U3 CAP_A_0603V-47UF,4V,20%,X5R,60A
     1 PVDDQ_ABC @BASEBOARD_FAB2_LIB.BASEBOARD_FAB2(SCH_1):PVDDQ_ABC   I284 @BASEBOARD_FAB2_LIB.BASEBOARD_FAB2(SCH_1):PAGE217
     2    GND @BASEBOARD_FAB2_LIB.BASEBOARD_FAB2(SCH_1):GND   I284 @BASEBOARD_FAB2_LIB.BASEBOARD_FAB2(SCH_1):PAGE217

C5U4 CAP_A_0603V-47UF,4V,20%,X5R,60A
     1 PVDDQ_ABC @BASEBOARD_FAB2_LIB.BASEBOARD_FAB2(SCH_1):PVDDQ_ABC   I285 @BASEBOARD_FAB2_LIB.BASEBOARD_FAB2(SCH_1):PAGE217
     2    GND @BASEBOARD_FAB2_LIB.BASEBOARD_FAB2(SCH_1):GND   I285 @BASEBOARD_FAB2_LIB.BASEBOARD_FAB2(SCH_1):PAGE217

C5U5 CAP_A_0603V-47UF,4V,20%,X5R,60A
     1 PVDDQ_ABC @BASEBOARD_FAB2_LIB.BASEBOARD_FAB2(SCH_1):PVDDQ_ABC   I286 @BASEBOARD_FAB2_LIB.BASEBOARD_FAB2(SCH_1):PAGE217
     2    GND @BASEBOARD_FAB2_LIB.BASEBOARD_FAB2(SCH_1):GND   I286 @BASEBOARD_FAB2_LIB.BASEBOARD_FAB2(SCH_1):PAGE217

C5U6 CAP_A_0603V-47UF,4V,20%,X5R,60A
     1 PVDDQ_ABC @BASEBOARD_FAB2_LIB.BASEBOARD_FAB2(SCH_1):PVDDQ_ABC   I287 @BASEBOARD_FAB2_LIB.BASEBOARD_FAB2(SCH_1):PAGE217
     2    GND @BASEBOARD_FAB2_LIB.BASEBOARD_FAB2(SCH_1):GND   I287 @BASEBOARD_FAB2_LIB.BASEBOARD_FAB2(SCH_1):PAGE217

C5U7 CAP_A_0603V-47UF,4V,20%,X5R,60A
     1 PVDDQ_ABC @BASEBOARD_FAB2_LIB.BASEBOARD_FAB2(SCH_1):PVDDQ_ABC   I288 @BASEBOARD_FAB2_LIB.BASEBOARD_FAB2(SCH_1):PAGE217
     2    GND @BASEBOARD_FAB2_LIB.BASEBOARD_FAB2(SCH_1):GND   I288 @BASEBOARD_FAB2_LIB.BASEBOARD_FAB2(SCH_1):PAGE217

C5U8 CAP_A_0603V-47UF,4V,20%,X5R,60A
     1 PVDDQ_ABC @BASEBOARD_FAB2_LIB.BASEBOARD_FAB2(SCH_1):PVDDQ_ABC   I289 @BASEBOARD_FAB2_LIB.BASEBOARD_FAB2(SCH_1):PAGE217
     2    GND @BASEBOARD_FAB2_LIB.BASEBOARD_FAB2(SCH_1):GND   I289 @BASEBOARD_FAB2_LIB.BASEBOARD_FAB2(SCH_1):PAGE217

C5U9 CAP_A_0603V-47UF,4V,20%,X5R,60A
     1 PVDDQ_ABC @BASEBOARD_FAB2_LIB.BASEBOARD_FAB2(SCH_1):PVDDQ_ABC   I290 @BASEBOARD_FAB2_LIB.BASEBOARD_FAB2(SCH_1):PAGE217
     2    GND @BASEBOARD_FAB2_LIB.BASEBOARD_FAB2(SCH_1):GND   I290 @BASEBOARD_FAB2_LIB.BASEBOARD_FAB2(SCH_1):PAGE217

C5U10 CAP_0805-100UF,4V,20%,X5R,6024A
     1 PVDDQ_ABC @BASEBOARD_FAB2_LIB.BASEBOARD_FAB2(SCH_1):PVDDQ_ABC   I317 @BASEBOARD_FAB2_LIB.BASEBOARD_FAB2(SCH_1):PAGE217
     2    GND @BASEBOARD_FAB2_LIB.BASEBOARD_FAB2(SCH_1):GND   I317 @BASEBOARD_FAB2_LIB.BASEBOARD_FAB2(SCH_1):PAGE217

C5U11 CAP_A_0603V-47UF,4V,20%,X5R,60A
     1 PVDDQ_ABC @BASEBOARD_FAB2_LIB.BASEBOARD_FAB2(SCH_1):PVDDQ_ABC   I209 @BASEBOARD_FAB2_LIB.BASEBOARD_FAB2(SCH_1):PAGE217
     2    GND @BASEBOARD_FAB2_LIB.BASEBOARD_FAB2(SCH_1):GND   I209 @BASEBOARD_FAB2_LIB.BASEBOARD_FAB2(SCH_1):PAGE217

C5U12 CAP_0805-100UF,4V,20%,X5R,6024A
     1 PVTT_ABC @BASEBOARD_FAB2_LIB.BASEBOARD_FAB2(SCH_1):PVTT_ABC    I45 @BASEBOARD_FAB2_LIB.BASEBOARD_FAB2(SCH_1):PAGE221
     2    GND @BASEBOARD_FAB2_LIB.BASEBOARD_FAB2(SCH_1):GND    I45 @BASEBOARD_FAB2_LIB.BASEBOARD_FAB2(SCH_1):PAGE221

C5U13 CAP_0805-100UF,4V,20%,X5R,6024A
     1 PVDDQ_ABC @BASEBOARD_FAB2_LIB.BASEBOARD_FAB2(SCH_1):PVDDQ_ABC   I321 @BASEBOARD_FAB2_LIB.BASEBOARD_FAB2(SCH_1):PAGE217
     2    GND @BASEBOARD_FAB2_LIB.BASEBOARD_FAB2(SCH_1):GND   I321 @BASEBOARD_FAB2_LIB.BASEBOARD_FAB2(SCH_1):PAGE217

C5U14 CAP_0805-100UF,4V,20%,X5R,6024A
     1 PVDDQ_ABC @BASEBOARD_FAB2_LIB.BASEBOARD_FAB2(SCH_1):PVDDQ_ABC   I322 @BASEBOARD_FAB2_LIB.BASEBOARD_FAB2(SCH_1):PAGE217
     2    GND @BASEBOARD_FAB2_LIB.BASEBOARD_FAB2(SCH_1):GND   I322 @BASEBOARD_FAB2_LIB.BASEBOARD_FAB2(SCH_1):PAGE217

C5U15 CAP_0805-100UF,4V,20%,X5R,6024A
     1 PVDDQ_ABC @BASEBOARD_FAB2_LIB.BASEBOARD_FAB2(SCH_1):PVDDQ_ABC   I320 @BASEBOARD_FAB2_LIB.BASEBOARD_FAB2(SCH_1):PAGE217
     2    GND @BASEBOARD_FAB2_LIB.BASEBOARD_FAB2(SCH_1):GND   I320 @BASEBOARD_FAB2_LIB.BASEBOARD_FAB2(SCH_1):PAGE217

C5U16 CAP_0805-100UF,4V,20%,X5R,6024A
     1 PVTT_ABC @BASEBOARD_FAB2_LIB.BASEBOARD_FAB2(SCH_1):PVTT_ABC    I46 @BASEBOARD_FAB2_LIB.BASEBOARD_FAB2(SCH_1):PAGE221
     2    GND @BASEBOARD_FAB2_LIB.BASEBOARD_FAB2(SCH_1):GND    I46 @BASEBOARD_FAB2_LIB.BASEBOARD_FAB2(SCH_1):PAGE221

C5W1 CAP_A_0603V-22.0UF,4V,20%,X6S,A
     1 PVCCMCP_CPU0 @BASEBOARD_FAB2_LIB.BASEBOARD_FAB2(SCH_1):PVCCMCP_CPU0   I217 @BASEBOARD_FAB2_LIB.BASEBOARD_FAB2(SCH_1):PAGE42
     2    GND @BASEBOARD_FAB2_LIB.BASEBOARD_FAB2(SCH_1):GND   I217 @BASEBOARD_FAB2_LIB.BASEBOARD_FAB2(SCH_1):PAGE42

C5W2 CAP_A_0603V-22.0UF,4V,20%,X6S,A
     1 PVCCMCP_CPU0 @BASEBOARD_FAB2_LIB.BASEBOARD_FAB2(SCH_1):PVCCMCP_CPU0   I218 @BASEBOARD_FAB2_LIB.BASEBOARD_FAB2(SCH_1):PAGE42
     2    GND @BASEBOARD_FAB2_LIB.BASEBOARD_FAB2(SCH_1):GND   I218 @BASEBOARD_FAB2_LIB.BASEBOARD_FAB2(SCH_1):PAGE42

C6A1 CAP_0805LF-22UF,4V,20%,X6S,C95A
     1 PVDDQ_DEF @BASEBOARD_FAB2_LIB.BASEBOARD_FAB2(SCH_1):PVDDQ_DEF    I87 @BASEBOARD_FAB2_LIB.BASEBOARD_FAB2(SCH_1):PAGE219
     2    GND @BASEBOARD_FAB2_LIB.BASEBOARD_FAB2(SCH_1):GND    I87 @BASEBOARD_FAB2_LIB.BASEBOARD_FAB2(SCH_1):PAGE219

C6A2 CAP_0603LF-10UF,4V,20%,X6S,E15A
     1 PVPP_DEF @BASEBOARD_FAB2_LIB.BASEBOARD_FAB2(SCH_1):PVPP_DEF   I105 @BASEBOARD_FAB2_LIB.BASEBOARD_FAB2(SCH_1):PAGE232
     2    GND @BASEBOARD_FAB2_LIB.BASEBOARD_FAB2(SCH_1):GND   I105 @BASEBOARD_FAB2_LIB.BASEBOARD_FAB2(SCH_1):PAGE232

C6A3 CAP_0603LF-10UF,4V,20%,X6S,E15A
     1 PVPP_DEF @BASEBOARD_FAB2_LIB.BASEBOARD_FAB2(SCH_1):PVPP_DEF   I104 @BASEBOARD_FAB2_LIB.BASEBOARD_FAB2(SCH_1):PAGE232
     2    GND @BASEBOARD_FAB2_LIB.BASEBOARD_FAB2(SCH_1):GND   I104 @BASEBOARD_FAB2_LIB.BASEBOARD_FAB2(SCH_1):PAGE232

C6A4 CAP_0805LF-22UF,4V,20%,X6S,C95A
     1 PVDDQ_DEF @BASEBOARD_FAB2_LIB.BASEBOARD_FAB2(SCH_1):PVDDQ_DEF    I68 @BASEBOARD_FAB2_LIB.BASEBOARD_FAB2(SCH_1):PAGE219
     2    GND @BASEBOARD_FAB2_LIB.BASEBOARD_FAB2(SCH_1):GND    I68 @BASEBOARD_FAB2_LIB.BASEBOARD_FAB2(SCH_1):PAGE219

C6A5 CAPP_3018-470UF,2.5V,20%,ALUM,A
     1 PVDDQ_DEF @BASEBOARD_FAB2_LIB.BASEBOARD_FAB2(SCH_1):PVDDQ_DEF    I77 @BASEBOARD_FAB2_LIB.BASEBOARD_FAB2(SCH_1):PAGE220
     2    GND @BASEBOARD_FAB2_LIB.BASEBOARD_FAB2(SCH_1):GND    I77 @BASEBOARD_FAB2_LIB.BASEBOARD_FAB2(SCH_1):PAGE220

C6A6 CAP_0603LF-10UF,4V,20%,X6S,E15A
     1 PVPP_DEF @BASEBOARD_FAB2_LIB.BASEBOARD_FAB2(SCH_1):PVPP_DEF   I110 @BASEBOARD_FAB2_LIB.BASEBOARD_FAB2(SCH_1):PAGE232
     2    GND @BASEBOARD_FAB2_LIB.BASEBOARD_FAB2(SCH_1):GND   I110 @BASEBOARD_FAB2_LIB.BASEBOARD_FAB2(SCH_1):PAGE232

C6A7 CAP_0603LF-10UF,4V,20%,X6S,E15A
     1 PVPP_DEF @BASEBOARD_FAB2_LIB.BASEBOARD_FAB2(SCH_1):PVPP_DEF   I109 @BASEBOARD_FAB2_LIB.BASEBOARD_FAB2(SCH_1):PAGE232
     2    GND @BASEBOARD_FAB2_LIB.BASEBOARD_FAB2(SCH_1):GND   I109 @BASEBOARD_FAB2_LIB.BASEBOARD_FAB2(SCH_1):PAGE232

C6B1 CAP_0603LF-10UF,4V,20%,X6S,E15A
     1 PVPP_DEF @BASEBOARD_FAB2_LIB.BASEBOARD_FAB2(SCH_1):PVPP_DEF   I128 @BASEBOARD_FAB2_LIB.BASEBOARD_FAB2(SCH_1):PAGE232
     2    GND @BASEBOARD_FAB2_LIB.BASEBOARD_FAB2(SCH_1):GND   I128 @BASEBOARD_FAB2_LIB.BASEBOARD_FAB2(SCH_1):PAGE232

C6B2 CAP_0603LF-10UF,4V,20%,X6S,E15A
     1 PVPP_DEF @BASEBOARD_FAB2_LIB.BASEBOARD_FAB2(SCH_1):PVPP_DEF   I126 @BASEBOARD_FAB2_LIB.BASEBOARD_FAB2(SCH_1):PAGE232
     2    GND @BASEBOARD_FAB2_LIB.BASEBOARD_FAB2(SCH_1):GND   I126 @BASEBOARD_FAB2_LIB.BASEBOARD_FAB2(SCH_1):PAGE232

C6B3 CAP_0805-47UF,4V,20%,X6S,C9533A
     1 PVPP_DEF @BASEBOARD_FAB2_LIB.BASEBOARD_FAB2(SCH_1):PVPP_DEF   I236 @BASEBOARD_FAB2_LIB.BASEBOARD_FAB2(SCH_1):PAGE232
     2    GND @BASEBOARD_FAB2_LIB.BASEBOARD_FAB2(SCH_1):GND   I236 @BASEBOARD_FAB2_LIB.BASEBOARD_FAB2(SCH_1):PAGE232

C6B4 CAP_0402-0.22UF,16V,10%,X7R,A3A
     1 P3E_CPU0_PE1_PCH_TXN<15> @BASEBOARD_FAB2_LIB.BASEBOARD_FAB2(SCH_1):P3E_CPU0_PE1_PCH_TXN(15)   I196 @BASEBOARD_FAB2_LIB.BASEBOARD_FAB2(SCH_1):PAGE105
     2 P3E_CPU0_PE1_PCH_C_TXN<15> @BASEBOARD_FAB2_LIB.BASEBOARD_FAB2(SCH_1):P3E_CPU0_PE1_PCH_C_TXN(15)   I196 @BASEBOARD_FAB2_LIB.BASEBOARD_FAB2(SCH_1):PAGE105

C6B5 CAP_0402-0.22UF,16V,10%,X7R,A3A
     1 P3E_CPU0_PE1_PCH_TXP<15> @BASEBOARD_FAB2_LIB.BASEBOARD_FAB2(SCH_1):P3E_CPU0_PE1_PCH_TXP(15)   I201 @BASEBOARD_FAB2_LIB.BASEBOARD_FAB2(SCH_1):PAGE105
     2 P3E_CPU0_PE1_PCH_C_TXP<15> @BASEBOARD_FAB2_LIB.BASEBOARD_FAB2(SCH_1):P3E_CPU0_PE1_PCH_C_TXP(15)   I201 @BASEBOARD_FAB2_LIB.BASEBOARD_FAB2(SCH_1):PAGE105

C6B6 CAP_0402-0.22UF,16V,10%,X7R,A3A
     1 P3E_CPU0_PE1_PCH_TXN<14> @BASEBOARD_FAB2_LIB.BASEBOARD_FAB2(SCH_1):P3E_CPU0_PE1_PCH_TXN(14)   I169 @BASEBOARD_FAB2_LIB.BASEBOARD_FAB2(SCH_1):PAGE105
     2 P3E_CPU0_PE1_PCH_C_TXN<14> @BASEBOARD_FAB2_LIB.BASEBOARD_FAB2(SCH_1):P3E_CPU0_PE1_PCH_C_TXN(14)   I169 @BASEBOARD_FAB2_LIB.BASEBOARD_FAB2(SCH_1):PAGE105

C6B7 CAPP_7343LF-330UF,6.3V,20%,POSA
     1 PVPP_DEF @BASEBOARD_FAB2_LIB.BASEBOARD_FAB2(SCH_1):PVPP_DEF   I229 @BASEBOARD_FAB2_LIB.BASEBOARD_FAB2(SCH_1):PAGE232
     2    GND @BASEBOARD_FAB2_LIB.BASEBOARD_FAB2(SCH_1):GND   I229 @BASEBOARD_FAB2_LIB.BASEBOARD_FAB2(SCH_1):PAGE232

C6B8 CAP_0402-0.22UF,16V,10%,X7R,A3A
     1 P3E_CPU0_PE1_PCH_TXP<14> @BASEBOARD_FAB2_LIB.BASEBOARD_FAB2(SCH_1):P3E_CPU0_PE1_PCH_TXP(14)   I198 @BASEBOARD_FAB2_LIB.BASEBOARD_FAB2(SCH_1):PAGE105
     2 P3E_CPU0_PE1_PCH_C_TXP<14> @BASEBOARD_FAB2_LIB.BASEBOARD_FAB2(SCH_1):P3E_CPU0_PE1_PCH_C_TXP(14)   I198 @BASEBOARD_FAB2_LIB.BASEBOARD_FAB2(SCH_1):PAGE105

C6B9 CAP_0402-0.22UF,16V,10%,X7R,A3A
     1 P3E_CPU0_PE1_PCH_TXN<13> @BASEBOARD_FAB2_LIB.BASEBOARD_FAB2(SCH_1):P3E_CPU0_PE1_PCH_TXN(13)   I185 @BASEBOARD_FAB2_LIB.BASEBOARD_FAB2(SCH_1):PAGE105
     2 P3E_CPU0_PE1_PCH_C_TXN<13> @BASEBOARD_FAB2_LIB.BASEBOARD_FAB2(SCH_1):P3E_CPU0_PE1_PCH_C_TXN(13)   I185 @BASEBOARD_FAB2_LIB.BASEBOARD_FAB2(SCH_1):PAGE105

C6B10 CAP_0402-0.22UF,16V,10%,X7R,A3A
     1 P3E_CPU0_PE1_PCH_TXP<13> @BASEBOARD_FAB2_LIB.BASEBOARD_FAB2(SCH_1):P3E_CPU0_PE1_PCH_TXP(13)   I193 @BASEBOARD_FAB2_LIB.BASEBOARD_FAB2(SCH_1):PAGE105
     2 P3E_CPU0_PE1_PCH_C_TXP<13> @BASEBOARD_FAB2_LIB.BASEBOARD_FAB2(SCH_1):P3E_CPU0_PE1_PCH_C_TXP(13)   I193 @BASEBOARD_FAB2_LIB.BASEBOARD_FAB2(SCH_1):PAGE105

C6B11 CAP_0402-0.22UF,16V,10%,X7R,A3A
     1 P3E_CPU0_PE1_PCH_TXN<12> @BASEBOARD_FAB2_LIB.BASEBOARD_FAB2(SCH_1):P3E_CPU0_PE1_PCH_TXN(12)   I166 @BASEBOARD_FAB2_LIB.BASEBOARD_FAB2(SCH_1):PAGE105
     2 P3E_CPU0_PE1_PCH_C_TXN<12> @BASEBOARD_FAB2_LIB.BASEBOARD_FAB2(SCH_1):P3E_CPU0_PE1_PCH_C_TXN(12)   I166 @BASEBOARD_FAB2_LIB.BASEBOARD_FAB2(SCH_1):PAGE105

C6B12 CAP_0402-0.22UF,16V,10%,X7R,A3A
     1 P3E_CPU0_PE1_PCH_TXP<12> @BASEBOARD_FAB2_LIB.BASEBOARD_FAB2(SCH_1):P3E_CPU0_PE1_PCH_TXP(12)   I187 @BASEBOARD_FAB2_LIB.BASEBOARD_FAB2(SCH_1):PAGE105
     2 P3E_CPU0_PE1_PCH_C_TXP<12> @BASEBOARD_FAB2_LIB.BASEBOARD_FAB2(SCH_1):P3E_CPU0_PE1_PCH_C_TXP(12)   I187 @BASEBOARD_FAB2_LIB.BASEBOARD_FAB2(SCH_1):PAGE105

C6B13 CAP_0402-0.22UF,16V,10%,X7R,A3A
     1 P3E_CPU0_PE1_PCH_TXP<11> @BASEBOARD_FAB2_LIB.BASEBOARD_FAB2(SCH_1):P3E_CPU0_PE1_PCH_TXP(11)   I189 @BASEBOARD_FAB2_LIB.BASEBOARD_FAB2(SCH_1):PAGE105
     2 P3E_CPU0_PE1_PCH_C_TXP<11> @BASEBOARD_FAB2_LIB.BASEBOARD_FAB2(SCH_1):P3E_CPU0_PE1_PCH_C_TXP(11)   I189 @BASEBOARD_FAB2_LIB.BASEBOARD_FAB2(SCH_1):PAGE105

C6B14 CAP_0402-0.22UF,16V,10%,X7R,A3A
     1 P3E_CPU0_PE1_PCH_TXN<11> @BASEBOARD_FAB2_LIB.BASEBOARD_FAB2(SCH_1):P3E_CPU0_PE1_PCH_TXN(11)   I181 @BASEBOARD_FAB2_LIB.BASEBOARD_FAB2(SCH_1):PAGE105
     2 P3E_CPU0_PE1_PCH_C_TXN<11> @BASEBOARD_FAB2_LIB.BASEBOARD_FAB2(SCH_1):P3E_CPU0_PE1_PCH_C_TXN(11)   I181 @BASEBOARD_FAB2_LIB.BASEBOARD_FAB2(SCH_1):PAGE105

C6B15 CAP_0402-0.22UF,16V,10%,X7R,A3A
     1 P3E_CPU0_PE1_PCH_TXN<10> @BASEBOARD_FAB2_LIB.BASEBOARD_FAB2(SCH_1):P3E_CPU0_PE1_PCH_TXN(10)   I163 @BASEBOARD_FAB2_LIB.BASEBOARD_FAB2(SCH_1):PAGE105
     2 P3E_CPU0_PE1_PCH_C_TXN<10> @BASEBOARD_FAB2_LIB.BASEBOARD_FAB2(SCH_1):P3E_CPU0_PE1_PCH_C_TXN(10)   I163 @BASEBOARD_FAB2_LIB.BASEBOARD_FAB2(SCH_1):PAGE105

C6B16 CAP_0402-0.22UF,16V,10%,X7R,A3A
     1 P3E_CPU0_PE1_PCH_TXP<10> @BASEBOARD_FAB2_LIB.BASEBOARD_FAB2(SCH_1):P3E_CPU0_PE1_PCH_TXP(10)   I180 @BASEBOARD_FAB2_LIB.BASEBOARD_FAB2(SCH_1):PAGE105
     2 P3E_CPU0_PE1_PCH_C_TXP<10> @BASEBOARD_FAB2_LIB.BASEBOARD_FAB2(SCH_1):P3E_CPU0_PE1_PCH_C_TXP(10)   I180 @BASEBOARD_FAB2_LIB.BASEBOARD_FAB2(SCH_1):PAGE105

C6B17 CAP_0402-0.22UF,16V,10%,X7R,A3A
     1 P3E_CPU0_PE1_PCH_TXN<9> @BASEBOARD_FAB2_LIB.BASEBOARD_FAB2(SCH_1):P3E_CPU0_PE1_PCH_TXN(9)   I175 @BASEBOARD_FAB2_LIB.BASEBOARD_FAB2(SCH_1):PAGE105
     2 P3E_CPU0_PE1_PCH_C_TXN<9> @BASEBOARD_FAB2_LIB.BASEBOARD_FAB2(SCH_1):P3E_CPU0_PE1_PCH_C_TXN(9)   I175 @BASEBOARD_FAB2_LIB.BASEBOARD_FAB2(SCH_1):PAGE105

C6B18 CAP_0402-0.22UF,16V,10%,X7R,A3A
     1 P3E_CPU0_PE1_PCH_TXP<9> @BASEBOARD_FAB2_LIB.BASEBOARD_FAB2(SCH_1):P3E_CPU0_PE1_PCH_TXP(9)   I153 @BASEBOARD_FAB2_LIB.BASEBOARD_FAB2(SCH_1):PAGE105
     2 P3E_CPU0_PE1_PCH_C_TXP<9> @BASEBOARD_FAB2_LIB.BASEBOARD_FAB2(SCH_1):P3E_CPU0_PE1_PCH_C_TXP(9)   I153 @BASEBOARD_FAB2_LIB.BASEBOARD_FAB2(SCH_1):PAGE105

C6B19 CAP_0402-0.22UF,16V,10%,X7R,A3A
     1 P3E_CPU0_PE1_PCH_TXN<8> @BASEBOARD_FAB2_LIB.BASEBOARD_FAB2(SCH_1):P3E_CPU0_PE1_PCH_TXN(8)   I160 @BASEBOARD_FAB2_LIB.BASEBOARD_FAB2(SCH_1):PAGE105
     2 P3E_CPU0_PE1_PCH_C_TXN<8> @BASEBOARD_FAB2_LIB.BASEBOARD_FAB2(SCH_1):P3E_CPU0_PE1_PCH_C_TXN(8)   I160 @BASEBOARD_FAB2_LIB.BASEBOARD_FAB2(SCH_1):PAGE105

C6B20 CAP_0402-0.22UF,16V,10%,X7R,A3A
     1 P3E_CPU0_PE1_PCH_TXP<8> @BASEBOARD_FAB2_LIB.BASEBOARD_FAB2(SCH_1):P3E_CPU0_PE1_PCH_TXP(8)   I173 @BASEBOARD_FAB2_LIB.BASEBOARD_FAB2(SCH_1):PAGE105
     2 P3E_CPU0_PE1_PCH_C_TXP<8> @BASEBOARD_FAB2_LIB.BASEBOARD_FAB2(SCH_1):P3E_CPU0_PE1_PCH_C_TXP(8)   I173 @BASEBOARD_FAB2_LIB.BASEBOARD_FAB2(SCH_1):PAGE105

C6D1 CAP_0603LF-10UF,4V,20%,X6S,E15A
     1 P1V8_MCP_CPU0 @BASEBOARD_FAB2_LIB.BASEBOARD_FAB2(SCH_1):P1V8_MCP_CPU0    I19 @BASEBOARD_FAB2_LIB.BASEBOARD_FAB2(SCH_1):PAGE38
     2    GND @BASEBOARD_FAB2_LIB.BASEBOARD_FAB2(SCH_1):GND    I19 @BASEBOARD_FAB2_LIB.BASEBOARD_FAB2(SCH_1):PAGE38

C6D2 CAP_A_0603V-22.0UF,4V,20%,X6S,A
     1 PVCCMCP_CPU0 @BASEBOARD_FAB2_LIB.BASEBOARD_FAB2(SCH_1):PVCCMCP_CPU0    I77 @BASEBOARD_FAB2_LIB.BASEBOARD_FAB2(SCH_1):PAGE42
     2    GND @BASEBOARD_FAB2_LIB.BASEBOARD_FAB2(SCH_1):GND    I77 @BASEBOARD_FAB2_LIB.BASEBOARD_FAB2(SCH_1):PAGE42

C6D3 CAP_A_0603V-22.0UF,4V,20%,X6S,A
     1 PVCCIO_CPU0 @BASEBOARD_FAB2_LIB.BASEBOARD_FAB2(SCH_1):PVCCIO_CPU0    I80 @BASEBOARD_FAB2_LIB.BASEBOARD_FAB2(SCH_1):PAGE42
     2    GND @BASEBOARD_FAB2_LIB.BASEBOARD_FAB2(SCH_1):GND    I80 @BASEBOARD_FAB2_LIB.BASEBOARD_FAB2(SCH_1):PAGE42

C6D4 CAP_A_0603V-22.0UF,4V,20%,X6S,A
     1 PVCCIO_CPU0 @BASEBOARD_FAB2_LIB.BASEBOARD_FAB2(SCH_1):PVCCIO_CPU0    I74 @BASEBOARD_FAB2_LIB.BASEBOARD_FAB2(SCH_1):PAGE42
     2    GND @BASEBOARD_FAB2_LIB.BASEBOARD_FAB2(SCH_1):GND    I74 @BASEBOARD_FAB2_LIB.BASEBOARD_FAB2(SCH_1):PAGE42

C6D5 CAP_A_0603V-22.0UF,4V,20%,X6S,A
     1 PVCCMCP_CPU0 @BASEBOARD_FAB2_LIB.BASEBOARD_FAB2(SCH_1):PVCCMCP_CPU0    I75 @BASEBOARD_FAB2_LIB.BASEBOARD_FAB2(SCH_1):PAGE42
     2    GND @BASEBOARD_FAB2_LIB.BASEBOARD_FAB2(SCH_1):GND    I75 @BASEBOARD_FAB2_LIB.BASEBOARD_FAB2(SCH_1):PAGE42

C6D6 CAP_A_0603V-22.0UF,4V,20%,X6S,A
     1 PVCCIO_CPU0 @BASEBOARD_FAB2_LIB.BASEBOARD_FAB2(SCH_1):PVCCIO_CPU0    I81 @BASEBOARD_FAB2_LIB.BASEBOARD_FAB2(SCH_1):PAGE42
     2    GND @BASEBOARD_FAB2_LIB.BASEBOARD_FAB2(SCH_1):GND    I81 @BASEBOARD_FAB2_LIB.BASEBOARD_FAB2(SCH_1):PAGE42

C6D7 CAP_A_0603V-22.0UF,4V,20%,X6S,A
     1 PVCCIO_CPU0 @BASEBOARD_FAB2_LIB.BASEBOARD_FAB2(SCH_1):PVCCIO_CPU0    I72 @BASEBOARD_FAB2_LIB.BASEBOARD_FAB2(SCH_1):PAGE42
     2    GND @BASEBOARD_FAB2_LIB.BASEBOARD_FAB2(SCH_1):GND    I72 @BASEBOARD_FAB2_LIB.BASEBOARD_FAB2(SCH_1):PAGE42

C6D8 CAP_A_0603V-22.0UF,4V,20%,X6S,A
     1 PVCCMCP_CPU0 @BASEBOARD_FAB2_LIB.BASEBOARD_FAB2(SCH_1):PVCCMCP_CPU0    I68 @BASEBOARD_FAB2_LIB.BASEBOARD_FAB2(SCH_1):PAGE42
     2    GND @BASEBOARD_FAB2_LIB.BASEBOARD_FAB2(SCH_1):GND    I68 @BASEBOARD_FAB2_LIB.BASEBOARD_FAB2(SCH_1):PAGE42

C6D9 CAP_A_0603V-22.0UF,4V,20%,X6S,A
     1 PVCCIO_CPU0 @BASEBOARD_FAB2_LIB.BASEBOARD_FAB2(SCH_1):PVCCIO_CPU0   I145 @BASEBOARD_FAB2_LIB.BASEBOARD_FAB2(SCH_1):PAGE42
     2    GND @BASEBOARD_FAB2_LIB.BASEBOARD_FAB2(SCH_1):GND   I145 @BASEBOARD_FAB2_LIB.BASEBOARD_FAB2(SCH_1):PAGE42

C6D10 CAP_A_0603V-22.0UF,4V,20%,X6S,A
     1 PVCCIO_CPU0 @BASEBOARD_FAB2_LIB.BASEBOARD_FAB2(SCH_1):PVCCIO_CPU0   I147 @BASEBOARD_FAB2_LIB.BASEBOARD_FAB2(SCH_1):PAGE42
     2    GND @BASEBOARD_FAB2_LIB.BASEBOARD_FAB2(SCH_1):GND   I147 @BASEBOARD_FAB2_LIB.BASEBOARD_FAB2(SCH_1):PAGE42

C6F1 CAP_A_0402V-0.1UF,16V,10%,X7R,A
     1   P3V3 @BASEBOARD_FAB2_LIB.BASEBOARD_FAB2(SCH_1):P3V3    I25 @BASEBOARD_FAB2_LIB.BASEBOARD_FAB2(SCH_1):PAGE104
     2    GND @BASEBOARD_FAB2_LIB.BASEBOARD_FAB2(SCH_1):GND    I25 @BASEBOARD_FAB2_LIB.BASEBOARD_FAB2(SCH_1):PAGE104

C6F2 CAP_A_0402V-0.1UF,16V,10%,X7R,A
     1 PVCCIO_CPU0 @BASEBOARD_FAB2_LIB.BASEBOARD_FAB2(SCH_1):PVCCIO_CPU0     I2 @BASEBOARD_FAB2_LIB.BASEBOARD_FAB2(SCH_1):PAGE99
     2    GND @BASEBOARD_FAB2_LIB.BASEBOARD_FAB2(SCH_1):GND     I2 @BASEBOARD_FAB2_LIB.BASEBOARD_FAB2(SCH_1):PAGE99

C6F3 CAP_A_0402V-0.1UF,16V,10%,X7R,A
     1 PVPP_ABC @BASEBOARD_FAB2_LIB.BASEBOARD_FAB2(SCH_1):PVPP_ABC     I7 @BASEBOARD_FAB2_LIB.BASEBOARD_FAB2(SCH_1):PAGE99
     2    GND @BASEBOARD_FAB2_LIB.BASEBOARD_FAB2(SCH_1):GND     I7 @BASEBOARD_FAB2_LIB.BASEBOARD_FAB2(SCH_1):PAGE99

C6F4 CAPP_7343LF-330UF,6.3V,20%,POSA
     1 PVPP_ABC @BASEBOARD_FAB2_LIB.BASEBOARD_FAB2(SCH_1):PVPP_ABC   I180 @BASEBOARD_FAB2_LIB.BASEBOARD_FAB2(SCH_1):PAGE231
     2    GND @BASEBOARD_FAB2_LIB.BASEBOARD_FAB2(SCH_1):GND   I180 @BASEBOARD_FAB2_LIB.BASEBOARD_FAB2(SCH_1):PAGE231

C6F5 CAP_0603LF-10UF,4V,20%,X6S,E15A
     1 PVPP_ABC @BASEBOARD_FAB2_LIB.BASEBOARD_FAB2(SCH_1):PVPP_ABC   I149 @BASEBOARD_FAB2_LIB.BASEBOARD_FAB2(SCH_1):PAGE231
     2    GND @BASEBOARD_FAB2_LIB.BASEBOARD_FAB2(SCH_1):GND   I149 @BASEBOARD_FAB2_LIB.BASEBOARD_FAB2(SCH_1):PAGE231

C6F6 CAP_0603LF-10UF,4V,20%,X6S,E15A
     1 PVPP_ABC @BASEBOARD_FAB2_LIB.BASEBOARD_FAB2(SCH_1):PVPP_ABC   I122 @BASEBOARD_FAB2_LIB.BASEBOARD_FAB2(SCH_1):PAGE231
     2    GND @BASEBOARD_FAB2_LIB.BASEBOARD_FAB2(SCH_1):GND   I122 @BASEBOARD_FAB2_LIB.BASEBOARD_FAB2(SCH_1):PAGE231

C6G1 CAP_0603LF-10UF,4V,20%,X6S,E15A
     1 PVPP_ABC @BASEBOARD_FAB2_LIB.BASEBOARD_FAB2(SCH_1):PVPP_ABC   I126 @BASEBOARD_FAB2_LIB.BASEBOARD_FAB2(SCH_1):PAGE231
     2    GND @BASEBOARD_FAB2_LIB.BASEBOARD_FAB2(SCH_1):GND   I126 @BASEBOARD_FAB2_LIB.BASEBOARD_FAB2(SCH_1):PAGE231

C6G2 CAP_0603LF-10UF,4V,20%,X6S,E15A
     1 PVPP_ABC @BASEBOARD_FAB2_LIB.BASEBOARD_FAB2(SCH_1):PVPP_ABC   I128 @BASEBOARD_FAB2_LIB.BASEBOARD_FAB2(SCH_1):PAGE231
     2    GND @BASEBOARD_FAB2_LIB.BASEBOARD_FAB2(SCH_1):GND   I128 @BASEBOARD_FAB2_LIB.BASEBOARD_FAB2(SCH_1):PAGE231

C6G3 CAP_0805LF-22UF,4V,20%,X6S,C95A
     1 PVDDQ_ABC @BASEBOARD_FAB2_LIB.BASEBOARD_FAB2(SCH_1):PVDDQ_ABC     I6 @BASEBOARD_FAB2_LIB.BASEBOARD_FAB2(SCH_1):PAGE216
     2    GND @BASEBOARD_FAB2_LIB.BASEBOARD_FAB2(SCH_1):GND     I6 @BASEBOARD_FAB2_LIB.BASEBOARD_FAB2(SCH_1):PAGE216

C6G4 CAP_0603LF-10UF,4V,20%,X6S,E15A
     1 PVPP_ABC @BASEBOARD_FAB2_LIB.BASEBOARD_FAB2(SCH_1):PVPP_ABC   I131 @BASEBOARD_FAB2_LIB.BASEBOARD_FAB2(SCH_1):PAGE231
     2    GND @BASEBOARD_FAB2_LIB.BASEBOARD_FAB2(SCH_1):GND   I131 @BASEBOARD_FAB2_LIB.BASEBOARD_FAB2(SCH_1):PAGE231

C6G5 CAP_0603LF-10UF,4V,20%,X6S,E15A
     1 PVPP_ABC @BASEBOARD_FAB2_LIB.BASEBOARD_FAB2(SCH_1):PVPP_ABC   I145 @BASEBOARD_FAB2_LIB.BASEBOARD_FAB2(SCH_1):PAGE231
     2    GND @BASEBOARD_FAB2_LIB.BASEBOARD_FAB2(SCH_1):GND   I145 @BASEBOARD_FAB2_LIB.BASEBOARD_FAB2(SCH_1):PAGE231

C6L1 CAP_A_0402V-0.01UF,25V,10%,X7RA
     1 M_F_VREF @BASEBOARD_FAB2_LIB.BASEBOARD_FAB2(SCH_1):M_F_VREF   I178 @BASEBOARD_FAB2_LIB.BASEBOARD_FAB2(SCH_1):PAGE53
     2    GND @BASEBOARD_FAB2_LIB.BASEBOARD_FAB2(SCH_1):GND   I178 @BASEBOARD_FAB2_LIB.BASEBOARD_FAB2(SCH_1):PAGE53

C6L2 CAP_A_0402V-0.01UF,25V,10%,X7RA
     1 M_F_CPU_VREF @BASEBOARD_FAB2_LIB.BASEBOARD_FAB2(SCH_1):M_F_CPU_VREF    I67 @BASEBOARD_FAB2_LIB.BASEBOARD_FAB2(SCH_1):PAGE98
     2    GND @BASEBOARD_FAB2_LIB.BASEBOARD_FAB2(SCH_1):GND    I67 @BASEBOARD_FAB2_LIB.BASEBOARD_FAB2(SCH_1):PAGE98

C6L3 CAP_0603LF-10UF,4V,20%,X6S,E15A
     1 PVDDQ_DEF @BASEBOARD_FAB2_LIB.BASEBOARD_FAB2(SCH_1):PVDDQ_DEF    I17 @BASEBOARD_FAB2_LIB.BASEBOARD_FAB2(SCH_1):PAGE222
     2    GND @BASEBOARD_FAB2_LIB.BASEBOARD_FAB2(SCH_1):GND    I17 @BASEBOARD_FAB2_LIB.BASEBOARD_FAB2(SCH_1):PAGE222

C6L4 CAP_0603LF-10UF,4V,20%,X6S,E15A
     1 PVDDQ_DEF @BASEBOARD_FAB2_LIB.BASEBOARD_FAB2(SCH_1):PVDDQ_DEF    I15 @BASEBOARD_FAB2_LIB.BASEBOARD_FAB2(SCH_1):PAGE222
     2    GND @BASEBOARD_FAB2_LIB.BASEBOARD_FAB2(SCH_1):GND    I15 @BASEBOARD_FAB2_LIB.BASEBOARD_FAB2(SCH_1):PAGE222

C6L5 CAP_0603LF-10UF,4V,20%,X6S,E15A
     1 PVDDQ_KLM @BASEBOARD_FAB2_LIB.BASEBOARD_FAB2(SCH_1):PVDDQ_KLM    I35 @BASEBOARD_FAB2_LIB.BASEBOARD_FAB2(SCH_1):PAGE230
     2    GND @BASEBOARD_FAB2_LIB.BASEBOARD_FAB2(SCH_1):GND    I35 @BASEBOARD_FAB2_LIB.BASEBOARD_FAB2(SCH_1):PAGE230

C6L6 CAP_A_0402V-0.01UF,25V,10%,X7RA
     1 M_E_VREF @BASEBOARD_FAB2_LIB.BASEBOARD_FAB2(SCH_1):M_E_VREF   I175 @BASEBOARD_FAB2_LIB.BASEBOARD_FAB2(SCH_1):PAGE51
     2    GND @BASEBOARD_FAB2_LIB.BASEBOARD_FAB2(SCH_1):GND   I175 @BASEBOARD_FAB2_LIB.BASEBOARD_FAB2(SCH_1):PAGE51

C6L7 CAP_A_0402V-0.01UF,25V,10%,X7RA
     1 M_E_CPU_VREF @BASEBOARD_FAB2_LIB.BASEBOARD_FAB2(SCH_1):M_E_CPU_VREF    I59 @BASEBOARD_FAB2_LIB.BASEBOARD_FAB2(SCH_1):PAGE98
     2    GND @BASEBOARD_FAB2_LIB.BASEBOARD_FAB2(SCH_1):GND    I59 @BASEBOARD_FAB2_LIB.BASEBOARD_FAB2(SCH_1):PAGE98

C6L8 CAPP_7343-220UF,4V,20%,POSCAP,A
     1 PVPP_KLM @BASEBOARD_FAB2_LIB.BASEBOARD_FAB2(SCH_1):PVPP_KLM   I210 @BASEBOARD_FAB2_LIB.BASEBOARD_FAB2(SCH_1):PAGE234
     2    GND @BASEBOARD_FAB2_LIB.BASEBOARD_FAB2(SCH_1):GND   I210 @BASEBOARD_FAB2_LIB.BASEBOARD_FAB2(SCH_1):PAGE234

C6L10 CAP_0805-10UF,16V,10%,X6S,C953A
     1 VR_FET_SW_P12V_STBY_PVPP_KLM @BASEBOARD_FAB2_LIB.BASEBOARD_FAB2(SCH_1):VR_FET_SW_P12V_STBY_PVPP_KLM   I202 @BASEBOARD_FAB2_LIB.BASEBOARD_FAB2(SCH_1):PAGE234
     2    GND @BASEBOARD_FAB2_LIB.BASEBOARD_FAB2(SCH_1):GND   I202 @BASEBOARD_FAB2_LIB.BASEBOARD_FAB2(SCH_1):PAGE234

C6L11 CAP_0402-1.0UF,16V,10%,X6S,D97A
     1 VR_FET_SW_P12V_STBY_PVPP_KLM @BASEBOARD_FAB2_LIB.BASEBOARD_FAB2(SCH_1):VR_FET_SW_P12V_STBY_PVPP_KLM   I152 @BASEBOARD_FAB2_LIB.BASEBOARD_FAB2(SCH_1):PAGE234
     2    GND @BASEBOARD_FAB2_LIB.BASEBOARD_FAB2(SCH_1):GND   I152 @BASEBOARD_FAB2_LIB.BASEBOARD_FAB2(SCH_1):PAGE234

C6L12 CAP_0603-4.7UF,6.3V,10%,X6S,E1A
     1 VR_VB_PVPP_KLM @BASEBOARD_FAB2_LIB.BASEBOARD_FAB2(SCH_1):VR_VB_PVPP_KLM   I144 @BASEBOARD_FAB2_LIB.BASEBOARD_FAB2(SCH_1):PAGE234
     2 AGND_PVPP_KLM @BASEBOARD_FAB2_LIB.BASEBOARD_FAB2(SCH_1):AGND_PVPP_KLM   I144 @BASEBOARD_FAB2_LIB.BASEBOARD_FAB2(SCH_1):PAGE234

C6M1 CAP_A_0402V-0.01UF,25V,10%,X7RA
     1 M_D_VREF @BASEBOARD_FAB2_LIB.BASEBOARD_FAB2(SCH_1):M_D_VREF   I177 @BASEBOARD_FAB2_LIB.BASEBOARD_FAB2(SCH_1):PAGE50
     2    GND @BASEBOARD_FAB2_LIB.BASEBOARD_FAB2(SCH_1):GND   I177 @BASEBOARD_FAB2_LIB.BASEBOARD_FAB2(SCH_1):PAGE50

C6M2 CAP_A_0402V-0.01UF,25V,10%,X7RA
     1 M_D_CPU_VREF @BASEBOARD_FAB2_LIB.BASEBOARD_FAB2(SCH_1):M_D_CPU_VREF    I33 @BASEBOARD_FAB2_LIB.BASEBOARD_FAB2(SCH_1):PAGE98
     2    GND @BASEBOARD_FAB2_LIB.BASEBOARD_FAB2(SCH_1):GND    I33 @BASEBOARD_FAB2_LIB.BASEBOARD_FAB2(SCH_1):PAGE98

C6M3 CAP_0805-10UF,16V,10%,X6S,C953A
     1 VR_FET_SW_P12V_STBY_PVPP_KLM @BASEBOARD_FAB2_LIB.BASEBOARD_FAB2(SCH_1):VR_FET_SW_P12V_STBY_PVPP_KLM   I203 @BASEBOARD_FAB2_LIB.BASEBOARD_FAB2(SCH_1):PAGE234
     2    GND @BASEBOARD_FAB2_LIB.BASEBOARD_FAB2(SCH_1):GND   I203 @BASEBOARD_FAB2_LIB.BASEBOARD_FAB2(SCH_1):PAGE234

C6M5 CAP_0805-10UF,16V,10%,X6S,C953A
     1 VR_FET_SW_P12V_STBY_PVPP_KLM @BASEBOARD_FAB2_LIB.BASEBOARD_FAB2(SCH_1):VR_FET_SW_P12V_STBY_PVPP_KLM   I204 @BASEBOARD_FAB2_LIB.BASEBOARD_FAB2(SCH_1):PAGE234
     2    GND @BASEBOARD_FAB2_LIB.BASEBOARD_FAB2(SCH_1):GND   I204 @BASEBOARD_FAB2_LIB.BASEBOARD_FAB2(SCH_1):PAGE234

C6M6 CAP_A_0402V-0.1UF,16V,10%,X7R,A
     1 JTAG_MCP_CPU1_TDI_R @BASEBOARD_FAB2_LIB.BASEBOARD_FAB2(SCH_1):JTAG_MCP_CPU1_TDI_R   I250 @BASEBOARD_FAB2_LIB.BASEBOARD_FAB2(SCH_1):PAGE113
     2    GND @BASEBOARD_FAB2_LIB.BASEBOARD_FAB2(SCH_1):GND   I250 @BASEBOARD_FAB2_LIB.BASEBOARD_FAB2(SCH_1):PAGE113

C6N1 CAPP_3018-470UF,2.5V,20%,ALUM,A
     1 PVSA_CPU0 @BASEBOARD_FAB2_LIB.BASEBOARD_FAB2(SCH_1):PVSA_CPU0    I12 @BASEBOARD_FAB2_LIB.BASEBOARD_FAB2(SCH_1):PAGE205
     2    GND @BASEBOARD_FAB2_LIB.BASEBOARD_FAB2(SCH_1):GND    I12 @BASEBOARD_FAB2_LIB.BASEBOARD_FAB2(SCH_1):PAGE205

C6N2 CAP_0805-10UF,16V,10%,X6S,C953A
     1 VR_FET_SW_P12V_STBY_PVCCIN_CPU0 @BASEBOARD_FAB2_LIB.BASEBOARD_FAB2(SCH_1):VR_FET_SW_P12V_STBY_PVCCIN_CPU0    I33 @BASEBOARD_FAB2_LIB.BASEBOARD_FAB2(SCH_1):PAGE205
     2    GND @BASEBOARD_FAB2_LIB.BASEBOARD_FAB2(SCH_1):GND    I33 @BASEBOARD_FAB2_LIB.BASEBOARD_FAB2(SCH_1):PAGE205

C6N3 CAP_0805-10UF,16V,10%,X6S,C953A
     1 VR_FET_SW_P12V_STBY_PVCCIN_CPU0 @BASEBOARD_FAB2_LIB.BASEBOARD_FAB2(SCH_1):VR_FET_SW_P12V_STBY_PVCCIN_CPU0    I34 @BASEBOARD_FAB2_LIB.BASEBOARD_FAB2(SCH_1):PAGE205
     2    GND @BASEBOARD_FAB2_LIB.BASEBOARD_FAB2(SCH_1):GND    I34 @BASEBOARD_FAB2_LIB.BASEBOARD_FAB2(SCH_1):PAGE205

C6N4 CAPP_3018-470UF,2.5V,20%,ALUM,A
     1 PVSA_CPU0 @BASEBOARD_FAB2_LIB.BASEBOARD_FAB2(SCH_1):PVSA_CPU0    I14 @BASEBOARD_FAB2_LIB.BASEBOARD_FAB2(SCH_1):PAGE205
     2    GND @BASEBOARD_FAB2_LIB.BASEBOARD_FAB2(SCH_1):GND    I14 @BASEBOARD_FAB2_LIB.BASEBOARD_FAB2(SCH_1):PAGE205

C6N5 CAPP_3018-68UF,16V,20%,TANT,72A
     1 P12V_STBY @BASEBOARD_FAB2_LIB.BASEBOARD_FAB2(SCH_1):P12V_STBY   I109 @BASEBOARD_FAB2_LIB.BASEBOARD_FAB2(SCH_1):PAGE195
     2    GND @BASEBOARD_FAB2_LIB.BASEBOARD_FAB2(SCH_1):GND   I109 @BASEBOARD_FAB2_LIB.BASEBOARD_FAB2(SCH_1):PAGE195

C6N6 CAP_0805-10UF,16V,10%,X6S,C953A
     1 VR_FET_SW_P12V_STBY_PVCCIN_CPU0 @BASEBOARD_FAB2_LIB.BASEBOARD_FAB2(SCH_1):VR_FET_SW_P12V_STBY_PVCCIN_CPU0    I35 @BASEBOARD_FAB2_LIB.BASEBOARD_FAB2(SCH_1):PAGE205
     2    GND @BASEBOARD_FAB2_LIB.BASEBOARD_FAB2(SCH_1):GND    I35 @BASEBOARD_FAB2_LIB.BASEBOARD_FAB2(SCH_1):PAGE205

C6N7 CAP_A_0603V-22.0UF,4V,20%,X6S,A
     1 PVSA_CPU0 @BASEBOARD_FAB2_LIB.BASEBOARD_FAB2(SCH_1):PVSA_CPU0     I5 @BASEBOARD_FAB2_LIB.BASEBOARD_FAB2(SCH_1):PAGE205
     2    GND @BASEBOARD_FAB2_LIB.BASEBOARD_FAB2(SCH_1):GND     I5 @BASEBOARD_FAB2_LIB.BASEBOARD_FAB2(SCH_1):PAGE205

C6N8 CAP_0805-10UF,16V,10%,X6S,C953A
     1 VR_FET_SW_P12V_STBY_PVCCIN_CPU0 @BASEBOARD_FAB2_LIB.BASEBOARD_FAB2(SCH_1):VR_FET_SW_P12V_STBY_PVCCIN_CPU0    I51 @BASEBOARD_FAB2_LIB.BASEBOARD_FAB2(SCH_1):PAGE202
     2    GND @BASEBOARD_FAB2_LIB.BASEBOARD_FAB2(SCH_1):GND    I51 @BASEBOARD_FAB2_LIB.BASEBOARD_FAB2(SCH_1):PAGE202

C6N9 CAPP_3018-470UF,2.5V,20%,ALUM,A
     1 PVCCIN_CPU0 @BASEBOARD_FAB2_LIB.BASEBOARD_FAB2(SCH_1):PVCCIN_CPU0    I34 @BASEBOARD_FAB2_LIB.BASEBOARD_FAB2(SCH_1):PAGE203
     2    GND @BASEBOARD_FAB2_LIB.BASEBOARD_FAB2(SCH_1):GND    I34 @BASEBOARD_FAB2_LIB.BASEBOARD_FAB2(SCH_1):PAGE203

C6N10 CAP_0805-10UF,16V,10%,X6S,C953A
     1 VR_FET_SW_P12V_STBY_PVCCIN_CPU0 @BASEBOARD_FAB2_LIB.BASEBOARD_FAB2(SCH_1):VR_FET_SW_P12V_STBY_PVCCIN_CPU0    I37 @BASEBOARD_FAB2_LIB.BASEBOARD_FAB2(SCH_1):PAGE204
     2    GND @BASEBOARD_FAB2_LIB.BASEBOARD_FAB2(SCH_1):GND    I37 @BASEBOARD_FAB2_LIB.BASEBOARD_FAB2(SCH_1):PAGE204

C6N11 CAP_0805-10UF,16V,10%,X6S,C953A
     1 VR_FET_SW_P12V_STBY_PVCCIN_CPU0 @BASEBOARD_FAB2_LIB.BASEBOARD_FAB2(SCH_1):VR_FET_SW_P12V_STBY_PVCCIN_CPU0    I42 @BASEBOARD_FAB2_LIB.BASEBOARD_FAB2(SCH_1):PAGE204
     2    GND @BASEBOARD_FAB2_LIB.BASEBOARD_FAB2(SCH_1):GND    I42 @BASEBOARD_FAB2_LIB.BASEBOARD_FAB2(SCH_1):PAGE204

C6P3 CAP_A_0603V-22.0UF,4V,20%,X6S,A
     1 PVCCIN_CPU0 @BASEBOARD_FAB2_LIB.BASEBOARD_FAB2(SCH_1):PVCCIN_CPU0    I25 @BASEBOARD_FAB2_LIB.BASEBOARD_FAB2(SCH_1):PAGE203
     2    GND @BASEBOARD_FAB2_LIB.BASEBOARD_FAB2(SCH_1):GND    I25 @BASEBOARD_FAB2_LIB.BASEBOARD_FAB2(SCH_1):PAGE203

C6P4 CAP_A_0402V-0.1UF,16V,10%,X7R,A
     1 P3V3_DB1200 @BASEBOARD_FAB2_LIB.BASEBOARD_FAB2(SCH_1):P3V3_DB1200    I11 @BASEBOARD_FAB2_LIB.BASEBOARD_FAB2(SCH_1):PAGE102
     2    GND @BASEBOARD_FAB2_LIB.BASEBOARD_FAB2(SCH_1):GND    I11 @BASEBOARD_FAB2_LIB.BASEBOARD_FAB2(SCH_1):PAGE102

C6P5 CAP_A_0402V-0.1UF,16V,10%,X7R,A
     1 P3V3_DB1200 @BASEBOARD_FAB2_LIB.BASEBOARD_FAB2(SCH_1):P3V3_DB1200    I14 @BASEBOARD_FAB2_LIB.BASEBOARD_FAB2(SCH_1):PAGE102
     2    GND @BASEBOARD_FAB2_LIB.BASEBOARD_FAB2(SCH_1):GND    I14 @BASEBOARD_FAB2_LIB.BASEBOARD_FAB2(SCH_1):PAGE102

C6P6 CAP_A_0402V-0.1UF,16V,10%,X7R,A
     1 P3V3_DB1200 @BASEBOARD_FAB2_LIB.BASEBOARD_FAB2(SCH_1):P3V3_DB1200    I12 @BASEBOARD_FAB2_LIB.BASEBOARD_FAB2(SCH_1):PAGE102
     2    GND @BASEBOARD_FAB2_LIB.BASEBOARD_FAB2(SCH_1):GND    I12 @BASEBOARD_FAB2_LIB.BASEBOARD_FAB2(SCH_1):PAGE102

C6P7 CAP_0805-10UF,16V,10%,X6S,C953A
     1 VR_FET_SW_P12V_STBY_PVCCIN_CPU0 @BASEBOARD_FAB2_LIB.BASEBOARD_FAB2(SCH_1):VR_FET_SW_P12V_STBY_PVCCIN_CPU0    I59 @BASEBOARD_FAB2_LIB.BASEBOARD_FAB2(SCH_1):PAGE203
     2    GND @BASEBOARD_FAB2_LIB.BASEBOARD_FAB2(SCH_1):GND    I59 @BASEBOARD_FAB2_LIB.BASEBOARD_FAB2(SCH_1):PAGE203

C6P8 CAPP_3018-470UF,2.5V,20%,ALUM,A
     1 PVCCIN_CPU0 @BASEBOARD_FAB2_LIB.BASEBOARD_FAB2(SCH_1):PVCCIN_CPU0    I32 @BASEBOARD_FAB2_LIB.BASEBOARD_FAB2(SCH_1):PAGE203
     2    GND @BASEBOARD_FAB2_LIB.BASEBOARD_FAB2(SCH_1):GND    I32 @BASEBOARD_FAB2_LIB.BASEBOARD_FAB2(SCH_1):PAGE203

C6P9 CAP_A_0402V-0.1UF,16V,10%,X7R,A
     1 P3V3_DB1200 @BASEBOARD_FAB2_LIB.BASEBOARD_FAB2(SCH_1):P3V3_DB1200    I79 @BASEBOARD_FAB2_LIB.BASEBOARD_FAB2(SCH_1):PAGE102
     2    GND @BASEBOARD_FAB2_LIB.BASEBOARD_FAB2(SCH_1):GND    I79 @BASEBOARD_FAB2_LIB.BASEBOARD_FAB2(SCH_1):PAGE102

C6P10 CAP_A_0402V-0.1UF,16V,10%,X7R,A
     1 P3V3_DB1200 @BASEBOARD_FAB2_LIB.BASEBOARD_FAB2(SCH_1):P3V3_DB1200    I13 @BASEBOARD_FAB2_LIB.BASEBOARD_FAB2(SCH_1):PAGE102
     2    GND @BASEBOARD_FAB2_LIB.BASEBOARD_FAB2(SCH_1):GND    I13 @BASEBOARD_FAB2_LIB.BASEBOARD_FAB2(SCH_1):PAGE102

C6P11 CAP_A_0402V-0.1UF,16V,10%,X7R,A
     1 P3V3_DB1200 @BASEBOARD_FAB2_LIB.BASEBOARD_FAB2(SCH_1):P3V3_DB1200    I16 @BASEBOARD_FAB2_LIB.BASEBOARD_FAB2(SCH_1):PAGE102
     2    GND @BASEBOARD_FAB2_LIB.BASEBOARD_FAB2(SCH_1):GND    I16 @BASEBOARD_FAB2_LIB.BASEBOARD_FAB2(SCH_1):PAGE102

C6P12 CAP_A_0402V-0.1UF,16V,10%,X7R,A
     1 P3V3_DB1200 @BASEBOARD_FAB2_LIB.BASEBOARD_FAB2(SCH_1):P3V3_DB1200    I15 @BASEBOARD_FAB2_LIB.BASEBOARD_FAB2(SCH_1):PAGE102
     2    GND @BASEBOARD_FAB2_LIB.BASEBOARD_FAB2(SCH_1):GND    I15 @BASEBOARD_FAB2_LIB.BASEBOARD_FAB2(SCH_1):PAGE102

C6P13 CAP_0805-10UF,16V,10%,X6S,C953A
     1 VR_FET_SW_P12V_STBY_PVCCIN_CPU0 @BASEBOARD_FAB2_LIB.BASEBOARD_FAB2(SCH_1):VR_FET_SW_P12V_STBY_PVCCIN_CPU0    I38 @BASEBOARD_FAB2_LIB.BASEBOARD_FAB2(SCH_1):PAGE202
     2    GND @BASEBOARD_FAB2_LIB.BASEBOARD_FAB2(SCH_1):GND    I38 @BASEBOARD_FAB2_LIB.BASEBOARD_FAB2(SCH_1):PAGE202

C6P14 CAPP_3018-470UF,2.5V,20%,ALUM,A
     1 PVCCIN_CPU0 @BASEBOARD_FAB2_LIB.BASEBOARD_FAB2(SCH_1):PVCCIN_CPU0    I29 @BASEBOARD_FAB2_LIB.BASEBOARD_FAB2(SCH_1):PAGE203
     2    GND @BASEBOARD_FAB2_LIB.BASEBOARD_FAB2(SCH_1):GND    I29 @BASEBOARD_FAB2_LIB.BASEBOARD_FAB2(SCH_1):PAGE203

C6P15 CAP_0805-10UF,16V,10%,X6S,C953A
     1 VR_FET_SW_P12V_STBY_PVCCIN_CPU0 @BASEBOARD_FAB2_LIB.BASEBOARD_FAB2(SCH_1):VR_FET_SW_P12V_STBY_PVCCIN_CPU0    I58 @BASEBOARD_FAB2_LIB.BASEBOARD_FAB2(SCH_1):PAGE203
     2    GND @BASEBOARD_FAB2_LIB.BASEBOARD_FAB2(SCH_1):GND    I58 @BASEBOARD_FAB2_LIB.BASEBOARD_FAB2(SCH_1):PAGE203

C6P16 CAP_A_0603V-22.0UF,4V,20%,X6S,A
     1 PVCCIN_CPU0 @BASEBOARD_FAB2_LIB.BASEBOARD_FAB2(SCH_1):PVCCIN_CPU0    I62 @BASEBOARD_FAB2_LIB.BASEBOARD_FAB2(SCH_1):PAGE202
     2    GND @BASEBOARD_FAB2_LIB.BASEBOARD_FAB2(SCH_1):GND    I62 @BASEBOARD_FAB2_LIB.BASEBOARD_FAB2(SCH_1):PAGE202

C6P17 CAP_0805-10UF,16V,10%,X6S,C953A
     1 VR_FET_SW_P12V_STBY_PVCCIN_CPU0 @BASEBOARD_FAB2_LIB.BASEBOARD_FAB2(SCH_1):VR_FET_SW_P12V_STBY_PVCCIN_CPU0    I38 @BASEBOARD_FAB2_LIB.BASEBOARD_FAB2(SCH_1):PAGE204
     2    GND @BASEBOARD_FAB2_LIB.BASEBOARD_FAB2(SCH_1):GND    I38 @BASEBOARD_FAB2_LIB.BASEBOARD_FAB2(SCH_1):PAGE204

C6P18 CAPP_3018-470UF,2.5V,20%,ALUM,A
     1 PVCCIN_CPU0 @BASEBOARD_FAB2_LIB.BASEBOARD_FAB2(SCH_1):PVCCIN_CPU0    I30 @BASEBOARD_FAB2_LIB.BASEBOARD_FAB2(SCH_1):PAGE203
     2    GND @BASEBOARD_FAB2_LIB.BASEBOARD_FAB2(SCH_1):GND    I30 @BASEBOARD_FAB2_LIB.BASEBOARD_FAB2(SCH_1):PAGE203

C6P19 CAP_0805-10UF,16V,10%,X6S,C953A
     1 VR_FET_SW_P12V_STBY_PVCCIN_CPU0 @BASEBOARD_FAB2_LIB.BASEBOARD_FAB2(SCH_1):VR_FET_SW_P12V_STBY_PVCCIN_CPU0    I54 @BASEBOARD_FAB2_LIB.BASEBOARD_FAB2(SCH_1):PAGE203
     2    GND @BASEBOARD_FAB2_LIB.BASEBOARD_FAB2(SCH_1):GND    I54 @BASEBOARD_FAB2_LIB.BASEBOARD_FAB2(SCH_1):PAGE203

C6P20 CAP_0805-10UF,16V,10%,X6S,C953A
     1 VR_FET_SW_P12V_STBY_PVCCIN_CPU0 @BASEBOARD_FAB2_LIB.BASEBOARD_FAB2(SCH_1):VR_FET_SW_P12V_STBY_PVCCIN_CPU0    I57 @BASEBOARD_FAB2_LIB.BASEBOARD_FAB2(SCH_1):PAGE203
     2    GND @BASEBOARD_FAB2_LIB.BASEBOARD_FAB2(SCH_1):GND    I57 @BASEBOARD_FAB2_LIB.BASEBOARD_FAB2(SCH_1):PAGE203

C6P21 CAP_A_0603V-22.0UF,4V,20%,X6S,A
     1 PVCCIN_CPU0 @BASEBOARD_FAB2_LIB.BASEBOARD_FAB2(SCH_1):PVCCIN_CPU0    I66 @BASEBOARD_FAB2_LIB.BASEBOARD_FAB2(SCH_1):PAGE203
     2    GND @BASEBOARD_FAB2_LIB.BASEBOARD_FAB2(SCH_1):GND    I66 @BASEBOARD_FAB2_LIB.BASEBOARD_FAB2(SCH_1):PAGE203

C6P22 CAP_0805-10UF,16V,10%,X6S,C953A
     1 VR_FET_SW_P12V_STBY_PVCCIN_CPU0 @BASEBOARD_FAB2_LIB.BASEBOARD_FAB2(SCH_1):VR_FET_SW_P12V_STBY_PVCCIN_CPU0    I49 @BASEBOARD_FAB2_LIB.BASEBOARD_FAB2(SCH_1):PAGE202
     2    GND @BASEBOARD_FAB2_LIB.BASEBOARD_FAB2(SCH_1):GND    I49 @BASEBOARD_FAB2_LIB.BASEBOARD_FAB2(SCH_1):PAGE202

C6P23 CAPP_3018-470UF,2.5V,20%,ALUM,A
     1 PVCCIN_CPU0 @BASEBOARD_FAB2_LIB.BASEBOARD_FAB2(SCH_1):PVCCIN_CPU0    I28 @BASEBOARD_FAB2_LIB.BASEBOARD_FAB2(SCH_1):PAGE203
     2    GND @BASEBOARD_FAB2_LIB.BASEBOARD_FAB2(SCH_1):GND    I28 @BASEBOARD_FAB2_LIB.BASEBOARD_FAB2(SCH_1):PAGE203

C6P24 CAP_0805-10UF,16V,10%,X6S,C953A
     1 VR_FET_SW_P12V_STBY_PVCCIN_CPU0 @BASEBOARD_FAB2_LIB.BASEBOARD_FAB2(SCH_1):VR_FET_SW_P12V_STBY_PVCCIN_CPU0     I1 @BASEBOARD_FAB2_LIB.BASEBOARD_FAB2(SCH_1):PAGE203
     2    GND @BASEBOARD_FAB2_LIB.BASEBOARD_FAB2(SCH_1):GND     I1 @BASEBOARD_FAB2_LIB.BASEBOARD_FAB2(SCH_1):PAGE203

C6R2 CAP_A_0603V-22.0UF,4V,20%,X6S,A
     1 PVCCIN_CPU0 @BASEBOARD_FAB2_LIB.BASEBOARD_FAB2(SCH_1):PVCCIN_CPU0    I70 @BASEBOARD_FAB2_LIB.BASEBOARD_FAB2(SCH_1):PAGE204
     2    GND @BASEBOARD_FAB2_LIB.BASEBOARD_FAB2(SCH_1):GND    I70 @BASEBOARD_FAB2_LIB.BASEBOARD_FAB2(SCH_1):PAGE204

C6R3 CAPP_3018-470UF,2.5V,20%,ALUM,A
     1 PVCCIN_CPU0 @BASEBOARD_FAB2_LIB.BASEBOARD_FAB2(SCH_1):PVCCIN_CPU0    I16 @BASEBOARD_FAB2_LIB.BASEBOARD_FAB2(SCH_1):PAGE203
     2    GND @BASEBOARD_FAB2_LIB.BASEBOARD_FAB2(SCH_1):GND    I16 @BASEBOARD_FAB2_LIB.BASEBOARD_FAB2(SCH_1):PAGE203

C6R4 CAP_0805-10UF,16V,10%,X6S,C953A
     1 VR_FET_SW_P12V_STBY_PVCCIN_CPU0 @BASEBOARD_FAB2_LIB.BASEBOARD_FAB2(SCH_1):VR_FET_SW_P12V_STBY_PVCCIN_CPU0    I48 @BASEBOARD_FAB2_LIB.BASEBOARD_FAB2(SCH_1):PAGE202
     2    GND @BASEBOARD_FAB2_LIB.BASEBOARD_FAB2(SCH_1):GND    I48 @BASEBOARD_FAB2_LIB.BASEBOARD_FAB2(SCH_1):PAGE202

C6R5 CAPP_3018-470UF,2.5V,20%,ALUM,A
     1 PVCCIO_CPU1 @BASEBOARD_FAB2_LIB.BASEBOARD_FAB2(SCH_1):PVCCIO_CPU1    I24 @BASEBOARD_FAB2_LIB.BASEBOARD_FAB2(SCH_1):PAGE214
     2    GND @BASEBOARD_FAB2_LIB.BASEBOARD_FAB2(SCH_1):GND    I24 @BASEBOARD_FAB2_LIB.BASEBOARD_FAB2(SCH_1):PAGE214

C6R6 CAP_0805-10UF,16V,10%,X6S,C953A
     1 VR_FET_SW_P12V_STBY_PVCCIN_CPU0 @BASEBOARD_FAB2_LIB.BASEBOARD_FAB2(SCH_1):VR_FET_SW_P12V_STBY_PVCCIN_CPU0     I2 @BASEBOARD_FAB2_LIB.BASEBOARD_FAB2(SCH_1):PAGE203
     2    GND @BASEBOARD_FAB2_LIB.BASEBOARD_FAB2(SCH_1):GND     I2 @BASEBOARD_FAB2_LIB.BASEBOARD_FAB2(SCH_1):PAGE203

C6R7 CAP_A_0603V-22.0UF,4V,20%,X6S,A
     1 PVCCIN_CPU0 @BASEBOARD_FAB2_LIB.BASEBOARD_FAB2(SCH_1):PVCCIN_CPU0     I9 @BASEBOARD_FAB2_LIB.BASEBOARD_FAB2(SCH_1):PAGE202
     2    GND @BASEBOARD_FAB2_LIB.BASEBOARD_FAB2(SCH_1):GND     I9 @BASEBOARD_FAB2_LIB.BASEBOARD_FAB2(SCH_1):PAGE202

C6R8 CAP_0805-10UF,16V,10%,X6S,C953A
     1 VR_FET_SW_P12V_STBY_PVCCIN_CPU0 @BASEBOARD_FAB2_LIB.BASEBOARD_FAB2(SCH_1):VR_FET_SW_P12V_STBY_PVCCIN_CPU0    I83 @BASEBOARD_FAB2_LIB.BASEBOARD_FAB2(SCH_1):PAGE214
     2    GND @BASEBOARD_FAB2_LIB.BASEBOARD_FAB2(SCH_1):GND    I83 @BASEBOARD_FAB2_LIB.BASEBOARD_FAB2(SCH_1):PAGE214

C6R9 CAPP_3018-470UF,2.5V,20%,ALUM,A
     1 PVCCIN_CPU0 @BASEBOARD_FAB2_LIB.BASEBOARD_FAB2(SCH_1):PVCCIN_CPU0    I18 @BASEBOARD_FAB2_LIB.BASEBOARD_FAB2(SCH_1):PAGE203
     2    GND @BASEBOARD_FAB2_LIB.BASEBOARD_FAB2(SCH_1):GND    I18 @BASEBOARD_FAB2_LIB.BASEBOARD_FAB2(SCH_1):PAGE203

C6R10 CAP_0805-10UF,16V,10%,X6S,C953A
     1 VR_FET_SW_P12V_STBY_PVCCIN_CPU0 @BASEBOARD_FAB2_LIB.BASEBOARD_FAB2(SCH_1):VR_FET_SW_P12V_STBY_PVCCIN_CPU0    I81 @BASEBOARD_FAB2_LIB.BASEBOARD_FAB2(SCH_1):PAGE214
     2    GND @BASEBOARD_FAB2_LIB.BASEBOARD_FAB2(SCH_1):GND    I81 @BASEBOARD_FAB2_LIB.BASEBOARD_FAB2(SCH_1):PAGE214

C6R11 CAP_0805-10UF,16V,10%,X6S,C953A
     1 VR_FET_SW_P12V_STBY_PVCCIN_CPU0 @BASEBOARD_FAB2_LIB.BASEBOARD_FAB2(SCH_1):VR_FET_SW_P12V_STBY_PVCCIN_CPU0    I37 @BASEBOARD_FAB2_LIB.BASEBOARD_FAB2(SCH_1):PAGE202
     2    GND @BASEBOARD_FAB2_LIB.BASEBOARD_FAB2(SCH_1):GND    I37 @BASEBOARD_FAB2_LIB.BASEBOARD_FAB2(SCH_1):PAGE202

C6R12 CAPP_3018-470UF,2.5V,20%,ALUM,A
     1 PVCCIO_CPU1 @BASEBOARD_FAB2_LIB.BASEBOARD_FAB2(SCH_1):PVCCIO_CPU1   I177 @BASEBOARD_FAB2_LIB.BASEBOARD_FAB2(SCH_1):PAGE214
     2    GND @BASEBOARD_FAB2_LIB.BASEBOARD_FAB2(SCH_1):GND   I177 @BASEBOARD_FAB2_LIB.BASEBOARD_FAB2(SCH_1):PAGE214

C6R13 CAP_0805-10UF,16V,10%,X6S,C953A
     1 VR_FET_SW_P12V_STBY_PVCCIN_CPU0 @BASEBOARD_FAB2_LIB.BASEBOARD_FAB2(SCH_1):VR_FET_SW_P12V_STBY_PVCCIN_CPU0    I42 @BASEBOARD_FAB2_LIB.BASEBOARD_FAB2(SCH_1):PAGE202
     2    GND @BASEBOARD_FAB2_LIB.BASEBOARD_FAB2(SCH_1):GND    I42 @BASEBOARD_FAB2_LIB.BASEBOARD_FAB2(SCH_1):PAGE202

C6R14 CAP_0805-10UF,16V,10%,X6S,C953A
     1 VR_FET_SW_P12V_STBY_PVCCIN_CPU0 @BASEBOARD_FAB2_LIB.BASEBOARD_FAB2(SCH_1):VR_FET_SW_P12V_STBY_PVCCIN_CPU0    I80 @BASEBOARD_FAB2_LIB.BASEBOARD_FAB2(SCH_1):PAGE214
     2    GND @BASEBOARD_FAB2_LIB.BASEBOARD_FAB2(SCH_1):GND    I80 @BASEBOARD_FAB2_LIB.BASEBOARD_FAB2(SCH_1):PAGE214

C6R16 CAPP_3018-470UF,2.5V,20%,ALUM,A
     1 PVCCMCP_CPU1 @BASEBOARD_FAB2_LIB.BASEBOARD_FAB2(SCH_1):PVCCMCP_CPU1    I62 @BASEBOARD_FAB2_LIB.BASEBOARD_FAB2(SCH_1):PAGE193
     2    GND @BASEBOARD_FAB2_LIB.BASEBOARD_FAB2(SCH_1):GND    I62 @BASEBOARD_FAB2_LIB.BASEBOARD_FAB2(SCH_1):PAGE193

C6T1 CAP_A_0402V-0.01UF,25V,10%,X7RA
     1 M_A_VREF @BASEBOARD_FAB2_LIB.BASEBOARD_FAB2(SCH_1):M_A_VREF     I2 @BASEBOARD_FAB2_LIB.BASEBOARD_FAB2(SCH_1):PAGE44
     2    GND @BASEBOARD_FAB2_LIB.BASEBOARD_FAB2(SCH_1):GND     I2 @BASEBOARD_FAB2_LIB.BASEBOARD_FAB2(SCH_1):PAGE44

C6T2 CAP_0805-10UF,16V,10%,X7R,G106A
     1 P12V_NVDIMM_ABC @BASEBOARD_FAB2_LIB.BASEBOARD_FAB2(SCH_1):P12V_NVDIMM_ABC    I71 @BASEBOARD_FAB2_LIB.BASEBOARD_FAB2(SCH_1):PAGE197
     2    GND @BASEBOARD_FAB2_LIB.BASEBOARD_FAB2(SCH_1):GND    I71 @BASEBOARD_FAB2_LIB.BASEBOARD_FAB2(SCH_1):PAGE197

C6U2 CAP_0805-47UF,4V,20%,X6S,C9533A
     1 PVPP_GHJ @BASEBOARD_FAB2_LIB.BASEBOARD_FAB2(SCH_1):PVPP_GHJ   I223 @BASEBOARD_FAB2_LIB.BASEBOARD_FAB2(SCH_1):PAGE233
     2    GND @BASEBOARD_FAB2_LIB.BASEBOARD_FAB2(SCH_1):GND   I223 @BASEBOARD_FAB2_LIB.BASEBOARD_FAB2(SCH_1):PAGE233

C6U3 CAP_0805-47UF,4V,20%,X6S,C9533A
     1 PVPP_GHJ @BASEBOARD_FAB2_LIB.BASEBOARD_FAB2(SCH_1):PVPP_GHJ   I221 @BASEBOARD_FAB2_LIB.BASEBOARD_FAB2(SCH_1):PAGE233
     2    GND @BASEBOARD_FAB2_LIB.BASEBOARD_FAB2(SCH_1):GND   I221 @BASEBOARD_FAB2_LIB.BASEBOARD_FAB2(SCH_1):PAGE233

C6U4 CAP_0805-10UF,16V,10%,X6S,C953A
     1 VR_FET_SW_P12V_STBY_PVPP_GHJ @BASEBOARD_FAB2_LIB.BASEBOARD_FAB2(SCH_1):VR_FET_SW_P12V_STBY_PVPP_GHJ   I248 @BASEBOARD_FAB2_LIB.BASEBOARD_FAB2(SCH_1):PAGE233
     2    GND @BASEBOARD_FAB2_LIB.BASEBOARD_FAB2(SCH_1):GND   I248 @BASEBOARD_FAB2_LIB.BASEBOARD_FAB2(SCH_1):PAGE233

C6U5 CAP_A_0402V-0.1UF,16V,10%,X7R,A
     1 VR_FET_SW_P12V_STBY_PVPP_GHJ @BASEBOARD_FAB2_LIB.BASEBOARD_FAB2(SCH_1):VR_FET_SW_P12V_STBY_PVPP_GHJ   I242 @BASEBOARD_FAB2_LIB.BASEBOARD_FAB2(SCH_1):PAGE233
     2    GND @BASEBOARD_FAB2_LIB.BASEBOARD_FAB2(SCH_1):GND   I242 @BASEBOARD_FAB2_LIB.BASEBOARD_FAB2(SCH_1):PAGE233

C6U6 CAP_0603-4.7UF,6.3V,10%,X6S,E1A
     1 VR_VB_PVPP_GHJ @BASEBOARD_FAB2_LIB.BASEBOARD_FAB2(SCH_1):VR_VB_PVPP_GHJ   I187 @BASEBOARD_FAB2_LIB.BASEBOARD_FAB2(SCH_1):PAGE233
     2 AGND_PVPP_GHJ @BASEBOARD_FAB2_LIB.BASEBOARD_FAB2(SCH_1):AGND_PVPP_GHJ   I187 @BASEBOARD_FAB2_LIB.BASEBOARD_FAB2(SCH_1):PAGE233

C6U7 CAP_0805-10UF,16V,10%,X6S,C953A
     1 VR_FET_SW_P12V_STBY_PVPP_GHJ @BASEBOARD_FAB2_LIB.BASEBOARD_FAB2(SCH_1):VR_FET_SW_P12V_STBY_PVPP_GHJ   I254 @BASEBOARD_FAB2_LIB.BASEBOARD_FAB2(SCH_1):PAGE233
     2    GND @BASEBOARD_FAB2_LIB.BASEBOARD_FAB2(SCH_1):GND   I254 @BASEBOARD_FAB2_LIB.BASEBOARD_FAB2(SCH_1):PAGE233

C6U8 CAP_0805-10UF,16V,10%,X6S,C953A
     1 VR_FET_SW_P12V_STBY_PVPP_GHJ @BASEBOARD_FAB2_LIB.BASEBOARD_FAB2(SCH_1):VR_FET_SW_P12V_STBY_PVPP_GHJ   I255 @BASEBOARD_FAB2_LIB.BASEBOARD_FAB2(SCH_1):PAGE233
     2    GND @BASEBOARD_FAB2_LIB.BASEBOARD_FAB2(SCH_1):GND   I255 @BASEBOARD_FAB2_LIB.BASEBOARD_FAB2(SCH_1):PAGE233

C6U9 CAP_A_0402V-0.01UF,25V,10%,X7RA
     1 M_B_VREF @BASEBOARD_FAB2_LIB.BASEBOARD_FAB2(SCH_1):M_B_VREF     I5 @BASEBOARD_FAB2_LIB.BASEBOARD_FAB2(SCH_1):PAGE46
     2    GND @BASEBOARD_FAB2_LIB.BASEBOARD_FAB2(SCH_1):GND     I5 @BASEBOARD_FAB2_LIB.BASEBOARD_FAB2(SCH_1):PAGE46

C6U10 CAP_0805-10UF,16V,10%,X7R,G106A
     1 P12V_NVDIMM_ABC @BASEBOARD_FAB2_LIB.BASEBOARD_FAB2(SCH_1):P12V_NVDIMM_ABC    I84 @BASEBOARD_FAB2_LIB.BASEBOARD_FAB2(SCH_1):PAGE197
     2    GND @BASEBOARD_FAB2_LIB.BASEBOARD_FAB2(SCH_1):GND    I84 @BASEBOARD_FAB2_LIB.BASEBOARD_FAB2(SCH_1):PAGE197

C6U11 CAP_0603-4.7UF,6.3V,10%,X6S,E1A
     1 VSENSE_PVDDQ_GHJ_VTT @BASEBOARD_FAB2_LIB.BASEBOARD_FAB2(SCH_1):VSENSE_PVDDQ_GHJ_VTT    I14 @BASEBOARD_FAB2_LIB.BASEBOARD_FAB2(SCH_1):PAGE229
     2    GND @BASEBOARD_FAB2_LIB.BASEBOARD_FAB2(SCH_1):GND    I14 @BASEBOARD_FAB2_LIB.BASEBOARD_FAB2(SCH_1):PAGE229

C6U12 CAP_0603-4.7UF,6.3V,10%,X6S,E1A
     1 VSENSE_PVDDQ_ABC_VTT @BASEBOARD_FAB2_LIB.BASEBOARD_FAB2(SCH_1):VSENSE_PVDDQ_ABC_VTT    I11 @BASEBOARD_FAB2_LIB.BASEBOARD_FAB2(SCH_1):PAGE221
     2    GND @BASEBOARD_FAB2_LIB.BASEBOARD_FAB2(SCH_1):GND    I11 @BASEBOARD_FAB2_LIB.BASEBOARD_FAB2(SCH_1):PAGE221

C6U13 CAP_0603LF-10UF,4V,20%,X6S,E15A
     1 PVDDQ_GHJ @BASEBOARD_FAB2_LIB.BASEBOARD_FAB2(SCH_1):PVDDQ_GHJ    I11 @BASEBOARD_FAB2_LIB.BASEBOARD_FAB2(SCH_1):PAGE229
     2    GND @BASEBOARD_FAB2_LIB.BASEBOARD_FAB2(SCH_1):GND    I11 @BASEBOARD_FAB2_LIB.BASEBOARD_FAB2(SCH_1):PAGE229

C6U14 CAP_0603LF-10UF,4V,20%,X6S,E15A
     1 PVDDQ_GHJ @BASEBOARD_FAB2_LIB.BASEBOARD_FAB2(SCH_1):PVDDQ_GHJ    I18 @BASEBOARD_FAB2_LIB.BASEBOARD_FAB2(SCH_1):PAGE229
     2    GND @BASEBOARD_FAB2_LIB.BASEBOARD_FAB2(SCH_1):GND    I18 @BASEBOARD_FAB2_LIB.BASEBOARD_FAB2(SCH_1):PAGE229

C6U15 CAP_0603LF-10UF,4V,20%,X6S,E15A
     1 PVDDQ_ABC @BASEBOARD_FAB2_LIB.BASEBOARD_FAB2(SCH_1):PVDDQ_ABC    I18 @BASEBOARD_FAB2_LIB.BASEBOARD_FAB2(SCH_1):PAGE221
     2    GND @BASEBOARD_FAB2_LIB.BASEBOARD_FAB2(SCH_1):GND    I18 @BASEBOARD_FAB2_LIB.BASEBOARD_FAB2(SCH_1):PAGE221

C6U16 CAP_0603LF-10UF,4V,20%,X6S,E15A
     1 PVDDQ_ABC @BASEBOARD_FAB2_LIB.BASEBOARD_FAB2(SCH_1):PVDDQ_ABC    I19 @BASEBOARD_FAB2_LIB.BASEBOARD_FAB2(SCH_1):PAGE221
     2    GND @BASEBOARD_FAB2_LIB.BASEBOARD_FAB2(SCH_1):GND    I19 @BASEBOARD_FAB2_LIB.BASEBOARD_FAB2(SCH_1):PAGE221

C6U17 CAP_A_0402V-0.01UF,25V,10%,X7RA
     1 M_C_VREF @BASEBOARD_FAB2_LIB.BASEBOARD_FAB2(SCH_1):M_C_VREF   I176 @BASEBOARD_FAB2_LIB.BASEBOARD_FAB2(SCH_1):PAGE48
     2    GND @BASEBOARD_FAB2_LIB.BASEBOARD_FAB2(SCH_1):GND   I176 @BASEBOARD_FAB2_LIB.BASEBOARD_FAB2(SCH_1):PAGE48

C6U18 CAP_0805-10UF,16V,10%,X7R,G106A
     1 P12V_NVDIMM_ABC @BASEBOARD_FAB2_LIB.BASEBOARD_FAB2(SCH_1):P12V_NVDIMM_ABC    I69 @BASEBOARD_FAB2_LIB.BASEBOARD_FAB2(SCH_1):PAGE197
     2    GND @BASEBOARD_FAB2_LIB.BASEBOARD_FAB2(SCH_1):GND    I69 @BASEBOARD_FAB2_LIB.BASEBOARD_FAB2(SCH_1):PAGE197

C6W1 CAP_A_0402V-0.1UF,16V,10%,X7R,A
     1 P3V3_STBY @BASEBOARD_FAB2_LIB.BASEBOARD_FAB2(SCH_1):P3V3_STBY   I151 @BASEBOARD_FAB2_LIB.BASEBOARD_FAB2(SCH_1):PAGE247
     2    GND @BASEBOARD_FAB2_LIB.BASEBOARD_FAB2(SCH_1):GND   I151 @BASEBOARD_FAB2_LIB.BASEBOARD_FAB2(SCH_1):PAGE247

C6W2 CAP_A_0402V-0.1UF,16V,10%,X7R,A
     1 P3V3_STBY @BASEBOARD_FAB2_LIB.BASEBOARD_FAB2(SCH_1):P3V3_STBY   I107 @BASEBOARD_FAB2_LIB.BASEBOARD_FAB2(SCH_1):PAGE247
     2    GND @BASEBOARD_FAB2_LIB.BASEBOARD_FAB2(SCH_1):GND   I107 @BASEBOARD_FAB2_LIB.BASEBOARD_FAB2(SCH_1):PAGE247

C6W3 CAP_A_0402V-0.1UF,16V,10%,X7R,A
     1 P3V3_STBY @BASEBOARD_FAB2_LIB.BASEBOARD_FAB2(SCH_1):P3V3_STBY    I85 @BASEBOARD_FAB2_LIB.BASEBOARD_FAB2(SCH_1):PAGE247
     2    GND @BASEBOARD_FAB2_LIB.BASEBOARD_FAB2(SCH_1):GND    I85 @BASEBOARD_FAB2_LIB.BASEBOARD_FAB2(SCH_1):PAGE247

C6W4 CAP_A_0402V-0.1UF,16V,10%,X7R,A
     1 P3V3_STBY @BASEBOARD_FAB2_LIB.BASEBOARD_FAB2(SCH_1):P3V3_STBY   I105 @BASEBOARD_FAB2_LIB.BASEBOARD_FAB2(SCH_1):PAGE247
     2    GND @BASEBOARD_FAB2_LIB.BASEBOARD_FAB2(SCH_1):GND   I105 @BASEBOARD_FAB2_LIB.BASEBOARD_FAB2(SCH_1):PAGE247

C6W10 CAP_A_0402V-0.1UF,16V,10%,X7R,A
     1 P3V3_STBY @BASEBOARD_FAB2_LIB.BASEBOARD_FAB2(SCH_1):P3V3_STBY   I139 @BASEBOARD_FAB2_LIB.BASEBOARD_FAB2(SCH_1):PAGE176
     2    GND @BASEBOARD_FAB2_LIB.BASEBOARD_FAB2(SCH_1):GND   I139 @BASEBOARD_FAB2_LIB.BASEBOARD_FAB2(SCH_1):PAGE176

C6W11 CAP_0805-100UF,4V,20%,X5R,6024A
     1 PVTT_ABC @BASEBOARD_FAB2_LIB.BASEBOARD_FAB2(SCH_1):PVTT_ABC    I44 @BASEBOARD_FAB2_LIB.BASEBOARD_FAB2(SCH_1):PAGE221
     2    GND @BASEBOARD_FAB2_LIB.BASEBOARD_FAB2(SCH_1):GND    I44 @BASEBOARD_FAB2_LIB.BASEBOARD_FAB2(SCH_1):PAGE221

C6W12 CAP_0805-100UF,4V,20%,X5R,6024A
     1 PVTT_GHJ @BASEBOARD_FAB2_LIB.BASEBOARD_FAB2(SCH_1):PVTT_GHJ    I43 @BASEBOARD_FAB2_LIB.BASEBOARD_FAB2(SCH_1):PAGE229
     2    GND @BASEBOARD_FAB2_LIB.BASEBOARD_FAB2(SCH_1):GND    I43 @BASEBOARD_FAB2_LIB.BASEBOARD_FAB2(SCH_1):PAGE229

C6W13 CAP_0805-100UF,4V,20%,X5R,6024A
     1 PVTT_KLM @BASEBOARD_FAB2_LIB.BASEBOARD_FAB2(SCH_1):PVTT_KLM    I43 @BASEBOARD_FAB2_LIB.BASEBOARD_FAB2(SCH_1):PAGE230
     2    GND @BASEBOARD_FAB2_LIB.BASEBOARD_FAB2(SCH_1):GND    I43 @BASEBOARD_FAB2_LIB.BASEBOARD_FAB2(SCH_1):PAGE230

C6W14 CAP_A_0402V-0.1UF,16V,10%,X7R,A
     1 P3V3_STBY @BASEBOARD_FAB2_LIB.BASEBOARD_FAB2(SCH_1):P3V3_STBY    I66 @BASEBOARD_FAB2_LIB.BASEBOARD_FAB2(SCH_1):PAGE164
     2    GND @BASEBOARD_FAB2_LIB.BASEBOARD_FAB2(SCH_1):GND    I66 @BASEBOARD_FAB2_LIB.BASEBOARD_FAB2(SCH_1):PAGE164

C7A5 CAP_A_0402V-0.1UF,16V,10%,X7R,A
     1 VR_FET_SW_P12V_STBY_PVDDQ_DEF @BASEBOARD_FAB2_LIB.BASEBOARD_FAB2(SCH_1):VR_FET_SW_P12V_STBY_PVDDQ_DEF    I51 @BASEBOARD_FAB2_LIB.BASEBOARD_FAB2(SCH_1):PAGE219
     2    GND @BASEBOARD_FAB2_LIB.BASEBOARD_FAB2(SCH_1):GND    I51 @BASEBOARD_FAB2_LIB.BASEBOARD_FAB2(SCH_1):PAGE219

C7A6 CAP_0402-1.0UF,16V,10%,X6S,D97A
     1 VR_PVNN_PCH_PH1_VCIN @BASEBOARD_FAB2_LIB.BASEBOARD_FAB2(SCH_1):VR_PVNN_PCH_PH1_VCIN    I19 @BASEBOARD_FAB2_LIB.BASEBOARD_FAB2(SCH_1):PAGE236
     2    GND @BASEBOARD_FAB2_LIB.BASEBOARD_FAB2(SCH_1):GND    I19 @BASEBOARD_FAB2_LIB.BASEBOARD_FAB2(SCH_1):PAGE236

C7A7 CAP_0402-1.0UF,16V,10%,X6S,D97A
     1 VR_FET_SW_P12V_STBY_PVDDQ_DEF @BASEBOARD_FAB2_LIB.BASEBOARD_FAB2(SCH_1):VR_FET_SW_P12V_STBY_PVDDQ_DEF    I22 @BASEBOARD_FAB2_LIB.BASEBOARD_FAB2(SCH_1):PAGE236
     2    GND @BASEBOARD_FAB2_LIB.BASEBOARD_FAB2(SCH_1):GND    I22 @BASEBOARD_FAB2_LIB.BASEBOARD_FAB2(SCH_1):PAGE236

C7A8 CAP_0402-0.22UF,16V,10%,X7R,A3A
     1 P5V_STBY @BASEBOARD_FAB2_LIB.BASEBOARD_FAB2(SCH_1):P5V_STBY    I16 @BASEBOARD_FAB2_LIB.BASEBOARD_FAB2(SCH_1):PAGE236
     2    GND @BASEBOARD_FAB2_LIB.BASEBOARD_FAB2(SCH_1):GND    I16 @BASEBOARD_FAB2_LIB.BASEBOARD_FAB2(SCH_1):PAGE236

C7A9 CAP_0402-1.0UF,16V,10%,X6S,D97A
     1 VR_FET_SW_P12V_STBY_PVDDQ_DEF @BASEBOARD_FAB2_LIB.BASEBOARD_FAB2(SCH_1):VR_FET_SW_P12V_STBY_PVDDQ_DEF    I33 @BASEBOARD_FAB2_LIB.BASEBOARD_FAB2(SCH_1):PAGE236
     2    GND @BASEBOARD_FAB2_LIB.BASEBOARD_FAB2(SCH_1):GND    I33 @BASEBOARD_FAB2_LIB.BASEBOARD_FAB2(SCH_1):PAGE236

C7A10 CAP_0402-1.0UF,16V,10%,X6S,D97A
     1 VR_P1V05_PCH_STBY_PH1_VCIN @BASEBOARD_FAB2_LIB.BASEBOARD_FAB2(SCH_1):VR_P1V05_PCH_STBY_PH1_VCIN    I36 @BASEBOARD_FAB2_LIB.BASEBOARD_FAB2(SCH_1):PAGE236
     2    GND @BASEBOARD_FAB2_LIB.BASEBOARD_FAB2(SCH_1):GND    I36 @BASEBOARD_FAB2_LIB.BASEBOARD_FAB2(SCH_1):PAGE236

C7A11 CAP_0402-1.0UF,16V,10%,X6S,D97A
     1 VR_FET_SW_P12V_STBY_PVDDQ_DEF @BASEBOARD_FAB2_LIB.BASEBOARD_FAB2(SCH_1):VR_FET_SW_P12V_STBY_PVDDQ_DEF    I48 @BASEBOARD_FAB2_LIB.BASEBOARD_FAB2(SCH_1):PAGE219
     2    GND @BASEBOARD_FAB2_LIB.BASEBOARD_FAB2(SCH_1):GND    I48 @BASEBOARD_FAB2_LIB.BASEBOARD_FAB2(SCH_1):PAGE219

C7A12 CAP_0402-0.220UF,16V,10%,X7R,AA
     1 VR_PVDDQ_DEF_PH1_BOOT @BASEBOARD_FAB2_LIB.BASEBOARD_FAB2(SCH_1):VR_PVDDQ_DEF_PH1_BOOT    I44 @BASEBOARD_FAB2_LIB.BASEBOARD_FAB2(SCH_1):PAGE219
     2 VR_PVDDQ_DEF_PH1_PHASE @BASEBOARD_FAB2_LIB.BASEBOARD_FAB2(SCH_1):VR_PVDDQ_DEF_PH1_PHASE    I44 @BASEBOARD_FAB2_LIB.BASEBOARD_FAB2(SCH_1):PAGE219

C7A13 SC22U16V5MX-4-GP_SMD-BCG5-SC22A
     1 VR_FET_SW_P12V_STBY_PVDDQ_DEF @BASEBOARD_FAB2_LIB.BASEBOARD_FAB2(SCH_1):VR_FET_SW_P12V_STBY_PVDDQ_DEF   I161 @BASEBOARD_FAB2_LIB.BASEBOARD_FAB2(SCH_1):PAGE236
     2    GND @BASEBOARD_FAB2_LIB.BASEBOARD_FAB2(SCH_1):GND   I161 @BASEBOARD_FAB2_LIB.BASEBOARD_FAB2(SCH_1):PAGE236

C7A14 SC22U16V5MX-4-GP_SMD-BCG5-SC22A
     1 VR_FET_SW_P12V_STBY_PVDDQ_DEF @BASEBOARD_FAB2_LIB.BASEBOARD_FAB2(SCH_1):VR_FET_SW_P12V_STBY_PVDDQ_DEF   I172 @BASEBOARD_FAB2_LIB.BASEBOARD_FAB2(SCH_1):PAGE236
     2    GND @BASEBOARD_FAB2_LIB.BASEBOARD_FAB2(SCH_1):GND   I172 @BASEBOARD_FAB2_LIB.BASEBOARD_FAB2(SCH_1):PAGE236

C7A16 CAP_0402-1.0UF,16V,10%,X6S,D97A
     1 VR_PVDDQ_DEF_PH1_VCIN @BASEBOARD_FAB2_LIB.BASEBOARD_FAB2(SCH_1):VR_PVDDQ_DEF_PH1_VCIN    I50 @BASEBOARD_FAB2_LIB.BASEBOARD_FAB2(SCH_1):PAGE219
     2    GND @BASEBOARD_FAB2_LIB.BASEBOARD_FAB2(SCH_1):GND    I50 @BASEBOARD_FAB2_LIB.BASEBOARD_FAB2(SCH_1):PAGE219

C7A17 CAP_0402-0.22UF,16V,10%,X7R,A3A
     1 P5V_STBY @BASEBOARD_FAB2_LIB.BASEBOARD_FAB2(SCH_1):P5V_STBY    I54 @BASEBOARD_FAB2_LIB.BASEBOARD_FAB2(SCH_1):PAGE219
     2    GND @BASEBOARD_FAB2_LIB.BASEBOARD_FAB2(SCH_1):GND    I54 @BASEBOARD_FAB2_LIB.BASEBOARD_FAB2(SCH_1):PAGE219

C7A18 SC1U10V2KX-4-GP_SMD-BCG6-SC1U1A
     1 P5V_STBY @BASEBOARD_FAB2_LIB.BASEBOARD_FAB2(SCH_1):P5V_STBY   I151 @BASEBOARD_FAB2_LIB.BASEBOARD_FAB2(SCH_1):PAGE219
     2    GND @BASEBOARD_FAB2_LIB.BASEBOARD_FAB2(SCH_1):GND   I151 @BASEBOARD_FAB2_LIB.BASEBOARD_FAB2(SCH_1):PAGE219

C7A20 CAP_A_0402V-0.1UF,16V,10%,X7R,A
     1 VR_FET_SW_P12V_STBY_PVDDQ_DEF @BASEBOARD_FAB2_LIB.BASEBOARD_FAB2(SCH_1):VR_FET_SW_P12V_STBY_PVDDQ_DEF    I78 @BASEBOARD_FAB2_LIB.BASEBOARD_FAB2(SCH_1):PAGE219
     2    GND @BASEBOARD_FAB2_LIB.BASEBOARD_FAB2(SCH_1):GND    I78 @BASEBOARD_FAB2_LIB.BASEBOARD_FAB2(SCH_1):PAGE219

C7A21 CAP_0402-1.0UF,16V,10%,X6S,D97A
     1 VR_FET_SW_P12V_STBY_PVDDQ_DEF @BASEBOARD_FAB2_LIB.BASEBOARD_FAB2(SCH_1):VR_FET_SW_P12V_STBY_PVDDQ_DEF    I79 @BASEBOARD_FAB2_LIB.BASEBOARD_FAB2(SCH_1):PAGE219
     2    GND @BASEBOARD_FAB2_LIB.BASEBOARD_FAB2(SCH_1):GND    I79 @BASEBOARD_FAB2_LIB.BASEBOARD_FAB2(SCH_1):PAGE219

C7A22 CAP_0402-0.220UF,16V,10%,X7R,AA
     1 VR_PVDDQ_DEF_PH2_BOOT @BASEBOARD_FAB2_LIB.BASEBOARD_FAB2(SCH_1):VR_PVDDQ_DEF_PH2_BOOT    I75 @BASEBOARD_FAB2_LIB.BASEBOARD_FAB2(SCH_1):PAGE219
     2 VR_PVDDQ_DEF_PH2_PHASE @BASEBOARD_FAB2_LIB.BASEBOARD_FAB2(SCH_1):VR_PVDDQ_DEF_PH2_PHASE    I75 @BASEBOARD_FAB2_LIB.BASEBOARD_FAB2(SCH_1):PAGE219

C7A24 CAP_0402-1.0UF,16V,10%,X6S,D97A
     1 VR_PVDDQ_DEF_PH2_VCIN @BASEBOARD_FAB2_LIB.BASEBOARD_FAB2(SCH_1):VR_PVDDQ_DEF_PH2_VCIN    I77 @BASEBOARD_FAB2_LIB.BASEBOARD_FAB2(SCH_1):PAGE219
     2    GND @BASEBOARD_FAB2_LIB.BASEBOARD_FAB2(SCH_1):GND    I77 @BASEBOARD_FAB2_LIB.BASEBOARD_FAB2(SCH_1):PAGE219

C7A25 CAP_0402-0.22UF,16V,10%,X7R,A3A
     1 P5V_STBY @BASEBOARD_FAB2_LIB.BASEBOARD_FAB2(SCH_1):P5V_STBY    I72 @BASEBOARD_FAB2_LIB.BASEBOARD_FAB2(SCH_1):PAGE219
     2    GND @BASEBOARD_FAB2_LIB.BASEBOARD_FAB2(SCH_1):GND    I72 @BASEBOARD_FAB2_LIB.BASEBOARD_FAB2(SCH_1):PAGE219

C7A26 SC1U10V2KX-4-GP_SMD-BCG6-SC1U1A
     1 P5V_STBY @BASEBOARD_FAB2_LIB.BASEBOARD_FAB2(SCH_1):P5V_STBY   I152 @BASEBOARD_FAB2_LIB.BASEBOARD_FAB2(SCH_1):PAGE219
     2    GND @BASEBOARD_FAB2_LIB.BASEBOARD_FAB2(SCH_1):GND   I152 @BASEBOARD_FAB2_LIB.BASEBOARD_FAB2(SCH_1):PAGE219

C7A27 CAPP_SM-470UF,2V,20%,ALUM,6990A
     1 PVNN_PCH_STBY @BASEBOARD_FAB2_LIB.BASEBOARD_FAB2(SCH_1):PVNN_PCH_STBY    I75 @BASEBOARD_FAB2_LIB.BASEBOARD_FAB2(SCH_1):PAGE236
     2    GND @BASEBOARD_FAB2_LIB.BASEBOARD_FAB2(SCH_1):GND    I75 @BASEBOARD_FAB2_LIB.BASEBOARD_FAB2(SCH_1):PAGE236

C7A28 CAP_0402LF-220PF,50V,10%,X7R,AA
     1 VR_PVDDQ_DEF_AVSP @BASEBOARD_FAB2_LIB.BASEBOARD_FAB2(SCH_1):VR_PVDDQ_DEF_AVSP    I14 @BASEBOARD_FAB2_LIB.BASEBOARD_FAB2(SCH_1):PAGE218
     2 VSENSE_PVDDQ_DEF_N @BASEBOARD_FAB2_LIB.BASEBOARD_FAB2(SCH_1):VSENSE_PVDDQ_DEF_N    I14 @BASEBOARD_FAB2_LIB.BASEBOARD_FAB2(SCH_1):PAGE218

C7A29 CAP_0402LF-220PF,50V,10%,X7R,AA
     1 A_TSENSE_PVDDQ_DEF @BASEBOARD_FAB2_LIB.BASEBOARD_FAB2(SCH_1):A_TSENSE_PVDDQ_DEF    I16 @BASEBOARD_FAB2_LIB.BASEBOARD_FAB2(SCH_1):PAGE218
     2    GND @BASEBOARD_FAB2_LIB.BASEBOARD_FAB2(SCH_1):GND    I16 @BASEBOARD_FAB2_LIB.BASEBOARD_FAB2(SCH_1):PAGE218

C7A30 CAP_0805LF-22UF,4V,20%,X6S,C95A
     1 PVNN_PCH_STBY @BASEBOARD_FAB2_LIB.BASEBOARD_FAB2(SCH_1):PVNN_PCH_STBY     I9 @BASEBOARD_FAB2_LIB.BASEBOARD_FAB2(SCH_1):PAGE236
     2    GND @BASEBOARD_FAB2_LIB.BASEBOARD_FAB2(SCH_1):GND     I9 @BASEBOARD_FAB2_LIB.BASEBOARD_FAB2(SCH_1):PAGE236

C7A31 CAP_0805-47UF,4V,20%,X6S,C9533A
     1 PVNN_PCH_STBY @BASEBOARD_FAB2_LIB.BASEBOARD_FAB2(SCH_1):PVNN_PCH_STBY    I40 @BASEBOARD_FAB2_LIB.BASEBOARD_FAB2(SCH_1):PAGE132
     2    GND @BASEBOARD_FAB2_LIB.BASEBOARD_FAB2(SCH_1):GND    I40 @BASEBOARD_FAB2_LIB.BASEBOARD_FAB2(SCH_1):PAGE132

C7A32 CAP_0805-47UF,4V,20%,X6S,C9533A
     1 PVNN_PCH_STBY @BASEBOARD_FAB2_LIB.BASEBOARD_FAB2(SCH_1):PVNN_PCH_STBY    I38 @BASEBOARD_FAB2_LIB.BASEBOARD_FAB2(SCH_1):PAGE132
     2    GND @BASEBOARD_FAB2_LIB.BASEBOARD_FAB2(SCH_1):GND    I38 @BASEBOARD_FAB2_LIB.BASEBOARD_FAB2(SCH_1):PAGE132

C7A33 CAP_0805-47UF,4V,20%,X6S,C9533A
     1 PVNN_PCH_STBY @BASEBOARD_FAB2_LIB.BASEBOARD_FAB2(SCH_1):PVNN_PCH_STBY    I23 @BASEBOARD_FAB2_LIB.BASEBOARD_FAB2(SCH_1):PAGE132
     2    GND @BASEBOARD_FAB2_LIB.BASEBOARD_FAB2(SCH_1):GND    I23 @BASEBOARD_FAB2_LIB.BASEBOARD_FAB2(SCH_1):PAGE132

C7A34 CAP_0402LF-3300PF,50V,10%,EMPTA
     1 VR_PVPP_DEF_PHASE @BASEBOARD_FAB2_LIB.BASEBOARD_FAB2(SCH_1):VR_PVPP_DEF_PHASE   I220 @BASEBOARD_FAB2_LIB.BASEBOARD_FAB2(SCH_1):PAGE232
     2 VR_PVPP_DEF_SNUB @BASEBOARD_FAB2_LIB.BASEBOARD_FAB2(SCH_1):VR_PVPP_DEF_SNUB   I220 @BASEBOARD_FAB2_LIB.BASEBOARD_FAB2(SCH_1):PAGE232

C7A36 CAP_A_0603V-22.0UF,4V,20%,X6S,A
     1 PVNN_PCH_STBY @BASEBOARD_FAB2_LIB.BASEBOARD_FAB2(SCH_1):PVNN_PCH_STBY    I11 @BASEBOARD_FAB2_LIB.BASEBOARD_FAB2(SCH_1):PAGE132
     2    GND @BASEBOARD_FAB2_LIB.BASEBOARD_FAB2(SCH_1):GND    I11 @BASEBOARD_FAB2_LIB.BASEBOARD_FAB2(SCH_1):PAGE132

C7A37 CAP_A_0402V-1.0UF,6.3V,10%,X6SA
     1 VR_PVDDQ_DEF_VDD @BASEBOARD_FAB2_LIB.BASEBOARD_FAB2(SCH_1):VR_PVDDQ_DEF_VDD    I40 @BASEBOARD_FAB2_LIB.BASEBOARD_FAB2(SCH_1):PAGE218
     2    GND @BASEBOARD_FAB2_LIB.BASEBOARD_FAB2(SCH_1):GND    I40 @BASEBOARD_FAB2_LIB.BASEBOARD_FAB2(SCH_1):PAGE218

C7A38 CAP_A_0402V-0.1UF,16V,10%,X7R,A
     1 VR_PVDDQ_DEF_VDD @BASEBOARD_FAB2_LIB.BASEBOARD_FAB2(SCH_1):VR_PVDDQ_DEF_VDD    I38 @BASEBOARD_FAB2_LIB.BASEBOARD_FAB2(SCH_1):PAGE218
     2    GND @BASEBOARD_FAB2_LIB.BASEBOARD_FAB2(SCH_1):GND    I38 @BASEBOARD_FAB2_LIB.BASEBOARD_FAB2(SCH_1):PAGE218

C7A39 CAP_A_0402V-0.1UF,16V,10%,X7R,A
     1 VR_FET_SW_P12V_STBY_PVDDQ_DEF @BASEBOARD_FAB2_LIB.BASEBOARD_FAB2(SCH_1):VR_FET_SW_P12V_STBY_PVDDQ_DEF    I20 @BASEBOARD_FAB2_LIB.BASEBOARD_FAB2(SCH_1):PAGE236
     2    GND @BASEBOARD_FAB2_LIB.BASEBOARD_FAB2(SCH_1):GND    I20 @BASEBOARD_FAB2_LIB.BASEBOARD_FAB2(SCH_1):PAGE236

C7A40 CAP_A_0402V-0.1UF,16V,10%,X7R,A
     1 VR_FET_SW_P12V_STBY_PVDDQ_DEF @BASEBOARD_FAB2_LIB.BASEBOARD_FAB2(SCH_1):VR_FET_SW_P12V_STBY_PVDDQ_DEF    I35 @BASEBOARD_FAB2_LIB.BASEBOARD_FAB2(SCH_1):PAGE236
     2    GND @BASEBOARD_FAB2_LIB.BASEBOARD_FAB2(SCH_1):GND    I35 @BASEBOARD_FAB2_LIB.BASEBOARD_FAB2(SCH_1):PAGE236

C7A41 CAP_0402-0.22UF,16V,10%,X7R,A3A
     1 P5V_STBY @BASEBOARD_FAB2_LIB.BASEBOARD_FAB2(SCH_1):P5V_STBY    I39 @BASEBOARD_FAB2_LIB.BASEBOARD_FAB2(SCH_1):PAGE236
     2    GND @BASEBOARD_FAB2_LIB.BASEBOARD_FAB2(SCH_1):GND    I39 @BASEBOARD_FAB2_LIB.BASEBOARD_FAB2(SCH_1):PAGE236

C7A42 CAP_0805LF-22UF,4V,20%,X6S,C95A
     1 P1V05_PCH_STBY @BASEBOARD_FAB2_LIB.BASEBOARD_FAB2(SCH_1):P1V05_PCH_STBY    I46 @BASEBOARD_FAB2_LIB.BASEBOARD_FAB2(SCH_1):PAGE236
     2    GND @BASEBOARD_FAB2_LIB.BASEBOARD_FAB2(SCH_1):GND    I46 @BASEBOARD_FAB2_LIB.BASEBOARD_FAB2(SCH_1):PAGE236

C7A43 CAP_0402-0.220UF,16V,10%,X7R,AA
     1 VR_PVNN_PCH_PH1_BOOT @BASEBOARD_FAB2_LIB.BASEBOARD_FAB2(SCH_1):VR_PVNN_PCH_PH1_BOOT    I21 @BASEBOARD_FAB2_LIB.BASEBOARD_FAB2(SCH_1):PAGE236
     2 VR_PVNN_PCH_PH1_PHASE @BASEBOARD_FAB2_LIB.BASEBOARD_FAB2(SCH_1):VR_PVNN_PCH_PH1_PHASE    I21 @BASEBOARD_FAB2_LIB.BASEBOARD_FAB2(SCH_1):PAGE236

C7A44 CAP_0402-0.220UF,16V,10%,X7R,AA
     1 VR_P1V05_PCH_STBY_PH1_BOOT @BASEBOARD_FAB2_LIB.BASEBOARD_FAB2(SCH_1):VR_P1V05_PCH_STBY_PH1_BOOT    I34 @BASEBOARD_FAB2_LIB.BASEBOARD_FAB2(SCH_1):PAGE236
     2 VR_P1V05_PCH_STBY_PH1_PHASE @BASEBOARD_FAB2_LIB.BASEBOARD_FAB2(SCH_1):VR_P1V05_PCH_STBY_PH1_PHASE    I34 @BASEBOARD_FAB2_LIB.BASEBOARD_FAB2(SCH_1):PAGE236

C7B1 CAP_A_0402V-1.0UF,6.3V,10%,X6SA
     1 VR_PVDDQ_DEF_VD12 @BASEBOARD_FAB2_LIB.BASEBOARD_FAB2(SCH_1):VR_PVDDQ_DEF_VD12    I30 @BASEBOARD_FAB2_LIB.BASEBOARD_FAB2(SCH_1):PAGE218
     2    GND @BASEBOARD_FAB2_LIB.BASEBOARD_FAB2(SCH_1):GND    I30 @BASEBOARD_FAB2_LIB.BASEBOARD_FAB2(SCH_1):PAGE218

C7B2 CAP_A_0402V-0.1UF,16V,10%,X7R,A
     1 VR_PVDDQ_DEF_VD12 @BASEBOARD_FAB2_LIB.BASEBOARD_FAB2(SCH_1):VR_PVDDQ_DEF_VD12    I28 @BASEBOARD_FAB2_LIB.BASEBOARD_FAB2(SCH_1):PAGE218
     2    GND @BASEBOARD_FAB2_LIB.BASEBOARD_FAB2(SCH_1):GND    I28 @BASEBOARD_FAB2_LIB.BASEBOARD_FAB2(SCH_1):PAGE218

C7B3 CAP_0402LF-1000PF,50V,10%,X7R,A
     1 PWRGD_PVDDQ_DEF_R @BASEBOARD_FAB2_LIB.BASEBOARD_FAB2(SCH_1):PWRGD_PVDDQ_DEF_R    I41 @BASEBOARD_FAB2_LIB.BASEBOARD_FAB2(SCH_1):PAGE218
     2    GND @BASEBOARD_FAB2_LIB.BASEBOARD_FAB2(SCH_1):GND    I41 @BASEBOARD_FAB2_LIB.BASEBOARD_FAB2(SCH_1):PAGE218

C7B4 CAP_0805-47UF,4V,20%,X6S,C9533A
     1 PVNN_PCH_STBY @BASEBOARD_FAB2_LIB.BASEBOARD_FAB2(SCH_1):PVNN_PCH_STBY    I24 @BASEBOARD_FAB2_LIB.BASEBOARD_FAB2(SCH_1):PAGE132
     2    GND @BASEBOARD_FAB2_LIB.BASEBOARD_FAB2(SCH_1):GND    I24 @BASEBOARD_FAB2_LIB.BASEBOARD_FAB2(SCH_1):PAGE132

C7B5 CAP_0805-10UF,16V,10%,X6S,C953A
     1 VR_FET_SW_P12V_STBY_PVPP_DEF @BASEBOARD_FAB2_LIB.BASEBOARD_FAB2(SCH_1):VR_FET_SW_P12V_STBY_PVPP_DEF   I262 @BASEBOARD_FAB2_LIB.BASEBOARD_FAB2(SCH_1):PAGE232
     2    GND @BASEBOARD_FAB2_LIB.BASEBOARD_FAB2(SCH_1):GND   I262 @BASEBOARD_FAB2_LIB.BASEBOARD_FAB2(SCH_1):PAGE232

C7B6 CAP_A_0402V-0.1UF,16V,10%,X7R,A
     1 VR_FET_SW_P12V_STBY_PVPP_DEF @BASEBOARD_FAB2_LIB.BASEBOARD_FAB2(SCH_1):VR_FET_SW_P12V_STBY_PVPP_DEF   I252 @BASEBOARD_FAB2_LIB.BASEBOARD_FAB2(SCH_1):PAGE232
     2    GND @BASEBOARD_FAB2_LIB.BASEBOARD_FAB2(SCH_1):GND   I252 @BASEBOARD_FAB2_LIB.BASEBOARD_FAB2(SCH_1):PAGE232

C7B7 CAP_0805-47UF,4V,20%,X6S,C9533A
     1 PVPP_DEF @BASEBOARD_FAB2_LIB.BASEBOARD_FAB2(SCH_1):PVPP_DEF   I238 @BASEBOARD_FAB2_LIB.BASEBOARD_FAB2(SCH_1):PAGE232
     2    GND @BASEBOARD_FAB2_LIB.BASEBOARD_FAB2(SCH_1):GND   I238 @BASEBOARD_FAB2_LIB.BASEBOARD_FAB2(SCH_1):PAGE232

C7B8 SC22U16V5MX-4-GP_SMD-BCG5-SC22A
     1 VR_FET_SW_P12V_STBY_PVPP_DEF @BASEBOARD_FAB2_LIB.BASEBOARD_FAB2(SCH_1):VR_FET_SW_P12V_STBY_PVPP_DEF   I309 @BASEBOARD_FAB2_LIB.BASEBOARD_FAB2(SCH_1):PAGE232
     2    GND @BASEBOARD_FAB2_LIB.BASEBOARD_FAB2(SCH_1):GND   I309 @BASEBOARD_FAB2_LIB.BASEBOARD_FAB2(SCH_1):PAGE232

C7B9 CAP_0402LF-1000PF,50V,10%,EMPTA
     1 FM_PVPP_CPU0_EN @BASEBOARD_FAB2_LIB.BASEBOARD_FAB2(SCH_1):FM_PVPP_CPU0_EN   I185 @BASEBOARD_FAB2_LIB.BASEBOARD_FAB2(SCH_1):PAGE232
     2 AGND_PVPP_DEF @BASEBOARD_FAB2_LIB.BASEBOARD_FAB2(SCH_1):AGND_PVPP_DEF   I185 @BASEBOARD_FAB2_LIB.BASEBOARD_FAB2(SCH_1):PAGE232

C7B10 CAP_0402LF-100.0PF,50V,5%,COG,A
     1 VR_FB_PVPP_DEF @BASEBOARD_FAB2_LIB.BASEBOARD_FAB2(SCH_1):VR_FB_PVPP_DEF   I301 @BASEBOARD_FAB2_LIB.BASEBOARD_FAB2(SCH_1):PAGE232
     2 VR_COMP_PVPP_DEF_3 @BASEBOARD_FAB2_LIB.BASEBOARD_FAB2(SCH_1):VR_COMP_PVPP_DEF_3   I301 @BASEBOARD_FAB2_LIB.BASEBOARD_FAB2(SCH_1):PAGE232

C7B11 CAP_0402-0.027UF,16V,10%,X7R,AA
     1 VR_PVPP_DEF_SS @BASEBOARD_FAB2_LIB.BASEBOARD_FAB2(SCH_1):VR_PVPP_DEF_SS   I197 @BASEBOARD_FAB2_LIB.BASEBOARD_FAB2(SCH_1):PAGE232
     2 AGND_PVPP_DEF @BASEBOARD_FAB2_LIB.BASEBOARD_FAB2(SCH_1):AGND_PVPP_DEF   I197 @BASEBOARD_FAB2_LIB.BASEBOARD_FAB2(SCH_1):PAGE232

C7B12 CAP_0402LF-1000PF,50V,10%,X7R,A
     1 PWRGD_PVPP_DEF_R @BASEBOARD_FAB2_LIB.BASEBOARD_FAB2(SCH_1):PWRGD_PVPP_DEF_R   I209 @BASEBOARD_FAB2_LIB.BASEBOARD_FAB2(SCH_1):PAGE232
     2    GND @BASEBOARD_FAB2_LIB.BASEBOARD_FAB2(SCH_1):GND   I209 @BASEBOARD_FAB2_LIB.BASEBOARD_FAB2(SCH_1):PAGE232

C7B13 CAP_0402LF-2200PF,50V,10%,X7R,A
     1 VR_COMP_PVPP_DEF @BASEBOARD_FAB2_LIB.BASEBOARD_FAB2(SCH_1):VR_COMP_PVPP_DEF   I302 @BASEBOARD_FAB2_LIB.BASEBOARD_FAB2(SCH_1):PAGE232
     2 VR_FB_PVPP_DEF @BASEBOARD_FAB2_LIB.BASEBOARD_FAB2(SCH_1):VR_FB_PVPP_DEF   I302 @BASEBOARD_FAB2_LIB.BASEBOARD_FAB2(SCH_1):PAGE232

C7B14 CAP_0402LF-2200PF,50V,10%,X7R,A
     1 VR_COMP_RC_PVPP_DEF @BASEBOARD_FAB2_LIB.BASEBOARD_FAB2(SCH_1):VR_COMP_RC_PVPP_DEF   I306 @BASEBOARD_FAB2_LIB.BASEBOARD_FAB2(SCH_1):PAGE232
     2 VR_COMP_PVPP_DEF_3 @BASEBOARD_FAB2_LIB.BASEBOARD_FAB2(SCH_1):VR_COMP_PVPP_DEF_3   I306 @BASEBOARD_FAB2_LIB.BASEBOARD_FAB2(SCH_1):PAGE232

C7B15 CAP_A_0603V-22.0UF,4V,20%,X6S,A
     1 P1V05_PCH_STBY @BASEBOARD_FAB2_LIB.BASEBOARD_FAB2(SCH_1):P1V05_PCH_STBY     I1 @BASEBOARD_FAB2_LIB.BASEBOARD_FAB2(SCH_1):PAGE131
     2    GND @BASEBOARD_FAB2_LIB.BASEBOARD_FAB2(SCH_1):GND     I1 @BASEBOARD_FAB2_LIB.BASEBOARD_FAB2(SCH_1):PAGE131

C7B16 CAP_A_0603V-22.0UF,4V,20%,X6S,A
     1 P1V05_PCH_STBY @BASEBOARD_FAB2_LIB.BASEBOARD_FAB2(SCH_1):P1V05_PCH_STBY     I3 @BASEBOARD_FAB2_LIB.BASEBOARD_FAB2(SCH_1):PAGE131
     2    GND @BASEBOARD_FAB2_LIB.BASEBOARD_FAB2(SCH_1):GND     I3 @BASEBOARD_FAB2_LIB.BASEBOARD_FAB2(SCH_1):PAGE131

C7B17 CAP_A_0603V-22.0UF,4V,20%,X6S,A
     1 P1V05_PCH_STBY @BASEBOARD_FAB2_LIB.BASEBOARD_FAB2(SCH_1):P1V05_PCH_STBY    I18 @BASEBOARD_FAB2_LIB.BASEBOARD_FAB2(SCH_1):PAGE131
     2    GND @BASEBOARD_FAB2_LIB.BASEBOARD_FAB2(SCH_1):GND    I18 @BASEBOARD_FAB2_LIB.BASEBOARD_FAB2(SCH_1):PAGE131

C7B18 CAP_A_0603V-22.0UF,4V,20%,X6S,A
     1 P1V05_PCH_STBY @BASEBOARD_FAB2_LIB.BASEBOARD_FAB2(SCH_1):P1V05_PCH_STBY    I12 @BASEBOARD_FAB2_LIB.BASEBOARD_FAB2(SCH_1):PAGE131
     2    GND @BASEBOARD_FAB2_LIB.BASEBOARD_FAB2(SCH_1):GND    I12 @BASEBOARD_FAB2_LIB.BASEBOARD_FAB2(SCH_1):PAGE131

C7B19 CAP_A_0603V-22.0UF,4V,20%,X6S,A
     1 P1V05_PCH_STBY @BASEBOARD_FAB2_LIB.BASEBOARD_FAB2(SCH_1):P1V05_PCH_STBY     I2 @BASEBOARD_FAB2_LIB.BASEBOARD_FAB2(SCH_1):PAGE131
     2    GND @BASEBOARD_FAB2_LIB.BASEBOARD_FAB2(SCH_1):GND     I2 @BASEBOARD_FAB2_LIB.BASEBOARD_FAB2(SCH_1):PAGE131

C7B20 CAP_A_0603V-22.0UF,4V,20%,X6S,A
     1 P1V05_PCH_STBY @BASEBOARD_FAB2_LIB.BASEBOARD_FAB2(SCH_1):P1V05_PCH_STBY     I6 @BASEBOARD_FAB2_LIB.BASEBOARD_FAB2(SCH_1):PAGE131
     2    GND @BASEBOARD_FAB2_LIB.BASEBOARD_FAB2(SCH_1):GND     I6 @BASEBOARD_FAB2_LIB.BASEBOARD_FAB2(SCH_1):PAGE131

C7B21 CAP_A_0603V-22.0UF,4V,20%,X6S,A
     1 P1V05_PCH_STBY @BASEBOARD_FAB2_LIB.BASEBOARD_FAB2(SCH_1):P1V05_PCH_STBY     I4 @BASEBOARD_FAB2_LIB.BASEBOARD_FAB2(SCH_1):PAGE131
     2    GND @BASEBOARD_FAB2_LIB.BASEBOARD_FAB2(SCH_1):GND     I4 @BASEBOARD_FAB2_LIB.BASEBOARD_FAB2(SCH_1):PAGE131

C7B22 CAP_A_0603V-22.0UF,4V,20%,X6S,A
     1 P1V05_PCH_STBY @BASEBOARD_FAB2_LIB.BASEBOARD_FAB2(SCH_1):P1V05_PCH_STBY    I10 @BASEBOARD_FAB2_LIB.BASEBOARD_FAB2(SCH_1):PAGE131
     2    GND @BASEBOARD_FAB2_LIB.BASEBOARD_FAB2(SCH_1):GND    I10 @BASEBOARD_FAB2_LIB.BASEBOARD_FAB2(SCH_1):PAGE131

C7B23 CAP_A_0603V-22.0UF,4V,20%,X6S,A
     1 P1V05_PCH_STBY @BASEBOARD_FAB2_LIB.BASEBOARD_FAB2(SCH_1):P1V05_PCH_STBY     I7 @BASEBOARD_FAB2_LIB.BASEBOARD_FAB2(SCH_1):PAGE131
     2    GND @BASEBOARD_FAB2_LIB.BASEBOARD_FAB2(SCH_1):GND     I7 @BASEBOARD_FAB2_LIB.BASEBOARD_FAB2(SCH_1):PAGE131

C7B24 CAP_A_0603V-22.0UF,4V,20%,X6S,A
     1 P1V05_PCH_STBY @BASEBOARD_FAB2_LIB.BASEBOARD_FAB2(SCH_1):P1V05_PCH_STBY    I11 @BASEBOARD_FAB2_LIB.BASEBOARD_FAB2(SCH_1):PAGE131
     2    GND @BASEBOARD_FAB2_LIB.BASEBOARD_FAB2(SCH_1):GND    I11 @BASEBOARD_FAB2_LIB.BASEBOARD_FAB2(SCH_1):PAGE131

C7B25 CAP_0402-0.22UF,16V,10%,X7R,A3A
     1 DMI_CPU0_PCH_TX_DP<3> @BASEBOARD_FAB2_LIB.BASEBOARD_FAB2(SCH_1):DMI_CPU0_PCH_TX_DP(3)    I35 @BASEBOARD_FAB2_LIB.BASEBOARD_FAB2(SCH_1):PAGE129
     2 DMI_CPU0_PCH_TX_C_DP<3> @BASEBOARD_FAB2_LIB.BASEBOARD_FAB2(SCH_1):DMI_CPU0_PCH_TX_C_DP(3)    I35 @BASEBOARD_FAB2_LIB.BASEBOARD_FAB2(SCH_1):PAGE129

C7B26 CAP_0402-0.22UF,16V,10%,X7R,A3A
     1 DMI_CPU0_PCH_TX_DN<3> @BASEBOARD_FAB2_LIB.BASEBOARD_FAB2(SCH_1):DMI_CPU0_PCH_TX_DN(3)    I79 @BASEBOARD_FAB2_LIB.BASEBOARD_FAB2(SCH_1):PAGE129
     2 DMI_CPU0_PCH_TX_C_DN<3> @BASEBOARD_FAB2_LIB.BASEBOARD_FAB2(SCH_1):DMI_CPU0_PCH_TX_C_DN(3)    I79 @BASEBOARD_FAB2_LIB.BASEBOARD_FAB2(SCH_1):PAGE129

C7B27 CAP_0402-0.22UF,16V,10%,X7R,A3A
     1 DMI_CPU0_PCH_TX_DP<2> @BASEBOARD_FAB2_LIB.BASEBOARD_FAB2(SCH_1):DMI_CPU0_PCH_TX_DP(2)    I69 @BASEBOARD_FAB2_LIB.BASEBOARD_FAB2(SCH_1):PAGE129
     2 DMI_CPU0_PCH_TX_C_DP<2> @BASEBOARD_FAB2_LIB.BASEBOARD_FAB2(SCH_1):DMI_CPU0_PCH_TX_C_DP(2)    I69 @BASEBOARD_FAB2_LIB.BASEBOARD_FAB2(SCH_1):PAGE129

C7B28 CAP_0402-0.22UF,16V,10%,X7R,A3A
     1 DMI_CPU0_PCH_TX_DP<1> @BASEBOARD_FAB2_LIB.BASEBOARD_FAB2(SCH_1):DMI_CPU0_PCH_TX_DP(1)    I70 @BASEBOARD_FAB2_LIB.BASEBOARD_FAB2(SCH_1):PAGE129
     2 DMI_CPU0_PCH_TX_C_DP<1> @BASEBOARD_FAB2_LIB.BASEBOARD_FAB2(SCH_1):DMI_CPU0_PCH_TX_C_DP(1)    I70 @BASEBOARD_FAB2_LIB.BASEBOARD_FAB2(SCH_1):PAGE129

C7B29 CAP_0402-0.22UF,16V,10%,X7R,A3A
     1 DMI_CPU0_PCH_TX_DN<2> @BASEBOARD_FAB2_LIB.BASEBOARD_FAB2(SCH_1):DMI_CPU0_PCH_TX_DN(2)    I78 @BASEBOARD_FAB2_LIB.BASEBOARD_FAB2(SCH_1):PAGE129
     2 DMI_CPU0_PCH_TX_C_DN<2> @BASEBOARD_FAB2_LIB.BASEBOARD_FAB2(SCH_1):DMI_CPU0_PCH_TX_C_DN(2)    I78 @BASEBOARD_FAB2_LIB.BASEBOARD_FAB2(SCH_1):PAGE129

C7B30 CAP_0603LF-0.1UF,25V,10%,X7R,6A
     1 VR_PVPP_DEF_PHASE @BASEBOARD_FAB2_LIB.BASEBOARD_FAB2(SCH_1):VR_PVPP_DEF_PHASE   I241 @BASEBOARD_FAB2_LIB.BASEBOARD_FAB2(SCH_1):PAGE232
     2 VR_PVPP_DEF_BOOT_R @BASEBOARD_FAB2_LIB.BASEBOARD_FAB2(SCH_1):VR_PVPP_DEF_BOOT_R   I241 @BASEBOARD_FAB2_LIB.BASEBOARD_FAB2(SCH_1):PAGE232

C7C1 CAP_0402-0.22UF,16V,10%,X7R,A3A
     1 DMI_CPU0_PCH_TX_DN<1> @BASEBOARD_FAB2_LIB.BASEBOARD_FAB2(SCH_1):DMI_CPU0_PCH_TX_DN(1)    I77 @BASEBOARD_FAB2_LIB.BASEBOARD_FAB2(SCH_1):PAGE129
     2 DMI_CPU0_PCH_TX_C_DN<1> @BASEBOARD_FAB2_LIB.BASEBOARD_FAB2(SCH_1):DMI_CPU0_PCH_TX_C_DN(1)    I77 @BASEBOARD_FAB2_LIB.BASEBOARD_FAB2(SCH_1):PAGE129

C7C2 CAP_0402-0.22UF,16V,10%,X7R,A3A
     1 DMI_CPU0_PCH_TX_DP<0> @BASEBOARD_FAB2_LIB.BASEBOARD_FAB2(SCH_1):DMI_CPU0_PCH_TX_DP(0)    I71 @BASEBOARD_FAB2_LIB.BASEBOARD_FAB2(SCH_1):PAGE129
     2 DMI_CPU0_PCH_TX_C_DP<0> @BASEBOARD_FAB2_LIB.BASEBOARD_FAB2(SCH_1):DMI_CPU0_PCH_TX_C_DP(0)    I71 @BASEBOARD_FAB2_LIB.BASEBOARD_FAB2(SCH_1):PAGE129

C7C3 CAP_0402-0.22UF,16V,10%,X7R,A3A
     1 DMI_CPU0_PCH_TX_DN<0> @BASEBOARD_FAB2_LIB.BASEBOARD_FAB2(SCH_1):DMI_CPU0_PCH_TX_DN(0)    I76 @BASEBOARD_FAB2_LIB.BASEBOARD_FAB2(SCH_1):PAGE129
     2 DMI_CPU0_PCH_TX_C_DN<0> @BASEBOARD_FAB2_LIB.BASEBOARD_FAB2(SCH_1):DMI_CPU0_PCH_TX_C_DN(0)    I76 @BASEBOARD_FAB2_LIB.BASEBOARD_FAB2(SCH_1):PAGE129

C7C4 CAP_0402LF-15.0PF,50V,5%,COG,AA
     1 XTAL_PCH_48M_IN @BASEBOARD_FAB2_LIB.BASEBOARD_FAB2(SCH_1):XTAL_PCH_48M_IN    I50 @BASEBOARD_FAB2_LIB.BASEBOARD_FAB2(SCH_1):PAGE114
     2    GND @BASEBOARD_FAB2_LIB.BASEBOARD_FAB2(SCH_1):GND    I50 @BASEBOARD_FAB2_LIB.BASEBOARD_FAB2(SCH_1):PAGE114

C7C5 CAP_0402LF-15.0PF,50V,5%,COG,AA
     1 XTAL_PCH_48M_OUT @BASEBOARD_FAB2_LIB.BASEBOARD_FAB2(SCH_1):XTAL_PCH_48M_OUT    I47 @BASEBOARD_FAB2_LIB.BASEBOARD_FAB2(SCH_1):PAGE114
     2    GND @BASEBOARD_FAB2_LIB.BASEBOARD_FAB2(SCH_1):GND    I47 @BASEBOARD_FAB2_LIB.BASEBOARD_FAB2(SCH_1):PAGE114

C7C6 CAP_A_0603V-22.0UF,4V,20%,X6S,A
     1 PVCCIO_CPU0 @BASEBOARD_FAB2_LIB.BASEBOARD_FAB2(SCH_1):PVCCIO_CPU0    I23 @BASEBOARD_FAB2_LIB.BASEBOARD_FAB2(SCH_1):PAGE212
     2    GND @BASEBOARD_FAB2_LIB.BASEBOARD_FAB2(SCH_1):GND    I23 @BASEBOARD_FAB2_LIB.BASEBOARD_FAB2(SCH_1):PAGE212

C7C7 SC22U16V5MX-4-GP_SMD-BCG5-SC22A
     1 VR_FET_SW_P12V_STBY_PVCCIO_CPU0 @BASEBOARD_FAB2_LIB.BASEBOARD_FAB2(SCH_1):VR_FET_SW_P12V_STBY_PVCCIO_CPU0   I138 @BASEBOARD_FAB2_LIB.BASEBOARD_FAB2(SCH_1):PAGE212
     2    GND @BASEBOARD_FAB2_LIB.BASEBOARD_FAB2(SCH_1):GND   I138 @BASEBOARD_FAB2_LIB.BASEBOARD_FAB2(SCH_1):PAGE212

C7C8 SC22U16V5MX-4-GP_SMD-BCG5-SC22A
     1 VR_FET_SW_P12V_STBY_PVCCIO_CPU0 @BASEBOARD_FAB2_LIB.BASEBOARD_FAB2(SCH_1):VR_FET_SW_P12V_STBY_PVCCIO_CPU0   I130 @BASEBOARD_FAB2_LIB.BASEBOARD_FAB2(SCH_1):PAGE212
     2    GND @BASEBOARD_FAB2_LIB.BASEBOARD_FAB2(SCH_1):GND   I130 @BASEBOARD_FAB2_LIB.BASEBOARD_FAB2(SCH_1):PAGE212

C7C9 CAP_A_0603V-22.0UF,4V,20%,X6S,A
     1 PVNN_PCH_STBY @BASEBOARD_FAB2_LIB.BASEBOARD_FAB2(SCH_1):PVNN_PCH_STBY     I7 @BASEBOARD_FAB2_LIB.BASEBOARD_FAB2(SCH_1):PAGE132
     2    GND @BASEBOARD_FAB2_LIB.BASEBOARD_FAB2(SCH_1):GND     I7 @BASEBOARD_FAB2_LIB.BASEBOARD_FAB2(SCH_1):PAGE132

C7C10 CAP_A_0603V-22.0UF,4V,20%,X6S,A
     1 PVCCIO_CPU0 @BASEBOARD_FAB2_LIB.BASEBOARD_FAB2(SCH_1):PVCCIO_CPU0    I77 @BASEBOARD_FAB2_LIB.BASEBOARD_FAB2(SCH_1):PAGE212
     2    GND @BASEBOARD_FAB2_LIB.BASEBOARD_FAB2(SCH_1):GND    I77 @BASEBOARD_FAB2_LIB.BASEBOARD_FAB2(SCH_1):PAGE212

C7C11 CAP_A_0402V-0.1UF,16V,10%,X7R,A
     1 VR_FET_SW_P12V_STBY_PVCCIO_CPU0 @BASEBOARD_FAB2_LIB.BASEBOARD_FAB2(SCH_1):VR_FET_SW_P12V_STBY_PVCCIO_CPU0    I38 @BASEBOARD_FAB2_LIB.BASEBOARD_FAB2(SCH_1):PAGE212
     2    GND @BASEBOARD_FAB2_LIB.BASEBOARD_FAB2(SCH_1):GND    I38 @BASEBOARD_FAB2_LIB.BASEBOARD_FAB2(SCH_1):PAGE212

C7C12 CAP_0402-1.0UF,16V,10%,X6S,D97A
     1 VR_FET_SW_P12V_STBY_PVCCIO_CPU0 @BASEBOARD_FAB2_LIB.BASEBOARD_FAB2(SCH_1):VR_FET_SW_P12V_STBY_PVCCIO_CPU0    I39 @BASEBOARD_FAB2_LIB.BASEBOARD_FAB2(SCH_1):PAGE212
     2    GND @BASEBOARD_FAB2_LIB.BASEBOARD_FAB2(SCH_1):GND    I39 @BASEBOARD_FAB2_LIB.BASEBOARD_FAB2(SCH_1):PAGE212

C7C13 CAP_0402LF-15.0PF,50V,5%,COG,AA
     1 XTAL_33K_RTC1 @BASEBOARD_FAB2_LIB.BASEBOARD_FAB2(SCH_1):XTAL_33K_RTC1   I195 @BASEBOARD_FAB2_LIB.BASEBOARD_FAB2(SCH_1):PAGE114
     2    GND @BASEBOARD_FAB2_LIB.BASEBOARD_FAB2(SCH_1):GND   I195 @BASEBOARD_FAB2_LIB.BASEBOARD_FAB2(SCH_1):PAGE114

C7C14 CAP_0402-0.220UF,16V,10%,X7R,AA
     1 VR_PVCCIO_CPU0_PH1_BOOT @BASEBOARD_FAB2_LIB.BASEBOARD_FAB2(SCH_1):VR_PVCCIO_CPU0_PH1_BOOT    I37 @BASEBOARD_FAB2_LIB.BASEBOARD_FAB2(SCH_1):PAGE212
     2 VR_PVCCIO_CPU0_PH1_PHASE @BASEBOARD_FAB2_LIB.BASEBOARD_FAB2(SCH_1):VR_PVCCIO_CPU0_PH1_PHASE    I37 @BASEBOARD_FAB2_LIB.BASEBOARD_FAB2(SCH_1):PAGE212

C7C15 CAP_0402LF-15.0PF,50V,5%,COG,AA
     1 XTAL_33K_RTC2 @BASEBOARD_FAB2_LIB.BASEBOARD_FAB2(SCH_1):XTAL_33K_RTC2   I196 @BASEBOARD_FAB2_LIB.BASEBOARD_FAB2(SCH_1):PAGE114
     2    GND @BASEBOARD_FAB2_LIB.BASEBOARD_FAB2(SCH_1):GND   I196 @BASEBOARD_FAB2_LIB.BASEBOARD_FAB2(SCH_1):PAGE114

C7C17 CAP_0402-1.0UF,16V,10%,X6S,D97A
     1 VR_PVCCIO_CPU0_PH1_VCIN @BASEBOARD_FAB2_LIB.BASEBOARD_FAB2(SCH_1):VR_PVCCIO_CPU0_PH1_VCIN    I36 @BASEBOARD_FAB2_LIB.BASEBOARD_FAB2(SCH_1):PAGE212
     2    GND @BASEBOARD_FAB2_LIB.BASEBOARD_FAB2(SCH_1):GND    I36 @BASEBOARD_FAB2_LIB.BASEBOARD_FAB2(SCH_1):PAGE212

C7C18 CAP_0402-0.22UF,16V,10%,X7R,A3A
     1 P5V_STBY @BASEBOARD_FAB2_LIB.BASEBOARD_FAB2(SCH_1):P5V_STBY    I33 @BASEBOARD_FAB2_LIB.BASEBOARD_FAB2(SCH_1):PAGE212
     2    GND @BASEBOARD_FAB2_LIB.BASEBOARD_FAB2(SCH_1):GND    I33 @BASEBOARD_FAB2_LIB.BASEBOARD_FAB2(SCH_1):PAGE212

C7C19 CAP_A_0402V-1.0UF,6.3V,10%,X6SA
     1 RST_RTCRST_N @BASEBOARD_FAB2_LIB.BASEBOARD_FAB2(SCH_1):RST_RTCRST_N    I14 @BASEBOARD_FAB2_LIB.BASEBOARD_FAB2(SCH_1):PAGE137
     2    GND @BASEBOARD_FAB2_LIB.BASEBOARD_FAB2(SCH_1):GND    I14 @BASEBOARD_FAB2_LIB.BASEBOARD_FAB2(SCH_1):PAGE137

C7C20 SC1U10V2KX-4-GP_SMD-BCG6-SC1U1A
     1 P5V_STBY @BASEBOARD_FAB2_LIB.BASEBOARD_FAB2(SCH_1):P5V_STBY   I143 @BASEBOARD_FAB2_LIB.BASEBOARD_FAB2(SCH_1):PAGE212
     2    GND @BASEBOARD_FAB2_LIB.BASEBOARD_FAB2(SCH_1):GND   I143 @BASEBOARD_FAB2_LIB.BASEBOARD_FAB2(SCH_1):PAGE212

C7D1 CAP_A_0402V-0.1UF,16V,10%,X7R,A
     1 P3V3_STBY @BASEBOARD_FAB2_LIB.BASEBOARD_FAB2(SCH_1):P3V3_STBY   I136 @BASEBOARD_FAB2_LIB.BASEBOARD_FAB2(SCH_1):PAGE118
     2    GND @BASEBOARD_FAB2_LIB.BASEBOARD_FAB2(SCH_1):GND   I136 @BASEBOARD_FAB2_LIB.BASEBOARD_FAB2(SCH_1):PAGE118

C7D2 CAP_0603-10UF,6.3V,20%,X6S,E15A
     1 P3V3_STBY @BASEBOARD_FAB2_LIB.BASEBOARD_FAB2(SCH_1):P3V3_STBY     I2 @BASEBOARD_FAB2_LIB.BASEBOARD_FAB2(SCH_1):PAGE130
     2    GND @BASEBOARD_FAB2_LIB.BASEBOARD_FAB2(SCH_1):GND     I2 @BASEBOARD_FAB2_LIB.BASEBOARD_FAB2(SCH_1):PAGE130

C7D3 CAP_A_0603V-22.0UF,4V,20%,X6S,A
     1 P1V8_PCH_STBY @BASEBOARD_FAB2_LIB.BASEBOARD_FAB2(SCH_1):P1V8_PCH_STBY    I38 @BASEBOARD_FAB2_LIB.BASEBOARD_FAB2(SCH_1):PAGE130
     2    GND @BASEBOARD_FAB2_LIB.BASEBOARD_FAB2(SCH_1):GND    I38 @BASEBOARD_FAB2_LIB.BASEBOARD_FAB2(SCH_1):PAGE130

C7D4 CAP_0402-1.0UF,16V,10%,X6S,D97A
     1   P3V3 @BASEBOARD_FAB2_LIB.BASEBOARD_FAB2(SCH_1):P3V3    I79 @BASEBOARD_FAB2_LIB.BASEBOARD_FAB2(SCH_1):PAGE92
     2    GND @BASEBOARD_FAB2_LIB.BASEBOARD_FAB2(SCH_1):GND    I79 @BASEBOARD_FAB2_LIB.BASEBOARD_FAB2(SCH_1):PAGE92

C7D5 CAP_A_0402V-0.1UF,16V,10%,X7R,A
     1 P0V7_GTL2104_VREF_0 @BASEBOARD_FAB2_LIB.BASEBOARD_FAB2(SCH_1):P0V7_GTL2104_VREF_0    I52 @BASEBOARD_FAB2_LIB.BASEBOARD_FAB2(SCH_1):PAGE92
     2    GND @BASEBOARD_FAB2_LIB.BASEBOARD_FAB2(SCH_1):GND    I52 @BASEBOARD_FAB2_LIB.BASEBOARD_FAB2(SCH_1):PAGE92

C7E1 CAP_A_0402V-0.1UF,16V,10%,X7R,A
     1 PVCCIO_CPU0 @BASEBOARD_FAB2_LIB.BASEBOARD_FAB2(SCH_1):PVCCIO_CPU0    I23 @BASEBOARD_FAB2_LIB.BASEBOARD_FAB2(SCH_1):PAGE99
     2    GND @BASEBOARD_FAB2_LIB.BASEBOARD_FAB2(SCH_1):GND    I23 @BASEBOARD_FAB2_LIB.BASEBOARD_FAB2(SCH_1):PAGE99

C7E2 CAP_A_0402V-0.1UF,16V,10%,X7R,A
     1 PVPP_DEF @BASEBOARD_FAB2_LIB.BASEBOARD_FAB2(SCH_1):PVPP_DEF    I32 @BASEBOARD_FAB2_LIB.BASEBOARD_FAB2(SCH_1):PAGE99
     2    GND @BASEBOARD_FAB2_LIB.BASEBOARD_FAB2(SCH_1):GND    I32 @BASEBOARD_FAB2_LIB.BASEBOARD_FAB2(SCH_1):PAGE99

C7E3 CAP_A_0402V-0.1UF,16V,10%,X7R,A
     1 P3V3_STBY @BASEBOARD_FAB2_LIB.BASEBOARD_FAB2(SCH_1):P3V3_STBY    I92 @BASEBOARD_FAB2_LIB.BASEBOARD_FAB2(SCH_1):PAGE95
     2    GND @BASEBOARD_FAB2_LIB.BASEBOARD_FAB2(SCH_1):GND    I92 @BASEBOARD_FAB2_LIB.BASEBOARD_FAB2(SCH_1):PAGE95

C7E4 CAP_A_0402V-0.1UF,16V,10%,X7R,A
     1 P3V3_STBY @BASEBOARD_FAB2_LIB.BASEBOARD_FAB2(SCH_1):P3V3_STBY   I115 @BASEBOARD_FAB2_LIB.BASEBOARD_FAB2(SCH_1):PAGE95
     2    GND @BASEBOARD_FAB2_LIB.BASEBOARD_FAB2(SCH_1):GND   I115 @BASEBOARD_FAB2_LIB.BASEBOARD_FAB2(SCH_1):PAGE95

C7E5 CAP_A_0402V-0.1UF,16V,10%,X7R,A
     1 P12V_STBY @BASEBOARD_FAB2_LIB.BASEBOARD_FAB2(SCH_1):P12V_STBY    I52 @BASEBOARD_FAB2_LIB.BASEBOARD_FAB2(SCH_1):PAGE198
     2    GND @BASEBOARD_FAB2_LIB.BASEBOARD_FAB2(SCH_1):GND    I52 @BASEBOARD_FAB2_LIB.BASEBOARD_FAB2(SCH_1):PAGE198

C7E6 CAP_0805-10UF,16V,10%,X6S,C953A
     1 P12V_STBY @BASEBOARD_FAB2_LIB.BASEBOARD_FAB2(SCH_1):P12V_STBY    I53 @BASEBOARD_FAB2_LIB.BASEBOARD_FAB2(SCH_1):PAGE198
     2    GND @BASEBOARD_FAB2_LIB.BASEBOARD_FAB2(SCH_1):GND    I53 @BASEBOARD_FAB2_LIB.BASEBOARD_FAB2(SCH_1):PAGE198

C7E8 CAP_0805-10UF,16V,10%,X6S,C953A
     1   P12V @BASEBOARD_FAB2_LIB.BASEBOARD_FAB2(SCH_1):P12V    I50 @BASEBOARD_FAB2_LIB.BASEBOARD_FAB2(SCH_1):PAGE198
     2    GND @BASEBOARD_FAB2_LIB.BASEBOARD_FAB2(SCH_1):GND    I50 @BASEBOARD_FAB2_LIB.BASEBOARD_FAB2(SCH_1):PAGE198

C7E9 CAP_A_0402V-0.1UF,16V,10%,X7R,A
     1   P12V @BASEBOARD_FAB2_LIB.BASEBOARD_FAB2(SCH_1):P12V    I49 @BASEBOARD_FAB2_LIB.BASEBOARD_FAB2(SCH_1):PAGE198
     2    GND @BASEBOARD_FAB2_LIB.BASEBOARD_FAB2(SCH_1):GND    I49 @BASEBOARD_FAB2_LIB.BASEBOARD_FAB2(SCH_1):PAGE198

C7E10 CAP_0402LF-1000PF,50V,10%,X7R,A
     1 PWRGD_P5V_STBY_R @BASEBOARD_FAB2_LIB.BASEBOARD_FAB2(SCH_1):PWRGD_P5V_STBY_R    I14 @BASEBOARD_FAB2_LIB.BASEBOARD_FAB2(SCH_1):PAGE241
     2    GND @BASEBOARD_FAB2_LIB.BASEBOARD_FAB2(SCH_1):GND    I14 @BASEBOARD_FAB2_LIB.BASEBOARD_FAB2(SCH_1):PAGE241

C7E11 CAP_1206LF-22UF,16V,10%,X6S,D3A
     1 VR_FET_SW_P5V_STBY_PVIN @BASEBOARD_FAB2_LIB.BASEBOARD_FAB2(SCH_1):VR_FET_SW_P5V_STBY_PVIN    I39 @BASEBOARD_FAB2_LIB.BASEBOARD_FAB2(SCH_1):PAGE241
     2    GND @BASEBOARD_FAB2_LIB.BASEBOARD_FAB2(SCH_1):GND    I39 @BASEBOARD_FAB2_LIB.BASEBOARD_FAB2(SCH_1):PAGE241

C7E12 SC22U16V5MX-4-GP_SMD-BCG5-SC22A
     1 VR_FET_SW_P5V_STBY_PVIN @BASEBOARD_FAB2_LIB.BASEBOARD_FAB2(SCH_1):VR_FET_SW_P5V_STBY_PVIN    I98 @BASEBOARD_FAB2_LIB.BASEBOARD_FAB2(SCH_1):PAGE241
     2    GND @BASEBOARD_FAB2_LIB.BASEBOARD_FAB2(SCH_1):GND    I98 @BASEBOARD_FAB2_LIB.BASEBOARD_FAB2(SCH_1):PAGE241

C7E13 SC22U16V5MX-4-GP_SMD-BCG5-SC22A
     1 VR_FET_SW_P5V_STBY_PVIN @BASEBOARD_FAB2_LIB.BASEBOARD_FAB2(SCH_1):VR_FET_SW_P5V_STBY_PVIN    I92 @BASEBOARD_FAB2_LIB.BASEBOARD_FAB2(SCH_1):PAGE241
     2    GND @BASEBOARD_FAB2_LIB.BASEBOARD_FAB2(SCH_1):GND    I92 @BASEBOARD_FAB2_LIB.BASEBOARD_FAB2(SCH_1):PAGE241

C7E14 CAP_0402-1.0UF,16V,10%,X6S,D97A
     1 VR_P5V_STBY_VIN @BASEBOARD_FAB2_LIB.BASEBOARD_FAB2(SCH_1):VR_P5V_STBY_VIN    I30 @BASEBOARD_FAB2_LIB.BASEBOARD_FAB2(SCH_1):PAGE241
     2    GND @BASEBOARD_FAB2_LIB.BASEBOARD_FAB2(SCH_1):GND    I30 @BASEBOARD_FAB2_LIB.BASEBOARD_FAB2(SCH_1):PAGE241

C7F1 CAP_A_0402V-0.01UF,25V,10%,X7RA
     1 P3V3_STBY @BASEBOARD_FAB2_LIB.BASEBOARD_FAB2(SCH_1):P3V3_STBY   I131 @BASEBOARD_FAB2_LIB.BASEBOARD_FAB2(SCH_1):PAGE153
     2    GND @BASEBOARD_FAB2_LIB.BASEBOARD_FAB2(SCH_1):GND   I131 @BASEBOARD_FAB2_LIB.BASEBOARD_FAB2(SCH_1):PAGE153

C7F2 CAP_A_0402V-1.0UF,6.3V,10%,X6SA
     1 P3V3_STBY @BASEBOARD_FAB2_LIB.BASEBOARD_FAB2(SCH_1):P3V3_STBY   I130 @BASEBOARD_FAB2_LIB.BASEBOARD_FAB2(SCH_1):PAGE153
     2    GND @BASEBOARD_FAB2_LIB.BASEBOARD_FAB2(SCH_1):GND   I130 @BASEBOARD_FAB2_LIB.BASEBOARD_FAB2(SCH_1):PAGE153

C7F3 CAP_0402LF-3300PF,50V,10%,EMPTA
     1 VR_PVPP_ABC_PHASE @BASEBOARD_FAB2_LIB.BASEBOARD_FAB2(SCH_1):VR_PVPP_ABC_PHASE   I175 @BASEBOARD_FAB2_LIB.BASEBOARD_FAB2(SCH_1):PAGE231
     2 VR_PVPP_ABC_SNUB @BASEBOARD_FAB2_LIB.BASEBOARD_FAB2(SCH_1):VR_PVPP_ABC_SNUB   I175 @BASEBOARD_FAB2_LIB.BASEBOARD_FAB2(SCH_1):PAGE231

C7F4 CAP_0603LF-0.1UF,25V,10%,X7R,6A
     1 VR_PVPP_ABC_PHASE @BASEBOARD_FAB2_LIB.BASEBOARD_FAB2(SCH_1):VR_PVPP_ABC_PHASE   I159 @BASEBOARD_FAB2_LIB.BASEBOARD_FAB2(SCH_1):PAGE231
     2 VR_PVPP_ABC_BOOT_R @BASEBOARD_FAB2_LIB.BASEBOARD_FAB2(SCH_1):VR_PVPP_ABC_BOOT_R   I159 @BASEBOARD_FAB2_LIB.BASEBOARD_FAB2(SCH_1):PAGE231

C7F5 CAP_0805-10UF,16V,10%,X6S,C953A
     1 VR_FET_SW_P12V_STBY_PVPP_ABC @BASEBOARD_FAB2_LIB.BASEBOARD_FAB2(SCH_1):VR_FET_SW_P12V_STBY_PVPP_ABC   I209 @BASEBOARD_FAB2_LIB.BASEBOARD_FAB2(SCH_1):PAGE231
     2    GND @BASEBOARD_FAB2_LIB.BASEBOARD_FAB2(SCH_1):GND   I209 @BASEBOARD_FAB2_LIB.BASEBOARD_FAB2(SCH_1):PAGE231

C7F6 CAP_A_0402V-0.1UF,16V,10%,X7R,A
     1 VR_FET_SW_P12V_STBY_PVPP_ABC @BASEBOARD_FAB2_LIB.BASEBOARD_FAB2(SCH_1):VR_FET_SW_P12V_STBY_PVPP_ABC   I205 @BASEBOARD_FAB2_LIB.BASEBOARD_FAB2(SCH_1):PAGE231
     2    GND @BASEBOARD_FAB2_LIB.BASEBOARD_FAB2(SCH_1):GND   I205 @BASEBOARD_FAB2_LIB.BASEBOARD_FAB2(SCH_1):PAGE231

C7F7 SC22U16V5MX-4-GP_SMD-BCG5-SC22A
     1 VR_FET_SW_P12V_STBY_PVPP_ABC @BASEBOARD_FAB2_LIB.BASEBOARD_FAB2(SCH_1):VR_FET_SW_P12V_STBY_PVPP_ABC   I226 @BASEBOARD_FAB2_LIB.BASEBOARD_FAB2(SCH_1):PAGE231
     2    GND @BASEBOARD_FAB2_LIB.BASEBOARD_FAB2(SCH_1):GND   I226 @BASEBOARD_FAB2_LIB.BASEBOARD_FAB2(SCH_1):PAGE231

C7F8 CAP_0402LF-1000PF,50V,10%,EMPTA
     1 FM_PVPP_CPU0_EN @BASEBOARD_FAB2_LIB.BASEBOARD_FAB2(SCH_1):FM_PVPP_CPU0_EN   I140 @BASEBOARD_FAB2_LIB.BASEBOARD_FAB2(SCH_1):PAGE231
     2 AGND_PVPP_ABC @BASEBOARD_FAB2_LIB.BASEBOARD_FAB2(SCH_1):AGND_PVPP_ABC   I140 @BASEBOARD_FAB2_LIB.BASEBOARD_FAB2(SCH_1):PAGE231

C7F9 CAP_0402LF-100.0PF,50V,5%,COG,A
     1 VR_FB_PVPP_ABC @BASEBOARD_FAB2_LIB.BASEBOARD_FAB2(SCH_1):VR_FB_PVPP_ABC   I199 @BASEBOARD_FAB2_LIB.BASEBOARD_FAB2(SCH_1):PAGE231
     2 VR_COMP_PVPP_ABC_3 @BASEBOARD_FAB2_LIB.BASEBOARD_FAB2(SCH_1):VR_COMP_PVPP_ABC_3   I199 @BASEBOARD_FAB2_LIB.BASEBOARD_FAB2(SCH_1):PAGE231

C7F10 CAP_0402-0.027UF,16V,10%,X7R,AA
     1 VR_PVPP_ABC_SS @BASEBOARD_FAB2_LIB.BASEBOARD_FAB2(SCH_1):VR_PVPP_ABC_SS   I194 @BASEBOARD_FAB2_LIB.BASEBOARD_FAB2(SCH_1):PAGE231
     2 AGND_PVPP_ABC @BASEBOARD_FAB2_LIB.BASEBOARD_FAB2(SCH_1):AGND_PVPP_ABC   I194 @BASEBOARD_FAB2_LIB.BASEBOARD_FAB2(SCH_1):PAGE231

C7F11 CAP_0402LF-1000PF,50V,10%,X7R,A
     1 PWRGD_PVPP_ABC_R @BASEBOARD_FAB2_LIB.BASEBOARD_FAB2(SCH_1):PWRGD_PVPP_ABC_R   I142 @BASEBOARD_FAB2_LIB.BASEBOARD_FAB2(SCH_1):PAGE231
     2    GND @BASEBOARD_FAB2_LIB.BASEBOARD_FAB2(SCH_1):GND   I142 @BASEBOARD_FAB2_LIB.BASEBOARD_FAB2(SCH_1):PAGE231

C7F12 CAP_0402LF-2200PF,50V,10%,X7R,A
     1 VR_COMP_RC_PVPP_ABC @BASEBOARD_FAB2_LIB.BASEBOARD_FAB2(SCH_1):VR_COMP_RC_PVPP_ABC   I200 @BASEBOARD_FAB2_LIB.BASEBOARD_FAB2(SCH_1):PAGE231
     2 VR_COMP_PVPP_ABC_3 @BASEBOARD_FAB2_LIB.BASEBOARD_FAB2(SCH_1):VR_COMP_PVPP_ABC_3   I200 @BASEBOARD_FAB2_LIB.BASEBOARD_FAB2(SCH_1):PAGE231

C7F13 CAP_0402LF-2200PF,50V,10%,X7R,A
     1 VR_COMP_PVPP_ABC @BASEBOARD_FAB2_LIB.BASEBOARD_FAB2(SCH_1):VR_COMP_PVPP_ABC   I219 @BASEBOARD_FAB2_LIB.BASEBOARD_FAB2(SCH_1):PAGE231
     2 VR_FB_PVPP_ABC @BASEBOARD_FAB2_LIB.BASEBOARD_FAB2(SCH_1):VR_FB_PVPP_ABC   I219 @BASEBOARD_FAB2_LIB.BASEBOARD_FAB2(SCH_1):PAGE231

C7F14 CAP_0402LF-1000PF,50V,10%,X7R,A
     1 PWRGD_PVDDQ_ABC_R @BASEBOARD_FAB2_LIB.BASEBOARD_FAB2(SCH_1):PWRGD_PVDDQ_ABC_R    I44 @BASEBOARD_FAB2_LIB.BASEBOARD_FAB2(SCH_1):PAGE215
     2    GND @BASEBOARD_FAB2_LIB.BASEBOARD_FAB2(SCH_1):GND    I44 @BASEBOARD_FAB2_LIB.BASEBOARD_FAB2(SCH_1):PAGE215

C7F15 CAP_A_0402V-0.1UF,16V,10%,X7R,A
     1 VR_PVDDQ_ABC_VD12 @BASEBOARD_FAB2_LIB.BASEBOARD_FAB2(SCH_1):VR_PVDDQ_ABC_VD12    I38 @BASEBOARD_FAB2_LIB.BASEBOARD_FAB2(SCH_1):PAGE215
     2    GND @BASEBOARD_FAB2_LIB.BASEBOARD_FAB2(SCH_1):GND    I38 @BASEBOARD_FAB2_LIB.BASEBOARD_FAB2(SCH_1):PAGE215

C7F16 CAP_A_0402V-1.0UF,6.3V,10%,X6SA
     1 VR_PVDDQ_ABC_VD12 @BASEBOARD_FAB2_LIB.BASEBOARD_FAB2(SCH_1):VR_PVDDQ_ABC_VD12    I40 @BASEBOARD_FAB2_LIB.BASEBOARD_FAB2(SCH_1):PAGE215
     2    GND @BASEBOARD_FAB2_LIB.BASEBOARD_FAB2(SCH_1):GND    I40 @BASEBOARD_FAB2_LIB.BASEBOARD_FAB2(SCH_1):PAGE215

C7F17 CAP_A_0402V-0.1UF,16V,10%,X7R,A
     1 VR_PVDDQ_ABC_VDD @BASEBOARD_FAB2_LIB.BASEBOARD_FAB2(SCH_1):VR_PVDDQ_ABC_VDD    I34 @BASEBOARD_FAB2_LIB.BASEBOARD_FAB2(SCH_1):PAGE215
     2    GND @BASEBOARD_FAB2_LIB.BASEBOARD_FAB2(SCH_1):GND    I34 @BASEBOARD_FAB2_LIB.BASEBOARD_FAB2(SCH_1):PAGE215

C7F18 CAP_A_0402V-1.0UF,6.3V,10%,X6SA
     1 VR_PVDDQ_ABC_VDD @BASEBOARD_FAB2_LIB.BASEBOARD_FAB2(SCH_1):VR_PVDDQ_ABC_VDD    I35 @BASEBOARD_FAB2_LIB.BASEBOARD_FAB2(SCH_1):PAGE215
     2    GND @BASEBOARD_FAB2_LIB.BASEBOARD_FAB2(SCH_1):GND    I35 @BASEBOARD_FAB2_LIB.BASEBOARD_FAB2(SCH_1):PAGE215

C7G2 CAPP_2626-270UF,16V,20%,OSCON,A
     1 VR_FET_SW_P12V_STBY_PVDDQ_ABC @BASEBOARD_FAB2_LIB.BASEBOARD_FAB2(SCH_1):VR_FET_SW_P12V_STBY_PVDDQ_ABC   I175 @BASEBOARD_FAB2_LIB.BASEBOARD_FAB2(SCH_1):PAGE217
     2    GND @BASEBOARD_FAB2_LIB.BASEBOARD_FAB2(SCH_1):GND   I175 @BASEBOARD_FAB2_LIB.BASEBOARD_FAB2(SCH_1):PAGE217

C7G3 CAP_0402LF-220PF,50V,10%,X7R,AA
     1 A_TSENSE_PVDDQ_ABC @BASEBOARD_FAB2_LIB.BASEBOARD_FAB2(SCH_1):A_TSENSE_PVDDQ_ABC    I22 @BASEBOARD_FAB2_LIB.BASEBOARD_FAB2(SCH_1):PAGE215
     2    GND @BASEBOARD_FAB2_LIB.BASEBOARD_FAB2(SCH_1):GND    I22 @BASEBOARD_FAB2_LIB.BASEBOARD_FAB2(SCH_1):PAGE215

C7G4 CAP_0402LF-220PF,50V,10%,X7R,AA
     1 VR_PVDDQ_ABC_AVSP @BASEBOARD_FAB2_LIB.BASEBOARD_FAB2(SCH_1):VR_PVDDQ_ABC_AVSP    I14 @BASEBOARD_FAB2_LIB.BASEBOARD_FAB2(SCH_1):PAGE215
     2 VSENSE_PVDDQ_ABC_N @BASEBOARD_FAB2_LIB.BASEBOARD_FAB2(SCH_1):VSENSE_PVDDQ_ABC_N    I14 @BASEBOARD_FAB2_LIB.BASEBOARD_FAB2(SCH_1):PAGE215

C7G5 CAP_0402-0.22UF,16V,10%,X7R,A3A
     1 P3E_CPU0_PE2_SS_TXP<15> @BASEBOARD_FAB2_LIB.BASEBOARD_FAB2(SCH_1):P3E_CPU0_PE2_SS_TXP(15)    I20 @BASEBOARD_FAB2_LIB.BASEBOARD_FAB2(SCH_1):PAGE105
     2 P3E_CPU0_PE2_SS_C_TXP<15> @BASEBOARD_FAB2_LIB.BASEBOARD_FAB2(SCH_1):P3E_CPU0_PE2_SS_C_TXP(15)    I20 @BASEBOARD_FAB2_LIB.BASEBOARD_FAB2(SCH_1):PAGE105

C7G6 CAP_0402-0.22UF,16V,10%,X7R,A3A
     1 P3E_CPU0_PE2_SS_TXN<15> @BASEBOARD_FAB2_LIB.BASEBOARD_FAB2(SCH_1):P3E_CPU0_PE2_SS_TXN(15)     I6 @BASEBOARD_FAB2_LIB.BASEBOARD_FAB2(SCH_1):PAGE105
     2 P3E_CPU0_PE2_SS_C_TXN<15> @BASEBOARD_FAB2_LIB.BASEBOARD_FAB2(SCH_1):P3E_CPU0_PE2_SS_C_TXN(15)     I6 @BASEBOARD_FAB2_LIB.BASEBOARD_FAB2(SCH_1):PAGE105

C7G7 CAP_0402-0.22UF,16V,10%,X7R,A3A
     1 P3E_CPU0_PE2_SS_TXN<14> @BASEBOARD_FAB2_LIB.BASEBOARD_FAB2(SCH_1):P3E_CPU0_PE2_SS_TXN(14)     I7 @BASEBOARD_FAB2_LIB.BASEBOARD_FAB2(SCH_1):PAGE105
     2 P3E_CPU0_PE2_SS_C_TXN<14> @BASEBOARD_FAB2_LIB.BASEBOARD_FAB2(SCH_1):P3E_CPU0_PE2_SS_C_TXN(14)     I7 @BASEBOARD_FAB2_LIB.BASEBOARD_FAB2(SCH_1):PAGE105

C7G8 CAP_0402-0.22UF,16V,10%,X7R,A3A
     1 P3E_CPU0_PE2_SS_TXP<14> @BASEBOARD_FAB2_LIB.BASEBOARD_FAB2(SCH_1):P3E_CPU0_PE2_SS_TXP(14)    I22 @BASEBOARD_FAB2_LIB.BASEBOARD_FAB2(SCH_1):PAGE105
     2 P3E_CPU0_PE2_SS_C_TXP<14> @BASEBOARD_FAB2_LIB.BASEBOARD_FAB2(SCH_1):P3E_CPU0_PE2_SS_C_TXP(14)    I22 @BASEBOARD_FAB2_LIB.BASEBOARD_FAB2(SCH_1):PAGE105

C7G9 CAP_0402-0.22UF,16V,10%,X7R,A3A
     1 P3E_CPU0_PE2_SS_TXP<13> @BASEBOARD_FAB2_LIB.BASEBOARD_FAB2(SCH_1):P3E_CPU0_PE2_SS_TXP(13)    I21 @BASEBOARD_FAB2_LIB.BASEBOARD_FAB2(SCH_1):PAGE105
     2 P3E_CPU0_PE2_SS_C_TXP<13> @BASEBOARD_FAB2_LIB.BASEBOARD_FAB2(SCH_1):P3E_CPU0_PE2_SS_C_TXP(13)    I21 @BASEBOARD_FAB2_LIB.BASEBOARD_FAB2(SCH_1):PAGE105

C7G10 CAP_0402-0.22UF,16V,10%,X7R,A3A
     1 P3E_CPU0_PE2_SS_TXN<13> @BASEBOARD_FAB2_LIB.BASEBOARD_FAB2(SCH_1):P3E_CPU0_PE2_SS_TXN(13)     I8 @BASEBOARD_FAB2_LIB.BASEBOARD_FAB2(SCH_1):PAGE105
     2 P3E_CPU0_PE2_SS_C_TXN<13> @BASEBOARD_FAB2_LIB.BASEBOARD_FAB2(SCH_1):P3E_CPU0_PE2_SS_C_TXN(13)     I8 @BASEBOARD_FAB2_LIB.BASEBOARD_FAB2(SCH_1):PAGE105

C7G11 CAP_0402-0.22UF,16V,10%,X7R,A3A
     1 P3E_CPU0_PE2_SS_TXP<12> @BASEBOARD_FAB2_LIB.BASEBOARD_FAB2(SCH_1):P3E_CPU0_PE2_SS_TXP(12)    I27 @BASEBOARD_FAB2_LIB.BASEBOARD_FAB2(SCH_1):PAGE105
     2 P3E_CPU0_PE2_SS_C_TXP<12> @BASEBOARD_FAB2_LIB.BASEBOARD_FAB2(SCH_1):P3E_CPU0_PE2_SS_C_TXP(12)    I27 @BASEBOARD_FAB2_LIB.BASEBOARD_FAB2(SCH_1):PAGE105

C7G12 CAP_0402-0.22UF,16V,10%,X7R,A3A
     1 P3E_CPU0_PE2_SS_TXN<12> @BASEBOARD_FAB2_LIB.BASEBOARD_FAB2(SCH_1):P3E_CPU0_PE2_SS_TXN(12)    I12 @BASEBOARD_FAB2_LIB.BASEBOARD_FAB2(SCH_1):PAGE105
     2 P3E_CPU0_PE2_SS_C_TXN<12> @BASEBOARD_FAB2_LIB.BASEBOARD_FAB2(SCH_1):P3E_CPU0_PE2_SS_C_TXN(12)    I12 @BASEBOARD_FAB2_LIB.BASEBOARD_FAB2(SCH_1):PAGE105

C7G13 CAP_0402-0.22UF,16V,10%,X7R,A3A
     1 P3E_CPU0_PE2_SS_TXN<11> @BASEBOARD_FAB2_LIB.BASEBOARD_FAB2(SCH_1):P3E_CPU0_PE2_SS_TXN(11)    I13 @BASEBOARD_FAB2_LIB.BASEBOARD_FAB2(SCH_1):PAGE105
     2 P3E_CPU0_PE2_SS_C_TXN<11> @BASEBOARD_FAB2_LIB.BASEBOARD_FAB2(SCH_1):P3E_CPU0_PE2_SS_C_TXN(11)    I13 @BASEBOARD_FAB2_LIB.BASEBOARD_FAB2(SCH_1):PAGE105

C7G14 CAP_0402-0.22UF,16V,10%,X7R,A3A
     1 P3E_CPU0_PE2_SS_TXP<11> @BASEBOARD_FAB2_LIB.BASEBOARD_FAB2(SCH_1):P3E_CPU0_PE2_SS_TXP(11)    I28 @BASEBOARD_FAB2_LIB.BASEBOARD_FAB2(SCH_1):PAGE105
     2 P3E_CPU0_PE2_SS_C_TXP<11> @BASEBOARD_FAB2_LIB.BASEBOARD_FAB2(SCH_1):P3E_CPU0_PE2_SS_C_TXP(11)    I28 @BASEBOARD_FAB2_LIB.BASEBOARD_FAB2(SCH_1):PAGE105

C7G15 CAP_0402-0.22UF,16V,10%,X7R,A3A
     1 P3E_CPU0_PE2_SS_TXP<10> @BASEBOARD_FAB2_LIB.BASEBOARD_FAB2(SCH_1):P3E_CPU0_PE2_SS_TXP(10)    I45 @BASEBOARD_FAB2_LIB.BASEBOARD_FAB2(SCH_1):PAGE105
     2 P3E_CPU0_PE2_SS_C_TXP<10> @BASEBOARD_FAB2_LIB.BASEBOARD_FAB2(SCH_1):P3E_CPU0_PE2_SS_C_TXP(10)    I45 @BASEBOARD_FAB2_LIB.BASEBOARD_FAB2(SCH_1):PAGE105

C7G16 CAP_0402-0.22UF,16V,10%,X7R,A3A
     1 P3E_CPU0_PE2_SS_TXN<10> @BASEBOARD_FAB2_LIB.BASEBOARD_FAB2(SCH_1):P3E_CPU0_PE2_SS_TXN(10)    I31 @BASEBOARD_FAB2_LIB.BASEBOARD_FAB2(SCH_1):PAGE105
     2 P3E_CPU0_PE2_SS_C_TXN<10> @BASEBOARD_FAB2_LIB.BASEBOARD_FAB2(SCH_1):P3E_CPU0_PE2_SS_C_TXN(10)    I31 @BASEBOARD_FAB2_LIB.BASEBOARD_FAB2(SCH_1):PAGE105

C7G17 CAP_0402-0.22UF,16V,10%,X7R,A3A
     1 P3E_CPU0_PE2_SS_TXP<9> @BASEBOARD_FAB2_LIB.BASEBOARD_FAB2(SCH_1):P3E_CPU0_PE2_SS_TXP(9)    I44 @BASEBOARD_FAB2_LIB.BASEBOARD_FAB2(SCH_1):PAGE105
     2 P3E_CPU0_PE2_SS_C_TXP<9> @BASEBOARD_FAB2_LIB.BASEBOARD_FAB2(SCH_1):P3E_CPU0_PE2_SS_C_TXP(9)    I44 @BASEBOARD_FAB2_LIB.BASEBOARD_FAB2(SCH_1):PAGE105

C7G18 CAP_0402-0.22UF,16V,10%,X7R,A3A
     1 P3E_CPU0_PE2_SS_TXN<9> @BASEBOARD_FAB2_LIB.BASEBOARD_FAB2(SCH_1):P3E_CPU0_PE2_SS_TXN(9)    I32 @BASEBOARD_FAB2_LIB.BASEBOARD_FAB2(SCH_1):PAGE105
     2 P3E_CPU0_PE2_SS_C_TXN<9> @BASEBOARD_FAB2_LIB.BASEBOARD_FAB2(SCH_1):P3E_CPU0_PE2_SS_C_TXN(9)    I32 @BASEBOARD_FAB2_LIB.BASEBOARD_FAB2(SCH_1):PAGE105

C7G19 CAP_0402-0.22UF,16V,10%,X7R,A3A
     1 P3E_CPU0_PE2_SS_TXN<8> @BASEBOARD_FAB2_LIB.BASEBOARD_FAB2(SCH_1):P3E_CPU0_PE2_SS_TXN(8)   I257 @BASEBOARD_FAB2_LIB.BASEBOARD_FAB2(SCH_1):PAGE105
     2 P3E_CPU0_PE2_SS_C_TXN<8> @BASEBOARD_FAB2_LIB.BASEBOARD_FAB2(SCH_1):P3E_CPU0_PE2_SS_C_TXN(8)   I257 @BASEBOARD_FAB2_LIB.BASEBOARD_FAB2(SCH_1):PAGE105

C7G20 CAP_0402-0.22UF,16V,10%,X7R,A3A
     1 P3E_CPU0_PE2_SS_TXP<8> @BASEBOARD_FAB2_LIB.BASEBOARD_FAB2(SCH_1):P3E_CPU0_PE2_SS_TXP(8)   I258 @BASEBOARD_FAB2_LIB.BASEBOARD_FAB2(SCH_1):PAGE105
     2 P3E_CPU0_PE2_SS_C_TXP<8> @BASEBOARD_FAB2_LIB.BASEBOARD_FAB2(SCH_1):P3E_CPU0_PE2_SS_C_TXP(8)   I258 @BASEBOARD_FAB2_LIB.BASEBOARD_FAB2(SCH_1):PAGE105

C7G21 CAP_0402-0.22UF,16V,10%,X7R,A3A
     1 P3E_CPU0_PE2_SS_TXP<7> @BASEBOARD_FAB2_LIB.BASEBOARD_FAB2(SCH_1):P3E_CPU0_PE2_SS_TXP(7)    I51 @BASEBOARD_FAB2_LIB.BASEBOARD_FAB2(SCH_1):PAGE105
     2 P3E_CPU0_PE2_SS_C_TXP<7> @BASEBOARD_FAB2_LIB.BASEBOARD_FAB2(SCH_1):P3E_CPU0_PE2_SS_C_TXP(7)    I51 @BASEBOARD_FAB2_LIB.BASEBOARD_FAB2(SCH_1):PAGE105

C7G22 CAP_0402-0.22UF,16V,10%,X7R,A3A
     1 P3E_CPU0_PE2_SS_TXN<7> @BASEBOARD_FAB2_LIB.BASEBOARD_FAB2(SCH_1):P3E_CPU0_PE2_SS_TXN(7)    I37 @BASEBOARD_FAB2_LIB.BASEBOARD_FAB2(SCH_1):PAGE105
     2 P3E_CPU0_PE2_SS_C_TXN<7> @BASEBOARD_FAB2_LIB.BASEBOARD_FAB2(SCH_1):P3E_CPU0_PE2_SS_C_TXN(7)    I37 @BASEBOARD_FAB2_LIB.BASEBOARD_FAB2(SCH_1):PAGE105

C7G23 CAP_0402-0.22UF,16V,10%,X7R,A3A
     1 P3E_CPU0_PE2_SS_TXP<6> @BASEBOARD_FAB2_LIB.BASEBOARD_FAB2(SCH_1):P3E_CPU0_PE2_SS_TXP(6)    I52 @BASEBOARD_FAB2_LIB.BASEBOARD_FAB2(SCH_1):PAGE105
     2 P3E_CPU0_PE2_SS_C_TXP<6> @BASEBOARD_FAB2_LIB.BASEBOARD_FAB2(SCH_1):P3E_CPU0_PE2_SS_C_TXP(6)    I52 @BASEBOARD_FAB2_LIB.BASEBOARD_FAB2(SCH_1):PAGE105

C7G24 CAP_0402-0.22UF,16V,10%,X7R,A3A
     1 P3E_CPU0_PE2_SS_TXN<6> @BASEBOARD_FAB2_LIB.BASEBOARD_FAB2(SCH_1):P3E_CPU0_PE2_SS_TXN(6)     I1 @BASEBOARD_FAB2_LIB.BASEBOARD_FAB2(SCH_1):PAGE105
     2 P3E_CPU0_PE2_SS_C_TXN<6> @BASEBOARD_FAB2_LIB.BASEBOARD_FAB2(SCH_1):P3E_CPU0_PE2_SS_C_TXN(6)     I1 @BASEBOARD_FAB2_LIB.BASEBOARD_FAB2(SCH_1):PAGE105

C7G25 CAP_0402-0.22UF,16V,10%,X7R,A3A
     1 P3E_CPU0_PE2_SS_TXP<5> @BASEBOARD_FAB2_LIB.BASEBOARD_FAB2(SCH_1):P3E_CPU0_PE2_SS_TXP(5)    I69 @BASEBOARD_FAB2_LIB.BASEBOARD_FAB2(SCH_1):PAGE105
     2 P3E_CPU0_PE2_SS_C_TXP<5> @BASEBOARD_FAB2_LIB.BASEBOARD_FAB2(SCH_1):P3E_CPU0_PE2_SS_C_TXP(5)    I69 @BASEBOARD_FAB2_LIB.BASEBOARD_FAB2(SCH_1):PAGE105

C7G26 CAP_0402-0.22UF,16V,10%,X7R,A3A
     1 P3E_CPU0_PE2_SS_TXN<5> @BASEBOARD_FAB2_LIB.BASEBOARD_FAB2(SCH_1):P3E_CPU0_PE2_SS_TXN(5)    I55 @BASEBOARD_FAB2_LIB.BASEBOARD_FAB2(SCH_1):PAGE105
     2 P3E_CPU0_PE2_SS_C_TXN<5> @BASEBOARD_FAB2_LIB.BASEBOARD_FAB2(SCH_1):P3E_CPU0_PE2_SS_C_TXN(5)    I55 @BASEBOARD_FAB2_LIB.BASEBOARD_FAB2(SCH_1):PAGE105

C7G27 CAP_0805LF-22UF,4V,20%,X6S,C95A
     1 PVDDQ_ABC @BASEBOARD_FAB2_LIB.BASEBOARD_FAB2(SCH_1):PVDDQ_ABC    I68 @BASEBOARD_FAB2_LIB.BASEBOARD_FAB2(SCH_1):PAGE216
     2    GND @BASEBOARD_FAB2_LIB.BASEBOARD_FAB2(SCH_1):GND    I68 @BASEBOARD_FAB2_LIB.BASEBOARD_FAB2(SCH_1):PAGE216

C7G28 CAPP_3018-470UF,2.5V,20%,ALUM,A
     1 PVDDQ_ABC @BASEBOARD_FAB2_LIB.BASEBOARD_FAB2(SCH_1):PVDDQ_ABC    I75 @BASEBOARD_FAB2_LIB.BASEBOARD_FAB2(SCH_1):PAGE217
     2    GND @BASEBOARD_FAB2_LIB.BASEBOARD_FAB2(SCH_1):GND    I75 @BASEBOARD_FAB2_LIB.BASEBOARD_FAB2(SCH_1):PAGE217

C7G29 CAP_A_0402V-0.1UF,16V,10%,X7R,A
     1 VR_FET_SW_P12V_STBY_PVDDQ_ABC @BASEBOARD_FAB2_LIB.BASEBOARD_FAB2(SCH_1):VR_FET_SW_P12V_STBY_PVDDQ_ABC    I51 @BASEBOARD_FAB2_LIB.BASEBOARD_FAB2(SCH_1):PAGE216
     2    GND @BASEBOARD_FAB2_LIB.BASEBOARD_FAB2(SCH_1):GND    I51 @BASEBOARD_FAB2_LIB.BASEBOARD_FAB2(SCH_1):PAGE216

C7G30 CAP_0402-1.0UF,16V,10%,X6S,D97A
     1 VR_FET_SW_P12V_STBY_PVDDQ_ABC @BASEBOARD_FAB2_LIB.BASEBOARD_FAB2(SCH_1):VR_FET_SW_P12V_STBY_PVDDQ_ABC    I79 @BASEBOARD_FAB2_LIB.BASEBOARD_FAB2(SCH_1):PAGE216
     2    GND @BASEBOARD_FAB2_LIB.BASEBOARD_FAB2(SCH_1):GND    I79 @BASEBOARD_FAB2_LIB.BASEBOARD_FAB2(SCH_1):PAGE216

C7G31 CAP_0402-0.220UF,16V,10%,X7R,AA
     1 VR_PVDDQ_ABC_PH1_BOOT @BASEBOARD_FAB2_LIB.BASEBOARD_FAB2(SCH_1):VR_PVDDQ_ABC_PH1_BOOT    I44 @BASEBOARD_FAB2_LIB.BASEBOARD_FAB2(SCH_1):PAGE216
     2 VR_PVDDQ_ABC_PH1_PHASE @BASEBOARD_FAB2_LIB.BASEBOARD_FAB2(SCH_1):VR_PVDDQ_ABC_PH1_PHASE    I44 @BASEBOARD_FAB2_LIB.BASEBOARD_FAB2(SCH_1):PAGE216

C7G33 CAP_0402-1.0UF,16V,10%,X6S,D97A
     1 VR_PVDDQ_ABC_PH1_VCIN @BASEBOARD_FAB2_LIB.BASEBOARD_FAB2(SCH_1):VR_PVDDQ_ABC_PH1_VCIN    I50 @BASEBOARD_FAB2_LIB.BASEBOARD_FAB2(SCH_1):PAGE216
     2    GND @BASEBOARD_FAB2_LIB.BASEBOARD_FAB2(SCH_1):GND    I50 @BASEBOARD_FAB2_LIB.BASEBOARD_FAB2(SCH_1):PAGE216

C7G34 CAP_0402-0.22UF,16V,10%,X7R,A3A
     1 P5V_STBY @BASEBOARD_FAB2_LIB.BASEBOARD_FAB2(SCH_1):P5V_STBY    I54 @BASEBOARD_FAB2_LIB.BASEBOARD_FAB2(SCH_1):PAGE216
     2    GND @BASEBOARD_FAB2_LIB.BASEBOARD_FAB2(SCH_1):GND    I54 @BASEBOARD_FAB2_LIB.BASEBOARD_FAB2(SCH_1):PAGE216

C7G35 SC1U10V2KX-4-GP_SMD-BCG6-SC1U1A
     1 P5V_STBY @BASEBOARD_FAB2_LIB.BASEBOARD_FAB2(SCH_1):P5V_STBY   I149 @BASEBOARD_FAB2_LIB.BASEBOARD_FAB2(SCH_1):PAGE216
     2    GND @BASEBOARD_FAB2_LIB.BASEBOARD_FAB2(SCH_1):GND   I149 @BASEBOARD_FAB2_LIB.BASEBOARD_FAB2(SCH_1):PAGE216

C7G36 CAP_A_0402V-0.1UF,16V,10%,X7R,A
     1 VR_FET_SW_P12V_STBY_PVDDQ_ABC @BASEBOARD_FAB2_LIB.BASEBOARD_FAB2(SCH_1):VR_FET_SW_P12V_STBY_PVDDQ_ABC    I78 @BASEBOARD_FAB2_LIB.BASEBOARD_FAB2(SCH_1):PAGE216
     2    GND @BASEBOARD_FAB2_LIB.BASEBOARD_FAB2(SCH_1):GND    I78 @BASEBOARD_FAB2_LIB.BASEBOARD_FAB2(SCH_1):PAGE216

C7G37 CAP_0402-1.0UF,16V,10%,X6S,D97A
     1 VR_FET_SW_P12V_STBY_PVDDQ_ABC @BASEBOARD_FAB2_LIB.BASEBOARD_FAB2(SCH_1):VR_FET_SW_P12V_STBY_PVDDQ_ABC    I48 @BASEBOARD_FAB2_LIB.BASEBOARD_FAB2(SCH_1):PAGE216
     2    GND @BASEBOARD_FAB2_LIB.BASEBOARD_FAB2(SCH_1):GND    I48 @BASEBOARD_FAB2_LIB.BASEBOARD_FAB2(SCH_1):PAGE216

C7G38 CAP_0402-0.220UF,16V,10%,X7R,AA
     1 VR_PVDDQ_ABC_PH2_BOOT @BASEBOARD_FAB2_LIB.BASEBOARD_FAB2(SCH_1):VR_PVDDQ_ABC_PH2_BOOT   I128 @BASEBOARD_FAB2_LIB.BASEBOARD_FAB2(SCH_1):PAGE216
     2 VR_PVDDQ_ABC_PH2_PHASE @BASEBOARD_FAB2_LIB.BASEBOARD_FAB2(SCH_1):VR_PVDDQ_ABC_PH2_PHASE   I128 @BASEBOARD_FAB2_LIB.BASEBOARD_FAB2(SCH_1):PAGE216

C7G40 CAP_0402-1.0UF,16V,10%,X6S,D97A
     1 VR_PVDDQ_ABC_PH2_VCIN @BASEBOARD_FAB2_LIB.BASEBOARD_FAB2(SCH_1):VR_PVDDQ_ABC_PH2_VCIN    I77 @BASEBOARD_FAB2_LIB.BASEBOARD_FAB2(SCH_1):PAGE216
     2    GND @BASEBOARD_FAB2_LIB.BASEBOARD_FAB2(SCH_1):GND    I77 @BASEBOARD_FAB2_LIB.BASEBOARD_FAB2(SCH_1):PAGE216

C7G41 CAP_0402-0.22UF,16V,10%,X7R,A3A
     1 P5V_STBY @BASEBOARD_FAB2_LIB.BASEBOARD_FAB2(SCH_1):P5V_STBY    I72 @BASEBOARD_FAB2_LIB.BASEBOARD_FAB2(SCH_1):PAGE216
     2    GND @BASEBOARD_FAB2_LIB.BASEBOARD_FAB2(SCH_1):GND    I72 @BASEBOARD_FAB2_LIB.BASEBOARD_FAB2(SCH_1):PAGE216

C7G42 SC1U10V2KX-4-GP_SMD-BCG6-SC1U1A
     1 P5V_STBY @BASEBOARD_FAB2_LIB.BASEBOARD_FAB2(SCH_1):P5V_STBY   I150 @BASEBOARD_FAB2_LIB.BASEBOARD_FAB2(SCH_1):PAGE216
     2    GND @BASEBOARD_FAB2_LIB.BASEBOARD_FAB2(SCH_1):GND   I150 @BASEBOARD_FAB2_LIB.BASEBOARD_FAB2(SCH_1):PAGE216

C7L1 CAP_0805-100UF,4V,20%,X5R,6024A
     1 PVDDQ_KLM @BASEBOARD_FAB2_LIB.BASEBOARD_FAB2(SCH_1):PVDDQ_KLM   I314 @BASEBOARD_FAB2_LIB.BASEBOARD_FAB2(SCH_1):PAGE228
     2    GND @BASEBOARD_FAB2_LIB.BASEBOARD_FAB2(SCH_1):GND   I314 @BASEBOARD_FAB2_LIB.BASEBOARD_FAB2(SCH_1):PAGE228

C7L2 CAP_0603LF-10UF,4V,20%,X6S,E15A
     1 PVPP_KLM @BASEBOARD_FAB2_LIB.BASEBOARD_FAB2(SCH_1):PVPP_KLM    I88 @BASEBOARD_FAB2_LIB.BASEBOARD_FAB2(SCH_1):PAGE234
     2    GND @BASEBOARD_FAB2_LIB.BASEBOARD_FAB2(SCH_1):GND    I88 @BASEBOARD_FAB2_LIB.BASEBOARD_FAB2(SCH_1):PAGE234

C7L3 CAP_0603LF-10UF,4V,20%,X6S,E15A
     1 PVPP_KLM @BASEBOARD_FAB2_LIB.BASEBOARD_FAB2(SCH_1):PVPP_KLM    I87 @BASEBOARD_FAB2_LIB.BASEBOARD_FAB2(SCH_1):PAGE234
     2    GND @BASEBOARD_FAB2_LIB.BASEBOARD_FAB2(SCH_1):GND    I87 @BASEBOARD_FAB2_LIB.BASEBOARD_FAB2(SCH_1):PAGE234

C7L4 CAP_A_0603V-47UF,4V,20%,X5R,60A
     1 PVDDQ_KLM @BASEBOARD_FAB2_LIB.BASEBOARD_FAB2(SCH_1):PVDDQ_KLM   I288 @BASEBOARD_FAB2_LIB.BASEBOARD_FAB2(SCH_1):PAGE228
     2    GND @BASEBOARD_FAB2_LIB.BASEBOARD_FAB2(SCH_1):GND   I288 @BASEBOARD_FAB2_LIB.BASEBOARD_FAB2(SCH_1):PAGE228

C7L5 CAP_A_0603V-47UF,4V,20%,X5R,60A
     1 PVDDQ_KLM @BASEBOARD_FAB2_LIB.BASEBOARD_FAB2(SCH_1):PVDDQ_KLM   I268 @BASEBOARD_FAB2_LIB.BASEBOARD_FAB2(SCH_1):PAGE228
     2    GND @BASEBOARD_FAB2_LIB.BASEBOARD_FAB2(SCH_1):GND   I268 @BASEBOARD_FAB2_LIB.BASEBOARD_FAB2(SCH_1):PAGE228

C7L6 CAP_0603LF-10UF,4V,20%,X6S,E15A
     1 PVPP_KLM @BASEBOARD_FAB2_LIB.BASEBOARD_FAB2(SCH_1):PVPP_KLM    I90 @BASEBOARD_FAB2_LIB.BASEBOARD_FAB2(SCH_1):PAGE234
     2    GND @BASEBOARD_FAB2_LIB.BASEBOARD_FAB2(SCH_1):GND    I90 @BASEBOARD_FAB2_LIB.BASEBOARD_FAB2(SCH_1):PAGE234

C7L7 CAP_0603LF-10UF,4V,20%,X6S,E15A
     1 PVPP_KLM @BASEBOARD_FAB2_LIB.BASEBOARD_FAB2(SCH_1):PVPP_KLM    I89 @BASEBOARD_FAB2_LIB.BASEBOARD_FAB2(SCH_1):PAGE234
     2    GND @BASEBOARD_FAB2_LIB.BASEBOARD_FAB2(SCH_1):GND    I89 @BASEBOARD_FAB2_LIB.BASEBOARD_FAB2(SCH_1):PAGE234

C7M1 CAP_A_0603V-47UF,4V,20%,X5R,60A
     1 PVDDQ_KLM @BASEBOARD_FAB2_LIB.BASEBOARD_FAB2(SCH_1):PVDDQ_KLM   I295 @BASEBOARD_FAB2_LIB.BASEBOARD_FAB2(SCH_1):PAGE228
     2    GND @BASEBOARD_FAB2_LIB.BASEBOARD_FAB2(SCH_1):GND   I295 @BASEBOARD_FAB2_LIB.BASEBOARD_FAB2(SCH_1):PAGE228

C7M2 CAP_A_0603V-47UF,4V,20%,X5R,60A
     1 PVDDQ_KLM @BASEBOARD_FAB2_LIB.BASEBOARD_FAB2(SCH_1):PVDDQ_KLM   I294 @BASEBOARD_FAB2_LIB.BASEBOARD_FAB2(SCH_1):PAGE228
     2    GND @BASEBOARD_FAB2_LIB.BASEBOARD_FAB2(SCH_1):GND   I294 @BASEBOARD_FAB2_LIB.BASEBOARD_FAB2(SCH_1):PAGE228

C7M3 CAP_0603LF-10UF,4V,20%,X6S,E15A
     1 PVPP_KLM @BASEBOARD_FAB2_LIB.BASEBOARD_FAB2(SCH_1):PVPP_KLM    I92 @BASEBOARD_FAB2_LIB.BASEBOARD_FAB2(SCH_1):PAGE234
     2    GND @BASEBOARD_FAB2_LIB.BASEBOARD_FAB2(SCH_1):GND    I92 @BASEBOARD_FAB2_LIB.BASEBOARD_FAB2(SCH_1):PAGE234

C7M4 CAP_0603LF-10UF,4V,20%,X6S,E15A
     1 PVPP_KLM @BASEBOARD_FAB2_LIB.BASEBOARD_FAB2(SCH_1):PVPP_KLM    I91 @BASEBOARD_FAB2_LIB.BASEBOARD_FAB2(SCH_1):PAGE234
     2    GND @BASEBOARD_FAB2_LIB.BASEBOARD_FAB2(SCH_1):GND    I91 @BASEBOARD_FAB2_LIB.BASEBOARD_FAB2(SCH_1):PAGE234

C7M5 CAP_A_0603V-47UF,4V,20%,X5R,60A
     1 PVDDQ_KLM @BASEBOARD_FAB2_LIB.BASEBOARD_FAB2(SCH_1):PVDDQ_KLM   I202 @BASEBOARD_FAB2_LIB.BASEBOARD_FAB2(SCH_1):PAGE228
     2    GND @BASEBOARD_FAB2_LIB.BASEBOARD_FAB2(SCH_1):GND   I202 @BASEBOARD_FAB2_LIB.BASEBOARD_FAB2(SCH_1):PAGE228

C7M6 CAPP_3018-68UF,16V,20%,TANT,72A
     1 P12V_STBY @BASEBOARD_FAB2_LIB.BASEBOARD_FAB2(SCH_1):P12V_STBY   I108 @BASEBOARD_FAB2_LIB.BASEBOARD_FAB2(SCH_1):PAGE195
     2    GND @BASEBOARD_FAB2_LIB.BASEBOARD_FAB2(SCH_1):GND   I108 @BASEBOARD_FAB2_LIB.BASEBOARD_FAB2(SCH_1):PAGE195

C7P1 CAP_0805-100UF,4V,20%,X5R,6024A
     1 PVDDQ_KLM @BASEBOARD_FAB2_LIB.BASEBOARD_FAB2(SCH_1):PVDDQ_KLM   I308 @BASEBOARD_FAB2_LIB.BASEBOARD_FAB2(SCH_1):PAGE228
     2    GND @BASEBOARD_FAB2_LIB.BASEBOARD_FAB2(SCH_1):GND   I308 @BASEBOARD_FAB2_LIB.BASEBOARD_FAB2(SCH_1):PAGE228

C7P2 CAP_0805-100UF,4V,20%,X5R,6024A
     1 PVDDQ_KLM @BASEBOARD_FAB2_LIB.BASEBOARD_FAB2(SCH_1):PVDDQ_KLM   I305 @BASEBOARD_FAB2_LIB.BASEBOARD_FAB2(SCH_1):PAGE228
     2    GND @BASEBOARD_FAB2_LIB.BASEBOARD_FAB2(SCH_1):GND   I305 @BASEBOARD_FAB2_LIB.BASEBOARD_FAB2(SCH_1):PAGE228

C7P3 CAP_0805-47UF,4V,20%,X6S,C9533A
     1 PVCCIO_CPU1 @BASEBOARD_FAB2_LIB.BASEBOARD_FAB2(SCH_1):PVCCIO_CPU1    I52 @BASEBOARD_FAB2_LIB.BASEBOARD_FAB2(SCH_1):PAGE76
     2    GND @BASEBOARD_FAB2_LIB.BASEBOARD_FAB2(SCH_1):GND    I52 @BASEBOARD_FAB2_LIB.BASEBOARD_FAB2(SCH_1):PAGE76

C7P4 CAP_0805-100UF,4V,20%,X5R,6024A
     1 PVCCMCP_CPU1 @BASEBOARD_FAB2_LIB.BASEBOARD_FAB2(SCH_1):PVCCMCP_CPU1   I271 @BASEBOARD_FAB2_LIB.BASEBOARD_FAB2(SCH_1):PAGE76
     2    GND @BASEBOARD_FAB2_LIB.BASEBOARD_FAB2(SCH_1):GND   I271 @BASEBOARD_FAB2_LIB.BASEBOARD_FAB2(SCH_1):PAGE76

C7P5 CAP_0805-100UF,4V,20%,X5R,6024A
     1 PVCCMCP_CPU1 @BASEBOARD_FAB2_LIB.BASEBOARD_FAB2(SCH_1):PVCCMCP_CPU1   I259 @BASEBOARD_FAB2_LIB.BASEBOARD_FAB2(SCH_1):PAGE76
     2    GND @BASEBOARD_FAB2_LIB.BASEBOARD_FAB2(SCH_1):GND   I259 @BASEBOARD_FAB2_LIB.BASEBOARD_FAB2(SCH_1):PAGE76

C7P6 CAP_0805-100UF,4V,20%,X5R,6024A
     1 PVCCMCP_CPU1 @BASEBOARD_FAB2_LIB.BASEBOARD_FAB2(SCH_1):PVCCMCP_CPU1   I268 @BASEBOARD_FAB2_LIB.BASEBOARD_FAB2(SCH_1):PAGE76
     2    GND @BASEBOARD_FAB2_LIB.BASEBOARD_FAB2(SCH_1):GND   I268 @BASEBOARD_FAB2_LIB.BASEBOARD_FAB2(SCH_1):PAGE76

C7P7 CAP_0805-100UF,4V,20%,X5R,6024A
     1 PVCCMCP_CPU1 @BASEBOARD_FAB2_LIB.BASEBOARD_FAB2(SCH_1):PVCCMCP_CPU1   I267 @BASEBOARD_FAB2_LIB.BASEBOARD_FAB2(SCH_1):PAGE76
     2    GND @BASEBOARD_FAB2_LIB.BASEBOARD_FAB2(SCH_1):GND   I267 @BASEBOARD_FAB2_LIB.BASEBOARD_FAB2(SCH_1):PAGE76

C7P8 CAP_0805-100UF,4V,20%,X5R,6024A
     1 PVCCMCP_CPU1 @BASEBOARD_FAB2_LIB.BASEBOARD_FAB2(SCH_1):PVCCMCP_CPU1   I265 @BASEBOARD_FAB2_LIB.BASEBOARD_FAB2(SCH_1):PAGE76
     2    GND @BASEBOARD_FAB2_LIB.BASEBOARD_FAB2(SCH_1):GND   I265 @BASEBOARD_FAB2_LIB.BASEBOARD_FAB2(SCH_1):PAGE76

C7P9 CAP_0805-100UF,4V,20%,X5R,6024A
     1 PVCCMCP_CPU1 @BASEBOARD_FAB2_LIB.BASEBOARD_FAB2(SCH_1):PVCCMCP_CPU1   I258 @BASEBOARD_FAB2_LIB.BASEBOARD_FAB2(SCH_1):PAGE76
     2    GND @BASEBOARD_FAB2_LIB.BASEBOARD_FAB2(SCH_1):GND   I258 @BASEBOARD_FAB2_LIB.BASEBOARD_FAB2(SCH_1):PAGE76

C7P10 CAP_0805-100UF,4V,20%,X5R,6024A
     1 PVCCMCP_CPU1 @BASEBOARD_FAB2_LIB.BASEBOARD_FAB2(SCH_1):PVCCMCP_CPU1   I266 @BASEBOARD_FAB2_LIB.BASEBOARD_FAB2(SCH_1):PAGE76
     2    GND @BASEBOARD_FAB2_LIB.BASEBOARD_FAB2(SCH_1):GND   I266 @BASEBOARD_FAB2_LIB.BASEBOARD_FAB2(SCH_1):PAGE76

C7P11 CAP_0805-100UF,4V,20%,X5R,6024A
     1 PVCCMCP_CPU1 @BASEBOARD_FAB2_LIB.BASEBOARD_FAB2(SCH_1):PVCCMCP_CPU1   I262 @BASEBOARD_FAB2_LIB.BASEBOARD_FAB2(SCH_1):PAGE76
     2    GND @BASEBOARD_FAB2_LIB.BASEBOARD_FAB2(SCH_1):GND   I262 @BASEBOARD_FAB2_LIB.BASEBOARD_FAB2(SCH_1):PAGE76

C7P12 CAP_A_0603V-22.0UF,4V,20%,X6S,A
     1 PVCCIO_CPU1 @BASEBOARD_FAB2_LIB.BASEBOARD_FAB2(SCH_1):PVCCIO_CPU1   I179 @BASEBOARD_FAB2_LIB.BASEBOARD_FAB2(SCH_1):PAGE76
     2    GND @BASEBOARD_FAB2_LIB.BASEBOARD_FAB2(SCH_1):GND   I179 @BASEBOARD_FAB2_LIB.BASEBOARD_FAB2(SCH_1):PAGE76

C7P13 CAP_0805-100UF,4V,20%,X5R,6024A
     1 PVCCMCP_CPU1 @BASEBOARD_FAB2_LIB.BASEBOARD_FAB2(SCH_1):PVCCMCP_CPU1   I269 @BASEBOARD_FAB2_LIB.BASEBOARD_FAB2(SCH_1):PAGE76
     2    GND @BASEBOARD_FAB2_LIB.BASEBOARD_FAB2(SCH_1):GND   I269 @BASEBOARD_FAB2_LIB.BASEBOARD_FAB2(SCH_1):PAGE76

C7P14 CAP_0805-100UF,4V,20%,X5R,6024A
     1 PVCCMCP_CPU1 @BASEBOARD_FAB2_LIB.BASEBOARD_FAB2(SCH_1):PVCCMCP_CPU1   I261 @BASEBOARD_FAB2_LIB.BASEBOARD_FAB2(SCH_1):PAGE76
     2    GND @BASEBOARD_FAB2_LIB.BASEBOARD_FAB2(SCH_1):GND   I261 @BASEBOARD_FAB2_LIB.BASEBOARD_FAB2(SCH_1):PAGE76

C7P15 CAP_0805-100UF,4V,20%,X5R,6024A
     1 PVCCMCP_CPU1 @BASEBOARD_FAB2_LIB.BASEBOARD_FAB2(SCH_1):PVCCMCP_CPU1   I263 @BASEBOARD_FAB2_LIB.BASEBOARD_FAB2(SCH_1):PAGE76
     2    GND @BASEBOARD_FAB2_LIB.BASEBOARD_FAB2(SCH_1):GND   I263 @BASEBOARD_FAB2_LIB.BASEBOARD_FAB2(SCH_1):PAGE76

C7P16 CAP_A_0603V-22.0UF,4V,20%,X6S,A
     1 PVCCIO_CPU1 @BASEBOARD_FAB2_LIB.BASEBOARD_FAB2(SCH_1):PVCCIO_CPU1   I206 @BASEBOARD_FAB2_LIB.BASEBOARD_FAB2(SCH_1):PAGE76
     2    GND @BASEBOARD_FAB2_LIB.BASEBOARD_FAB2(SCH_1):GND   I206 @BASEBOARD_FAB2_LIB.BASEBOARD_FAB2(SCH_1):PAGE76

C7P17 CAP_0805-47UF,4V,20%,X6S,C9533A
     1 PVCCIO_CPU1 @BASEBOARD_FAB2_LIB.BASEBOARD_FAB2(SCH_1):PVCCIO_CPU1    I29 @BASEBOARD_FAB2_LIB.BASEBOARD_FAB2(SCH_1):PAGE76
     2    GND @BASEBOARD_FAB2_LIB.BASEBOARD_FAB2(SCH_1):GND    I29 @BASEBOARD_FAB2_LIB.BASEBOARD_FAB2(SCH_1):PAGE76

C7P18 CAP_0805-47UF,4V,20%,X6S,C9533A
     1 PVCCIO_CPU1 @BASEBOARD_FAB2_LIB.BASEBOARD_FAB2(SCH_1):PVCCIO_CPU1    I51 @BASEBOARD_FAB2_LIB.BASEBOARD_FAB2(SCH_1):PAGE76
     2    GND @BASEBOARD_FAB2_LIB.BASEBOARD_FAB2(SCH_1):GND    I51 @BASEBOARD_FAB2_LIB.BASEBOARD_FAB2(SCH_1):PAGE76

C7P19 CAP_0805-47UF,4V,20%,X6S,C9533A
     1 PVCCIN_CPU1 @BASEBOARD_FAB2_LIB.BASEBOARD_FAB2(SCH_1):PVCCIN_CPU1   I215 @BASEBOARD_FAB2_LIB.BASEBOARD_FAB2(SCH_1):PAGE76
     2    GND @BASEBOARD_FAB2_LIB.BASEBOARD_FAB2(SCH_1):GND   I215 @BASEBOARD_FAB2_LIB.BASEBOARD_FAB2(SCH_1):PAGE76

C7P20 CAP_0805-100UF,4V,20%,X5R,6024A
     1 PVDDQ_GHJ @BASEBOARD_FAB2_LIB.BASEBOARD_FAB2(SCH_1):PVDDQ_GHJ   I318 @BASEBOARD_FAB2_LIB.BASEBOARD_FAB2(SCH_1):PAGE225
     2    GND @BASEBOARD_FAB2_LIB.BASEBOARD_FAB2(SCH_1):GND   I318 @BASEBOARD_FAB2_LIB.BASEBOARD_FAB2(SCH_1):PAGE225

C7R1 CAP_A_0603V-22.0UF,4V,20%,X6S,A
     1 PVCCIO_CPU1 @BASEBOARD_FAB2_LIB.BASEBOARD_FAB2(SCH_1):PVCCIO_CPU1    I65 @BASEBOARD_FAB2_LIB.BASEBOARD_FAB2(SCH_1):PAGE214
     2    GND @BASEBOARD_FAB2_LIB.BASEBOARD_FAB2(SCH_1):GND    I65 @BASEBOARD_FAB2_LIB.BASEBOARD_FAB2(SCH_1):PAGE214

C7T1 CAP_0805-100UF,4V,20%,X5R,6024A
     1 PVDDQ_GHJ @BASEBOARD_FAB2_LIB.BASEBOARD_FAB2(SCH_1):PVDDQ_GHJ   I309 @BASEBOARD_FAB2_LIB.BASEBOARD_FAB2(SCH_1):PAGE225
     2    GND @BASEBOARD_FAB2_LIB.BASEBOARD_FAB2(SCH_1):GND   I309 @BASEBOARD_FAB2_LIB.BASEBOARD_FAB2(SCH_1):PAGE225

C7T2 CAP_0603LF-10UF,4V,20%,X6S,E15A
     1 PVPP_GHJ @BASEBOARD_FAB2_LIB.BASEBOARD_FAB2(SCH_1):PVPP_GHJ   I112 @BASEBOARD_FAB2_LIB.BASEBOARD_FAB2(SCH_1):PAGE233
     2    GND @BASEBOARD_FAB2_LIB.BASEBOARD_FAB2(SCH_1):GND   I112 @BASEBOARD_FAB2_LIB.BASEBOARD_FAB2(SCH_1):PAGE233

C7T3 CAP_0603LF-10UF,4V,20%,X6S,E15A
     1 PVPP_GHJ @BASEBOARD_FAB2_LIB.BASEBOARD_FAB2(SCH_1):PVPP_GHJ   I113 @BASEBOARD_FAB2_LIB.BASEBOARD_FAB2(SCH_1):PAGE233
     2    GND @BASEBOARD_FAB2_LIB.BASEBOARD_FAB2(SCH_1):GND   I113 @BASEBOARD_FAB2_LIB.BASEBOARD_FAB2(SCH_1):PAGE233

C7T4 CAP_A_0603V-47UF,4V,20%,X5R,60A
     1 PVDDQ_GHJ @BASEBOARD_FAB2_LIB.BASEBOARD_FAB2(SCH_1):PVDDQ_GHJ   I295 @BASEBOARD_FAB2_LIB.BASEBOARD_FAB2(SCH_1):PAGE225
     2    GND @BASEBOARD_FAB2_LIB.BASEBOARD_FAB2(SCH_1):GND   I295 @BASEBOARD_FAB2_LIB.BASEBOARD_FAB2(SCH_1):PAGE225

C7T5 CAP_A_0603V-47UF,4V,20%,X5R,60A
     1 PVDDQ_GHJ @BASEBOARD_FAB2_LIB.BASEBOARD_FAB2(SCH_1):PVDDQ_GHJ   I296 @BASEBOARD_FAB2_LIB.BASEBOARD_FAB2(SCH_1):PAGE225
     2    GND @BASEBOARD_FAB2_LIB.BASEBOARD_FAB2(SCH_1):GND   I296 @BASEBOARD_FAB2_LIB.BASEBOARD_FAB2(SCH_1):PAGE225

C7U1 CAP_A_0603V-47UF,4V,20%,X5R,60A
     1 PVDDQ_GHJ @BASEBOARD_FAB2_LIB.BASEBOARD_FAB2(SCH_1):PVDDQ_GHJ   I293 @BASEBOARD_FAB2_LIB.BASEBOARD_FAB2(SCH_1):PAGE225
     2    GND @BASEBOARD_FAB2_LIB.BASEBOARD_FAB2(SCH_1):GND   I293 @BASEBOARD_FAB2_LIB.BASEBOARD_FAB2(SCH_1):PAGE225

C7U2 CAP_A_0603V-47UF,4V,20%,X5R,60A
     1 PVDDQ_GHJ @BASEBOARD_FAB2_LIB.BASEBOARD_FAB2(SCH_1):PVDDQ_GHJ   I292 @BASEBOARD_FAB2_LIB.BASEBOARD_FAB2(SCH_1):PAGE225
     2    GND @BASEBOARD_FAB2_LIB.BASEBOARD_FAB2(SCH_1):GND   I292 @BASEBOARD_FAB2_LIB.BASEBOARD_FAB2(SCH_1):PAGE225

C7U3 CAP_0603LF-10UF,4V,20%,X6S,E15A
     1 PVPP_GHJ @BASEBOARD_FAB2_LIB.BASEBOARD_FAB2(SCH_1):PVPP_GHJ   I136 @BASEBOARD_FAB2_LIB.BASEBOARD_FAB2(SCH_1):PAGE233
     2    GND @BASEBOARD_FAB2_LIB.BASEBOARD_FAB2(SCH_1):GND   I136 @BASEBOARD_FAB2_LIB.BASEBOARD_FAB2(SCH_1):PAGE233

C7U4 CAP_0603LF-10UF,4V,20%,X6S,E15A
     1 PVPP_GHJ @BASEBOARD_FAB2_LIB.BASEBOARD_FAB2(SCH_1):PVPP_GHJ   I109 @BASEBOARD_FAB2_LIB.BASEBOARD_FAB2(SCH_1):PAGE233
     2    GND @BASEBOARD_FAB2_LIB.BASEBOARD_FAB2(SCH_1):GND   I109 @BASEBOARD_FAB2_LIB.BASEBOARD_FAB2(SCH_1):PAGE233

C7U5 CAP_0603LF-10UF,4V,20%,X6S,E15A
     1 PVPP_GHJ @BASEBOARD_FAB2_LIB.BASEBOARD_FAB2(SCH_1):PVPP_GHJ   I111 @BASEBOARD_FAB2_LIB.BASEBOARD_FAB2(SCH_1):PAGE233
     2    GND @BASEBOARD_FAB2_LIB.BASEBOARD_FAB2(SCH_1):GND   I111 @BASEBOARD_FAB2_LIB.BASEBOARD_FAB2(SCH_1):PAGE233

C7U6 CAP_0603LF-10UF,4V,20%,X6S,E15A
     1 PVPP_GHJ @BASEBOARD_FAB2_LIB.BASEBOARD_FAB2(SCH_1):PVPP_GHJ   I115 @BASEBOARD_FAB2_LIB.BASEBOARD_FAB2(SCH_1):PAGE233
     2    GND @BASEBOARD_FAB2_LIB.BASEBOARD_FAB2(SCH_1):GND   I115 @BASEBOARD_FAB2_LIB.BASEBOARD_FAB2(SCH_1):PAGE233

C7U7 CAP_0805-100UF,4V,20%,X5R,6024A
     1 PVDDQ_GHJ @BASEBOARD_FAB2_LIB.BASEBOARD_FAB2(SCH_1):PVDDQ_GHJ   I308 @BASEBOARD_FAB2_LIB.BASEBOARD_FAB2(SCH_1):PAGE225
     2    GND @BASEBOARD_FAB2_LIB.BASEBOARD_FAB2(SCH_1):GND   I308 @BASEBOARD_FAB2_LIB.BASEBOARD_FAB2(SCH_1):PAGE225

C7W1 CAP_A_0402V-0.1UF,16V,10%,X7R,A
     1 P3V3_STBY @BASEBOARD_FAB2_LIB.BASEBOARD_FAB2(SCH_1):P3V3_STBY    I36 @BASEBOARD_FAB2_LIB.BASEBOARD_FAB2(SCH_1):PAGE166
     2    GND @BASEBOARD_FAB2_LIB.BASEBOARD_FAB2(SCH_1):GND    I36 @BASEBOARD_FAB2_LIB.BASEBOARD_FAB2(SCH_1):PAGE166

C7W2 SE100U16VM-48-GP_SMD-TCG2-SE10A
     1 VR_FET_SW_P12V_STBY_PVDDQ_DEF @BASEBOARD_FAB2_LIB.BASEBOARD_FAB2(SCH_1):VR_FET_SW_P12V_STBY_PVDDQ_DEF   I324 @BASEBOARD_FAB2_LIB.BASEBOARD_FAB2(SCH_1):PAGE220
     2    GND @BASEBOARD_FAB2_LIB.BASEBOARD_FAB2(SCH_1):GND   I324 @BASEBOARD_FAB2_LIB.BASEBOARD_FAB2(SCH_1):PAGE220

C7W5 SC22U16V5MX-4-GP_SMD-BCG5-SC22A
     1 VR_FET_SW_P12V_STBY_PVDDQ_DEF @BASEBOARD_FAB2_LIB.BASEBOARD_FAB2(SCH_1):VR_FET_SW_P12V_STBY_PVDDQ_DEF   I298 @BASEBOARD_FAB2_LIB.BASEBOARD_FAB2(SCH_1):PAGE220
     2    GND @BASEBOARD_FAB2_LIB.BASEBOARD_FAB2(SCH_1):GND   I298 @BASEBOARD_FAB2_LIB.BASEBOARD_FAB2(SCH_1):PAGE220

C7W6 SC22U16V5MX-4-GP_SMD-BCG5-SC22A
     1 VR_FET_SW_P12V_STBY_PVDDQ_DEF @BASEBOARD_FAB2_LIB.BASEBOARD_FAB2(SCH_1):VR_FET_SW_P12V_STBY_PVDDQ_DEF   I302 @BASEBOARD_FAB2_LIB.BASEBOARD_FAB2(SCH_1):PAGE220
     2    GND @BASEBOARD_FAB2_LIB.BASEBOARD_FAB2(SCH_1):GND   I302 @BASEBOARD_FAB2_LIB.BASEBOARD_FAB2(SCH_1):PAGE220

C7W7 SC22U16V5MX-4-GP_SMD-BCG5-SC22A
     1 VR_FET_SW_P12V_STBY_PVDDQ_DEF @BASEBOARD_FAB2_LIB.BASEBOARD_FAB2(SCH_1):VR_FET_SW_P12V_STBY_PVDDQ_DEF   I301 @BASEBOARD_FAB2_LIB.BASEBOARD_FAB2(SCH_1):PAGE220
     2    GND @BASEBOARD_FAB2_LIB.BASEBOARD_FAB2(SCH_1):GND   I301 @BASEBOARD_FAB2_LIB.BASEBOARD_FAB2(SCH_1):PAGE220

C7W8 SC22U16V5MX-4-GP_SMD-BCG5-SC22A
     1 VR_FET_SW_P12V_STBY_PVDDQ_DEF @BASEBOARD_FAB2_LIB.BASEBOARD_FAB2(SCH_1):VR_FET_SW_P12V_STBY_PVDDQ_DEF   I300 @BASEBOARD_FAB2_LIB.BASEBOARD_FAB2(SCH_1):PAGE220
     2    GND @BASEBOARD_FAB2_LIB.BASEBOARD_FAB2(SCH_1):GND   I300 @BASEBOARD_FAB2_LIB.BASEBOARD_FAB2(SCH_1):PAGE220

C7W9 SC22U16V5MX-4-GP_SMD-BCG5-SC22A
     1 VR_FET_SW_P12V_STBY_PVDDQ_DEF @BASEBOARD_FAB2_LIB.BASEBOARD_FAB2(SCH_1):VR_FET_SW_P12V_STBY_PVDDQ_DEF   I299 @BASEBOARD_FAB2_LIB.BASEBOARD_FAB2(SCH_1):PAGE220
     2    GND @BASEBOARD_FAB2_LIB.BASEBOARD_FAB2(SCH_1):GND   I299 @BASEBOARD_FAB2_LIB.BASEBOARD_FAB2(SCH_1):PAGE220

C7W10 SC22U16V5MX-4-GP_SMD-BCG5-SC22A
     1 VR_FET_SW_P12V_STBY_PVDDQ_DEF @BASEBOARD_FAB2_LIB.BASEBOARD_FAB2(SCH_1):VR_FET_SW_P12V_STBY_PVDDQ_DEF   I306 @BASEBOARD_FAB2_LIB.BASEBOARD_FAB2(SCH_1):PAGE220
     2    GND @BASEBOARD_FAB2_LIB.BASEBOARD_FAB2(SCH_1):GND   I306 @BASEBOARD_FAB2_LIB.BASEBOARD_FAB2(SCH_1):PAGE220

C7W11 SC22U16V5MX-4-GP_SMD-BCG5-SC22A
     1 VR_FET_SW_P12V_STBY_PVDDQ_DEF @BASEBOARD_FAB2_LIB.BASEBOARD_FAB2(SCH_1):VR_FET_SW_P12V_STBY_PVDDQ_DEF   I305 @BASEBOARD_FAB2_LIB.BASEBOARD_FAB2(SCH_1):PAGE220
     2    GND @BASEBOARD_FAB2_LIB.BASEBOARD_FAB2(SCH_1):GND   I305 @BASEBOARD_FAB2_LIB.BASEBOARD_FAB2(SCH_1):PAGE220

C7W12 SC22U16V5MX-4-GP_SMD-BCG5-SC22A
     1 VR_FET_SW_P12V_STBY_PVDDQ_DEF @BASEBOARD_FAB2_LIB.BASEBOARD_FAB2(SCH_1):VR_FET_SW_P12V_STBY_PVDDQ_DEF   I304 @BASEBOARD_FAB2_LIB.BASEBOARD_FAB2(SCH_1):PAGE220
     2    GND @BASEBOARD_FAB2_LIB.BASEBOARD_FAB2(SCH_1):GND   I304 @BASEBOARD_FAB2_LIB.BASEBOARD_FAB2(SCH_1):PAGE220

C7W13 SC22U16V5MX-4-GP_SMD-BCG5-SC22A
     1 VR_FET_SW_P12V_STBY_PVDDQ_DEF @BASEBOARD_FAB2_LIB.BASEBOARD_FAB2(SCH_1):VR_FET_SW_P12V_STBY_PVDDQ_DEF   I303 @BASEBOARD_FAB2_LIB.BASEBOARD_FAB2(SCH_1):PAGE220
     2    GND @BASEBOARD_FAB2_LIB.BASEBOARD_FAB2(SCH_1):GND   I303 @BASEBOARD_FAB2_LIB.BASEBOARD_FAB2(SCH_1):PAGE220

C8A2 CAP_0402LF-220PF,50V,10%,X7R,AA
     1 VR_PVNN_PCH_AVSP @BASEBOARD_FAB2_LIB.BASEBOARD_FAB2(SCH_1):VR_PVNN_PCH_AVSP   I209 @BASEBOARD_FAB2_LIB.BASEBOARD_FAB2(SCH_1):PAGE235
     2 VSENSE_PVNN_PCH_STBY_AVSN @BASEBOARD_FAB2_LIB.BASEBOARD_FAB2(SCH_1):VSENSE_PVNN_PCH_STBY_AVSN   I209 @BASEBOARD_FAB2_LIB.BASEBOARD_FAB2(SCH_1):PAGE235

C8A3 CAP_A_0402V-0.1UF,16V,10%,X7R,A
     1 VR_PVNN_PCH_VINSEN @BASEBOARD_FAB2_LIB.BASEBOARD_FAB2(SCH_1):VR_PVNN_PCH_VINSEN   I255 @BASEBOARD_FAB2_LIB.BASEBOARD_FAB2(SCH_1):PAGE235
     2    GND @BASEBOARD_FAB2_LIB.BASEBOARD_FAB2(SCH_1):GND   I255 @BASEBOARD_FAB2_LIB.BASEBOARD_FAB2(SCH_1):PAGE235

C8A4 CAP_0603LF-0.1UF,25V,10%,X7R,6A
     1 P3V3_STBY @BASEBOARD_FAB2_LIB.BASEBOARD_FAB2(SCH_1):P3V3_STBY    I31 @BASEBOARD_FAB2_LIB.BASEBOARD_FAB2(SCH_1):PAGE237
     2    GND @BASEBOARD_FAB2_LIB.BASEBOARD_FAB2(SCH_1):GND    I31 @BASEBOARD_FAB2_LIB.BASEBOARD_FAB2(SCH_1):PAGE237

C8A6 CAP_0603-10UF,6.3V,20%,X6S,E15A
     1 P3V3_STBY @BASEBOARD_FAB2_LIB.BASEBOARD_FAB2(SCH_1):P3V3_STBY    I29 @BASEBOARD_FAB2_LIB.BASEBOARD_FAB2(SCH_1):PAGE237
     2    GND @BASEBOARD_FAB2_LIB.BASEBOARD_FAB2(SCH_1):GND    I29 @BASEBOARD_FAB2_LIB.BASEBOARD_FAB2(SCH_1):PAGE237

C8A7 CAP_A_0402V-1.0UF,6.3V,10%,X6SA
     1 VR_PVNN_P1V05_PCH_VD12 @BASEBOARD_FAB2_LIB.BASEBOARD_FAB2(SCH_1):VR_PVNN_P1V05_PCH_VD12   I143 @BASEBOARD_FAB2_LIB.BASEBOARD_FAB2(SCH_1):PAGE235
     2    GND @BASEBOARD_FAB2_LIB.BASEBOARD_FAB2(SCH_1):GND   I143 @BASEBOARD_FAB2_LIB.BASEBOARD_FAB2(SCH_1):PAGE235

C8A8 CAP_A_0402V-0.1UF,16V,10%,X7R,A
     1 VR_PVNN_P1V05_PCH_VD12 @BASEBOARD_FAB2_LIB.BASEBOARD_FAB2(SCH_1):VR_PVNN_P1V05_PCH_VD12   I145 @BASEBOARD_FAB2_LIB.BASEBOARD_FAB2(SCH_1):PAGE235
     2    GND @BASEBOARD_FAB2_LIB.BASEBOARD_FAB2(SCH_1):GND   I145 @BASEBOARD_FAB2_LIB.BASEBOARD_FAB2(SCH_1):PAGE235

C8A9 CAP_0402LF-1000PF,50V,10%,X7R,A
     1 PWRGD_PVNN_PCH_R @BASEBOARD_FAB2_LIB.BASEBOARD_FAB2(SCH_1):PWRGD_PVNN_PCH_R   I218 @BASEBOARD_FAB2_LIB.BASEBOARD_FAB2(SCH_1):PAGE235
     2    GND @BASEBOARD_FAB2_LIB.BASEBOARD_FAB2(SCH_1):GND   I218 @BASEBOARD_FAB2_LIB.BASEBOARD_FAB2(SCH_1):PAGE235

C8A10 CAP_0402LF-1000PF,50V,10%,EMPTA
     1 PWRGD_P3V3_STBY @BASEBOARD_FAB2_LIB.BASEBOARD_FAB2(SCH_1):PWRGD_P3V3_STBY    I55 @BASEBOARD_FAB2_LIB.BASEBOARD_FAB2(SCH_1):PAGE237
     2    GND @BASEBOARD_FAB2_LIB.BASEBOARD_FAB2(SCH_1):GND    I55 @BASEBOARD_FAB2_LIB.BASEBOARD_FAB2(SCH_1):PAGE237

C8A11 CAP_0402LF-1000PF,50V,10%,X7R,A
     1 PWRGD_P1V8_PCH_STBY_R @BASEBOARD_FAB2_LIB.BASEBOARD_FAB2(SCH_1):PWRGD_P1V8_PCH_STBY_R     I5 @BASEBOARD_FAB2_LIB.BASEBOARD_FAB2(SCH_1):PAGE237
     2    GND @BASEBOARD_FAB2_LIB.BASEBOARD_FAB2(SCH_1):GND     I5 @BASEBOARD_FAB2_LIB.BASEBOARD_FAB2(SCH_1):PAGE237

C8A12 CAP_0805-47UF,4V,20%,X6S,C9533A
     1 P1V8_PCH_STBY @BASEBOARD_FAB2_LIB.BASEBOARD_FAB2(SCH_1):P1V8_PCH_STBY    I77 @BASEBOARD_FAB2_LIB.BASEBOARD_FAB2(SCH_1):PAGE237
     2    GND @BASEBOARD_FAB2_LIB.BASEBOARD_FAB2(SCH_1):GND    I77 @BASEBOARD_FAB2_LIB.BASEBOARD_FAB2(SCH_1):PAGE237

C8A13 CAP_0805-47UF,4V,20%,X6S,C9533A
     1 P1V05_PCH_STBY @BASEBOARD_FAB2_LIB.BASEBOARD_FAB2(SCH_1):P1V05_PCH_STBY    I37 @BASEBOARD_FAB2_LIB.BASEBOARD_FAB2(SCH_1):PAGE131
     2    GND @BASEBOARD_FAB2_LIB.BASEBOARD_FAB2(SCH_1):GND    I37 @BASEBOARD_FAB2_LIB.BASEBOARD_FAB2(SCH_1):PAGE131

C8A14 CAP_0805-22UF,6.3V,20%,X6S,C95A
     1 P1V8_PCH_STBY @BASEBOARD_FAB2_LIB.BASEBOARD_FAB2(SCH_1):P1V8_PCH_STBY    I13 @BASEBOARD_FAB2_LIB.BASEBOARD_FAB2(SCH_1):PAGE237
     2    GND @BASEBOARD_FAB2_LIB.BASEBOARD_FAB2(SCH_1):GND    I13 @BASEBOARD_FAB2_LIB.BASEBOARD_FAB2(SCH_1):PAGE237

C8A15 CAPP_SM-470UF,2V,20%,ALUM,6990A
     1 P1V05_PCH_STBY @BASEBOARD_FAB2_LIB.BASEBOARD_FAB2(SCH_1):P1V05_PCH_STBY    I78 @BASEBOARD_FAB2_LIB.BASEBOARD_FAB2(SCH_1):PAGE236
     2    GND @BASEBOARD_FAB2_LIB.BASEBOARD_FAB2(SCH_1):GND    I78 @BASEBOARD_FAB2_LIB.BASEBOARD_FAB2(SCH_1):PAGE236

C8B1 CAP_A_0603V-22.0UF,4V,20%,X6S,A
     1 P1V8_PCH_STBY @BASEBOARD_FAB2_LIB.BASEBOARD_FAB2(SCH_1):P1V8_PCH_STBY    I41 @BASEBOARD_FAB2_LIB.BASEBOARD_FAB2(SCH_1):PAGE130
     2    GND @BASEBOARD_FAB2_LIB.BASEBOARD_FAB2(SCH_1):GND    I41 @BASEBOARD_FAB2_LIB.BASEBOARD_FAB2(SCH_1):PAGE130

C8B2 CAP_A_0603V-22.0UF,4V,20%,X6S,A
     1 P1V8_PCH_STBY @BASEBOARD_FAB2_LIB.BASEBOARD_FAB2(SCH_1):P1V8_PCH_STBY    I30 @BASEBOARD_FAB2_LIB.BASEBOARD_FAB2(SCH_1):PAGE130
     2    GND @BASEBOARD_FAB2_LIB.BASEBOARD_FAB2(SCH_1):GND    I30 @BASEBOARD_FAB2_LIB.BASEBOARD_FAB2(SCH_1):PAGE130

C8B3 CAP_A_0603V-22.0UF,4V,20%,X6S,A
     1 P1V8_PCH_STBY @BASEBOARD_FAB2_LIB.BASEBOARD_FAB2(SCH_1):P1V8_PCH_STBY    I32 @BASEBOARD_FAB2_LIB.BASEBOARD_FAB2(SCH_1):PAGE130
     2    GND @BASEBOARD_FAB2_LIB.BASEBOARD_FAB2(SCH_1):GND    I32 @BASEBOARD_FAB2_LIB.BASEBOARD_FAB2(SCH_1):PAGE130

C8B4 CAP_A_0603V-22.0UF,4V,20%,X6S,A
     1 P1V8_PCH_STBY @BASEBOARD_FAB2_LIB.BASEBOARD_FAB2(SCH_1):P1V8_PCH_STBY    I39 @BASEBOARD_FAB2_LIB.BASEBOARD_FAB2(SCH_1):PAGE130
     2    GND @BASEBOARD_FAB2_LIB.BASEBOARD_FAB2(SCH_1):GND    I39 @BASEBOARD_FAB2_LIB.BASEBOARD_FAB2(SCH_1):PAGE130

C8B5 CAP_A_0402V-0.1UF,16V,10%,X7R,A
     1 P5V_STBY @BASEBOARD_FAB2_LIB.BASEBOARD_FAB2(SCH_1):P5V_STBY    I37 @BASEBOARD_FAB2_LIB.BASEBOARD_FAB2(SCH_1):PAGE198
     2    GND @BASEBOARD_FAB2_LIB.BASEBOARD_FAB2(SCH_1):GND    I37 @BASEBOARD_FAB2_LIB.BASEBOARD_FAB2(SCH_1):PAGE198

C8B6 CAP_0805-10UF,16V,10%,X6S,C953A
     1    P5V @BASEBOARD_FAB2_LIB.BASEBOARD_FAB2(SCH_1):P5V    I40 @BASEBOARD_FAB2_LIB.BASEBOARD_FAB2(SCH_1):PAGE198
     2    GND @BASEBOARD_FAB2_LIB.BASEBOARD_FAB2(SCH_1):GND    I40 @BASEBOARD_FAB2_LIB.BASEBOARD_FAB2(SCH_1):PAGE198

C8B7 CAP_A_0402V-0.1UF,16V,10%,X7R,A
     1    P5V @BASEBOARD_FAB2_LIB.BASEBOARD_FAB2(SCH_1):P5V    I41 @BASEBOARD_FAB2_LIB.BASEBOARD_FAB2(SCH_1):PAGE198
     2    GND @BASEBOARD_FAB2_LIB.BASEBOARD_FAB2(SCH_1):GND    I41 @BASEBOARD_FAB2_LIB.BASEBOARD_FAB2(SCH_1):PAGE198

C8B8 CAP_A_0402V-0.1UF,16V,10%,X7R,A
     1 P5V_STBY @BASEBOARD_FAB2_LIB.BASEBOARD_FAB2(SCH_1):P5V_STBY    I26 @BASEBOARD_FAB2_LIB.BASEBOARD_FAB2(SCH_1):PAGE198
     2    GND @BASEBOARD_FAB2_LIB.BASEBOARD_FAB2(SCH_1):GND    I26 @BASEBOARD_FAB2_LIB.BASEBOARD_FAB2(SCH_1):PAGE198

C8B9 CAP_A_0603V-22.0UF,4V,20%,X6S,A
     1 P1V05_PCH_STBY @BASEBOARD_FAB2_LIB.BASEBOARD_FAB2(SCH_1):P1V05_PCH_STBY    I14 @BASEBOARD_FAB2_LIB.BASEBOARD_FAB2(SCH_1):PAGE131
     2    GND @BASEBOARD_FAB2_LIB.BASEBOARD_FAB2(SCH_1):GND    I14 @BASEBOARD_FAB2_LIB.BASEBOARD_FAB2(SCH_1):PAGE131

C8B10 CAP_A_0603V-22.0UF,4V,20%,X6S,A
     1 P1V05_PCH_STBY @BASEBOARD_FAB2_LIB.BASEBOARD_FAB2(SCH_1):P1V05_PCH_STBY     I8 @BASEBOARD_FAB2_LIB.BASEBOARD_FAB2(SCH_1):PAGE131
     2    GND @BASEBOARD_FAB2_LIB.BASEBOARD_FAB2(SCH_1):GND     I8 @BASEBOARD_FAB2_LIB.BASEBOARD_FAB2(SCH_1):PAGE131

C8B11 CAP_A_0603V-22.0UF,4V,20%,X6S,A
     1 P1V05_PCH_STBY @BASEBOARD_FAB2_LIB.BASEBOARD_FAB2(SCH_1):P1V05_PCH_STBY    I15 @BASEBOARD_FAB2_LIB.BASEBOARD_FAB2(SCH_1):PAGE131
     2    GND @BASEBOARD_FAB2_LIB.BASEBOARD_FAB2(SCH_1):GND    I15 @BASEBOARD_FAB2_LIB.BASEBOARD_FAB2(SCH_1):PAGE131

C8B12 CAP_0805-10UF,16V,10%,X6S,C953A
     1 P5V_STBY @BASEBOARD_FAB2_LIB.BASEBOARD_FAB2(SCH_1):P5V_STBY    I38 @BASEBOARD_FAB2_LIB.BASEBOARD_FAB2(SCH_1):PAGE198
     2    GND @BASEBOARD_FAB2_LIB.BASEBOARD_FAB2(SCH_1):GND    I38 @BASEBOARD_FAB2_LIB.BASEBOARD_FAB2(SCH_1):PAGE198

C8B13 CAP_A_0603V-22.0UF,4V,20%,X6S,A
     1 P1V05_PCH_STBY @BASEBOARD_FAB2_LIB.BASEBOARD_FAB2(SCH_1):P1V05_PCH_STBY    I20 @BASEBOARD_FAB2_LIB.BASEBOARD_FAB2(SCH_1):PAGE131
     2    GND @BASEBOARD_FAB2_LIB.BASEBOARD_FAB2(SCH_1):GND    I20 @BASEBOARD_FAB2_LIB.BASEBOARD_FAB2(SCH_1):PAGE131

C8B14 CAP_A_0603V-22.0UF,4V,20%,X6S,A
     1 P1V05_PCH_STBY @BASEBOARD_FAB2_LIB.BASEBOARD_FAB2(SCH_1):P1V05_PCH_STBY    I16 @BASEBOARD_FAB2_LIB.BASEBOARD_FAB2(SCH_1):PAGE131
     2    GND @BASEBOARD_FAB2_LIB.BASEBOARD_FAB2(SCH_1):GND    I16 @BASEBOARD_FAB2_LIB.BASEBOARD_FAB2(SCH_1):PAGE131

C8B15 CAP_0805-47UF,4V,20%,X6S,C9533A
     1 P1V05_PCH_STBY @BASEBOARD_FAB2_LIB.BASEBOARD_FAB2(SCH_1):P1V05_PCH_STBY    I24 @BASEBOARD_FAB2_LIB.BASEBOARD_FAB2(SCH_1):PAGE131
     2    GND @BASEBOARD_FAB2_LIB.BASEBOARD_FAB2(SCH_1):GND    I24 @BASEBOARD_FAB2_LIB.BASEBOARD_FAB2(SCH_1):PAGE131

C8B16 CAP_0805-47UF,4V,20%,X6S,C9533A
     1 P1V05_PCH_STBY @BASEBOARD_FAB2_LIB.BASEBOARD_FAB2(SCH_1):P1V05_PCH_STBY    I22 @BASEBOARD_FAB2_LIB.BASEBOARD_FAB2(SCH_1):PAGE131
     2    GND @BASEBOARD_FAB2_LIB.BASEBOARD_FAB2(SCH_1):GND    I22 @BASEBOARD_FAB2_LIB.BASEBOARD_FAB2(SCH_1):PAGE131

C8C1 CAP_0402LF-33.0PF,50V,5%,COG,AA
     1 XTAL_KR_25M_IN @BASEBOARD_FAB2_LIB.BASEBOARD_FAB2(SCH_1):XTAL_KR_25M_IN   I178 @BASEBOARD_FAB2_LIB.BASEBOARD_FAB2(SCH_1):PAGE118
     2    GND @BASEBOARD_FAB2_LIB.BASEBOARD_FAB2(SCH_1):GND   I178 @BASEBOARD_FAB2_LIB.BASEBOARD_FAB2(SCH_1):PAGE118

C8C2 CAP_0402LF-33.0PF,50V,5%,COG,AA
     1 XTAL_KR_25M_OUT @BASEBOARD_FAB2_LIB.BASEBOARD_FAB2(SCH_1):XTAL_KR_25M_OUT   I179 @BASEBOARD_FAB2_LIB.BASEBOARD_FAB2(SCH_1):PAGE118
     2    GND @BASEBOARD_FAB2_LIB.BASEBOARD_FAB2(SCH_1):GND   I179 @BASEBOARD_FAB2_LIB.BASEBOARD_FAB2(SCH_1):PAGE118

C8C3 CAP_0603-10UF,6.3V,20%,X6S,E15A
     1 P3V3_STBY @BASEBOARD_FAB2_LIB.BASEBOARD_FAB2(SCH_1):P3V3_STBY    I19 @BASEBOARD_FAB2_LIB.BASEBOARD_FAB2(SCH_1):PAGE130
     2    GND @BASEBOARD_FAB2_LIB.BASEBOARD_FAB2(SCH_1):GND    I19 @BASEBOARD_FAB2_LIB.BASEBOARD_FAB2(SCH_1):PAGE130

C8C4 CAP_0603-10UF,6.3V,20%,X6S,E15A
     1 P3V3_STBY @BASEBOARD_FAB2_LIB.BASEBOARD_FAB2(SCH_1):P3V3_STBY    I20 @BASEBOARD_FAB2_LIB.BASEBOARD_FAB2(SCH_1):PAGE130
     2    GND @BASEBOARD_FAB2_LIB.BASEBOARD_FAB2(SCH_1):GND    I20 @BASEBOARD_FAB2_LIB.BASEBOARD_FAB2(SCH_1):PAGE130

C8C5 CAP_0603-10UF,6.3V,20%,X6S,E15A
     1 P3V3_STBY @BASEBOARD_FAB2_LIB.BASEBOARD_FAB2(SCH_1):P3V3_STBY    I21 @BASEBOARD_FAB2_LIB.BASEBOARD_FAB2(SCH_1):PAGE130
     2    GND @BASEBOARD_FAB2_LIB.BASEBOARD_FAB2(SCH_1):GND    I21 @BASEBOARD_FAB2_LIB.BASEBOARD_FAB2(SCH_1):PAGE130

C8C6 CAP_0603-10UF,6.3V,20%,X6S,E15A
     1 P3V3_STBY @BASEBOARD_FAB2_LIB.BASEBOARD_FAB2(SCH_1):P3V3_STBY    I22 @BASEBOARD_FAB2_LIB.BASEBOARD_FAB2(SCH_1):PAGE130
     2    GND @BASEBOARD_FAB2_LIB.BASEBOARD_FAB2(SCH_1):GND    I22 @BASEBOARD_FAB2_LIB.BASEBOARD_FAB2(SCH_1):PAGE130

C8C12 CAP_A_0402V-0.1UF,16V,10%,X7R,A
     1 KR_P1_OCP_RX_DP @BASEBOARD_FAB2_LIB.BASEBOARD_FAB2(SCH_1):KR_P1_OCP_RX_DP   I121 @BASEBOARD_FAB2_LIB.BASEBOARD_FAB2(SCH_1):PAGE188
     2 KR_P1_OCP_RX_C_DP @BASEBOARD_FAB2_LIB.BASEBOARD_FAB2(SCH_1):KR_P1_OCP_RX_C_DP   I121 @BASEBOARD_FAB2_LIB.BASEBOARD_FAB2(SCH_1):PAGE188

C8C13 CAP_A_0402V-0.1UF,16V,10%,X7R,A
     1 KR_P1_OCP_RX_DN @BASEBOARD_FAB2_LIB.BASEBOARD_FAB2(SCH_1):KR_P1_OCP_RX_DN   I120 @BASEBOARD_FAB2_LIB.BASEBOARD_FAB2(SCH_1):PAGE188
     2 KR_P1_OCP_RX_C_DN @BASEBOARD_FAB2_LIB.BASEBOARD_FAB2(SCH_1):KR_P1_OCP_RX_C_DN   I120 @BASEBOARD_FAB2_LIB.BASEBOARD_FAB2(SCH_1):PAGE188

C8C14 CAP_A_0402V-0.1UF,16V,10%,X7R,A
     1 KR_P0_OCP_RX_DN @BASEBOARD_FAB2_LIB.BASEBOARD_FAB2(SCH_1):KR_P0_OCP_RX_DN    I86 @BASEBOARD_FAB2_LIB.BASEBOARD_FAB2(SCH_1):PAGE188
     2 KR_P0_OCP_RX_C_DN @BASEBOARD_FAB2_LIB.BASEBOARD_FAB2(SCH_1):KR_P0_OCP_RX_C_DN    I86 @BASEBOARD_FAB2_LIB.BASEBOARD_FAB2(SCH_1):PAGE188

C8C15 CAP_A_0402V-0.1UF,16V,10%,X7R,A
     1 KR_P0_OCP_RX_DP @BASEBOARD_FAB2_LIB.BASEBOARD_FAB2(SCH_1):KR_P0_OCP_RX_DP    I82 @BASEBOARD_FAB2_LIB.BASEBOARD_FAB2(SCH_1):PAGE188
     2 KR_P0_OCP_RX_C_DP @BASEBOARD_FAB2_LIB.BASEBOARD_FAB2(SCH_1):KR_P0_OCP_RX_C_DP    I82 @BASEBOARD_FAB2_LIB.BASEBOARD_FAB2(SCH_1):PAGE188

C8D1 CAP_A_0402V-0.1UF,16V,10%,X7R,A
     1 P3V3_STBY @BASEBOARD_FAB2_LIB.BASEBOARD_FAB2(SCH_1):P3V3_STBY   I376 @BASEBOARD_FAB2_LIB.BASEBOARD_FAB2(SCH_1):PAGE157
     2    GND @BASEBOARD_FAB2_LIB.BASEBOARD_FAB2(SCH_1):GND   I376 @BASEBOARD_FAB2_LIB.BASEBOARD_FAB2(SCH_1):PAGE157

C8D2 CAP_A_0402V-0.1UF,16V,10%,X7R,A
     1 P3V3_STBY @BASEBOARD_FAB2_LIB.BASEBOARD_FAB2(SCH_1):P3V3_STBY    I33 @BASEBOARD_FAB2_LIB.BASEBOARD_FAB2(SCH_1):PAGE170
     2    GND @BASEBOARD_FAB2_LIB.BASEBOARD_FAB2(SCH_1):GND    I33 @BASEBOARD_FAB2_LIB.BASEBOARD_FAB2(SCH_1):PAGE170

C8D3 CAP_0402LF-470PF,50V,10%,EMPTYA
     1 IRQ_SML1_PMBUS_ALERT_N @BASEBOARD_FAB2_LIB.BASEBOARD_FAB2(SCH_1):IRQ_SML1_PMBUS_ALERT_N    I42 @BASEBOARD_FAB2_LIB.BASEBOARD_FAB2(SCH_1):PAGE170
     2    GND @BASEBOARD_FAB2_LIB.BASEBOARD_FAB2(SCH_1):GND    I42 @BASEBOARD_FAB2_LIB.BASEBOARD_FAB2(SCH_1):PAGE170

C8D4 CAP_A_0402V-0.1UF,16V,10%,X7R,A
     1 P3V3_STBY @BASEBOARD_FAB2_LIB.BASEBOARD_FAB2(SCH_1):P3V3_STBY   I105 @BASEBOARD_FAB2_LIB.BASEBOARD_FAB2(SCH_1):PAGE196
     2    GND @BASEBOARD_FAB2_LIB.BASEBOARD_FAB2(SCH_1):GND   I105 @BASEBOARD_FAB2_LIB.BASEBOARD_FAB2(SCH_1):PAGE196

C8E1 CAP_A_0402V-0.1UF,16V,10%,X7R,A
     1 P3V3_STBY @BASEBOARD_FAB2_LIB.BASEBOARD_FAB2(SCH_1):P3V3_STBY    I34 @BASEBOARD_FAB2_LIB.BASEBOARD_FAB2(SCH_1):PAGE181
     2    GND @BASEBOARD_FAB2_LIB.BASEBOARD_FAB2(SCH_1):GND    I34 @BASEBOARD_FAB2_LIB.BASEBOARD_FAB2(SCH_1):PAGE181

C8E2 CAP_A_0402V-0.1UF,16V,10%,X7R,A
     1 P3V3_STBY @BASEBOARD_FAB2_LIB.BASEBOARD_FAB2(SCH_1):P3V3_STBY    I40 @BASEBOARD_FAB2_LIB.BASEBOARD_FAB2(SCH_1):PAGE170
     2    GND @BASEBOARD_FAB2_LIB.BASEBOARD_FAB2(SCH_1):GND    I40 @BASEBOARD_FAB2_LIB.BASEBOARD_FAB2(SCH_1):PAGE170

C8E3 CAP_A_0402V-0.1UF,16V,10%,X7R,A
     1 PWRGD_P12V_HSC @BASEBOARD_FAB2_LIB.BASEBOARD_FAB2(SCH_1):PWRGD_P12V_HSC    I94 @BASEBOARD_FAB2_LIB.BASEBOARD_FAB2(SCH_1):PAGE196
     2    GND @BASEBOARD_FAB2_LIB.BASEBOARD_FAB2(SCH_1):GND    I94 @BASEBOARD_FAB2_LIB.BASEBOARD_FAB2(SCH_1):PAGE196

C8E4 ST220U10VDM-LGP_SMD-TCG-ST220UA
     1 P5V_STBY @BASEBOARD_FAB2_LIB.BASEBOARD_FAB2(SCH_1):P5V_STBY   I100 @BASEBOARD_FAB2_LIB.BASEBOARD_FAB2(SCH_1):PAGE241
     2    GND @BASEBOARD_FAB2_LIB.BASEBOARD_FAB2(SCH_1):GND   I100 @BASEBOARD_FAB2_LIB.BASEBOARD_FAB2(SCH_1):PAGE241

C8E5 CAP_A_0402V-0.1UF,16V,10%,X7R,A
     1 P3V3_STBY @BASEBOARD_FAB2_LIB.BASEBOARD_FAB2(SCH_1):P3V3_STBY    I20 @BASEBOARD_FAB2_LIB.BASEBOARD_FAB2(SCH_1):PAGE142
     2    GND @BASEBOARD_FAB2_LIB.BASEBOARD_FAB2(SCH_1):GND    I20 @BASEBOARD_FAB2_LIB.BASEBOARD_FAB2(SCH_1):PAGE142

C8E6 CAP_0603LF-0.1UF,25V,10%,X7R,6A
     1 VR_P5V_STBY_BOOT @BASEBOARD_FAB2_LIB.BASEBOARD_FAB2(SCH_1):VR_P5V_STBY_BOOT    I12 @BASEBOARD_FAB2_LIB.BASEBOARD_FAB2(SCH_1):PAGE241
     2 VR_P5V_STBY_PHASE @BASEBOARD_FAB2_LIB.BASEBOARD_FAB2(SCH_1):VR_P5V_STBY_PHASE    I12 @BASEBOARD_FAB2_LIB.BASEBOARD_FAB2(SCH_1):PAGE241

C8E7 SC22U16V5MX-4-GP_SMD-BCG5-SC22A
     1 P5V_STBY @BASEBOARD_FAB2_LIB.BASEBOARD_FAB2(SCH_1):P5V_STBY   I103 @BASEBOARD_FAB2_LIB.BASEBOARD_FAB2(SCH_1):PAGE241
     2    GND @BASEBOARD_FAB2_LIB.BASEBOARD_FAB2(SCH_1):GND   I103 @BASEBOARD_FAB2_LIB.BASEBOARD_FAB2(SCH_1):PAGE241

C8E8 CAP_A_0402V-0.1UF,16V,10%,X7R,A
     1 P3V3_STBY @BASEBOARD_FAB2_LIB.BASEBOARD_FAB2(SCH_1):P3V3_STBY   I128 @BASEBOARD_FAB2_LIB.BASEBOARD_FAB2(SCH_1):PAGE136
     2    GND @BASEBOARD_FAB2_LIB.BASEBOARD_FAB2(SCH_1):GND   I128 @BASEBOARD_FAB2_LIB.BASEBOARD_FAB2(SCH_1):PAGE136

C8E9 SC22U16V5MX-4-GP_SMD-BCG5-SC22A
     1 P5V_STBY @BASEBOARD_FAB2_LIB.BASEBOARD_FAB2(SCH_1):P5V_STBY   I104 @BASEBOARD_FAB2_LIB.BASEBOARD_FAB2(SCH_1):PAGE241
     2    GND @BASEBOARD_FAB2_LIB.BASEBOARD_FAB2(SCH_1):GND   I104 @BASEBOARD_FAB2_LIB.BASEBOARD_FAB2(SCH_1):PAGE241

C8E10 CAP_1206LF-22UF,16V,10%,X6S,D3A
     1 VR_FET_SW_P12V_STBY_P3V3_STBY @BASEBOARD_FAB2_LIB.BASEBOARD_FAB2(SCH_1):VR_FET_SW_P12V_STBY_P3V3_STBY   I137 @BASEBOARD_FAB2_LIB.BASEBOARD_FAB2(SCH_1):PAGE240
     2    GND @BASEBOARD_FAB2_LIB.BASEBOARD_FAB2(SCH_1):GND   I137 @BASEBOARD_FAB2_LIB.BASEBOARD_FAB2(SCH_1):PAGE240

C8E11 SC22U16V5MX-4-GP_SMD-BCG5-SC22A
     1 VR_FET_SW_P12V_STBY_P3V3_STBY @BASEBOARD_FAB2_LIB.BASEBOARD_FAB2(SCH_1):VR_FET_SW_P12V_STBY_P3V3_STBY   I183 @BASEBOARD_FAB2_LIB.BASEBOARD_FAB2(SCH_1):PAGE240
     2    GND @BASEBOARD_FAB2_LIB.BASEBOARD_FAB2(SCH_1):GND   I183 @BASEBOARD_FAB2_LIB.BASEBOARD_FAB2(SCH_1):PAGE240

C8E12 CAP_0603LF-0.1UF,25V,10%,X7R,6A
     1 VR_P3V3_STBY_PHASE @BASEBOARD_FAB2_LIB.BASEBOARD_FAB2(SCH_1):VR_P3V3_STBY_PHASE   I129 @BASEBOARD_FAB2_LIB.BASEBOARD_FAB2(SCH_1):PAGE240
     2 VR_P3V3_STBY_BOOT_R @BASEBOARD_FAB2_LIB.BASEBOARD_FAB2(SCH_1):VR_P3V3_STBY_BOOT_R   I129 @BASEBOARD_FAB2_LIB.BASEBOARD_FAB2(SCH_1):PAGE240

C8E13 CAP_0402LF-1000PF,50V,10%,EMPTA
     1 PWRGD_P12V_HSC_DLY @BASEBOARD_FAB2_LIB.BASEBOARD_FAB2(SCH_1):PWRGD_P12V_HSC_DLY    I41 @BASEBOARD_FAB2_LIB.BASEBOARD_FAB2(SCH_1):PAGE241
     2 AGND_P5V_STBY @BASEBOARD_FAB2_LIB.BASEBOARD_FAB2(SCH_1):AGND_P5V_STBY    I41 @BASEBOARD_FAB2_LIB.BASEBOARD_FAB2(SCH_1):PAGE241

C8E14 CAP_0402-1.0UF,16V,10%,X6S,D97A
     1 VR_FET_SW_P12V_STBY_P3V3_STBY @BASEBOARD_FAB2_LIB.BASEBOARD_FAB2(SCH_1):VR_FET_SW_P12V_STBY_P3V3_STBY   I139 @BASEBOARD_FAB2_LIB.BASEBOARD_FAB2(SCH_1):PAGE240
     2    GND @BASEBOARD_FAB2_LIB.BASEBOARD_FAB2(SCH_1):GND   I139 @BASEBOARD_FAB2_LIB.BASEBOARD_FAB2(SCH_1):PAGE240

C8E15 CAP_0402LF-0.022UF,16V,10%,X7RA
     1 VR_P5V_STBY_SS @BASEBOARD_FAB2_LIB.BASEBOARD_FAB2(SCH_1):VR_P5V_STBY_SS    I63 @BASEBOARD_FAB2_LIB.BASEBOARD_FAB2(SCH_1):PAGE241
     2 AGND_P5V_STBY @BASEBOARD_FAB2_LIB.BASEBOARD_FAB2(SCH_1):AGND_P5V_STBY    I63 @BASEBOARD_FAB2_LIB.BASEBOARD_FAB2(SCH_1):PAGE241

C8E16 CAP_0402LF-270PF,50V,10%,X7R,AA
     1 VR_P5V_STBY_COMP @BASEBOARD_FAB2_LIB.BASEBOARD_FAB2(SCH_1):VR_P5V_STBY_COMP    I53 @BASEBOARD_FAB2_LIB.BASEBOARD_FAB2(SCH_1):PAGE241
     2 AGND_P5V_STBY @BASEBOARD_FAB2_LIB.BASEBOARD_FAB2(SCH_1):AGND_P5V_STBY    I53 @BASEBOARD_FAB2_LIB.BASEBOARD_FAB2(SCH_1):PAGE241

C8E17 CAP_0402LF-1000PF,50V,10%,EMPTA
     1 PWRGD_P5V_STBY @BASEBOARD_FAB2_LIB.BASEBOARD_FAB2(SCH_1):PWRGD_P5V_STBY   I113 @BASEBOARD_FAB2_LIB.BASEBOARD_FAB2(SCH_1):PAGE240
     2 AGND_P3V3_STBY @BASEBOARD_FAB2_LIB.BASEBOARD_FAB2(SCH_1):AGND_P3V3_STBY   I113 @BASEBOARD_FAB2_LIB.BASEBOARD_FAB2(SCH_1):PAGE240

C8E18 CAP_A_0402V-0.1UF,16V,10%,X7R,A
     1 P3V3_STBY @BASEBOARD_FAB2_LIB.BASEBOARD_FAB2(SCH_1):P3V3_STBY    I14 @BASEBOARD_FAB2_LIB.BASEBOARD_FAB2(SCH_1):PAGE154
     2    GND @BASEBOARD_FAB2_LIB.BASEBOARD_FAB2(SCH_1):GND    I14 @BASEBOARD_FAB2_LIB.BASEBOARD_FAB2(SCH_1):PAGE154

C8E19 CAP_A_0402V-0.1UF,16V,10%,X7R,A
     1 P5V_STBY @BASEBOARD_FAB2_LIB.BASEBOARD_FAB2(SCH_1):P5V_STBY    I28 @BASEBOARD_FAB2_LIB.BASEBOARD_FAB2(SCH_1):PAGE198
     2    GND @BASEBOARD_FAB2_LIB.BASEBOARD_FAB2(SCH_1):GND    I28 @BASEBOARD_FAB2_LIB.BASEBOARD_FAB2(SCH_1):PAGE198

C8F1 CAP_0402LF-2200PF,50V,10%,X7R,A
     1 VR_P5V_STBY_RC_COMP @BASEBOARD_FAB2_LIB.BASEBOARD_FAB2(SCH_1):VR_P5V_STBY_RC_COMP    I57 @BASEBOARD_FAB2_LIB.BASEBOARD_FAB2(SCH_1):PAGE241
     2 AGND_P5V_STBY @BASEBOARD_FAB2_LIB.BASEBOARD_FAB2(SCH_1):AGND_P5V_STBY    I57 @BASEBOARD_FAB2_LIB.BASEBOARD_FAB2(SCH_1):PAGE241

C8F2 CAP_0402LF-1000PF,50V,10%,X7R,A
     1 PWRGD_P3V3_STBY_R @BASEBOARD_FAB2_LIB.BASEBOARD_FAB2(SCH_1):PWRGD_P3V3_STBY_R   I116 @BASEBOARD_FAB2_LIB.BASEBOARD_FAB2(SCH_1):PAGE240
     2    GND @BASEBOARD_FAB2_LIB.BASEBOARD_FAB2(SCH_1):GND   I116 @BASEBOARD_FAB2_LIB.BASEBOARD_FAB2(SCH_1):PAGE240

C8F3 CAP_0402LF-3300PF,50V,10%,EMPTA
     1 VR_P3V3_STBY_PHASE @BASEBOARD_FAB2_LIB.BASEBOARD_FAB2(SCH_1):VR_P3V3_STBY_PHASE   I163 @BASEBOARD_FAB2_LIB.BASEBOARD_FAB2(SCH_1):PAGE240
     2 VR_P3V3_STBY_SNUB @BASEBOARD_FAB2_LIB.BASEBOARD_FAB2(SCH_1):VR_P3V3_STBY_SNUB   I163 @BASEBOARD_FAB2_LIB.BASEBOARD_FAB2(SCH_1):PAGE240

C8F4 CAP_A_0402V-1.0UF,6.3V,10%,X6SA
     1 P3V3_STBY @BASEBOARD_FAB2_LIB.BASEBOARD_FAB2(SCH_1):P3V3_STBY    I30 @BASEBOARD_FAB2_LIB.BASEBOARD_FAB2(SCH_1):PAGE162
     2    GND @BASEBOARD_FAB2_LIB.BASEBOARD_FAB2(SCH_1):GND    I30 @BASEBOARD_FAB2_LIB.BASEBOARD_FAB2(SCH_1):PAGE162

C8F5 CAP_A_0402V-0.01UF,25V,10%,X7RA
     1 P3V3_STBY @BASEBOARD_FAB2_LIB.BASEBOARD_FAB2(SCH_1):P3V3_STBY    I28 @BASEBOARD_FAB2_LIB.BASEBOARD_FAB2(SCH_1):PAGE162
     2    GND @BASEBOARD_FAB2_LIB.BASEBOARD_FAB2(SCH_1):GND    I28 @BASEBOARD_FAB2_LIB.BASEBOARD_FAB2(SCH_1):PAGE162

C8F6 CAP_A_0402V-0.01UF,25V,10%,X7RA
     1 SATA6G_S0_TX_DP @BASEBOARD_FAB2_LIB.BASEBOARD_FAB2(SCH_1):SATA6G_S0_TX_DP   I138 @BASEBOARD_FAB2_LIB.BASEBOARD_FAB2(SCH_1):PAGE185
     2 P3E_PCH_M2_SATA6G_TX_R_DP @BASEBOARD_FAB2_LIB.BASEBOARD_FAB2(SCH_1):P3E_PCH_M2_SATA6G_TX_R_DP   I138 @BASEBOARD_FAB2_LIB.BASEBOARD_FAB2(SCH_1):PAGE185

C8F7 CAP_0402-0.22UF,16V,10%,X7R,A3A
     1 P3E_PCH_TX_0_DP @BASEBOARD_FAB2_LIB.BASEBOARD_FAB2(SCH_1):P3E_PCH_TX_0_DP    I96 @BASEBOARD_FAB2_LIB.BASEBOARD_FAB2(SCH_1):PAGE185
     2 P3E_PCH_M2_SATA6G_TX_R_DP @BASEBOARD_FAB2_LIB.BASEBOARD_FAB2(SCH_1):P3E_PCH_M2_SATA6G_TX_R_DP    I96 @BASEBOARD_FAB2_LIB.BASEBOARD_FAB2(SCH_1):PAGE185

C8F8 ST470U6D3VDM-7-GP_SMD-TCG4-ST4A
     1 P3V3_STBY @BASEBOARD_FAB2_LIB.BASEBOARD_FAB2(SCH_1):P3V3_STBY   I190 @BASEBOARD_FAB2_LIB.BASEBOARD_FAB2(SCH_1):PAGE240
     2    GND @BASEBOARD_FAB2_LIB.BASEBOARD_FAB2(SCH_1):GND   I190 @BASEBOARD_FAB2_LIB.BASEBOARD_FAB2(SCH_1):PAGE240

C8F11 CAP_A_0402V-0.01UF,25V,10%,X7RA
     1 SATA6G_S0_TX_DN @BASEBOARD_FAB2_LIB.BASEBOARD_FAB2(SCH_1):SATA6G_S0_TX_DN   I139 @BASEBOARD_FAB2_LIB.BASEBOARD_FAB2(SCH_1):PAGE185
     2 P3E_PCH_M2_SATA6G_TX_R_DN @BASEBOARD_FAB2_LIB.BASEBOARD_FAB2(SCH_1):P3E_PCH_M2_SATA6G_TX_R_DN   I139 @BASEBOARD_FAB2_LIB.BASEBOARD_FAB2(SCH_1):PAGE185

C8F12 CAP_0402-0.22UF,16V,10%,X7R,A3A
     1 P3E_PCH_TX_0_DN @BASEBOARD_FAB2_LIB.BASEBOARD_FAB2(SCH_1):P3E_PCH_TX_0_DN   I140 @BASEBOARD_FAB2_LIB.BASEBOARD_FAB2(SCH_1):PAGE185
     2 P3E_PCH_M2_SATA6G_TX_R_DN @BASEBOARD_FAB2_LIB.BASEBOARD_FAB2(SCH_1):P3E_PCH_M2_SATA6G_TX_R_DN   I140 @BASEBOARD_FAB2_LIB.BASEBOARD_FAB2(SCH_1):PAGE185

C8F13 CAP_A_0402V-0.01UF,25V,10%,X7RA
     1 SATA6G_S0_RX_DP @BASEBOARD_FAB2_LIB.BASEBOARD_FAB2(SCH_1):SATA6G_S0_RX_DP   I141 @BASEBOARD_FAB2_LIB.BASEBOARD_FAB2(SCH_1):PAGE185
     2 P3E_PCH_M2_SATA6G_RX_R_DP @BASEBOARD_FAB2_LIB.BASEBOARD_FAB2(SCH_1):P3E_PCH_M2_SATA6G_RX_R_DP   I141 @BASEBOARD_FAB2_LIB.BASEBOARD_FAB2(SCH_1):PAGE185

C8F14 ST470U6D3VDM-7-GP_SMD-TCG4-ST4A
     1 P3V3_STBY @BASEBOARD_FAB2_LIB.BASEBOARD_FAB2(SCH_1):P3V3_STBY   I189 @BASEBOARD_FAB2_LIB.BASEBOARD_FAB2(SCH_1):PAGE240
     2    GND @BASEBOARD_FAB2_LIB.BASEBOARD_FAB2(SCH_1):GND   I189 @BASEBOARD_FAB2_LIB.BASEBOARD_FAB2(SCH_1):PAGE240

C8F15 CAP_A_0402V-0.01UF,25V,10%,X7RA
     1 SATA6G_S0_RX_DN @BASEBOARD_FAB2_LIB.BASEBOARD_FAB2(SCH_1):SATA6G_S0_RX_DN   I142 @BASEBOARD_FAB2_LIB.BASEBOARD_FAB2(SCH_1):PAGE185
     2 P3E_PCH_M2_SATA6G_RX_R_DN @BASEBOARD_FAB2_LIB.BASEBOARD_FAB2(SCH_1):P3E_PCH_M2_SATA6G_RX_R_DN   I142 @BASEBOARD_FAB2_LIB.BASEBOARD_FAB2(SCH_1):PAGE185

C8F16 CAP_A_0402V-0.1UF,16V,10%,X7R,A
     1 P3V3_STBY @BASEBOARD_FAB2_LIB.BASEBOARD_FAB2(SCH_1):P3V3_STBY   I275 @BASEBOARD_FAB2_LIB.BASEBOARD_FAB2(SCH_1):PAGE156
     2    GND @BASEBOARD_FAB2_LIB.BASEBOARD_FAB2(SCH_1):GND   I275 @BASEBOARD_FAB2_LIB.BASEBOARD_FAB2(SCH_1):PAGE156

C8F17 CAP_A_0402V-0.1UF,16V,10%,X7R,A
     1 P5V_STBY @BASEBOARD_FAB2_LIB.BASEBOARD_FAB2(SCH_1):P5V_STBY    I24 @BASEBOARD_FAB2_LIB.BASEBOARD_FAB2(SCH_1):PAGE198
     2    GND @BASEBOARD_FAB2_LIB.BASEBOARD_FAB2(SCH_1):GND    I24 @BASEBOARD_FAB2_LIB.BASEBOARD_FAB2(SCH_1):PAGE198

C8F18 CAP_0402LF-15.0PF,50V,5%,COG,AA
     1 XTAL_CK_MNG_IN @BASEBOARD_FAB2_LIB.BASEBOARD_FAB2(SCH_1):XTAL_CK_MNG_IN   I147 @BASEBOARD_FAB2_LIB.BASEBOARD_FAB2(SCH_1):PAGE101
     2    GND @BASEBOARD_FAB2_LIB.BASEBOARD_FAB2(SCH_1):GND   I147 @BASEBOARD_FAB2_LIB.BASEBOARD_FAB2(SCH_1):PAGE101

C8F19 CAP_0402LF-15.0PF,50V,5%,COG,AA
     1 XTAL_CK_MNG_OUT @BASEBOARD_FAB2_LIB.BASEBOARD_FAB2(SCH_1):XTAL_CK_MNG_OUT   I146 @BASEBOARD_FAB2_LIB.BASEBOARD_FAB2(SCH_1):PAGE101
     2    GND @BASEBOARD_FAB2_LIB.BASEBOARD_FAB2(SCH_1):GND   I146 @BASEBOARD_FAB2_LIB.BASEBOARD_FAB2(SCH_1):PAGE101

C8G1 CAP_0402-0.22UF,16V,10%,X7R,A3A
     1 P3E_CPU0_PE2_SS_TXP<4> @BASEBOARD_FAB2_LIB.BASEBOARD_FAB2(SCH_1):P3E_CPU0_PE2_SS_TXP(4)    I70 @BASEBOARD_FAB2_LIB.BASEBOARD_FAB2(SCH_1):PAGE105
     2 P3E_CPU0_PE2_SS_C_TXP<4> @BASEBOARD_FAB2_LIB.BASEBOARD_FAB2(SCH_1):P3E_CPU0_PE2_SS_C_TXP(4)    I70 @BASEBOARD_FAB2_LIB.BASEBOARD_FAB2(SCH_1):PAGE105

C8G2 CAP_0402-0.22UF,16V,10%,X7R,A3A
     1 P3E_CPU0_PE2_SS_TXN<4> @BASEBOARD_FAB2_LIB.BASEBOARD_FAB2(SCH_1):P3E_CPU0_PE2_SS_TXN(4)    I58 @BASEBOARD_FAB2_LIB.BASEBOARD_FAB2(SCH_1):PAGE105
     2 P3E_CPU0_PE2_SS_C_TXN<4> @BASEBOARD_FAB2_LIB.BASEBOARD_FAB2(SCH_1):P3E_CPU0_PE2_SS_C_TXN(4)    I58 @BASEBOARD_FAB2_LIB.BASEBOARD_FAB2(SCH_1):PAGE105

C8G3 CAP_0402-0.22UF,16V,10%,X7R,A3A
     1 P3E_CPU0_PE2_SS_TXP<3> @BASEBOARD_FAB2_LIB.BASEBOARD_FAB2(SCH_1):P3E_CPU0_PE2_SS_TXP(3)    I71 @BASEBOARD_FAB2_LIB.BASEBOARD_FAB2(SCH_1):PAGE105
     2 P3E_CPU0_PE2_SS_C_TXP<3> @BASEBOARD_FAB2_LIB.BASEBOARD_FAB2(SCH_1):P3E_CPU0_PE2_SS_C_TXP(3)    I71 @BASEBOARD_FAB2_LIB.BASEBOARD_FAB2(SCH_1):PAGE105

C8G4 CAP_0402-0.22UF,16V,10%,X7R,A3A
     1 P3E_CPU0_PE2_SS_TXN<3> @BASEBOARD_FAB2_LIB.BASEBOARD_FAB2(SCH_1):P3E_CPU0_PE2_SS_TXN(3)    I56 @BASEBOARD_FAB2_LIB.BASEBOARD_FAB2(SCH_1):PAGE105
     2 P3E_CPU0_PE2_SS_C_TXN<3> @BASEBOARD_FAB2_LIB.BASEBOARD_FAB2(SCH_1):P3E_CPU0_PE2_SS_C_TXN(3)    I56 @BASEBOARD_FAB2_LIB.BASEBOARD_FAB2(SCH_1):PAGE105

C8G5 CAP_0402-0.22UF,16V,10%,X7R,A3A
     1 P3E_CPU0_PE2_SS_TXP<2> @BASEBOARD_FAB2_LIB.BASEBOARD_FAB2(SCH_1):P3E_CPU0_PE2_SS_TXP(2)    I75 @BASEBOARD_FAB2_LIB.BASEBOARD_FAB2(SCH_1):PAGE105
     2 P3E_CPU0_PE2_SS_C_TXP<2> @BASEBOARD_FAB2_LIB.BASEBOARD_FAB2(SCH_1):P3E_CPU0_PE2_SS_C_TXP(2)    I75 @BASEBOARD_FAB2_LIB.BASEBOARD_FAB2(SCH_1):PAGE105

C8G6 CAP_0402-0.22UF,16V,10%,X7R,A3A
     1 P3E_CPU0_PE2_SS_TXN<2> @BASEBOARD_FAB2_LIB.BASEBOARD_FAB2(SCH_1):P3E_CPU0_PE2_SS_TXN(2)    I61 @BASEBOARD_FAB2_LIB.BASEBOARD_FAB2(SCH_1):PAGE105
     2 P3E_CPU0_PE2_SS_C_TXN<2> @BASEBOARD_FAB2_LIB.BASEBOARD_FAB2(SCH_1):P3E_CPU0_PE2_SS_C_TXN(2)    I61 @BASEBOARD_FAB2_LIB.BASEBOARD_FAB2(SCH_1):PAGE105

C8G7 CAP_0402-0.22UF,16V,10%,X7R,A3A
     1 P3E_CPU0_PE2_SS_TXN<1> @BASEBOARD_FAB2_LIB.BASEBOARD_FAB2(SCH_1):P3E_CPU0_PE2_SS_TXN(1)    I62 @BASEBOARD_FAB2_LIB.BASEBOARD_FAB2(SCH_1):PAGE105
     2 P3E_CPU0_PE2_SS_C_TXN<1> @BASEBOARD_FAB2_LIB.BASEBOARD_FAB2(SCH_1):P3E_CPU0_PE2_SS_C_TXN(1)    I62 @BASEBOARD_FAB2_LIB.BASEBOARD_FAB2(SCH_1):PAGE105

C8G8 CAP_0402-0.22UF,16V,10%,X7R,A3A
     1 P3E_CPU0_PE2_SS_TXP<1> @BASEBOARD_FAB2_LIB.BASEBOARD_FAB2(SCH_1):P3E_CPU0_PE2_SS_TXP(1)    I76 @BASEBOARD_FAB2_LIB.BASEBOARD_FAB2(SCH_1):PAGE105
     2 P3E_CPU0_PE2_SS_C_TXP<1> @BASEBOARD_FAB2_LIB.BASEBOARD_FAB2(SCH_1):P3E_CPU0_PE2_SS_C_TXP(1)    I76 @BASEBOARD_FAB2_LIB.BASEBOARD_FAB2(SCH_1):PAGE105

C8G9 CAP_0402-0.22UF,16V,10%,X7R,A3A
     1 P3E_CPU0_PE2_SS_TXP<0> @BASEBOARD_FAB2_LIB.BASEBOARD_FAB2(SCH_1):P3E_CPU0_PE2_SS_TXP(0)    I93 @BASEBOARD_FAB2_LIB.BASEBOARD_FAB2(SCH_1):PAGE105
     2 P3E_CPU0_PE2_SS_C_TXP<0> @BASEBOARD_FAB2_LIB.BASEBOARD_FAB2(SCH_1):P3E_CPU0_PE2_SS_C_TXP(0)    I93 @BASEBOARD_FAB2_LIB.BASEBOARD_FAB2(SCH_1):PAGE105

C8G10 CAP_0402-0.22UF,16V,10%,X7R,A3A
     1 P3E_CPU0_PE2_SS_TXN<0> @BASEBOARD_FAB2_LIB.BASEBOARD_FAB2(SCH_1):P3E_CPU0_PE2_SS_TXN(0)    I96 @BASEBOARD_FAB2_LIB.BASEBOARD_FAB2(SCH_1):PAGE105
     2 P3E_CPU0_PE2_SS_C_TXN<0> @BASEBOARD_FAB2_LIB.BASEBOARD_FAB2(SCH_1):P3E_CPU0_PE2_SS_C_TXN(0)    I96 @BASEBOARD_FAB2_LIB.BASEBOARD_FAB2(SCH_1):PAGE105

C8L1 CAP_0805-100UF,4V,20%,X5R,6024A
     1 PVDDQ_KLM @BASEBOARD_FAB2_LIB.BASEBOARD_FAB2(SCH_1):PVDDQ_KLM   I301 @BASEBOARD_FAB2_LIB.BASEBOARD_FAB2(SCH_1):PAGE228
     2    GND @BASEBOARD_FAB2_LIB.BASEBOARD_FAB2(SCH_1):GND   I301 @BASEBOARD_FAB2_LIB.BASEBOARD_FAB2(SCH_1):PAGE228

C8L2 CAP_0805-100UF,4V,20%,X5R,6024A
     1 PVDDQ_KLM @BASEBOARD_FAB2_LIB.BASEBOARD_FAB2(SCH_1):PVDDQ_KLM   I310 @BASEBOARD_FAB2_LIB.BASEBOARD_FAB2(SCH_1):PAGE228
     2    GND @BASEBOARD_FAB2_LIB.BASEBOARD_FAB2(SCH_1):GND   I310 @BASEBOARD_FAB2_LIB.BASEBOARD_FAB2(SCH_1):PAGE228

C8L3 CAP_0805-100UF,4V,20%,X5R,6024A
     1 PVTT_KLM @BASEBOARD_FAB2_LIB.BASEBOARD_FAB2(SCH_1):PVTT_KLM    I41 @BASEBOARD_FAB2_LIB.BASEBOARD_FAB2(SCH_1):PAGE230
     2    GND @BASEBOARD_FAB2_LIB.BASEBOARD_FAB2(SCH_1):GND    I41 @BASEBOARD_FAB2_LIB.BASEBOARD_FAB2(SCH_1):PAGE230

C8L4 CAP_0805-100UF,4V,20%,X5R,6024A
     1 PVTT_KLM @BASEBOARD_FAB2_LIB.BASEBOARD_FAB2(SCH_1):PVTT_KLM    I42 @BASEBOARD_FAB2_LIB.BASEBOARD_FAB2(SCH_1):PAGE230
     2    GND @BASEBOARD_FAB2_LIB.BASEBOARD_FAB2(SCH_1):GND    I42 @BASEBOARD_FAB2_LIB.BASEBOARD_FAB2(SCH_1):PAGE230

C8L5 CAP_A_0603V-47UF,4V,20%,X5R,60A
     1 PVDDQ_KLM @BASEBOARD_FAB2_LIB.BASEBOARD_FAB2(SCH_1):PVDDQ_KLM   I285 @BASEBOARD_FAB2_LIB.BASEBOARD_FAB2(SCH_1):PAGE228
     2    GND @BASEBOARD_FAB2_LIB.BASEBOARD_FAB2(SCH_1):GND   I285 @BASEBOARD_FAB2_LIB.BASEBOARD_FAB2(SCH_1):PAGE228

C8L6 CAP_A_0603V-47UF,4V,20%,X5R,60A
     1 PVDDQ_KLM @BASEBOARD_FAB2_LIB.BASEBOARD_FAB2(SCH_1):PVDDQ_KLM   I286 @BASEBOARD_FAB2_LIB.BASEBOARD_FAB2(SCH_1):PAGE228
     2    GND @BASEBOARD_FAB2_LIB.BASEBOARD_FAB2(SCH_1):GND   I286 @BASEBOARD_FAB2_LIB.BASEBOARD_FAB2(SCH_1):PAGE228

C8L7 CAP_A_0603V-47UF,4V,20%,X5R,60A
     1 PVDDQ_KLM @BASEBOARD_FAB2_LIB.BASEBOARD_FAB2(SCH_1):PVDDQ_KLM   I287 @BASEBOARD_FAB2_LIB.BASEBOARD_FAB2(SCH_1):PAGE228
     2    GND @BASEBOARD_FAB2_LIB.BASEBOARD_FAB2(SCH_1):GND   I287 @BASEBOARD_FAB2_LIB.BASEBOARD_FAB2(SCH_1):PAGE228

C8L8 CAP_A_0603V-47UF,4V,20%,X5R,60A
     1 PVDDQ_KLM @BASEBOARD_FAB2_LIB.BASEBOARD_FAB2(SCH_1):PVDDQ_KLM   I289 @BASEBOARD_FAB2_LIB.BASEBOARD_FAB2(SCH_1):PAGE228
     2    GND @BASEBOARD_FAB2_LIB.BASEBOARD_FAB2(SCH_1):GND   I289 @BASEBOARD_FAB2_LIB.BASEBOARD_FAB2(SCH_1):PAGE228

C8L9 CAP_A_0603V-47UF,4V,20%,X5R,60A
     1 PVDDQ_KLM @BASEBOARD_FAB2_LIB.BASEBOARD_FAB2(SCH_1):PVDDQ_KLM   I290 @BASEBOARD_FAB2_LIB.BASEBOARD_FAB2(SCH_1):PAGE228
     2    GND @BASEBOARD_FAB2_LIB.BASEBOARD_FAB2(SCH_1):GND   I290 @BASEBOARD_FAB2_LIB.BASEBOARD_FAB2(SCH_1):PAGE228

C8L10 CAP_A_0603V-47UF,4V,20%,X5R,60A
     1 PVDDQ_KLM @BASEBOARD_FAB2_LIB.BASEBOARD_FAB2(SCH_1):PVDDQ_KLM   I297 @BASEBOARD_FAB2_LIB.BASEBOARD_FAB2(SCH_1):PAGE228
     2    GND @BASEBOARD_FAB2_LIB.BASEBOARD_FAB2(SCH_1):GND   I297 @BASEBOARD_FAB2_LIB.BASEBOARD_FAB2(SCH_1):PAGE228

C8L11 CAP_0805-100UF,4V,20%,X5R,6024A
     1 PVDDQ_KLM @BASEBOARD_FAB2_LIB.BASEBOARD_FAB2(SCH_1):PVDDQ_KLM   I302 @BASEBOARD_FAB2_LIB.BASEBOARD_FAB2(SCH_1):PAGE228
     2    GND @BASEBOARD_FAB2_LIB.BASEBOARD_FAB2(SCH_1):GND   I302 @BASEBOARD_FAB2_LIB.BASEBOARD_FAB2(SCH_1):PAGE228

C8L12 CAP_A_0603V-47UF,4V,20%,X5R,60A
     1 PVDDQ_KLM @BASEBOARD_FAB2_LIB.BASEBOARD_FAB2(SCH_1):PVDDQ_KLM   I201 @BASEBOARD_FAB2_LIB.BASEBOARD_FAB2(SCH_1):PAGE228
     2    GND @BASEBOARD_FAB2_LIB.BASEBOARD_FAB2(SCH_1):GND   I201 @BASEBOARD_FAB2_LIB.BASEBOARD_FAB2(SCH_1):PAGE228

C8M1 CAP_A_0603V-47UF,4V,20%,X5R,60A
     1 PVDDQ_KLM @BASEBOARD_FAB2_LIB.BASEBOARD_FAB2(SCH_1):PVDDQ_KLM   I284 @BASEBOARD_FAB2_LIB.BASEBOARD_FAB2(SCH_1):PAGE228
     2    GND @BASEBOARD_FAB2_LIB.BASEBOARD_FAB2(SCH_1):GND   I284 @BASEBOARD_FAB2_LIB.BASEBOARD_FAB2(SCH_1):PAGE228

C8M2 CAP_A_0603V-47UF,4V,20%,X5R,60A
     1 PVDDQ_KLM @BASEBOARD_FAB2_LIB.BASEBOARD_FAB2(SCH_1):PVDDQ_KLM   I206 @BASEBOARD_FAB2_LIB.BASEBOARD_FAB2(SCH_1):PAGE228
     2    GND @BASEBOARD_FAB2_LIB.BASEBOARD_FAB2(SCH_1):GND   I206 @BASEBOARD_FAB2_LIB.BASEBOARD_FAB2(SCH_1):PAGE228

C8M3 CAP_A_0603V-47UF,4V,20%,X5R,60A
     1 PVDDQ_KLM @BASEBOARD_FAB2_LIB.BASEBOARD_FAB2(SCH_1):PVDDQ_KLM   I299 @BASEBOARD_FAB2_LIB.BASEBOARD_FAB2(SCH_1):PAGE228
     2    GND @BASEBOARD_FAB2_LIB.BASEBOARD_FAB2(SCH_1):GND   I299 @BASEBOARD_FAB2_LIB.BASEBOARD_FAB2(SCH_1):PAGE228

C8M4 CAP_A_0603V-47UF,4V,20%,X5R,60A
     1 PVDDQ_KLM @BASEBOARD_FAB2_LIB.BASEBOARD_FAB2(SCH_1):PVDDQ_KLM   I293 @BASEBOARD_FAB2_LIB.BASEBOARD_FAB2(SCH_1):PAGE228
     2    GND @BASEBOARD_FAB2_LIB.BASEBOARD_FAB2(SCH_1):GND   I293 @BASEBOARD_FAB2_LIB.BASEBOARD_FAB2(SCH_1):PAGE228

C8M5 CAP_A_0603V-47UF,4V,20%,X5R,60A
     1 PVDDQ_KLM @BASEBOARD_FAB2_LIB.BASEBOARD_FAB2(SCH_1):PVDDQ_KLM   I298 @BASEBOARD_FAB2_LIB.BASEBOARD_FAB2(SCH_1):PAGE228
     2    GND @BASEBOARD_FAB2_LIB.BASEBOARD_FAB2(SCH_1):GND   I298 @BASEBOARD_FAB2_LIB.BASEBOARD_FAB2(SCH_1):PAGE228

C8M6 CAP_A_0603V-47UF,4V,20%,X5R,60A
     1 PVDDQ_KLM @BASEBOARD_FAB2_LIB.BASEBOARD_FAB2(SCH_1):PVDDQ_KLM   I291 @BASEBOARD_FAB2_LIB.BASEBOARD_FAB2(SCH_1):PAGE228
     2    GND @BASEBOARD_FAB2_LIB.BASEBOARD_FAB2(SCH_1):GND   I291 @BASEBOARD_FAB2_LIB.BASEBOARD_FAB2(SCH_1):PAGE228

C8M7 CAP_0805-100UF,4V,20%,X5R,6024A
     1 PVDDQ_KLM @BASEBOARD_FAB2_LIB.BASEBOARD_FAB2(SCH_1):PVDDQ_KLM   I312 @BASEBOARD_FAB2_LIB.BASEBOARD_FAB2(SCH_1):PAGE228
     2    GND @BASEBOARD_FAB2_LIB.BASEBOARD_FAB2(SCH_1):GND   I312 @BASEBOARD_FAB2_LIB.BASEBOARD_FAB2(SCH_1):PAGE228

C8M8 CAP_A_0603V-47UF,4V,20%,X5R,60A
     1 PVDDQ_KLM @BASEBOARD_FAB2_LIB.BASEBOARD_FAB2(SCH_1):PVDDQ_KLM   I198 @BASEBOARD_FAB2_LIB.BASEBOARD_FAB2(SCH_1):PAGE228
     2    GND @BASEBOARD_FAB2_LIB.BASEBOARD_FAB2(SCH_1):GND   I198 @BASEBOARD_FAB2_LIB.BASEBOARD_FAB2(SCH_1):PAGE228

C8M9 CAP_A_0603V-47UF,4V,20%,X5R,60A
     1 PVDDQ_KLM @BASEBOARD_FAB2_LIB.BASEBOARD_FAB2(SCH_1):PVDDQ_KLM   I205 @BASEBOARD_FAB2_LIB.BASEBOARD_FAB2(SCH_1):PAGE228
     2    GND @BASEBOARD_FAB2_LIB.BASEBOARD_FAB2(SCH_1):GND   I205 @BASEBOARD_FAB2_LIB.BASEBOARD_FAB2(SCH_1):PAGE228

C8M10 CAP_A_0603V-47UF,4V,20%,X5R,60A
     1 PVDDQ_KLM @BASEBOARD_FAB2_LIB.BASEBOARD_FAB2(SCH_1):PVDDQ_KLM   I203 @BASEBOARD_FAB2_LIB.BASEBOARD_FAB2(SCH_1):PAGE228
     2    GND @BASEBOARD_FAB2_LIB.BASEBOARD_FAB2(SCH_1):GND   I203 @BASEBOARD_FAB2_LIB.BASEBOARD_FAB2(SCH_1):PAGE228

C8M11 CAP_0805-100UF,4V,20%,X5R,6024A
     1 PVDDQ_KLM @BASEBOARD_FAB2_LIB.BASEBOARD_FAB2(SCH_1):PVDDQ_KLM   I311 @BASEBOARD_FAB2_LIB.BASEBOARD_FAB2(SCH_1):PAGE228
     2    GND @BASEBOARD_FAB2_LIB.BASEBOARD_FAB2(SCH_1):GND   I311 @BASEBOARD_FAB2_LIB.BASEBOARD_FAB2(SCH_1):PAGE228

C8M12 CAP_A_0603V-47UF,4V,20%,X5R,60A
     1 PVTT_KLM @BASEBOARD_FAB2_LIB.BASEBOARD_FAB2(SCH_1):PVTT_KLM    I24 @BASEBOARD_FAB2_LIB.BASEBOARD_FAB2(SCH_1):PAGE230
     2    GND @BASEBOARD_FAB2_LIB.BASEBOARD_FAB2(SCH_1):GND    I24 @BASEBOARD_FAB2_LIB.BASEBOARD_FAB2(SCH_1):PAGE230

C8P1 CAP_0805-100UF,4V,20%,X5R,6024A
     1 PVDDQ_KLM @BASEBOARD_FAB2_LIB.BASEBOARD_FAB2(SCH_1):PVDDQ_KLM   I304 @BASEBOARD_FAB2_LIB.BASEBOARD_FAB2(SCH_1):PAGE228
     2    GND @BASEBOARD_FAB2_LIB.BASEBOARD_FAB2(SCH_1):GND   I304 @BASEBOARD_FAB2_LIB.BASEBOARD_FAB2(SCH_1):PAGE228

C8P2 CAP_0805-100UF,4V,20%,X5R,6024A
     1 PVDDQ_KLM @BASEBOARD_FAB2_LIB.BASEBOARD_FAB2(SCH_1):PVDDQ_KLM   I303 @BASEBOARD_FAB2_LIB.BASEBOARD_FAB2(SCH_1):PAGE228
     2    GND @BASEBOARD_FAB2_LIB.BASEBOARD_FAB2(SCH_1):GND   I303 @BASEBOARD_FAB2_LIB.BASEBOARD_FAB2(SCH_1):PAGE228

C8P3 CAP_0805-100UF,4V,20%,X5R,6024A
     1 PVDDQ_KLM @BASEBOARD_FAB2_LIB.BASEBOARD_FAB2(SCH_1):PVDDQ_KLM   I306 @BASEBOARD_FAB2_LIB.BASEBOARD_FAB2(SCH_1):PAGE228
     2    GND @BASEBOARD_FAB2_LIB.BASEBOARD_FAB2(SCH_1):GND   I306 @BASEBOARD_FAB2_LIB.BASEBOARD_FAB2(SCH_1):PAGE228

C8P4 CAP_0805-100UF,4V,20%,X5R,6024A
     1 PVDDQ_KLM @BASEBOARD_FAB2_LIB.BASEBOARD_FAB2(SCH_1):PVDDQ_KLM   I307 @BASEBOARD_FAB2_LIB.BASEBOARD_FAB2(SCH_1):PAGE228
     2    GND @BASEBOARD_FAB2_LIB.BASEBOARD_FAB2(SCH_1):GND   I307 @BASEBOARD_FAB2_LIB.BASEBOARD_FAB2(SCH_1):PAGE228

C8P5 CAP_0805LF-22UF,4V,20%,X6S,C95A
     1 PVSA_CPU1 @BASEBOARD_FAB2_LIB.BASEBOARD_FAB2(SCH_1):PVSA_CPU1   I246 @BASEBOARD_FAB2_LIB.BASEBOARD_FAB2(SCH_1):PAGE76
     2    GND @BASEBOARD_FAB2_LIB.BASEBOARD_FAB2(SCH_1):GND   I246 @BASEBOARD_FAB2_LIB.BASEBOARD_FAB2(SCH_1):PAGE76

C8P6 CAP_0805LF-22UF,4V,20%,X6S,C95A
     1 PVSA_CPU1 @BASEBOARD_FAB2_LIB.BASEBOARD_FAB2(SCH_1):PVSA_CPU1   I247 @BASEBOARD_FAB2_LIB.BASEBOARD_FAB2(SCH_1):PAGE76
     2    GND @BASEBOARD_FAB2_LIB.BASEBOARD_FAB2(SCH_1):GND   I247 @BASEBOARD_FAB2_LIB.BASEBOARD_FAB2(SCH_1):PAGE76

C8P7 CAP_0805LF-22UF,4V,20%,X6S,C95A
     1 PVSA_CPU1 @BASEBOARD_FAB2_LIB.BASEBOARD_FAB2(SCH_1):PVSA_CPU1   I248 @BASEBOARD_FAB2_LIB.BASEBOARD_FAB2(SCH_1):PAGE76
     2    GND @BASEBOARD_FAB2_LIB.BASEBOARD_FAB2(SCH_1):GND   I248 @BASEBOARD_FAB2_LIB.BASEBOARD_FAB2(SCH_1):PAGE76

C8P8 CAP_0805-100UF,4V,20%,X5R,6024A
     1 PVCCMCP_CPU1 @BASEBOARD_FAB2_LIB.BASEBOARD_FAB2(SCH_1):PVCCMCP_CPU1   I274 @BASEBOARD_FAB2_LIB.BASEBOARD_FAB2(SCH_1):PAGE76
     2    GND @BASEBOARD_FAB2_LIB.BASEBOARD_FAB2(SCH_1):GND   I274 @BASEBOARD_FAB2_LIB.BASEBOARD_FAB2(SCH_1):PAGE76

C8P9 CAP_0805-100UF,4V,20%,X5R,6024A
     1 PVCCMCP_CPU1 @BASEBOARD_FAB2_LIB.BASEBOARD_FAB2(SCH_1):PVCCMCP_CPU1   I273 @BASEBOARD_FAB2_LIB.BASEBOARD_FAB2(SCH_1):PAGE76
     2    GND @BASEBOARD_FAB2_LIB.BASEBOARD_FAB2(SCH_1):GND   I273 @BASEBOARD_FAB2_LIB.BASEBOARD_FAB2(SCH_1):PAGE76

C8P10 CAP_0805-47UF,4V,20%,X6S,C9533A
     1 PVCCIN_CPU1 @BASEBOARD_FAB2_LIB.BASEBOARD_FAB2(SCH_1):PVCCIN_CPU1   I127 @BASEBOARD_FAB2_LIB.BASEBOARD_FAB2(SCH_1):PAGE76
     2    GND @BASEBOARD_FAB2_LIB.BASEBOARD_FAB2(SCH_1):GND   I127 @BASEBOARD_FAB2_LIB.BASEBOARD_FAB2(SCH_1):PAGE76

C8P11 CAP_0805-47UF,4V,20%,X6S,C9533A
     1 PVCCIN_CPU1 @BASEBOARD_FAB2_LIB.BASEBOARD_FAB2(SCH_1):PVCCIN_CPU1   I139 @BASEBOARD_FAB2_LIB.BASEBOARD_FAB2(SCH_1):PAGE76
     2    GND @BASEBOARD_FAB2_LIB.BASEBOARD_FAB2(SCH_1):GND   I139 @BASEBOARD_FAB2_LIB.BASEBOARD_FAB2(SCH_1):PAGE76

C8P12 CAP_0805-47UF,4V,20%,X6S,C9533A
     1 PVCCIN_CPU1 @BASEBOARD_FAB2_LIB.BASEBOARD_FAB2(SCH_1):PVCCIN_CPU1   I107 @BASEBOARD_FAB2_LIB.BASEBOARD_FAB2(SCH_1):PAGE76
     2    GND @BASEBOARD_FAB2_LIB.BASEBOARD_FAB2(SCH_1):GND   I107 @BASEBOARD_FAB2_LIB.BASEBOARD_FAB2(SCH_1):PAGE76

C8P13 CAP_0805-47UF,4V,20%,X6S,C9533A
     1 PVCCIN_CPU1 @BASEBOARD_FAB2_LIB.BASEBOARD_FAB2(SCH_1):PVCCIN_CPU1   I132 @BASEBOARD_FAB2_LIB.BASEBOARD_FAB2(SCH_1):PAGE76
     2    GND @BASEBOARD_FAB2_LIB.BASEBOARD_FAB2(SCH_1):GND   I132 @BASEBOARD_FAB2_LIB.BASEBOARD_FAB2(SCH_1):PAGE76

C8P14 CAP_0805-100UF,4V,20%,X5R,6024A
     1 PVCCMCP_CPU1 @BASEBOARD_FAB2_LIB.BASEBOARD_FAB2(SCH_1):PVCCMCP_CPU1   I272 @BASEBOARD_FAB2_LIB.BASEBOARD_FAB2(SCH_1):PAGE76
     2    GND @BASEBOARD_FAB2_LIB.BASEBOARD_FAB2(SCH_1):GND   I272 @BASEBOARD_FAB2_LIB.BASEBOARD_FAB2(SCH_1):PAGE76

C8P15 CAP_0805-100UF,4V,20%,X5R,6024A
     1 PVCCMCP_CPU1 @BASEBOARD_FAB2_LIB.BASEBOARD_FAB2(SCH_1):PVCCMCP_CPU1   I270 @BASEBOARD_FAB2_LIB.BASEBOARD_FAB2(SCH_1):PAGE76
     2    GND @BASEBOARD_FAB2_LIB.BASEBOARD_FAB2(SCH_1):GND   I270 @BASEBOARD_FAB2_LIB.BASEBOARD_FAB2(SCH_1):PAGE76

C8P16 CAP_0805-47UF,4V,20%,X6S,C9533A
     1 PVCCIN_CPU1 @BASEBOARD_FAB2_LIB.BASEBOARD_FAB2(SCH_1):PVCCIN_CPU1   I129 @BASEBOARD_FAB2_LIB.BASEBOARD_FAB2(SCH_1):PAGE76
     2    GND @BASEBOARD_FAB2_LIB.BASEBOARD_FAB2(SCH_1):GND   I129 @BASEBOARD_FAB2_LIB.BASEBOARD_FAB2(SCH_1):PAGE76

C8P17 CAP_0805-47UF,4V,20%,X6S,C9533A
     1 PVCCIN_CPU1 @BASEBOARD_FAB2_LIB.BASEBOARD_FAB2(SCH_1):PVCCIN_CPU1   I252 @BASEBOARD_FAB2_LIB.BASEBOARD_FAB2(SCH_1):PAGE76
     2    GND @BASEBOARD_FAB2_LIB.BASEBOARD_FAB2(SCH_1):GND   I252 @BASEBOARD_FAB2_LIB.BASEBOARD_FAB2(SCH_1):PAGE76

C8P18 CAP_0805-47UF,4V,20%,X6S,C9533A
     1 PVCCIN_CPU1 @BASEBOARD_FAB2_LIB.BASEBOARD_FAB2(SCH_1):PVCCIN_CPU1    I92 @BASEBOARD_FAB2_LIB.BASEBOARD_FAB2(SCH_1):PAGE76
     2    GND @BASEBOARD_FAB2_LIB.BASEBOARD_FAB2(SCH_1):GND    I92 @BASEBOARD_FAB2_LIB.BASEBOARD_FAB2(SCH_1):PAGE76

C8P19 CAP_0805-47UF,4V,20%,X6S,C9533A
     1 PVCCIN_CPU1 @BASEBOARD_FAB2_LIB.BASEBOARD_FAB2(SCH_1):PVCCIN_CPU1   I103 @BASEBOARD_FAB2_LIB.BASEBOARD_FAB2(SCH_1):PAGE76
     2    GND @BASEBOARD_FAB2_LIB.BASEBOARD_FAB2(SCH_1):GND   I103 @BASEBOARD_FAB2_LIB.BASEBOARD_FAB2(SCH_1):PAGE76

C8P20 CAP_0805-47UF,4V,20%,X6S,C9533A
     1 PVCCIN_CPU1 @BASEBOARD_FAB2_LIB.BASEBOARD_FAB2(SCH_1):PVCCIN_CPU1    I89 @BASEBOARD_FAB2_LIB.BASEBOARD_FAB2(SCH_1):PAGE76
     2    GND @BASEBOARD_FAB2_LIB.BASEBOARD_FAB2(SCH_1):GND    I89 @BASEBOARD_FAB2_LIB.BASEBOARD_FAB2(SCH_1):PAGE76

C8P21 CAP_0805-47UF,4V,20%,X6S,C9533A
     1 PVCCIN_CPU1 @BASEBOARD_FAB2_LIB.BASEBOARD_FAB2(SCH_1):PVCCIN_CPU1   I249 @BASEBOARD_FAB2_LIB.BASEBOARD_FAB2(SCH_1):PAGE76
     2    GND @BASEBOARD_FAB2_LIB.BASEBOARD_FAB2(SCH_1):GND   I249 @BASEBOARD_FAB2_LIB.BASEBOARD_FAB2(SCH_1):PAGE76

C8P22 CAP_0805-100UF,4V,20%,X5R,6024A
     1 PVCCMCP_CPU1 @BASEBOARD_FAB2_LIB.BASEBOARD_FAB2(SCH_1):PVCCMCP_CPU1   I264 @BASEBOARD_FAB2_LIB.BASEBOARD_FAB2(SCH_1):PAGE76
     2    GND @BASEBOARD_FAB2_LIB.BASEBOARD_FAB2(SCH_1):GND   I264 @BASEBOARD_FAB2_LIB.BASEBOARD_FAB2(SCH_1):PAGE76

C8P23 CAP_0805-100UF,4V,20%,X5R,6024A
     1 PVCCMCP_CPU1 @BASEBOARD_FAB2_LIB.BASEBOARD_FAB2(SCH_1):PVCCMCP_CPU1   I260 @BASEBOARD_FAB2_LIB.BASEBOARD_FAB2(SCH_1):PAGE76
     2    GND @BASEBOARD_FAB2_LIB.BASEBOARD_FAB2(SCH_1):GND   I260 @BASEBOARD_FAB2_LIB.BASEBOARD_FAB2(SCH_1):PAGE76

C8P24 CAP_0805-47UF,4V,20%,X6S,C9533A
     1 PVCCIN_CPU1 @BASEBOARD_FAB2_LIB.BASEBOARD_FAB2(SCH_1):PVCCIN_CPU1   I217 @BASEBOARD_FAB2_LIB.BASEBOARD_FAB2(SCH_1):PAGE76
     2    GND @BASEBOARD_FAB2_LIB.BASEBOARD_FAB2(SCH_1):GND   I217 @BASEBOARD_FAB2_LIB.BASEBOARD_FAB2(SCH_1):PAGE76

C8P25 CAP_0805-47UF,4V,20%,X6S,C9533A
     1 PVCCIN_CPU1 @BASEBOARD_FAB2_LIB.BASEBOARD_FAB2(SCH_1):PVCCIN_CPU1   I251 @BASEBOARD_FAB2_LIB.BASEBOARD_FAB2(SCH_1):PAGE76
     2    GND @BASEBOARD_FAB2_LIB.BASEBOARD_FAB2(SCH_1):GND   I251 @BASEBOARD_FAB2_LIB.BASEBOARD_FAB2(SCH_1):PAGE76

C8P26 CAP_0805-47UF,4V,20%,X6S,C9533A
     1 PVCCIN_CPU1 @BASEBOARD_FAB2_LIB.BASEBOARD_FAB2(SCH_1):PVCCIN_CPU1   I118 @BASEBOARD_FAB2_LIB.BASEBOARD_FAB2(SCH_1):PAGE76
     2    GND @BASEBOARD_FAB2_LIB.BASEBOARD_FAB2(SCH_1):GND   I118 @BASEBOARD_FAB2_LIB.BASEBOARD_FAB2(SCH_1):PAGE76

C8P27 CAP_0805-47UF,4V,20%,X6S,C9533A
     1 PVCCIN_CPU1 @BASEBOARD_FAB2_LIB.BASEBOARD_FAB2(SCH_1):PVCCIN_CPU1   I250 @BASEBOARD_FAB2_LIB.BASEBOARD_FAB2(SCH_1):PAGE76
     2    GND @BASEBOARD_FAB2_LIB.BASEBOARD_FAB2(SCH_1):GND   I250 @BASEBOARD_FAB2_LIB.BASEBOARD_FAB2(SCH_1):PAGE76

C8P28 CAP_0805-47UF,4V,20%,X6S,C9533A
     1 PVCCIN_CPU1 @BASEBOARD_FAB2_LIB.BASEBOARD_FAB2(SCH_1):PVCCIN_CPU1   I137 @BASEBOARD_FAB2_LIB.BASEBOARD_FAB2(SCH_1):PAGE76
     2    GND @BASEBOARD_FAB2_LIB.BASEBOARD_FAB2(SCH_1):GND   I137 @BASEBOARD_FAB2_LIB.BASEBOARD_FAB2(SCH_1):PAGE76

C8P29 CAP_0805-47UF,4V,20%,X6S,C9533A
     1 PVCCIN_CPU1 @BASEBOARD_FAB2_LIB.BASEBOARD_FAB2(SCH_1):PVCCIN_CPU1   I125 @BASEBOARD_FAB2_LIB.BASEBOARD_FAB2(SCH_1):PAGE76
     2    GND @BASEBOARD_FAB2_LIB.BASEBOARD_FAB2(SCH_1):GND   I125 @BASEBOARD_FAB2_LIB.BASEBOARD_FAB2(SCH_1):PAGE76

C8P30 CAP_0805-100UF,4V,20%,X5R,6024A
     1 PVDDQ_GHJ @BASEBOARD_FAB2_LIB.BASEBOARD_FAB2(SCH_1):PVDDQ_GHJ   I313 @BASEBOARD_FAB2_LIB.BASEBOARD_FAB2(SCH_1):PAGE225
     2    GND @BASEBOARD_FAB2_LIB.BASEBOARD_FAB2(SCH_1):GND   I313 @BASEBOARD_FAB2_LIB.BASEBOARD_FAB2(SCH_1):PAGE225

C8P31 CAP_0805-100UF,4V,20%,X5R,6024A
     1 PVDDQ_GHJ @BASEBOARD_FAB2_LIB.BASEBOARD_FAB2(SCH_1):PVDDQ_GHJ   I314 @BASEBOARD_FAB2_LIB.BASEBOARD_FAB2(SCH_1):PAGE225
     2    GND @BASEBOARD_FAB2_LIB.BASEBOARD_FAB2(SCH_1):GND   I314 @BASEBOARD_FAB2_LIB.BASEBOARD_FAB2(SCH_1):PAGE225

C8P32 CAP_0805-100UF,4V,20%,X5R,6024A
     1 PVDDQ_GHJ @BASEBOARD_FAB2_LIB.BASEBOARD_FAB2(SCH_1):PVDDQ_GHJ   I317 @BASEBOARD_FAB2_LIB.BASEBOARD_FAB2(SCH_1):PAGE225
     2    GND @BASEBOARD_FAB2_LIB.BASEBOARD_FAB2(SCH_1):GND   I317 @BASEBOARD_FAB2_LIB.BASEBOARD_FAB2(SCH_1):PAGE225

C8P33 CAP_0805-100UF,4V,20%,X5R,6024A
     1 PVDDQ_GHJ @BASEBOARD_FAB2_LIB.BASEBOARD_FAB2(SCH_1):PVDDQ_GHJ   I316 @BASEBOARD_FAB2_LIB.BASEBOARD_FAB2(SCH_1):PAGE225
     2    GND @BASEBOARD_FAB2_LIB.BASEBOARD_FAB2(SCH_1):GND   I316 @BASEBOARD_FAB2_LIB.BASEBOARD_FAB2(SCH_1):PAGE225

C8P34 CAP_0805-100UF,4V,20%,X5R,6024A
     1 PVDDQ_GHJ @BASEBOARD_FAB2_LIB.BASEBOARD_FAB2(SCH_1):PVDDQ_GHJ   I315 @BASEBOARD_FAB2_LIB.BASEBOARD_FAB2(SCH_1):PAGE225
     2    GND @BASEBOARD_FAB2_LIB.BASEBOARD_FAB2(SCH_1):GND   I315 @BASEBOARD_FAB2_LIB.BASEBOARD_FAB2(SCH_1):PAGE225

C8T1 CAP_A_0603V-47UF,4V,20%,X5R,60A
     1 PVDDQ_GHJ @BASEBOARD_FAB2_LIB.BASEBOARD_FAB2(SCH_1):PVDDQ_GHJ   I202 @BASEBOARD_FAB2_LIB.BASEBOARD_FAB2(SCH_1):PAGE225
     2    GND @BASEBOARD_FAB2_LIB.BASEBOARD_FAB2(SCH_1):GND   I202 @BASEBOARD_FAB2_LIB.BASEBOARD_FAB2(SCH_1):PAGE225

C8T2 CAP_A_0603V-47UF,4V,20%,X5R,60A
     1 PVDDQ_GHJ @BASEBOARD_FAB2_LIB.BASEBOARD_FAB2(SCH_1):PVDDQ_GHJ   I198 @BASEBOARD_FAB2_LIB.BASEBOARD_FAB2(SCH_1):PAGE225
     2    GND @BASEBOARD_FAB2_LIB.BASEBOARD_FAB2(SCH_1):GND   I198 @BASEBOARD_FAB2_LIB.BASEBOARD_FAB2(SCH_1):PAGE225

C8T3 CAP_0805-100UF,4V,20%,X5R,6024A
     1 PVTT_GHJ @BASEBOARD_FAB2_LIB.BASEBOARD_FAB2(SCH_1):PVTT_GHJ    I41 @BASEBOARD_FAB2_LIB.BASEBOARD_FAB2(SCH_1):PAGE229
     2    GND @BASEBOARD_FAB2_LIB.BASEBOARD_FAB2(SCH_1):GND    I41 @BASEBOARD_FAB2_LIB.BASEBOARD_FAB2(SCH_1):PAGE229

C8T4 CAP_A_0603V-47UF,4V,20%,X5R,60A
     1 PVDDQ_GHJ @BASEBOARD_FAB2_LIB.BASEBOARD_FAB2(SCH_1):PVDDQ_GHJ   I196 @BASEBOARD_FAB2_LIB.BASEBOARD_FAB2(SCH_1):PAGE225
     2    GND @BASEBOARD_FAB2_LIB.BASEBOARD_FAB2(SCH_1):GND   I196 @BASEBOARD_FAB2_LIB.BASEBOARD_FAB2(SCH_1):PAGE225

C8T5 CAP_A_0603V-47UF,4V,20%,X5R,60A
     1 PVDDQ_GHJ @BASEBOARD_FAB2_LIB.BASEBOARD_FAB2(SCH_1):PVDDQ_GHJ   I297 @BASEBOARD_FAB2_LIB.BASEBOARD_FAB2(SCH_1):PAGE225
     2    GND @BASEBOARD_FAB2_LIB.BASEBOARD_FAB2(SCH_1):GND   I297 @BASEBOARD_FAB2_LIB.BASEBOARD_FAB2(SCH_1):PAGE225

C8T6 CAP_A_0603V-47UF,4V,20%,X5R,60A
     1 PVDDQ_GHJ @BASEBOARD_FAB2_LIB.BASEBOARD_FAB2(SCH_1):PVDDQ_GHJ   I299 @BASEBOARD_FAB2_LIB.BASEBOARD_FAB2(SCH_1):PAGE225
     2    GND @BASEBOARD_FAB2_LIB.BASEBOARD_FAB2(SCH_1):GND   I299 @BASEBOARD_FAB2_LIB.BASEBOARD_FAB2(SCH_1):PAGE225

C8T7 CAP_A_0603V-47UF,4V,20%,X5R,60A
     1 PVDDQ_GHJ @BASEBOARD_FAB2_LIB.BASEBOARD_FAB2(SCH_1):PVDDQ_GHJ   I300 @BASEBOARD_FAB2_LIB.BASEBOARD_FAB2(SCH_1):PAGE225
     2    GND @BASEBOARD_FAB2_LIB.BASEBOARD_FAB2(SCH_1):GND   I300 @BASEBOARD_FAB2_LIB.BASEBOARD_FAB2(SCH_1):PAGE225

C8T8 CAP_A_0603V-47UF,4V,20%,X5R,60A
     1 PVDDQ_GHJ @BASEBOARD_FAB2_LIB.BASEBOARD_FAB2(SCH_1):PVDDQ_GHJ   I301 @BASEBOARD_FAB2_LIB.BASEBOARD_FAB2(SCH_1):PAGE225
     2    GND @BASEBOARD_FAB2_LIB.BASEBOARD_FAB2(SCH_1):GND   I301 @BASEBOARD_FAB2_LIB.BASEBOARD_FAB2(SCH_1):PAGE225

C8T9 CAP_A_0603V-47UF,4V,20%,X5R,60A
     1 PVDDQ_GHJ @BASEBOARD_FAB2_LIB.BASEBOARD_FAB2(SCH_1):PVDDQ_GHJ   I303 @BASEBOARD_FAB2_LIB.BASEBOARD_FAB2(SCH_1):PAGE225
     2    GND @BASEBOARD_FAB2_LIB.BASEBOARD_FAB2(SCH_1):GND   I303 @BASEBOARD_FAB2_LIB.BASEBOARD_FAB2(SCH_1):PAGE225

C8T10 CAP_A_0603V-47UF,4V,20%,X5R,60A
     1 PVDDQ_GHJ @BASEBOARD_FAB2_LIB.BASEBOARD_FAB2(SCH_1):PVDDQ_GHJ   I304 @BASEBOARD_FAB2_LIB.BASEBOARD_FAB2(SCH_1):PAGE225
     2    GND @BASEBOARD_FAB2_LIB.BASEBOARD_FAB2(SCH_1):GND   I304 @BASEBOARD_FAB2_LIB.BASEBOARD_FAB2(SCH_1):PAGE225

C8T11 CAP_A_0603V-47UF,4V,20%,X5R,60A
     1 PVDDQ_GHJ @BASEBOARD_FAB2_LIB.BASEBOARD_FAB2(SCH_1):PVDDQ_GHJ   I204 @BASEBOARD_FAB2_LIB.BASEBOARD_FAB2(SCH_1):PAGE225
     2    GND @BASEBOARD_FAB2_LIB.BASEBOARD_FAB2(SCH_1):GND   I204 @BASEBOARD_FAB2_LIB.BASEBOARD_FAB2(SCH_1):PAGE225

C8U1 CAP_0805-100UF,4V,20%,X5R,6024A
     1 PVDDQ_GHJ @BASEBOARD_FAB2_LIB.BASEBOARD_FAB2(SCH_1):PVDDQ_GHJ   I319 @BASEBOARD_FAB2_LIB.BASEBOARD_FAB2(SCH_1):PAGE225
     2    GND @BASEBOARD_FAB2_LIB.BASEBOARD_FAB2(SCH_1):GND   I319 @BASEBOARD_FAB2_LIB.BASEBOARD_FAB2(SCH_1):PAGE225

C8U2 CAP_A_0603V-47UF,4V,20%,X5R,60A
     1 PVDDQ_GHJ @BASEBOARD_FAB2_LIB.BASEBOARD_FAB2(SCH_1):PVDDQ_GHJ   I291 @BASEBOARD_FAB2_LIB.BASEBOARD_FAB2(SCH_1):PAGE225
     2    GND @BASEBOARD_FAB2_LIB.BASEBOARD_FAB2(SCH_1):GND   I291 @BASEBOARD_FAB2_LIB.BASEBOARD_FAB2(SCH_1):PAGE225

C8U3 CAP_A_0603V-47UF,4V,20%,X5R,60A
     1 PVDDQ_GHJ @BASEBOARD_FAB2_LIB.BASEBOARD_FAB2(SCH_1):PVDDQ_GHJ   I294 @BASEBOARD_FAB2_LIB.BASEBOARD_FAB2(SCH_1):PAGE225
     2    GND @BASEBOARD_FAB2_LIB.BASEBOARD_FAB2(SCH_1):GND   I294 @BASEBOARD_FAB2_LIB.BASEBOARD_FAB2(SCH_1):PAGE225

C8U4 CAP_A_0603V-47UF,4V,20%,X5R,60A
     1 PVDDQ_GHJ @BASEBOARD_FAB2_LIB.BASEBOARD_FAB2(SCH_1):PVDDQ_GHJ   I305 @BASEBOARD_FAB2_LIB.BASEBOARD_FAB2(SCH_1):PAGE225
     2    GND @BASEBOARD_FAB2_LIB.BASEBOARD_FAB2(SCH_1):GND   I305 @BASEBOARD_FAB2_LIB.BASEBOARD_FAB2(SCH_1):PAGE225

C8U5 CAP_A_0603V-47UF,4V,20%,X5R,60A
     1 PVDDQ_GHJ @BASEBOARD_FAB2_LIB.BASEBOARD_FAB2(SCH_1):PVDDQ_GHJ   I302 @BASEBOARD_FAB2_LIB.BASEBOARD_FAB2(SCH_1):PAGE225
     2    GND @BASEBOARD_FAB2_LIB.BASEBOARD_FAB2(SCH_1):GND   I302 @BASEBOARD_FAB2_LIB.BASEBOARD_FAB2(SCH_1):PAGE225

C8U6 CAP_A_0603V-47UF,4V,20%,X5R,60A
     1 PVDDQ_GHJ @BASEBOARD_FAB2_LIB.BASEBOARD_FAB2(SCH_1):PVDDQ_GHJ   I298 @BASEBOARD_FAB2_LIB.BASEBOARD_FAB2(SCH_1):PAGE225
     2    GND @BASEBOARD_FAB2_LIB.BASEBOARD_FAB2(SCH_1):GND   I298 @BASEBOARD_FAB2_LIB.BASEBOARD_FAB2(SCH_1):PAGE225

C8U7 CAP_A_0603V-47UF,4V,20%,X5R,60A
     1 PVDDQ_GHJ @BASEBOARD_FAB2_LIB.BASEBOARD_FAB2(SCH_1):PVDDQ_GHJ   I290 @BASEBOARD_FAB2_LIB.BASEBOARD_FAB2(SCH_1):PAGE225
     2    GND @BASEBOARD_FAB2_LIB.BASEBOARD_FAB2(SCH_1):GND   I290 @BASEBOARD_FAB2_LIB.BASEBOARD_FAB2(SCH_1):PAGE225

C8U8 CAP_0805-100UF,4V,20%,X5R,6024A
     1 PVDDQ_GHJ @BASEBOARD_FAB2_LIB.BASEBOARD_FAB2(SCH_1):PVDDQ_GHJ   I320 @BASEBOARD_FAB2_LIB.BASEBOARD_FAB2(SCH_1):PAGE225
     2    GND @BASEBOARD_FAB2_LIB.BASEBOARD_FAB2(SCH_1):GND   I320 @BASEBOARD_FAB2_LIB.BASEBOARD_FAB2(SCH_1):PAGE225

C8U9 CAP_A_0603V-47UF,4V,20%,X5R,60A
     1 PVDDQ_GHJ @BASEBOARD_FAB2_LIB.BASEBOARD_FAB2(SCH_1):PVDDQ_GHJ   I203 @BASEBOARD_FAB2_LIB.BASEBOARD_FAB2(SCH_1):PAGE225
     2    GND @BASEBOARD_FAB2_LIB.BASEBOARD_FAB2(SCH_1):GND   I203 @BASEBOARD_FAB2_LIB.BASEBOARD_FAB2(SCH_1):PAGE225

C8U10 CAP_0805-100UF,4V,20%,X5R,6024A
     1 PVTT_GHJ @BASEBOARD_FAB2_LIB.BASEBOARD_FAB2(SCH_1):PVTT_GHJ    I42 @BASEBOARD_FAB2_LIB.BASEBOARD_FAB2(SCH_1):PAGE229
     2    GND @BASEBOARD_FAB2_LIB.BASEBOARD_FAB2(SCH_1):GND    I42 @BASEBOARD_FAB2_LIB.BASEBOARD_FAB2(SCH_1):PAGE229

C8U11 CAP_0805-100UF,4V,20%,X5R,6024A
     1 PVDDQ_GHJ @BASEBOARD_FAB2_LIB.BASEBOARD_FAB2(SCH_1):PVDDQ_GHJ   I307 @BASEBOARD_FAB2_LIB.BASEBOARD_FAB2(SCH_1):PAGE225
     2    GND @BASEBOARD_FAB2_LIB.BASEBOARD_FAB2(SCH_1):GND   I307 @BASEBOARD_FAB2_LIB.BASEBOARD_FAB2(SCH_1):PAGE225

C8U12 CAP_0805-100UF,4V,20%,X5R,6024A
     1 PVDDQ_GHJ @BASEBOARD_FAB2_LIB.BASEBOARD_FAB2(SCH_1):PVDDQ_GHJ   I310 @BASEBOARD_FAB2_LIB.BASEBOARD_FAB2(SCH_1):PAGE225
     2    GND @BASEBOARD_FAB2_LIB.BASEBOARD_FAB2(SCH_1):GND   I310 @BASEBOARD_FAB2_LIB.BASEBOARD_FAB2(SCH_1):PAGE225

C8U13 CAP_A_0603V-47UF,4V,20%,X5R,60A
     1 PVDDQ_GHJ @BASEBOARD_FAB2_LIB.BASEBOARD_FAB2(SCH_1):PVDDQ_GHJ   I199 @BASEBOARD_FAB2_LIB.BASEBOARD_FAB2(SCH_1):PAGE225
     2    GND @BASEBOARD_FAB2_LIB.BASEBOARD_FAB2(SCH_1):GND   I199 @BASEBOARD_FAB2_LIB.BASEBOARD_FAB2(SCH_1):PAGE225

C8W1 SC1U16V3KX-2GP_SMD-BCG-SC1U16VA
     1 BMC_SELF_HW_D_RST @BASEBOARD_FAB2_LIB.BASEBOARD_FAB2(SCH_1):BMC_SELF_HW_D_RST    I52 @BASEBOARD_FAB2_LIB.BASEBOARD_FAB2(SCH_1):PAGE249
     2 BMC_TPM_HW_C_RST @BASEBOARD_FAB2_LIB.BASEBOARD_FAB2(SCH_1):BMC_TPM_HW_C_RST    I52 @BASEBOARD_FAB2_LIB.BASEBOARD_FAB2(SCH_1):PAGE249

C8W2 CAP_A_0402V-0.1UF,16V,10%,X7R,A
     1 P5V_STBY @BASEBOARD_FAB2_LIB.BASEBOARD_FAB2(SCH_1):P5V_STBY    I37 @BASEBOARD_FAB2_LIB.BASEBOARD_FAB2(SCH_1):PAGE249
     2    GND @BASEBOARD_FAB2_LIB.BASEBOARD_FAB2(SCH_1):GND    I37 @BASEBOARD_FAB2_LIB.BASEBOARD_FAB2(SCH_1):PAGE249

C8W3 CAP_0805-100UF,4V,20%,X5R,6024A
     1 PVCCIN_CPU0 @BASEBOARD_FAB2_LIB.BASEBOARD_FAB2(SCH_1):PVCCIN_CPU0   I211 @BASEBOARD_FAB2_LIB.BASEBOARD_FAB2(SCH_1):PAGE42
     2    GND @BASEBOARD_FAB2_LIB.BASEBOARD_FAB2(SCH_1):GND   I211 @BASEBOARD_FAB2_LIB.BASEBOARD_FAB2(SCH_1):PAGE42

C8W4 CAP_0805-100UF,4V,20%,X5R,6024A
     1 PVCCIN_CPU1 @BASEBOARD_FAB2_LIB.BASEBOARD_FAB2(SCH_1):PVCCIN_CPU1   I245 @BASEBOARD_FAB2_LIB.BASEBOARD_FAB2(SCH_1):PAGE76
     2    GND @BASEBOARD_FAB2_LIB.BASEBOARD_FAB2(SCH_1):GND   I245 @BASEBOARD_FAB2_LIB.BASEBOARD_FAB2(SCH_1):PAGE76

C8W5 CAP_A_0402V-1.0UF,6.3V,10%,X6SA
     1 P3V3_STBY @BASEBOARD_FAB2_LIB.BASEBOARD_FAB2(SCH_1):P3V3_STBY    I74 @BASEBOARD_FAB2_LIB.BASEBOARD_FAB2(SCH_1):PAGE245
     2    GND @BASEBOARD_FAB2_LIB.BASEBOARD_FAB2(SCH_1):GND    I74 @BASEBOARD_FAB2_LIB.BASEBOARD_FAB2(SCH_1):PAGE245

C8W6 CAP_A_0402V-0.01UF,25V,10%,X7RA
     1 P3V3_STBY @BASEBOARD_FAB2_LIB.BASEBOARD_FAB2(SCH_1):P3V3_STBY    I71 @BASEBOARD_FAB2_LIB.BASEBOARD_FAB2(SCH_1):PAGE245
     2    GND @BASEBOARD_FAB2_LIB.BASEBOARD_FAB2(SCH_1):GND    I71 @BASEBOARD_FAB2_LIB.BASEBOARD_FAB2(SCH_1):PAGE245

C9A1 CAP_A_0402V-0.1UF,16V,10%,X7R,A
     1 P5V_STBY_DGB_FS @BASEBOARD_FAB2_LIB.BASEBOARD_FAB2(SCH_1):P5V_STBY_DGB_FS   I127 @BASEBOARD_FAB2_LIB.BASEBOARD_FAB2(SCH_1):PAGE155
     2    GND @BASEBOARD_FAB2_LIB.BASEBOARD_FAB2(SCH_1):GND   I127 @BASEBOARD_FAB2_LIB.BASEBOARD_FAB2(SCH_1):PAGE155

C9A2 CAP_A_0402V-0.1UF,16V,10%,X7R,A
     1 XDP_SYSPWROK @BASEBOARD_FAB2_LIB.BASEBOARD_FAB2(SCH_1):XDP_SYSPWROK    I10 @BASEBOARD_FAB2_LIB.BASEBOARD_FAB2(SCH_1):PAGE111
     2    GND @BASEBOARD_FAB2_LIB.BASEBOARD_FAB2(SCH_1):GND    I10 @BASEBOARD_FAB2_LIB.BASEBOARD_FAB2(SCH_1):PAGE111

C9A3 CAP_A_0402V-0.1UF,16V,10%,X7R,A
     1 P3V3_STBY @BASEBOARD_FAB2_LIB.BASEBOARD_FAB2(SCH_1):P3V3_STBY    I40 @BASEBOARD_FAB2_LIB.BASEBOARD_FAB2(SCH_1):PAGE175
     2    GND @BASEBOARD_FAB2_LIB.BASEBOARD_FAB2(SCH_1):GND    I40 @BASEBOARD_FAB2_LIB.BASEBOARD_FAB2(SCH_1):PAGE175

C9A4 CAP_A_0402V-0.1UF,16V,10%,X7R,A
     1 XDP_CPU_PWR_DEBUG_N @BASEBOARD_FAB2_LIB.BASEBOARD_FAB2(SCH_1):XDP_CPU_PWR_DEBUG_N    I59 @BASEBOARD_FAB2_LIB.BASEBOARD_FAB2(SCH_1):PAGE111
     2    GND @BASEBOARD_FAB2_LIB.BASEBOARD_FAB2(SCH_1):GND    I59 @BASEBOARD_FAB2_LIB.BASEBOARD_FAB2(SCH_1):PAGE111

C9A5 CAP_A_0402V-0.1UF,16V,10%,X7R,A
     1 XDP_RST_CO_N @BASEBOARD_FAB2_LIB.BASEBOARD_FAB2(SCH_1):XDP_RST_CO_N    I12 @BASEBOARD_FAB2_LIB.BASEBOARD_FAB2(SCH_1):PAGE111
     2    GND @BASEBOARD_FAB2_LIB.BASEBOARD_FAB2(SCH_1):GND    I12 @BASEBOARD_FAB2_LIB.BASEBOARD_FAB2(SCH_1):PAGE111

C9A6 CAP_A_0402V-1.0UF,6.3V,10%,X6SA
     1 P1V05_PCH_STBY @BASEBOARD_FAB2_LIB.BASEBOARD_FAB2(SCH_1):P1V05_PCH_STBY    I25 @BASEBOARD_FAB2_LIB.BASEBOARD_FAB2(SCH_1):PAGE111
     2    GND @BASEBOARD_FAB2_LIB.BASEBOARD_FAB2(SCH_1):GND    I25 @BASEBOARD_FAB2_LIB.BASEBOARD_FAB2(SCH_1):PAGE111

C9B1 CAP_0805-10UF,16V,10%,X6S,C953A
     1 P5V_HDD_SATA @BASEBOARD_FAB2_LIB.BASEBOARD_FAB2(SCH_1):P5V_HDD_SATA    I39 @BASEBOARD_FAB2_LIB.BASEBOARD_FAB2(SCH_1):PAGE172
     2    GND @BASEBOARD_FAB2_LIB.BASEBOARD_FAB2(SCH_1):GND    I39 @BASEBOARD_FAB2_LIB.BASEBOARD_FAB2(SCH_1):PAGE172

C9B2 CAP_0805-10UF,16V,10%,X6S,C953A
     1 P12V_HDD_SATA @BASEBOARD_FAB2_LIB.BASEBOARD_FAB2(SCH_1):P12V_HDD_SATA    I36 @BASEBOARD_FAB2_LIB.BASEBOARD_FAB2(SCH_1):PAGE172
     2    GND @BASEBOARD_FAB2_LIB.BASEBOARD_FAB2(SCH_1):GND    I36 @BASEBOARD_FAB2_LIB.BASEBOARD_FAB2(SCH_1):PAGE172

C9B7 CAP_A_0402V-0.1UF,16V,10%,X7R,A
     1 P3V3_STBY @BASEBOARD_FAB2_LIB.BASEBOARD_FAB2(SCH_1):P3V3_STBY    I39 @BASEBOARD_FAB2_LIB.BASEBOARD_FAB2(SCH_1):PAGE167
     2    GND @BASEBOARD_FAB2_LIB.BASEBOARD_FAB2(SCH_1):GND    I39 @BASEBOARD_FAB2_LIB.BASEBOARD_FAB2(SCH_1):PAGE167

C9B8 CAPP_7343HLF-330UF,10V,20%,POSA
     1 P5V_USB @BASEBOARD_FAB2_LIB.BASEBOARD_FAB2(SCH_1):P5V_USB   I113 @BASEBOARD_FAB2_LIB.BASEBOARD_FAB2(SCH_1):PAGE176
     2    GND @BASEBOARD_FAB2_LIB.BASEBOARD_FAB2(SCH_1):GND   I113 @BASEBOARD_FAB2_LIB.BASEBOARD_FAB2(SCH_1):PAGE176

C9B9 SC1U10V2KX-4-GP_SMD-BCG6-SC1U1A
     1 P5V_STBY @BASEBOARD_FAB2_LIB.BASEBOARD_FAB2(SCH_1):P5V_STBY   I357 @BASEBOARD_FAB2_LIB.BASEBOARD_FAB2(SCH_1):PAGE186
     2    GND @BASEBOARD_FAB2_LIB.BASEBOARD_FAB2(SCH_1):GND   I357 @BASEBOARD_FAB2_LIB.BASEBOARD_FAB2(SCH_1):PAGE186

C9B10 CAP_A_0402V-0.1UF,16V,10%,X7R,A
     1 P5V_STBY @BASEBOARD_FAB2_LIB.BASEBOARD_FAB2(SCH_1):P5V_STBY   I345 @BASEBOARD_FAB2_LIB.BASEBOARD_FAB2(SCH_1):PAGE186
     2    GND @BASEBOARD_FAB2_LIB.BASEBOARD_FAB2(SCH_1):GND   I345 @BASEBOARD_FAB2_LIB.BASEBOARD_FAB2(SCH_1):PAGE186

C9E1 CAP_A_0603V-22.0UF,4V,20%,EMPTA
     1 P0V9_LAN @BASEBOARD_FAB2_LIB.BASEBOARD_FAB2(SCH_1):P0V9_LAN   I163 @BASEBOARD_FAB2_LIB.BASEBOARD_FAB2(SCH_1):PAGE139
     2    GND @BASEBOARD_FAB2_LIB.BASEBOARD_FAB2(SCH_1):GND   I163 @BASEBOARD_FAB2_LIB.BASEBOARD_FAB2(SCH_1):PAGE139

C9E4 CAP_A_0402V-0.1UF,16V,10%,X7R,A
     1 PE_PCH_SPRV_RX_DP @BASEBOARD_FAB2_LIB.BASEBOARD_FAB2(SCH_1):PE_PCH_SPRV_RX_DP    I88 @BASEBOARD_FAB2_LIB.BASEBOARD_FAB2(SCH_1):PAGE139
     2 PE_PCH_SPRV_RX_C_DP @BASEBOARD_FAB2_LIB.BASEBOARD_FAB2(SCH_1):PE_PCH_SPRV_RX_C_DP    I88 @BASEBOARD_FAB2_LIB.BASEBOARD_FAB2(SCH_1):PAGE139

C9E5 CAP_A_0402V-0.1UF,16V,10%,X7R,A
     1 PE_PCH_SPRV_RX_DN @BASEBOARD_FAB2_LIB.BASEBOARD_FAB2(SCH_1):PE_PCH_SPRV_RX_DN    I87 @BASEBOARD_FAB2_LIB.BASEBOARD_FAB2(SCH_1):PAGE139
     2 PE_PCH_SPRV_RX_C_DN @BASEBOARD_FAB2_LIB.BASEBOARD_FAB2(SCH_1):PE_PCH_SPRV_RX_C_DN    I87 @BASEBOARD_FAB2_LIB.BASEBOARD_FAB2(SCH_1):PAGE139

C9E6 SC22U16V5MX-4-GP_SMD-BCG5-SC22A
     1 P1V5_LAN @BASEBOARD_FAB2_LIB.BASEBOARD_FAB2(SCH_1):P1V5_LAN   I248 @BASEBOARD_FAB2_LIB.BASEBOARD_FAB2(SCH_1):PAGE139
     2    GND @BASEBOARD_FAB2_LIB.BASEBOARD_FAB2(SCH_1):GND   I248 @BASEBOARD_FAB2_LIB.BASEBOARD_FAB2(SCH_1):PAGE139

C9E7 CAP_0402LF-0.039UF,25V,10%,X7RA
     1 A_CTOP @BASEBOARD_FAB2_LIB.BASEBOARD_FAB2(SCH_1):A_CTOP    I76 @BASEBOARD_FAB2_LIB.BASEBOARD_FAB2(SCH_1):PAGE139
     2 A_CBOT @BASEBOARD_FAB2_LIB.BASEBOARD_FAB2(SCH_1):A_CBOT    I76 @BASEBOARD_FAB2_LIB.BASEBOARD_FAB2(SCH_1):PAGE139

C9E8 CAP_0402LF-15.0PF,50V,5%,COG,AA
     1 XTAL_25MHZ_OUT_R @BASEBOARD_FAB2_LIB.BASEBOARD_FAB2(SCH_1):XTAL_25MHZ_OUT_R   I250 @BASEBOARD_FAB2_LIB.BASEBOARD_FAB2(SCH_1):PAGE139
     2    GND @BASEBOARD_FAB2_LIB.BASEBOARD_FAB2(SCH_1):GND   I250 @BASEBOARD_FAB2_LIB.BASEBOARD_FAB2(SCH_1):PAGE139

C9E9 CAP_0402LF-15.0PF,50V,5%,COG,AA
     1 XTAL_25MHZ_IN @BASEBOARD_FAB2_LIB.BASEBOARD_FAB2(SCH_1):XTAL_25MHZ_IN   I249 @BASEBOARD_FAB2_LIB.BASEBOARD_FAB2(SCH_1):PAGE139
     2    GND @BASEBOARD_FAB2_LIB.BASEBOARD_FAB2(SCH_1):GND   I249 @BASEBOARD_FAB2_LIB.BASEBOARD_FAB2(SCH_1):PAGE139

C9E10 CAP_0603-10UF,6.3V,20%,X6S,E15A
     1 P1V15_AUX_BMC @BASEBOARD_FAB2_LIB.BASEBOARD_FAB2(SCH_1):P1V15_AUX_BMC    I23 @BASEBOARD_FAB2_LIB.BASEBOARD_FAB2(SCH_1):PAGE238
     2    GND @BASEBOARD_FAB2_LIB.BASEBOARD_FAB2(SCH_1):GND    I23 @BASEBOARD_FAB2_LIB.BASEBOARD_FAB2(SCH_1):PAGE238

C9E11 CAP_0402-1.0UF,16V,10%,X6S,D97A
     1 P3V3_STBY @BASEBOARD_FAB2_LIB.BASEBOARD_FAB2(SCH_1):P3V3_STBY    I39 @BASEBOARD_FAB2_LIB.BASEBOARD_FAB2(SCH_1):PAGE238
     2    GND @BASEBOARD_FAB2_LIB.BASEBOARD_FAB2(SCH_1):GND    I39 @BASEBOARD_FAB2_LIB.BASEBOARD_FAB2(SCH_1):PAGE238

C9E12 CAP_A_0603V-22.0UF,4V,20%,EMPTA
     1 P0V9_LAN @BASEBOARD_FAB2_LIB.BASEBOARD_FAB2(SCH_1):P0V9_LAN   I241 @BASEBOARD_FAB2_LIB.BASEBOARD_FAB2(SCH_1):PAGE139
     2    GND @BASEBOARD_FAB2_LIB.BASEBOARD_FAB2(SCH_1):GND   I241 @BASEBOARD_FAB2_LIB.BASEBOARD_FAB2(SCH_1):PAGE139

C9F1 SC22U16V5MX-4-GP_SMD-BCG5-SC22A
     1 VR_FET_SW_P12V_STBY_P3V3_STBY @BASEBOARD_FAB2_LIB.BASEBOARD_FAB2(SCH_1):VR_FET_SW_P12V_STBY_P3V3_STBY   I181 @BASEBOARD_FAB2_LIB.BASEBOARD_FAB2(SCH_1):PAGE240
     2    GND @BASEBOARD_FAB2_LIB.BASEBOARD_FAB2(SCH_1):GND   I181 @BASEBOARD_FAB2_LIB.BASEBOARD_FAB2(SCH_1):PAGE240

C9F2 SC22U16V5MX-4-GP_SMD-BCG5-SC22A
     1 P3V3_STBY @BASEBOARD_FAB2_LIB.BASEBOARD_FAB2(SCH_1):P3V3_STBY   I245 @BASEBOARD_FAB2_LIB.BASEBOARD_FAB2(SCH_1):PAGE139
     2    GND @BASEBOARD_FAB2_LIB.BASEBOARD_FAB2(SCH_1):GND   I245 @BASEBOARD_FAB2_LIB.BASEBOARD_FAB2(SCH_1):PAGE139

C9F3 CAP_0603-10UF,6.3V,20%,X6S,E15A
     1 P3V3_STBY @BASEBOARD_FAB2_LIB.BASEBOARD_FAB2(SCH_1):P3V3_STBY     I7 @BASEBOARD_FAB2_LIB.BASEBOARD_FAB2(SCH_1):PAGE238
     2    GND @BASEBOARD_FAB2_LIB.BASEBOARD_FAB2(SCH_1):GND     I7 @BASEBOARD_FAB2_LIB.BASEBOARD_FAB2(SCH_1):PAGE238

C9F4 CAP_0805LF-22UF,4V,20%,X6S,C95A
     1 P1V15_AUX_BMC @BASEBOARD_FAB2_LIB.BASEBOARD_FAB2(SCH_1):P1V15_AUX_BMC    I30 @BASEBOARD_FAB2_LIB.BASEBOARD_FAB2(SCH_1):PAGE238
     2    GND @BASEBOARD_FAB2_LIB.BASEBOARD_FAB2(SCH_1):GND    I30 @BASEBOARD_FAB2_LIB.BASEBOARD_FAB2(SCH_1):PAGE238

C9F5 CAP_A_0402V-0.1UF,16V,10%,X7R,A
     1 P3V3_STBY @BASEBOARD_FAB2_LIB.BASEBOARD_FAB2(SCH_1):P3V3_STBY    I71 @BASEBOARD_FAB2_LIB.BASEBOARD_FAB2(SCH_1):PAGE239
     2    GND @BASEBOARD_FAB2_LIB.BASEBOARD_FAB2(SCH_1):GND    I71 @BASEBOARD_FAB2_LIB.BASEBOARD_FAB2(SCH_1):PAGE239

C9F6 CAP_0402LF-1000PF,50V,10%,EMPTA
     1 PWRGD_P2V5_BMC_STBY @BASEBOARD_FAB2_LIB.BASEBOARD_FAB2(SCH_1):PWRGD_P2V5_BMC_STBY    I30 @BASEBOARD_FAB2_LIB.BASEBOARD_FAB2(SCH_1):PAGE239
     2    GND @BASEBOARD_FAB2_LIB.BASEBOARD_FAB2(SCH_1):GND    I30 @BASEBOARD_FAB2_LIB.BASEBOARD_FAB2(SCH_1):PAGE239

C9F8 CAP_0402LF-1000PF,50V,10%,X7R,A
     1 PWRGD_P1V15_BMC_STBY_R @BASEBOARD_FAB2_LIB.BASEBOARD_FAB2(SCH_1):PWRGD_P1V15_BMC_STBY_R    I19 @BASEBOARD_FAB2_LIB.BASEBOARD_FAB2(SCH_1):PAGE238
     2    GND @BASEBOARD_FAB2_LIB.BASEBOARD_FAB2(SCH_1):GND    I19 @BASEBOARD_FAB2_LIB.BASEBOARD_FAB2(SCH_1):PAGE238

C9F9 CAP_0402LF-1000PF,50V,10%,EMPTA
     1 PWRGD_P1V2_BMC_STBY @BASEBOARD_FAB2_LIB.BASEBOARD_FAB2(SCH_1):PWRGD_P1V2_BMC_STBY     I5 @BASEBOARD_FAB2_LIB.BASEBOARD_FAB2(SCH_1):PAGE238
     2    GND @BASEBOARD_FAB2_LIB.BASEBOARD_FAB2(SCH_1):GND     I5 @BASEBOARD_FAB2_LIB.BASEBOARD_FAB2(SCH_1):PAGE238

C9F10 CAP_0402LF-1000PF,50V,10%,X7R,A
     1 PWRGD_P1V2_BMC_STBY_R @BASEBOARD_FAB2_LIB.BASEBOARD_FAB2(SCH_1):PWRGD_P1V2_BMC_STBY_R     I4 @BASEBOARD_FAB2_LIB.BASEBOARD_FAB2(SCH_1):PAGE239
     2    GND @BASEBOARD_FAB2_LIB.BASEBOARD_FAB2(SCH_1):GND     I4 @BASEBOARD_FAB2_LIB.BASEBOARD_FAB2(SCH_1):PAGE239

C9F13 CAP_0805LF-22UF,4V,20%,X6S,C95A
     1 P1V2_AUX_BMC @BASEBOARD_FAB2_LIB.BASEBOARD_FAB2(SCH_1):P1V2_AUX_BMC     I7 @BASEBOARD_FAB2_LIB.BASEBOARD_FAB2(SCH_1):PAGE239
     2    GND @BASEBOARD_FAB2_LIB.BASEBOARD_FAB2(SCH_1):GND     I7 @BASEBOARD_FAB2_LIB.BASEBOARD_FAB2(SCH_1):PAGE239

C9F22 CAP_0402LF-470PF,50V,10%,X7R,AA
     1 LED_LAN_1_N @BASEBOARD_FAB2_LIB.BASEBOARD_FAB2(SCH_1):LED_LAN_1_N   I159 @BASEBOARD_FAB2_LIB.BASEBOARD_FAB2(SCH_1):PAGE141
     2    GND @BASEBOARD_FAB2_LIB.BASEBOARD_FAB2(SCH_1):GND   I159 @BASEBOARD_FAB2_LIB.BASEBOARD_FAB2(SCH_1):PAGE141

C9F23 CAP_A_0402V-0.1UF,16V,10%,X7R,A
     1 P3V3_STBY @BASEBOARD_FAB2_LIB.BASEBOARD_FAB2(SCH_1):P3V3_STBY    I15 @BASEBOARD_FAB2_LIB.BASEBOARD_FAB2(SCH_1):PAGE145
     2    GND @BASEBOARD_FAB2_LIB.BASEBOARD_FAB2(SCH_1):GND    I15 @BASEBOARD_FAB2_LIB.BASEBOARD_FAB2(SCH_1):PAGE145

C9G1 CAP_0402LF-470PF,50V,10%,X7R,AA
     1 LED_LAN_2_N @BASEBOARD_FAB2_LIB.BASEBOARD_FAB2(SCH_1):LED_LAN_2_N   I140 @BASEBOARD_FAB2_LIB.BASEBOARD_FAB2(SCH_1):PAGE141
     2    GND @BASEBOARD_FAB2_LIB.BASEBOARD_FAB2(SCH_1):GND   I140 @BASEBOARD_FAB2_LIB.BASEBOARD_FAB2(SCH_1):PAGE141

C9G2 CAP_0402LF-470PF,50V,10%,X7R,AA
     1 P3V3_STBY @BASEBOARD_FAB2_LIB.BASEBOARD_FAB2(SCH_1):P3V3_STBY   I152 @BASEBOARD_FAB2_LIB.BASEBOARD_FAB2(SCH_1):PAGE141
     2    GND @BASEBOARD_FAB2_LIB.BASEBOARD_FAB2(SCH_1):GND   I152 @BASEBOARD_FAB2_LIB.BASEBOARD_FAB2(SCH_1):PAGE141

C9G3 CAP_0402LF-470PF,50V,10%,X7R,AA
     1 LED_LAN_0_N @BASEBOARD_FAB2_LIB.BASEBOARD_FAB2(SCH_1):LED_LAN_0_N   I138 @BASEBOARD_FAB2_LIB.BASEBOARD_FAB2(SCH_1):PAGE141
     2    GND @BASEBOARD_FAB2_LIB.BASEBOARD_FAB2(SCH_1):GND   I138 @BASEBOARD_FAB2_LIB.BASEBOARD_FAB2(SCH_1):PAGE141

C9G4 CAP_A_0402V-0.1UF,16V,10%,X7R,A
     1 GND_LAN_TRCT1234_C @BASEBOARD_FAB2_LIB.BASEBOARD_FAB2(SCH_1):GND_LAN_TRCT1234_C    I46 @BASEBOARD_FAB2_LIB.BASEBOARD_FAB2(SCH_1):PAGE141
     2    GND @BASEBOARD_FAB2_LIB.BASEBOARD_FAB2(SCH_1):GND    I46 @BASEBOARD_FAB2_LIB.BASEBOARD_FAB2(SCH_1):PAGE141

C9G5 CAP_0402-1.0UF,16V,10%,X7S,G71A
     1 GND_LAN_TRCT1234_C @BASEBOARD_FAB2_LIB.BASEBOARD_FAB2(SCH_1):GND_LAN_TRCT1234_C    I48 @BASEBOARD_FAB2_LIB.BASEBOARD_FAB2(SCH_1):PAGE141
     2    GND @BASEBOARD_FAB2_LIB.BASEBOARD_FAB2(SCH_1):GND    I48 @BASEBOARD_FAB2_LIB.BASEBOARD_FAB2(SCH_1):PAGE141

C9G6 CAP_A_0402V-0.1UF,16V,10%,X7R,A
     1 GND_LAN_TRCT1234_C @BASEBOARD_FAB2_LIB.BASEBOARD_FAB2(SCH_1):GND_LAN_TRCT1234_C    I47 @BASEBOARD_FAB2_LIB.BASEBOARD_FAB2(SCH_1):PAGE141
     2    GND @BASEBOARD_FAB2_LIB.BASEBOARD_FAB2(SCH_1):GND    I47 @BASEBOARD_FAB2_LIB.BASEBOARD_FAB2(SCH_1):PAGE141

C9G9 CAP_0402LF-4700PF,50V,10%,EMPTA
     1 NIC_SER_P_MDI_3_DP @BASEBOARD_FAB2_LIB.BASEBOARD_FAB2(SCH_1):NIC_SER_P_MDI_3_DP    I99 @BASEBOARD_FAB2_LIB.BASEBOARD_FAB2(SCH_1):PAGE141
     2 NIC_MDI_MNG_RX_DP @BASEBOARD_FAB2_LIB.BASEBOARD_FAB2(SCH_1):NIC_MDI_MNG_RX_DP    I99 @BASEBOARD_FAB2_LIB.BASEBOARD_FAB2(SCH_1):PAGE141

C9G12 CAP_0402LF-4700PF,50V,10%,EMPTA
     1 NIC_SER_N_MDI_3_DN @BASEBOARD_FAB2_LIB.BASEBOARD_FAB2(SCH_1):NIC_SER_N_MDI_3_DN   I100 @BASEBOARD_FAB2_LIB.BASEBOARD_FAB2(SCH_1):PAGE141
     2 NIC_MDI_MNG_RX_DN @BASEBOARD_FAB2_LIB.BASEBOARD_FAB2(SCH_1):NIC_MDI_MNG_RX_DN   I100 @BASEBOARD_FAB2_LIB.BASEBOARD_FAB2(SCH_1):PAGE141

C9G13 CAP_0402LF-4700PF,50V,10%,EMPTA
     1 NIC_SET_N_MDI_2_DN @BASEBOARD_FAB2_LIB.BASEBOARD_FAB2(SCH_1):NIC_SET_N_MDI_2_DN   I102 @BASEBOARD_FAB2_LIB.BASEBOARD_FAB2(SCH_1):PAGE141
     2 NIC_MDI_MNG_TX_DN @BASEBOARD_FAB2_LIB.BASEBOARD_FAB2(SCH_1):NIC_MDI_MNG_TX_DN   I102 @BASEBOARD_FAB2_LIB.BASEBOARD_FAB2(SCH_1):PAGE141

C9G14 CAP_0402LF-47.0PF,50V,5%,COG,AA
     1 A_P3V3_SCALED @BASEBOARD_FAB2_LIB.BASEBOARD_FAB2(SCH_1):A_P3V3_SCALED   I146 @BASEBOARD_FAB2_LIB.BASEBOARD_FAB2(SCH_1):PAGE169
     2    GND @BASEBOARD_FAB2_LIB.BASEBOARD_FAB2(SCH_1):GND   I146 @BASEBOARD_FAB2_LIB.BASEBOARD_FAB2(SCH_1):PAGE169

C9G15 CAP_0402LF-47.0PF,50V,5%,COG,AA
     1 A_P5V_SCALED @BASEBOARD_FAB2_LIB.BASEBOARD_FAB2(SCH_1):A_P5V_SCALED   I139 @BASEBOARD_FAB2_LIB.BASEBOARD_FAB2(SCH_1):PAGE169
     2    GND @BASEBOARD_FAB2_LIB.BASEBOARD_FAB2(SCH_1):GND   I139 @BASEBOARD_FAB2_LIB.BASEBOARD_FAB2(SCH_1):PAGE169

C9G16 CAP_0402LF-4700PF,50V,10%,EMPTA
     1 NIC_SET_P_MDI_2_DP @BASEBOARD_FAB2_LIB.BASEBOARD_FAB2(SCH_1):NIC_SET_P_MDI_2_DP   I101 @BASEBOARD_FAB2_LIB.BASEBOARD_FAB2(SCH_1):PAGE141
     2 NIC_MDI_MNG_TX_DP @BASEBOARD_FAB2_LIB.BASEBOARD_FAB2(SCH_1):NIC_MDI_MNG_TX_DP   I101 @BASEBOARD_FAB2_LIB.BASEBOARD_FAB2(SCH_1):PAGE141

C9G17 CAP_0402LF-47.0PF,50V,5%,COG,AA
     1 A_P12V_STBY_SCALED @BASEBOARD_FAB2_LIB.BASEBOARD_FAB2(SCH_1):A_P12V_STBY_SCALED    I80 @BASEBOARD_FAB2_LIB.BASEBOARD_FAB2(SCH_1):PAGE169
     2    GND @BASEBOARD_FAB2_LIB.BASEBOARD_FAB2(SCH_1):GND    I80 @BASEBOARD_FAB2_LIB.BASEBOARD_FAB2(SCH_1):PAGE169

C9G18 CAP_0402LF-47.0PF,50V,5%,COG,AA
     1 A_PVNN_STBY_PCH_SENSOR @BASEBOARD_FAB2_LIB.BASEBOARD_FAB2(SCH_1):A_PVNN_STBY_PCH_SENSOR   I153 @BASEBOARD_FAB2_LIB.BASEBOARD_FAB2(SCH_1):PAGE169
     2    GND @BASEBOARD_FAB2_LIB.BASEBOARD_FAB2(SCH_1):GND   I153 @BASEBOARD_FAB2_LIB.BASEBOARD_FAB2(SCH_1):PAGE169

C9G20 CAP_0402LF-47.0PF,50V,5%,COG,AA
     1 A_P3V3_STBY_SCALED @BASEBOARD_FAB2_LIB.BASEBOARD_FAB2(SCH_1):A_P3V3_STBY_SCALED    I86 @BASEBOARD_FAB2_LIB.BASEBOARD_FAB2(SCH_1):PAGE169
     2    GND @BASEBOARD_FAB2_LIB.BASEBOARD_FAB2(SCH_1):GND    I86 @BASEBOARD_FAB2_LIB.BASEBOARD_FAB2(SCH_1):PAGE169

C9G21 CAP_0402LF-47.0PF,50V,5%,COG,AA
     1 A_P5V_STBY_SCALED @BASEBOARD_FAB2_LIB.BASEBOARD_FAB2(SCH_1):A_P5V_STBY_SCALED    I68 @BASEBOARD_FAB2_LIB.BASEBOARD_FAB2(SCH_1):PAGE169
     2    GND @BASEBOARD_FAB2_LIB.BASEBOARD_FAB2(SCH_1):GND    I68 @BASEBOARD_FAB2_LIB.BASEBOARD_FAB2(SCH_1):PAGE169

C9G22 CAP_0402LF-10.0PF,50V,5%,COG,AA
     1 A_P3V_BAT_SCALED @BASEBOARD_FAB2_LIB.BASEBOARD_FAB2(SCH_1):A_P3V_BAT_SCALED   I108 @BASEBOARD_FAB2_LIB.BASEBOARD_FAB2(SCH_1):PAGE169
     2    GND @BASEBOARD_FAB2_LIB.BASEBOARD_FAB2(SCH_1):GND   I108 @BASEBOARD_FAB2_LIB.BASEBOARD_FAB2(SCH_1):PAGE169

C9L1 CAP_A_0402V-0.01UF,25V,10%,X7RA
     1 M_M_VREF @BASEBOARD_FAB2_LIB.BASEBOARD_FAB2(SCH_1):M_M_VREF   I177 @BASEBOARD_FAB2_LIB.BASEBOARD_FAB2(SCH_1):PAGE88
     2    GND @BASEBOARD_FAB2_LIB.BASEBOARD_FAB2(SCH_1):GND   I177 @BASEBOARD_FAB2_LIB.BASEBOARD_FAB2(SCH_1):PAGE88

C9L2 CAPP_3018-470UF,2.5V,20%,ALUM,A
     1 PVDDQ_KLM @BASEBOARD_FAB2_LIB.BASEBOARD_FAB2(SCH_1):PVDDQ_KLM    I78 @BASEBOARD_FAB2_LIB.BASEBOARD_FAB2(SCH_1):PAGE228
     2    GND @BASEBOARD_FAB2_LIB.BASEBOARD_FAB2(SCH_1):GND    I78 @BASEBOARD_FAB2_LIB.BASEBOARD_FAB2(SCH_1):PAGE228

C9L3 CAP_A_0402V-0.01UF,25V,10%,X7RA
     1 M_M_CPU_VREF @BASEBOARD_FAB2_LIB.BASEBOARD_FAB2(SCH_1):M_M_CPU_VREF    I46 @BASEBOARD_FAB2_LIB.BASEBOARD_FAB2(SCH_1):PAGE100
     2    GND @BASEBOARD_FAB2_LIB.BASEBOARD_FAB2(SCH_1):GND    I46 @BASEBOARD_FAB2_LIB.BASEBOARD_FAB2(SCH_1):PAGE100

C9L4 CAPP_3018-470UF,2.5V,20%,ALUM,A
     1 PVDDQ_KLM @BASEBOARD_FAB2_LIB.BASEBOARD_FAB2(SCH_1):PVDDQ_KLM    I77 @BASEBOARD_FAB2_LIB.BASEBOARD_FAB2(SCH_1):PAGE228
     2    GND @BASEBOARD_FAB2_LIB.BASEBOARD_FAB2(SCH_1):GND    I77 @BASEBOARD_FAB2_LIB.BASEBOARD_FAB2(SCH_1):PAGE228

C9L5 CAP_0805-10UF,16V,10%,X6S,C953A
     1 VR_FET_SW_P12V_STBY_PVDDQ_KLM @BASEBOARD_FAB2_LIB.BASEBOARD_FAB2(SCH_1):VR_FET_SW_P12V_STBY_PVDDQ_KLM    I80 @BASEBOARD_FAB2_LIB.BASEBOARD_FAB2(SCH_1):PAGE227
     2    GND @BASEBOARD_FAB2_LIB.BASEBOARD_FAB2(SCH_1):GND    I80 @BASEBOARD_FAB2_LIB.BASEBOARD_FAB2(SCH_1):PAGE227

C9L6 CAP_0805-10UF,16V,10%,X6S,C953A
     1 VR_FET_SW_P12V_STBY_PVDDQ_KLM @BASEBOARD_FAB2_LIB.BASEBOARD_FAB2(SCH_1):VR_FET_SW_P12V_STBY_PVDDQ_KLM    I47 @BASEBOARD_FAB2_LIB.BASEBOARD_FAB2(SCH_1):PAGE227
     2    GND @BASEBOARD_FAB2_LIB.BASEBOARD_FAB2(SCH_1):GND    I47 @BASEBOARD_FAB2_LIB.BASEBOARD_FAB2(SCH_1):PAGE227

C9L7 CAP_A_0402V-0.01UF,25V,10%,X7RA
     1 M_L_VREF @BASEBOARD_FAB2_LIB.BASEBOARD_FAB2(SCH_1):M_L_VREF   I181 @BASEBOARD_FAB2_LIB.BASEBOARD_FAB2(SCH_1):PAGE85
     2    GND @BASEBOARD_FAB2_LIB.BASEBOARD_FAB2(SCH_1):GND   I181 @BASEBOARD_FAB2_LIB.BASEBOARD_FAB2(SCH_1):PAGE85

C9L8 CAP_A_0402V-0.01UF,25V,10%,X7RA
     1 M_L_CPU_VREF @BASEBOARD_FAB2_LIB.BASEBOARD_FAB2(SCH_1):M_L_CPU_VREF    I30 @BASEBOARD_FAB2_LIB.BASEBOARD_FAB2(SCH_1):PAGE100
     2    GND @BASEBOARD_FAB2_LIB.BASEBOARD_FAB2(SCH_1):GND    I30 @BASEBOARD_FAB2_LIB.BASEBOARD_FAB2(SCH_1):PAGE100

C9L9 CAPP_3018-470UF,2.5V,20%,ALUM,A
     1 PVDDQ_KLM @BASEBOARD_FAB2_LIB.BASEBOARD_FAB2(SCH_1):PVDDQ_KLM    I75 @BASEBOARD_FAB2_LIB.BASEBOARD_FAB2(SCH_1):PAGE228
     2    GND @BASEBOARD_FAB2_LIB.BASEBOARD_FAB2(SCH_1):GND    I75 @BASEBOARD_FAB2_LIB.BASEBOARD_FAB2(SCH_1):PAGE228

C9L10 CAP_0805-10UF,16V,10%,X6S,C953A
     1 VR_FET_SW_P12V_STBY_PVDDQ_KLM @BASEBOARD_FAB2_LIB.BASEBOARD_FAB2(SCH_1):VR_FET_SW_P12V_STBY_PVDDQ_KLM    I46 @BASEBOARD_FAB2_LIB.BASEBOARD_FAB2(SCH_1):PAGE227
     2    GND @BASEBOARD_FAB2_LIB.BASEBOARD_FAB2(SCH_1):GND    I46 @BASEBOARD_FAB2_LIB.BASEBOARD_FAB2(SCH_1):PAGE227

C9L11 CAP_0805-10UF,16V,10%,X6S,C953A
     1 VR_FET_SW_P12V_STBY_PVDDQ_KLM @BASEBOARD_FAB2_LIB.BASEBOARD_FAB2(SCH_1):VR_FET_SW_P12V_STBY_PVDDQ_KLM    I45 @BASEBOARD_FAB2_LIB.BASEBOARD_FAB2(SCH_1):PAGE227
     2    GND @BASEBOARD_FAB2_LIB.BASEBOARD_FAB2(SCH_1):GND    I45 @BASEBOARD_FAB2_LIB.BASEBOARD_FAB2(SCH_1):PAGE227

C9L12 CAPP_3018-470UF,2.5V,20%,ALUM,A
     1 PVDDQ_KLM @BASEBOARD_FAB2_LIB.BASEBOARD_FAB2(SCH_1):PVDDQ_KLM    I76 @BASEBOARD_FAB2_LIB.BASEBOARD_FAB2(SCH_1):PAGE228
     2    GND @BASEBOARD_FAB2_LIB.BASEBOARD_FAB2(SCH_1):GND    I76 @BASEBOARD_FAB2_LIB.BASEBOARD_FAB2(SCH_1):PAGE228

C9L13 CAP_0805-10UF,16V,10%,X6S,C953A
     1 VR_FET_SW_P12V_STBY_PVDDQ_KLM @BASEBOARD_FAB2_LIB.BASEBOARD_FAB2(SCH_1):VR_FET_SW_P12V_STBY_PVDDQ_KLM    I81 @BASEBOARD_FAB2_LIB.BASEBOARD_FAB2(SCH_1):PAGE227
     2    GND @BASEBOARD_FAB2_LIB.BASEBOARD_FAB2(SCH_1):GND    I81 @BASEBOARD_FAB2_LIB.BASEBOARD_FAB2(SCH_1):PAGE227

C9L14 CAP_0805-10UF,16V,10%,X6S,C953A
     1 VR_FET_SW_P12V_STBY_PVDDQ_KLM @BASEBOARD_FAB2_LIB.BASEBOARD_FAB2(SCH_1):VR_FET_SW_P12V_STBY_PVDDQ_KLM    I84 @BASEBOARD_FAB2_LIB.BASEBOARD_FAB2(SCH_1):PAGE227
     2    GND @BASEBOARD_FAB2_LIB.BASEBOARD_FAB2(SCH_1):GND    I84 @BASEBOARD_FAB2_LIB.BASEBOARD_FAB2(SCH_1):PAGE227

C9M1 CAP_A_0402V-0.01UF,25V,10%,X7RA
     1 M_K_VREF @BASEBOARD_FAB2_LIB.BASEBOARD_FAB2(SCH_1):M_K_VREF     I4 @BASEBOARD_FAB2_LIB.BASEBOARD_FAB2(SCH_1):PAGE84
     2    GND @BASEBOARD_FAB2_LIB.BASEBOARD_FAB2(SCH_1):GND     I4 @BASEBOARD_FAB2_LIB.BASEBOARD_FAB2(SCH_1):PAGE84

C9M2 CAP_A_0402V-0.01UF,25V,10%,X7RA
     1 M_K_CPU_VREF @BASEBOARD_FAB2_LIB.BASEBOARD_FAB2(SCH_1):M_K_CPU_VREF    I15 @BASEBOARD_FAB2_LIB.BASEBOARD_FAB2(SCH_1):PAGE100
     2    GND @BASEBOARD_FAB2_LIB.BASEBOARD_FAB2(SCH_1):GND    I15 @BASEBOARD_FAB2_LIB.BASEBOARD_FAB2(SCH_1):PAGE100

C9M3 CAPP_3018-68UF,16V,20%,TANT,72A
     1 P12V_STBY @BASEBOARD_FAB2_LIB.BASEBOARD_FAB2(SCH_1):P12V_STBY    I99 @BASEBOARD_FAB2_LIB.BASEBOARD_FAB2(SCH_1):PAGE195
     2    GND @BASEBOARD_FAB2_LIB.BASEBOARD_FAB2(SCH_1):GND    I99 @BASEBOARD_FAB2_LIB.BASEBOARD_FAB2(SCH_1):PAGE195

C9M4 CAP_0805-10UF,16V,10%,X6S,C953A
     1 P12V_FAN @BASEBOARD_FAB2_LIB.BASEBOARD_FAB2(SCH_1):P12V_FAN    I27 @BASEBOARD_FAB2_LIB.BASEBOARD_FAB2(SCH_1):PAGE161
     2    GND @BASEBOARD_FAB2_LIB.BASEBOARD_FAB2(SCH_1):GND    I27 @BASEBOARD_FAB2_LIB.BASEBOARD_FAB2(SCH_1):PAGE161

C9M5 CAP_A_0402V-0.1UF,16V,10%,X7R,A
     1 P12V_FAN @BASEBOARD_FAB2_LIB.BASEBOARD_FAB2(SCH_1):P12V_FAN    I26 @BASEBOARD_FAB2_LIB.BASEBOARD_FAB2(SCH_1):PAGE161
     2    GND @BASEBOARD_FAB2_LIB.BASEBOARD_FAB2(SCH_1):GND    I26 @BASEBOARD_FAB2_LIB.BASEBOARD_FAB2(SCH_1):PAGE161

C9M6 CAP_A_0402V-0.1UF,16V,10%,X7R,A
     1 P5V_STBY @BASEBOARD_FAB2_LIB.BASEBOARD_FAB2(SCH_1):P5V_STBY    I67 @BASEBOARD_FAB2_LIB.BASEBOARD_FAB2(SCH_1):PAGE198
     2    GND @BASEBOARD_FAB2_LIB.BASEBOARD_FAB2(SCH_1):GND    I67 @BASEBOARD_FAB2_LIB.BASEBOARD_FAB2(SCH_1):PAGE198

C9M7 CAP_A_0402V-0.1UF,16V,10%,X7R,A
     1 P3V3_STBY @BASEBOARD_FAB2_LIB.BASEBOARD_FAB2(SCH_1):P3V3_STBY    I12 @BASEBOARD_FAB2_LIB.BASEBOARD_FAB2(SCH_1):PAGE163
     2    GND @BASEBOARD_FAB2_LIB.BASEBOARD_FAB2(SCH_1):GND    I12 @BASEBOARD_FAB2_LIB.BASEBOARD_FAB2(SCH_1):PAGE163

C9M8 CAP_A_0402V-0.1UF,16V,10%,X7R,A
     1 PVCCIO_CPU1 @BASEBOARD_FAB2_LIB.BASEBOARD_FAB2(SCH_1):PVCCIO_CPU1    I10 @BASEBOARD_FAB2_LIB.BASEBOARD_FAB2(SCH_1):PAGE163
     2    GND @BASEBOARD_FAB2_LIB.BASEBOARD_FAB2(SCH_1):GND    I10 @BASEBOARD_FAB2_LIB.BASEBOARD_FAB2(SCH_1):PAGE163

C9M9 CAP_A_0402V-0.1UF,16V,10%,X7R,A
     1 P12V_STBY @BASEBOARD_FAB2_LIB.BASEBOARD_FAB2(SCH_1):P12V_STBY    I76 @BASEBOARD_FAB2_LIB.BASEBOARD_FAB2(SCH_1):PAGE198
     2    GND @BASEBOARD_FAB2_LIB.BASEBOARD_FAB2(SCH_1):GND    I76 @BASEBOARD_FAB2_LIB.BASEBOARD_FAB2(SCH_1):PAGE198

C9M10 CAP_0805-10UF,16V,10%,X6S,C953A
     1 P12V_STBY @BASEBOARD_FAB2_LIB.BASEBOARD_FAB2(SCH_1):P12V_STBY    I74 @BASEBOARD_FAB2_LIB.BASEBOARD_FAB2(SCH_1):PAGE198
     2    GND @BASEBOARD_FAB2_LIB.BASEBOARD_FAB2(SCH_1):GND    I74 @BASEBOARD_FAB2_LIB.BASEBOARD_FAB2(SCH_1):PAGE198

C9N1 CAP_0402-0.22UF,16V,10%,X7R,A3A
     1 P3E_CPU1_PE3_MP_C_TXP<10> @BASEBOARD_FAB2_LIB.BASEBOARD_FAB2(SCH_1):P3E_CPU1_PE3_MP_C_TXP(10)    I40 @BASEBOARD_FAB2_LIB.BASEBOARD_FAB2(SCH_1):PAGE182
     2 P3E_CPU1_PE3_MP_TXP<10> @BASEBOARD_FAB2_LIB.BASEBOARD_FAB2(SCH_1):P3E_CPU1_PE3_MP_TXP(10)    I40 @BASEBOARD_FAB2_LIB.BASEBOARD_FAB2(SCH_1):PAGE182

C9N2 CAP_0402-0.22UF,16V,10%,X7R,A3A
     1 P3E_CPU1_PE3_MP_C_TXN<10> @BASEBOARD_FAB2_LIB.BASEBOARD_FAB2(SCH_1):P3E_CPU1_PE3_MP_C_TXN(10)    I36 @BASEBOARD_FAB2_LIB.BASEBOARD_FAB2(SCH_1):PAGE182
     2 P3E_CPU1_PE3_MP_TXN<10> @BASEBOARD_FAB2_LIB.BASEBOARD_FAB2(SCH_1):P3E_CPU1_PE3_MP_TXN(10)    I36 @BASEBOARD_FAB2_LIB.BASEBOARD_FAB2(SCH_1):PAGE182

C9N3 CAP_0402-0.22UF,16V,10%,X7R,A3A
     1 P3E_CPU1_PE3_MP_C_TXN<11> @BASEBOARD_FAB2_LIB.BASEBOARD_FAB2(SCH_1):P3E_CPU1_PE3_MP_C_TXN(11)    I47 @BASEBOARD_FAB2_LIB.BASEBOARD_FAB2(SCH_1):PAGE182
     2 P3E_CPU1_PE3_MP_TXN<11> @BASEBOARD_FAB2_LIB.BASEBOARD_FAB2(SCH_1):P3E_CPU1_PE3_MP_TXN(11)    I47 @BASEBOARD_FAB2_LIB.BASEBOARD_FAB2(SCH_1):PAGE182

C9N4 CAP_0402-0.22UF,16V,10%,X7R,A3A
     1 P3E_CPU1_PE3_MP_C_TXP<11> @BASEBOARD_FAB2_LIB.BASEBOARD_FAB2(SCH_1):P3E_CPU1_PE3_MP_C_TXP(11)    I44 @BASEBOARD_FAB2_LIB.BASEBOARD_FAB2(SCH_1):PAGE182
     2 P3E_CPU1_PE3_MP_TXP<11> @BASEBOARD_FAB2_LIB.BASEBOARD_FAB2(SCH_1):P3E_CPU1_PE3_MP_TXP(11)    I44 @BASEBOARD_FAB2_LIB.BASEBOARD_FAB2(SCH_1):PAGE182

C9N5 CAP_0402-0.22UF,16V,10%,X7R,A3A
     1 P3E_CPU1_PE3_MP_C_TXP<13> @BASEBOARD_FAB2_LIB.BASEBOARD_FAB2(SCH_1):P3E_CPU1_PE3_MP_C_TXP(13)    I45 @BASEBOARD_FAB2_LIB.BASEBOARD_FAB2(SCH_1):PAGE182
     2 P3E_CPU1_PE3_MP_TXP<13> @BASEBOARD_FAB2_LIB.BASEBOARD_FAB2(SCH_1):P3E_CPU1_PE3_MP_TXP(13)    I45 @BASEBOARD_FAB2_LIB.BASEBOARD_FAB2(SCH_1):PAGE182

C9N6 CAP_0402-0.22UF,16V,10%,X7R,A3A
     1 P3E_CPU1_PE3_MP_C_TXN<13> @BASEBOARD_FAB2_LIB.BASEBOARD_FAB2(SCH_1):P3E_CPU1_PE3_MP_C_TXN(13)    I42 @BASEBOARD_FAB2_LIB.BASEBOARD_FAB2(SCH_1):PAGE182
     2 P3E_CPU1_PE3_MP_TXN<13> @BASEBOARD_FAB2_LIB.BASEBOARD_FAB2(SCH_1):P3E_CPU1_PE3_MP_TXN(13)    I42 @BASEBOARD_FAB2_LIB.BASEBOARD_FAB2(SCH_1):PAGE182

C9N7 CAP_0402-0.22UF,16V,10%,X7R,A3A
     1 P3E_CPU1_PE3_MP_C_TXP<15> @BASEBOARD_FAB2_LIB.BASEBOARD_FAB2(SCH_1):P3E_CPU1_PE3_MP_C_TXP(15)    I48 @BASEBOARD_FAB2_LIB.BASEBOARD_FAB2(SCH_1):PAGE182
     2 P3E_CPU1_PE3_MP_TXP<15> @BASEBOARD_FAB2_LIB.BASEBOARD_FAB2(SCH_1):P3E_CPU1_PE3_MP_TXP(15)    I48 @BASEBOARD_FAB2_LIB.BASEBOARD_FAB2(SCH_1):PAGE182

C9N8 CAP_0402-0.22UF,16V,10%,X7R,A3A
     1 P3E_CPU1_PE3_MP_C_TXN<14> @BASEBOARD_FAB2_LIB.BASEBOARD_FAB2(SCH_1):P3E_CPU1_PE3_MP_C_TXN(14)    I53 @BASEBOARD_FAB2_LIB.BASEBOARD_FAB2(SCH_1):PAGE182
     2 P3E_CPU1_PE3_MP_TXN<14> @BASEBOARD_FAB2_LIB.BASEBOARD_FAB2(SCH_1):P3E_CPU1_PE3_MP_TXN(14)    I53 @BASEBOARD_FAB2_LIB.BASEBOARD_FAB2(SCH_1):PAGE182

C9N9 CAP_0402-0.22UF,16V,10%,X7R,A3A
     1 P3E_CPU1_PE3_MP_C_TXN<15> @BASEBOARD_FAB2_LIB.BASEBOARD_FAB2(SCH_1):P3E_CPU1_PE3_MP_C_TXN(15)    I52 @BASEBOARD_FAB2_LIB.BASEBOARD_FAB2(SCH_1):PAGE182
     2 P3E_CPU1_PE3_MP_TXN<15> @BASEBOARD_FAB2_LIB.BASEBOARD_FAB2(SCH_1):P3E_CPU1_PE3_MP_TXN(15)    I52 @BASEBOARD_FAB2_LIB.BASEBOARD_FAB2(SCH_1):PAGE182

C9N10 CAP_0402-0.22UF,16V,10%,X7R,A3A
     1 P3E_CPU1_PE3_MP_C_TXP<14> @BASEBOARD_FAB2_LIB.BASEBOARD_FAB2(SCH_1):P3E_CPU1_PE3_MP_C_TXP(14)    I49 @BASEBOARD_FAB2_LIB.BASEBOARD_FAB2(SCH_1):PAGE182
     2 P3E_CPU1_PE3_MP_TXP<14> @BASEBOARD_FAB2_LIB.BASEBOARD_FAB2(SCH_1):P3E_CPU1_PE3_MP_TXP(14)    I49 @BASEBOARD_FAB2_LIB.BASEBOARD_FAB2(SCH_1):PAGE182

C9N11 CAPP_3018-470UF,2.5V,20%,ALUM,A
     1 PVSA_CPU1 @BASEBOARD_FAB2_LIB.BASEBOARD_FAB2(SCH_1):PVSA_CPU1    I12 @BASEBOARD_FAB2_LIB.BASEBOARD_FAB2(SCH_1):PAGE210
     2    GND @BASEBOARD_FAB2_LIB.BASEBOARD_FAB2(SCH_1):GND    I12 @BASEBOARD_FAB2_LIB.BASEBOARD_FAB2(SCH_1):PAGE210

C9N12 CAP_0402-0.22UF,16V,10%,X7R,A3A
     1 P3E_CPU1_PE3_MP_C_TXP<9> @BASEBOARD_FAB2_LIB.BASEBOARD_FAB2(SCH_1):P3E_CPU1_PE3_MP_C_TXP(9)    I37 @BASEBOARD_FAB2_LIB.BASEBOARD_FAB2(SCH_1):PAGE182
     2 P3E_CPU1_PE3_MP_TXP<9> @BASEBOARD_FAB2_LIB.BASEBOARD_FAB2(SCH_1):P3E_CPU1_PE3_MP_TXP(9)    I37 @BASEBOARD_FAB2_LIB.BASEBOARD_FAB2(SCH_1):PAGE182

C9N13 CAP_0805-10UF,16V,10%,X6S,C953A
     1 VR_FET_SW_P12V_STBY_PVCCIN_CPU1 @BASEBOARD_FAB2_LIB.BASEBOARD_FAB2(SCH_1):VR_FET_SW_P12V_STBY_PVCCIN_CPU1    I35 @BASEBOARD_FAB2_LIB.BASEBOARD_FAB2(SCH_1):PAGE210
     2    GND @BASEBOARD_FAB2_LIB.BASEBOARD_FAB2(SCH_1):GND    I35 @BASEBOARD_FAB2_LIB.BASEBOARD_FAB2(SCH_1):PAGE210

C9N14 CAP_0402-0.22UF,16V,10%,X7R,A3A
     1 P3E_CPU1_PE3_MP_C_TXP<12> @BASEBOARD_FAB2_LIB.BASEBOARD_FAB2(SCH_1):P3E_CPU1_PE3_MP_C_TXP(12)    I43 @BASEBOARD_FAB2_LIB.BASEBOARD_FAB2(SCH_1):PAGE182
     2 P3E_CPU1_PE3_MP_TXP<12> @BASEBOARD_FAB2_LIB.BASEBOARD_FAB2(SCH_1):P3E_CPU1_PE3_MP_TXP(12)    I43 @BASEBOARD_FAB2_LIB.BASEBOARD_FAB2(SCH_1):PAGE182

C9N15 CAP_0402-0.22UF,16V,10%,X7R,A3A
     1 P3E_CPU1_PE3_MP_C_TXN<9> @BASEBOARD_FAB2_LIB.BASEBOARD_FAB2(SCH_1):P3E_CPU1_PE3_MP_C_TXN(9)    I41 @BASEBOARD_FAB2_LIB.BASEBOARD_FAB2(SCH_1):PAGE182
     2 P3E_CPU1_PE3_MP_TXN<9> @BASEBOARD_FAB2_LIB.BASEBOARD_FAB2(SCH_1):P3E_CPU1_PE3_MP_TXN(9)    I41 @BASEBOARD_FAB2_LIB.BASEBOARD_FAB2(SCH_1):PAGE182

C9N16 CAP_0402-0.22UF,16V,10%,X7R,A3A
     1 P3E_CPU1_PE3_MP_C_TXN<12> @BASEBOARD_FAB2_LIB.BASEBOARD_FAB2(SCH_1):P3E_CPU1_PE3_MP_C_TXN(12)    I46 @BASEBOARD_FAB2_LIB.BASEBOARD_FAB2(SCH_1):PAGE182
     2 P3E_CPU1_PE3_MP_TXN<12> @BASEBOARD_FAB2_LIB.BASEBOARD_FAB2(SCH_1):P3E_CPU1_PE3_MP_TXN(12)    I46 @BASEBOARD_FAB2_LIB.BASEBOARD_FAB2(SCH_1):PAGE182

C9N17 CAP_0402-0.22UF,16V,10%,X7R,A3A
     1 P3E_CPU1_PE3_MP_C_TXP<8> @BASEBOARD_FAB2_LIB.BASEBOARD_FAB2(SCH_1):P3E_CPU1_PE3_MP_C_TXP(8)    I38 @BASEBOARD_FAB2_LIB.BASEBOARD_FAB2(SCH_1):PAGE182
     2 P3E_CPU1_PE3_MP_TXP<8> @BASEBOARD_FAB2_LIB.BASEBOARD_FAB2(SCH_1):P3E_CPU1_PE3_MP_TXP(8)    I38 @BASEBOARD_FAB2_LIB.BASEBOARD_FAB2(SCH_1):PAGE182

C9N18 CAP_0402-0.22UF,16V,10%,X7R,A3A
     1 P3E_CPU1_PE3_MP_C_TXN<8> @BASEBOARD_FAB2_LIB.BASEBOARD_FAB2(SCH_1):P3E_CPU1_PE3_MP_C_TXN(8)    I39 @BASEBOARD_FAB2_LIB.BASEBOARD_FAB2(SCH_1):PAGE182
     2 P3E_CPU1_PE3_MP_TXN<8> @BASEBOARD_FAB2_LIB.BASEBOARD_FAB2(SCH_1):P3E_CPU1_PE3_MP_TXN(8)    I39 @BASEBOARD_FAB2_LIB.BASEBOARD_FAB2(SCH_1):PAGE182

C9N19 CAP_0805-10UF,16V,10%,X6S,C953A
     1 VR_FET_SW_P12V_STBY_PVCCIN_CPU1 @BASEBOARD_FAB2_LIB.BASEBOARD_FAB2(SCH_1):VR_FET_SW_P12V_STBY_PVCCIN_CPU1    I36 @BASEBOARD_FAB2_LIB.BASEBOARD_FAB2(SCH_1):PAGE210
     2    GND @BASEBOARD_FAB2_LIB.BASEBOARD_FAB2(SCH_1):GND    I36 @BASEBOARD_FAB2_LIB.BASEBOARD_FAB2(SCH_1):PAGE210

C9N20 CAPP_3018-470UF,2.5V,20%,ALUM,A
     1 PVSA_CPU1 @BASEBOARD_FAB2_LIB.BASEBOARD_FAB2(SCH_1):PVSA_CPU1    I14 @BASEBOARD_FAB2_LIB.BASEBOARD_FAB2(SCH_1):PAGE210
     2    GND @BASEBOARD_FAB2_LIB.BASEBOARD_FAB2(SCH_1):GND    I14 @BASEBOARD_FAB2_LIB.BASEBOARD_FAB2(SCH_1):PAGE210

C9N21 CAP_0805-10UF,16V,10%,X6S,C953A
     1 VR_FET_SW_P12V_STBY_PVCCIN_CPU1 @BASEBOARD_FAB2_LIB.BASEBOARD_FAB2(SCH_1):VR_FET_SW_P12V_STBY_PVCCIN_CPU1    I38 @BASEBOARD_FAB2_LIB.BASEBOARD_FAB2(SCH_1):PAGE210
     2    GND @BASEBOARD_FAB2_LIB.BASEBOARD_FAB2(SCH_1):GND    I38 @BASEBOARD_FAB2_LIB.BASEBOARD_FAB2(SCH_1):PAGE210

C9N22 CAP_A_0603V-22.0UF,4V,20%,X6S,A
     1 PVSA_CPU1 @BASEBOARD_FAB2_LIB.BASEBOARD_FAB2(SCH_1):PVSA_CPU1    I44 @BASEBOARD_FAB2_LIB.BASEBOARD_FAB2(SCH_1):PAGE210
     2    GND @BASEBOARD_FAB2_LIB.BASEBOARD_FAB2(SCH_1):GND    I44 @BASEBOARD_FAB2_LIB.BASEBOARD_FAB2(SCH_1):PAGE210

C9N24 CAPP_3018-470UF,2.5V,20%,ALUM,A
     1 PVCCIN_CPU1 @BASEBOARD_FAB2_LIB.BASEBOARD_FAB2(SCH_1):PVCCIN_CPU1    I24 @BASEBOARD_FAB2_LIB.BASEBOARD_FAB2(SCH_1):PAGE208
     2    GND @BASEBOARD_FAB2_LIB.BASEBOARD_FAB2(SCH_1):GND    I24 @BASEBOARD_FAB2_LIB.BASEBOARD_FAB2(SCH_1):PAGE208

C9N25 CAP_0805-10UF,16V,10%,X6S,C953A
     1 VR_FET_SW_P12V_STBY_PVCCIN_CPU1 @BASEBOARD_FAB2_LIB.BASEBOARD_FAB2(SCH_1):VR_FET_SW_P12V_STBY_PVCCIN_CPU1     I8 @BASEBOARD_FAB2_LIB.BASEBOARD_FAB2(SCH_1):PAGE209
     2    GND @BASEBOARD_FAB2_LIB.BASEBOARD_FAB2(SCH_1):GND     I8 @BASEBOARD_FAB2_LIB.BASEBOARD_FAB2(SCH_1):PAGE209

C9N26 CAP_0805-10UF,16V,10%,X6S,C953A
     1 VR_FET_SW_P12V_STBY_PVCCIN_CPU1 @BASEBOARD_FAB2_LIB.BASEBOARD_FAB2(SCH_1):VR_FET_SW_P12V_STBY_PVCCIN_CPU1     I7 @BASEBOARD_FAB2_LIB.BASEBOARD_FAB2(SCH_1):PAGE209
     2    GND @BASEBOARD_FAB2_LIB.BASEBOARD_FAB2(SCH_1):GND     I7 @BASEBOARD_FAB2_LIB.BASEBOARD_FAB2(SCH_1):PAGE209

C9N27 CAP_0805-10UF,16V,10%,X6S,C953A
     1 VR_FET_SW_P12V_STBY_PVCCIN_CPU1 @BASEBOARD_FAB2_LIB.BASEBOARD_FAB2(SCH_1):VR_FET_SW_P12V_STBY_PVCCIN_CPU1     I5 @BASEBOARD_FAB2_LIB.BASEBOARD_FAB2(SCH_1):PAGE209
     2    GND @BASEBOARD_FAB2_LIB.BASEBOARD_FAB2(SCH_1):GND     I5 @BASEBOARD_FAB2_LIB.BASEBOARD_FAB2(SCH_1):PAGE209

C9P1 CAP_0805-10UF,16V,10%,X6S,C953A
     1 VR_FET_SW_P12V_STBY_PVCCIN_CPU1 @BASEBOARD_FAB2_LIB.BASEBOARD_FAB2(SCH_1):VR_FET_SW_P12V_STBY_PVCCIN_CPU1    I59 @BASEBOARD_FAB2_LIB.BASEBOARD_FAB2(SCH_1):PAGE208
     2    GND @BASEBOARD_FAB2_LIB.BASEBOARD_FAB2(SCH_1):GND    I59 @BASEBOARD_FAB2_LIB.BASEBOARD_FAB2(SCH_1):PAGE208

C9P2 CAP_0805-10UF,16V,10%,X6S,C953A
     1 VR_FET_SW_P12V_STBY_PVCCIN_CPU1 @BASEBOARD_FAB2_LIB.BASEBOARD_FAB2(SCH_1):VR_FET_SW_P12V_STBY_PVCCIN_CPU1    I60 @BASEBOARD_FAB2_LIB.BASEBOARD_FAB2(SCH_1):PAGE208
     2    GND @BASEBOARD_FAB2_LIB.BASEBOARD_FAB2(SCH_1):GND    I60 @BASEBOARD_FAB2_LIB.BASEBOARD_FAB2(SCH_1):PAGE208

C9P3 CAP_A_0603V-22.0UF,4V,20%,X6S,A
     1 PVCCIN_CPU1 @BASEBOARD_FAB2_LIB.BASEBOARD_FAB2(SCH_1):PVCCIN_CPU1    I59 @BASEBOARD_FAB2_LIB.BASEBOARD_FAB2(SCH_1):PAGE207
     2    GND @BASEBOARD_FAB2_LIB.BASEBOARD_FAB2(SCH_1):GND    I59 @BASEBOARD_FAB2_LIB.BASEBOARD_FAB2(SCH_1):PAGE207

C9P4 CAP_0805-10UF,16V,10%,X6S,C953A
     1 VR_FET_SW_P12V_STBY_PVCCIN_CPU1 @BASEBOARD_FAB2_LIB.BASEBOARD_FAB2(SCH_1):VR_FET_SW_P12V_STBY_PVCCIN_CPU1    I53 @BASEBOARD_FAB2_LIB.BASEBOARD_FAB2(SCH_1):PAGE208
     2    GND @BASEBOARD_FAB2_LIB.BASEBOARD_FAB2(SCH_1):GND    I53 @BASEBOARD_FAB2_LIB.BASEBOARD_FAB2(SCH_1):PAGE208

C9P5 CAPP_3018-470UF,2.5V,20%,ALUM,A
     1 PVCCIN_CPU1 @BASEBOARD_FAB2_LIB.BASEBOARD_FAB2(SCH_1):PVCCIN_CPU1    I14 @BASEBOARD_FAB2_LIB.BASEBOARD_FAB2(SCH_1):PAGE208
     2    GND @BASEBOARD_FAB2_LIB.BASEBOARD_FAB2(SCH_1):GND    I14 @BASEBOARD_FAB2_LIB.BASEBOARD_FAB2(SCH_1):PAGE208

C9P6 CAP_A_0402V-0.1UF,16V,10%,X7R,A
     1 P12V_STBY @BASEBOARD_FAB2_LIB.BASEBOARD_FAB2(SCH_1):P12V_STBY   I185 @BASEBOARD_FAB2_LIB.BASEBOARD_FAB2(SCH_1):PAGE200
     2 AGND_HSC @BASEBOARD_FAB2_LIB.BASEBOARD_FAB2(SCH_1):AGND_HSC   I185 @BASEBOARD_FAB2_LIB.BASEBOARD_FAB2(SCH_1):PAGE200

C9P7 CAP_0805-10UF,16V,10%,X6S,C953A
     1 VR_FET_SW_P12V_STBY_PVCCIN_CPU1 @BASEBOARD_FAB2_LIB.BASEBOARD_FAB2(SCH_1):VR_FET_SW_P12V_STBY_PVCCIN_CPU1    I54 @BASEBOARD_FAB2_LIB.BASEBOARD_FAB2(SCH_1):PAGE208
     2    GND @BASEBOARD_FAB2_LIB.BASEBOARD_FAB2(SCH_1):GND    I54 @BASEBOARD_FAB2_LIB.BASEBOARD_FAB2(SCH_1):PAGE208

C9P8 CAPP_3018-470UF,2.5V,20%,ALUM,A
     1 PVCCIN_CPU1 @BASEBOARD_FAB2_LIB.BASEBOARD_FAB2(SCH_1):PVCCIN_CPU1    I12 @BASEBOARD_FAB2_LIB.BASEBOARD_FAB2(SCH_1):PAGE208
     2    GND @BASEBOARD_FAB2_LIB.BASEBOARD_FAB2(SCH_1):GND    I12 @BASEBOARD_FAB2_LIB.BASEBOARD_FAB2(SCH_1):PAGE208

C9P9 CAP_0805-10UF,16V,10%,X6S,C953A
     1 VR_FET_SW_P12V_STBY_PVCCIN_CPU1 @BASEBOARD_FAB2_LIB.BASEBOARD_FAB2(SCH_1):VR_FET_SW_P12V_STBY_PVCCIN_CPU1    I55 @BASEBOARD_FAB2_LIB.BASEBOARD_FAB2(SCH_1):PAGE208
     2    GND @BASEBOARD_FAB2_LIB.BASEBOARD_FAB2(SCH_1):GND    I55 @BASEBOARD_FAB2_LIB.BASEBOARD_FAB2(SCH_1):PAGE208

C9P10 CAP_A_0603V-22.0UF,4V,20%,X6S,A
     1 PVCCIN_CPU1 @BASEBOARD_FAB2_LIB.BASEBOARD_FAB2(SCH_1):PVCCIN_CPU1    I66 @BASEBOARD_FAB2_LIB.BASEBOARD_FAB2(SCH_1):PAGE208
     2    GND @BASEBOARD_FAB2_LIB.BASEBOARD_FAB2(SCH_1):GND    I66 @BASEBOARD_FAB2_LIB.BASEBOARD_FAB2(SCH_1):PAGE208

C9P11 CAP_A_0402V-0.1UF,16V,10%,X7R,A
     1 P3V3_STBY @BASEBOARD_FAB2_LIB.BASEBOARD_FAB2(SCH_1):P3V3_STBY   I201 @BASEBOARD_FAB2_LIB.BASEBOARD_FAB2(SCH_1):PAGE200
     2    GND @BASEBOARD_FAB2_LIB.BASEBOARD_FAB2(SCH_1):GND   I201 @BASEBOARD_FAB2_LIB.BASEBOARD_FAB2(SCH_1):PAGE200

C9P12 CAP_A_0402V-0.1UF,16V,10%,EMPTA
     1 A_HSC_VOUT @BASEBOARD_FAB2_LIB.BASEBOARD_FAB2(SCH_1):A_HSC_VOUT    I67 @BASEBOARD_FAB2_LIB.BASEBOARD_FAB2(SCH_1):PAGE199
     2 AGND_HSC @BASEBOARD_FAB2_LIB.BASEBOARD_FAB2(SCH_1):AGND_HSC    I67 @BASEBOARD_FAB2_LIB.BASEBOARD_FAB2(SCH_1):PAGE199

C9P14 CAP_0603LF-0.033UF,50V,10%,X7RA
     1 A_HSC_TIMER @BASEBOARD_FAB2_LIB.BASEBOARD_FAB2(SCH_1):A_HSC_TIMER    I24 @BASEBOARD_FAB2_LIB.BASEBOARD_FAB2(SCH_1):PAGE199
     2 AGND_HSC @BASEBOARD_FAB2_LIB.BASEBOARD_FAB2(SCH_1):AGND_HSC    I24 @BASEBOARD_FAB2_LIB.BASEBOARD_FAB2(SCH_1):PAGE199

C9P15 CAP_A_0402V-0.1UF,16V,10%,X7R,A
     1 A_HSC_ISET @BASEBOARD_FAB2_LIB.BASEBOARD_FAB2(SCH_1):A_HSC_ISET   I105 @BASEBOARD_FAB2_LIB.BASEBOARD_FAB2(SCH_1):PAGE199
     2 AGND_HSC @BASEBOARD_FAB2_LIB.BASEBOARD_FAB2(SCH_1):AGND_HSC   I105 @BASEBOARD_FAB2_LIB.BASEBOARD_FAB2(SCH_1):PAGE199

C9P16 CAP_A_0402V-0.1UF,16V,10%,EMPTA
     1 A_HSC_MOP @BASEBOARD_FAB2_LIB.BASEBOARD_FAB2(SCH_1):A_HSC_MOP    I40 @BASEBOARD_FAB2_LIB.BASEBOARD_FAB2(SCH_1):PAGE200
     2 AGND_HSC @BASEBOARD_FAB2_LIB.BASEBOARD_FAB2(SCH_1):AGND_HSC    I40 @BASEBOARD_FAB2_LIB.BASEBOARD_FAB2(SCH_1):PAGE200

C9P17 CAP_A_0402V-0.1UF,16V,10%,EMPTA
     1 A_HSC_MON @BASEBOARD_FAB2_LIB.BASEBOARD_FAB2(SCH_1):A_HSC_MON    I36 @BASEBOARD_FAB2_LIB.BASEBOARD_FAB2(SCH_1):PAGE200
     2 AGND_HSC @BASEBOARD_FAB2_LIB.BASEBOARD_FAB2(SCH_1):AGND_HSC    I36 @BASEBOARD_FAB2_LIB.BASEBOARD_FAB2(SCH_1):PAGE200

C9P18 CAPP_3018-470UF,2.5V,20%,ALUM,A
     1 PVCCIN_CPU1 @BASEBOARD_FAB2_LIB.BASEBOARD_FAB2(SCH_1):PVCCIN_CPU1    I30 @BASEBOARD_FAB2_LIB.BASEBOARD_FAB2(SCH_1):PAGE208
     2    GND @BASEBOARD_FAB2_LIB.BASEBOARD_FAB2(SCH_1):GND    I30 @BASEBOARD_FAB2_LIB.BASEBOARD_FAB2(SCH_1):PAGE208

C9P20 CAP_A_0603V-22.0UF,4V,20%,X6S,A
     1 PVCCIN_CPU1 @BASEBOARD_FAB2_LIB.BASEBOARD_FAB2(SCH_1):PVCCIN_CPU1    I55 @BASEBOARD_FAB2_LIB.BASEBOARD_FAB2(SCH_1):PAGE209
     2    GND @BASEBOARD_FAB2_LIB.BASEBOARD_FAB2(SCH_1):GND    I55 @BASEBOARD_FAB2_LIB.BASEBOARD_FAB2(SCH_1):PAGE209

C9P22 CAP_0805-10UF,16V,10%,X6S,C953A
     1 VR_FET_SW_P12V_STBY_PVCCIN_CPU1 @BASEBOARD_FAB2_LIB.BASEBOARD_FAB2(SCH_1):VR_FET_SW_P12V_STBY_PVCCIN_CPU1    I50 @BASEBOARD_FAB2_LIB.BASEBOARD_FAB2(SCH_1):PAGE207
     2    GND @BASEBOARD_FAB2_LIB.BASEBOARD_FAB2(SCH_1):GND    I50 @BASEBOARD_FAB2_LIB.BASEBOARD_FAB2(SCH_1):PAGE207

C9P23 CAPP_3018-470UF,2.5V,20%,ALUM,A
     1 PVCCIN_CPU1 @BASEBOARD_FAB2_LIB.BASEBOARD_FAB2(SCH_1):PVCCIN_CPU1    I28 @BASEBOARD_FAB2_LIB.BASEBOARD_FAB2(SCH_1):PAGE208
     2    GND @BASEBOARD_FAB2_LIB.BASEBOARD_FAB2(SCH_1):GND    I28 @BASEBOARD_FAB2_LIB.BASEBOARD_FAB2(SCH_1):PAGE208

C9P24 CAP_0805-10UF,16V,10%,X6S,C953A
     1 VR_FET_SW_P12V_STBY_PVCCIN_CPU1 @BASEBOARD_FAB2_LIB.BASEBOARD_FAB2(SCH_1):VR_FET_SW_P12V_STBY_PVCCIN_CPU1    I58 @BASEBOARD_FAB2_LIB.BASEBOARD_FAB2(SCH_1):PAGE208
     2    GND @BASEBOARD_FAB2_LIB.BASEBOARD_FAB2(SCH_1):GND    I58 @BASEBOARD_FAB2_LIB.BASEBOARD_FAB2(SCH_1):PAGE208

C9P25 CAP_0805-10UF,16V,10%,X6S,C953A
     1 VR_FET_SW_P12V_STBY_PVCCIN_CPU1 @BASEBOARD_FAB2_LIB.BASEBOARD_FAB2(SCH_1):VR_FET_SW_P12V_STBY_PVCCIN_CPU1    I51 @BASEBOARD_FAB2_LIB.BASEBOARD_FAB2(SCH_1):PAGE207
     2    GND @BASEBOARD_FAB2_LIB.BASEBOARD_FAB2(SCH_1):GND    I51 @BASEBOARD_FAB2_LIB.BASEBOARD_FAB2(SCH_1):PAGE207

C9P26 CAP_0805-10UF,16V,10%,X6S,C953A
     1 VR_FET_SW_P12V_STBY_PVCCIN_CPU1 @BASEBOARD_FAB2_LIB.BASEBOARD_FAB2(SCH_1):VR_FET_SW_P12V_STBY_PVCCIN_CPU1    I54 @BASEBOARD_FAB2_LIB.BASEBOARD_FAB2(SCH_1):PAGE207
     2    GND @BASEBOARD_FAB2_LIB.BASEBOARD_FAB2(SCH_1):GND    I54 @BASEBOARD_FAB2_LIB.BASEBOARD_FAB2(SCH_1):PAGE207

C9R2 CAP_A_0603V-22.0UF,4V,20%,X6S,A
     1 PVCCIN_CPU1 @BASEBOARD_FAB2_LIB.BASEBOARD_FAB2(SCH_1):PVCCIN_CPU1    I67 @BASEBOARD_FAB2_LIB.BASEBOARD_FAB2(SCH_1):PAGE208
     2    GND @BASEBOARD_FAB2_LIB.BASEBOARD_FAB2(SCH_1):GND    I67 @BASEBOARD_FAB2_LIB.BASEBOARD_FAB2(SCH_1):PAGE208

C9R3 CAPP_3018-470UF,2.5V,20%,ALUM,A
     1 PVCCIN_CPU1 @BASEBOARD_FAB2_LIB.BASEBOARD_FAB2(SCH_1):PVCCIN_CPU1    I26 @BASEBOARD_FAB2_LIB.BASEBOARD_FAB2(SCH_1):PAGE208
     2    GND @BASEBOARD_FAB2_LIB.BASEBOARD_FAB2(SCH_1):GND    I26 @BASEBOARD_FAB2_LIB.BASEBOARD_FAB2(SCH_1):PAGE208

C9R5 CAP_0805-10UF,16V,10%,X6S,C953A
     1 P12V_PSU @BASEBOARD_FAB2_LIB.BASEBOARD_FAB2(SCH_1):P12V_PSU    I31 @BASEBOARD_FAB2_LIB.BASEBOARD_FAB2(SCH_1):PAGE195
     2    GND @BASEBOARD_FAB2_LIB.BASEBOARD_FAB2(SCH_1):GND    I31 @BASEBOARD_FAB2_LIB.BASEBOARD_FAB2(SCH_1):PAGE195

C9R6 CAP_A_0402V-0.1UF,16V,10%,X7R,A
     1 P12V_PSU @BASEBOARD_FAB2_LIB.BASEBOARD_FAB2(SCH_1):P12V_PSU    I37 @BASEBOARD_FAB2_LIB.BASEBOARD_FAB2(SCH_1):PAGE195
     2    GND @BASEBOARD_FAB2_LIB.BASEBOARD_FAB2(SCH_1):GND    I37 @BASEBOARD_FAB2_LIB.BASEBOARD_FAB2(SCH_1):PAGE195

C9R7 CAP_0805-10UF,16V,10%,X6S,C953A
     1 VR_FET_SW_P12V_STBY_PVCCIN_CPU1 @BASEBOARD_FAB2_LIB.BASEBOARD_FAB2(SCH_1):VR_FET_SW_P12V_STBY_PVCCIN_CPU1    I43 @BASEBOARD_FAB2_LIB.BASEBOARD_FAB2(SCH_1):PAGE207
     2    GND @BASEBOARD_FAB2_LIB.BASEBOARD_FAB2(SCH_1):GND    I43 @BASEBOARD_FAB2_LIB.BASEBOARD_FAB2(SCH_1):PAGE207

C9R8 CAP_A_0603V-22.0UF,4V,20%,X6S,A
     1 PVCCIN_CPU1 @BASEBOARD_FAB2_LIB.BASEBOARD_FAB2(SCH_1):PVCCIN_CPU1     I8 @BASEBOARD_FAB2_LIB.BASEBOARD_FAB2(SCH_1):PAGE207
     2    GND @BASEBOARD_FAB2_LIB.BASEBOARD_FAB2(SCH_1):GND     I8 @BASEBOARD_FAB2_LIB.BASEBOARD_FAB2(SCH_1):PAGE207

C9R9 CAPP_3018-470UF,2.5V,20%,ALUM,A
     1 PVCCIN_CPU1 @BASEBOARD_FAB2_LIB.BASEBOARD_FAB2(SCH_1):PVCCIN_CPU1    I25 @BASEBOARD_FAB2_LIB.BASEBOARD_FAB2(SCH_1):PAGE208
     2    GND @BASEBOARD_FAB2_LIB.BASEBOARD_FAB2(SCH_1):GND    I25 @BASEBOARD_FAB2_LIB.BASEBOARD_FAB2(SCH_1):PAGE208

C9R10 CAP_0805-10UF,16V,10%,X6S,C953A
     1 VR_FET_SW_P12V_STBY_PVCCIN_CPU1 @BASEBOARD_FAB2_LIB.BASEBOARD_FAB2(SCH_1):VR_FET_SW_P12V_STBY_PVCCIN_CPU1    I44 @BASEBOARD_FAB2_LIB.BASEBOARD_FAB2(SCH_1):PAGE207
     2    GND @BASEBOARD_FAB2_LIB.BASEBOARD_FAB2(SCH_1):GND    I44 @BASEBOARD_FAB2_LIB.BASEBOARD_FAB2(SCH_1):PAGE207

C9R11 CAP_0805-10UF,16V,10%,X6S,C953A
     1 VR_FET_SW_P12V_STBY_PVCCIN_CPU1 @BASEBOARD_FAB2_LIB.BASEBOARD_FAB2(SCH_1):VR_FET_SW_P12V_STBY_PVCCIN_CPU1    I48 @BASEBOARD_FAB2_LIB.BASEBOARD_FAB2(SCH_1):PAGE207
     2    GND @BASEBOARD_FAB2_LIB.BASEBOARD_FAB2(SCH_1):GND    I48 @BASEBOARD_FAB2_LIB.BASEBOARD_FAB2(SCH_1):PAGE207

C9R12 CAP_A_0402V-0.1UF,16V,10%,X7R,A
     1 P12V_PSU @BASEBOARD_FAB2_LIB.BASEBOARD_FAB2(SCH_1):P12V_PSU    I36 @BASEBOARD_FAB2_LIB.BASEBOARD_FAB2(SCH_1):PAGE195
     2    GND @BASEBOARD_FAB2_LIB.BASEBOARD_FAB2(SCH_1):GND    I36 @BASEBOARD_FAB2_LIB.BASEBOARD_FAB2(SCH_1):PAGE195

C9R13 CAP_A_0402V-0.1UF,16V,10%,X7R,A
     1 P3V3_STBY @BASEBOARD_FAB2_LIB.BASEBOARD_FAB2(SCH_1):P3V3_STBY    I42 @BASEBOARD_FAB2_LIB.BASEBOARD_FAB2(SCH_1):PAGE167
     2    GND @BASEBOARD_FAB2_LIB.BASEBOARD_FAB2(SCH_1):GND    I42 @BASEBOARD_FAB2_LIB.BASEBOARD_FAB2(SCH_1):PAGE167

C9R14 CAP_A_0402V-0.1UF,16V,10%,X7R,A
     1 P3V3_STBY @BASEBOARD_FAB2_LIB.BASEBOARD_FAB2(SCH_1):P3V3_STBY    I41 @BASEBOARD_FAB2_LIB.BASEBOARD_FAB2(SCH_1):PAGE167
     2    GND @BASEBOARD_FAB2_LIB.BASEBOARD_FAB2(SCH_1):GND    I41 @BASEBOARD_FAB2_LIB.BASEBOARD_FAB2(SCH_1):PAGE167

C9T3 CAPP_3018-68UF,16V,20%,TANT,72A
     1 P12V_STBY @BASEBOARD_FAB2_LIB.BASEBOARD_FAB2(SCH_1):P12V_STBY   I111 @BASEBOARD_FAB2_LIB.BASEBOARD_FAB2(SCH_1):PAGE195
     2    GND @BASEBOARD_FAB2_LIB.BASEBOARD_FAB2(SCH_1):GND   I111 @BASEBOARD_FAB2_LIB.BASEBOARD_FAB2(SCH_1):PAGE195

C9T4 CAP_0805-10UF,16V,10%,X6S,C953A
     1 VR_FET_SW_P12V_STBY_PVDDQ_GHJ @BASEBOARD_FAB2_LIB.BASEBOARD_FAB2(SCH_1):VR_FET_SW_P12V_STBY_PVDDQ_GHJ    I47 @BASEBOARD_FAB2_LIB.BASEBOARD_FAB2(SCH_1):PAGE224
     2    GND @BASEBOARD_FAB2_LIB.BASEBOARD_FAB2(SCH_1):GND    I47 @BASEBOARD_FAB2_LIB.BASEBOARD_FAB2(SCH_1):PAGE224

C9T5 CAPP_3018-470UF,2.5V,20%,ALUM,A
     1 PVDDQ_GHJ @BASEBOARD_FAB2_LIB.BASEBOARD_FAB2(SCH_1):PVDDQ_GHJ    I75 @BASEBOARD_FAB2_LIB.BASEBOARD_FAB2(SCH_1):PAGE225
     2    GND @BASEBOARD_FAB2_LIB.BASEBOARD_FAB2(SCH_1):GND    I75 @BASEBOARD_FAB2_LIB.BASEBOARD_FAB2(SCH_1):PAGE225

C9T6 CAP_0805-10UF,16V,10%,X6S,C953A
     1 VR_FET_SW_P12V_STBY_PVDDQ_GHJ @BASEBOARD_FAB2_LIB.BASEBOARD_FAB2(SCH_1):VR_FET_SW_P12V_STBY_PVDDQ_GHJ    I81 @BASEBOARD_FAB2_LIB.BASEBOARD_FAB2(SCH_1):PAGE224
     2    GND @BASEBOARD_FAB2_LIB.BASEBOARD_FAB2(SCH_1):GND    I81 @BASEBOARD_FAB2_LIB.BASEBOARD_FAB2(SCH_1):PAGE224

C9T7 CAP_A_0402V-0.01UF,25V,10%,X7RA
     1 M_G_VREF @BASEBOARD_FAB2_LIB.BASEBOARD_FAB2(SCH_1):M_G_VREF     I2 @BASEBOARD_FAB2_LIB.BASEBOARD_FAB2(SCH_1):PAGE78
     2    GND @BASEBOARD_FAB2_LIB.BASEBOARD_FAB2(SCH_1):GND     I2 @BASEBOARD_FAB2_LIB.BASEBOARD_FAB2(SCH_1):PAGE78

C9T8 CAP_0805-10UF,16V,10%,X7R,G106A
     1 P12V_NVDIMM_GHJ @BASEBOARD_FAB2_LIB.BASEBOARD_FAB2(SCH_1):P12V_NVDIMM_GHJ    I56 @BASEBOARD_FAB2_LIB.BASEBOARD_FAB2(SCH_1):PAGE197
     2    GND @BASEBOARD_FAB2_LIB.BASEBOARD_FAB2(SCH_1):GND    I56 @BASEBOARD_FAB2_LIB.BASEBOARD_FAB2(SCH_1):PAGE197

C9T9 CAP_0805-10UF,16V,10%,X6S,C953A
     1 VR_FET_SW_P12V_STBY_PVDDQ_GHJ @BASEBOARD_FAB2_LIB.BASEBOARD_FAB2(SCH_1):VR_FET_SW_P12V_STBY_PVDDQ_GHJ    I84 @BASEBOARD_FAB2_LIB.BASEBOARD_FAB2(SCH_1):PAGE224
     2    GND @BASEBOARD_FAB2_LIB.BASEBOARD_FAB2(SCH_1):GND    I84 @BASEBOARD_FAB2_LIB.BASEBOARD_FAB2(SCH_1):PAGE224

C9U2 CAPP_3018-470UF,2.5V,20%,ALUM,A
     1 PVDDQ_GHJ @BASEBOARD_FAB2_LIB.BASEBOARD_FAB2(SCH_1):PVDDQ_GHJ    I76 @BASEBOARD_FAB2_LIB.BASEBOARD_FAB2(SCH_1):PAGE225
     2    GND @BASEBOARD_FAB2_LIB.BASEBOARD_FAB2(SCH_1):GND    I76 @BASEBOARD_FAB2_LIB.BASEBOARD_FAB2(SCH_1):PAGE225

C9U3 CAP_0805-10UF,16V,10%,X6S,C953A
     1 VR_FET_SW_P12V_STBY_PVDDQ_GHJ @BASEBOARD_FAB2_LIB.BASEBOARD_FAB2(SCH_1):VR_FET_SW_P12V_STBY_PVDDQ_GHJ    I80 @BASEBOARD_FAB2_LIB.BASEBOARD_FAB2(SCH_1):PAGE224
     2    GND @BASEBOARD_FAB2_LIB.BASEBOARD_FAB2(SCH_1):GND    I80 @BASEBOARD_FAB2_LIB.BASEBOARD_FAB2(SCH_1):PAGE224

C9U4 CAP_0805-10UF,16V,10%,X6S,C953A
     1 VR_FET_SW_P12V_STBY_PVDDQ_GHJ @BASEBOARD_FAB2_LIB.BASEBOARD_FAB2(SCH_1):VR_FET_SW_P12V_STBY_PVDDQ_GHJ    I46 @BASEBOARD_FAB2_LIB.BASEBOARD_FAB2(SCH_1):PAGE224
     2    GND @BASEBOARD_FAB2_LIB.BASEBOARD_FAB2(SCH_1):GND    I46 @BASEBOARD_FAB2_LIB.BASEBOARD_FAB2(SCH_1):PAGE224

C9U5 CAPP_3018-470UF,2.5V,20%,ALUM,A
     1 PVDDQ_GHJ @BASEBOARD_FAB2_LIB.BASEBOARD_FAB2(SCH_1):PVDDQ_GHJ    I78 @BASEBOARD_FAB2_LIB.BASEBOARD_FAB2(SCH_1):PAGE225
     2    GND @BASEBOARD_FAB2_LIB.BASEBOARD_FAB2(SCH_1):GND    I78 @BASEBOARD_FAB2_LIB.BASEBOARD_FAB2(SCH_1):PAGE225

C9U6 CAP_0805-10UF,16V,10%,X6S,C953A
     1 VR_FET_SW_P12V_STBY_PVDDQ_GHJ @BASEBOARD_FAB2_LIB.BASEBOARD_FAB2(SCH_1):VR_FET_SW_P12V_STBY_PVDDQ_GHJ    I45 @BASEBOARD_FAB2_LIB.BASEBOARD_FAB2(SCH_1):PAGE224
     2    GND @BASEBOARD_FAB2_LIB.BASEBOARD_FAB2(SCH_1):GND    I45 @BASEBOARD_FAB2_LIB.BASEBOARD_FAB2(SCH_1):PAGE224

C9U7 CAP_A_0402V-0.01UF,25V,10%,X7RA
     1 M_H_VREF @BASEBOARD_FAB2_LIB.BASEBOARD_FAB2(SCH_1):M_H_VREF   I178 @BASEBOARD_FAB2_LIB.BASEBOARD_FAB2(SCH_1):PAGE79
     2    GND @BASEBOARD_FAB2_LIB.BASEBOARD_FAB2(SCH_1):GND   I178 @BASEBOARD_FAB2_LIB.BASEBOARD_FAB2(SCH_1):PAGE79

C9U8 CAP_0805-10UF,16V,10%,X7R,G106A
     1 P12V_NVDIMM_GHJ @BASEBOARD_FAB2_LIB.BASEBOARD_FAB2(SCH_1):P12V_NVDIMM_GHJ    I66 @BASEBOARD_FAB2_LIB.BASEBOARD_FAB2(SCH_1):PAGE197
     2    GND @BASEBOARD_FAB2_LIB.BASEBOARD_FAB2(SCH_1):GND    I66 @BASEBOARD_FAB2_LIB.BASEBOARD_FAB2(SCH_1):PAGE197

C9U9 CAPP_3018-470UF,2.5V,20%,ALUM,A
     1 PVDDQ_GHJ @BASEBOARD_FAB2_LIB.BASEBOARD_FAB2(SCH_1):PVDDQ_GHJ    I77 @BASEBOARD_FAB2_LIB.BASEBOARD_FAB2(SCH_1):PAGE225
     2    GND @BASEBOARD_FAB2_LIB.BASEBOARD_FAB2(SCH_1):GND    I77 @BASEBOARD_FAB2_LIB.BASEBOARD_FAB2(SCH_1):PAGE225

C9U10 CAP_A_0402V-0.01UF,25V,10%,X7RA
     1 M_J_VREF @BASEBOARD_FAB2_LIB.BASEBOARD_FAB2(SCH_1):M_J_VREF   I178 @BASEBOARD_FAB2_LIB.BASEBOARD_FAB2(SCH_1):PAGE81
     2    GND @BASEBOARD_FAB2_LIB.BASEBOARD_FAB2(SCH_1):GND   I178 @BASEBOARD_FAB2_LIB.BASEBOARD_FAB2(SCH_1):PAGE81

C9U11 CAP_0805-10UF,16V,10%,X7R,G106A
     1 P12V_NVDIMM_GHJ @BASEBOARD_FAB2_LIB.BASEBOARD_FAB2(SCH_1):P12V_NVDIMM_GHJ    I63 @BASEBOARD_FAB2_LIB.BASEBOARD_FAB2(SCH_1):PAGE197
     2    GND @BASEBOARD_FAB2_LIB.BASEBOARD_FAB2(SCH_1):GND    I63 @BASEBOARD_FAB2_LIB.BASEBOARD_FAB2(SCH_1):PAGE197

C9W1 SC22P50V2JN-4GP_SMD-BCG-SC22P5A
     1 A_P12V_STBY_FP_TRIGGER @BASEBOARD_FAB2_LIB.BASEBOARD_FAB2(SCH_1):A_P12V_STBY_FP_TRIGGER   I235 @BASEBOARD_FAB2_LIB.BASEBOARD_FAB2(SCH_1):PAGE200
     2 AGND_HSC @BASEBOARD_FAB2_LIB.BASEBOARD_FAB2(SCH_1):AGND_HSC   I235 @BASEBOARD_FAB2_LIB.BASEBOARD_FAB2(SCH_1):PAGE200

C9W2 SC22P50V2JN-4GP_SMD-BCG-SC22P5A
     1 A_P12V_STBY_ADR_TRIGGER @BASEBOARD_FAB2_LIB.BASEBOARD_FAB2(SCH_1):A_P12V_STBY_ADR_TRIGGER   I236 @BASEBOARD_FAB2_LIB.BASEBOARD_FAB2(SCH_1):PAGE200
     2 AGND_HSC @BASEBOARD_FAB2_LIB.BASEBOARD_FAB2(SCH_1):AGND_HSC   I236 @BASEBOARD_FAB2_LIB.BASEBOARD_FAB2(SCH_1):PAGE200

C9W5 CAP_A_0402V-0.1UF,16V,10%,X7R,A
     1 P3V3_STBY @BASEBOARD_FAB2_LIB.BASEBOARD_FAB2(SCH_1):P3V3_STBY    I90 @BASEBOARD_FAB2_LIB.BASEBOARD_FAB2(SCH_1):PAGE239
     2    GND @BASEBOARD_FAB2_LIB.BASEBOARD_FAB2(SCH_1):GND    I90 @BASEBOARD_FAB2_LIB.BASEBOARD_FAB2(SCH_1):PAGE239

C9W6 CAP_0402LF-1000PF,50V,10%,EMPTA
     1 PWRGD_P3V3_STBY @BASEBOARD_FAB2_LIB.BASEBOARD_FAB2(SCH_1):PWRGD_P3V3_STBY    I91 @BASEBOARD_FAB2_LIB.BASEBOARD_FAB2(SCH_1):PAGE239
     2    GND @BASEBOARD_FAB2_LIB.BASEBOARD_FAB2(SCH_1):GND    I91 @BASEBOARD_FAB2_LIB.BASEBOARD_FAB2(SCH_1):PAGE239

C9W7 CAP_A_0402V-0.1UF,16V,10%,X7R,A
     1 P3V3_STBY @BASEBOARD_FAB2_LIB.BASEBOARD_FAB2(SCH_1):P3V3_STBY    I32 @BASEBOARD_FAB2_LIB.BASEBOARD_FAB2(SCH_1):PAGE248
     2    GND @BASEBOARD_FAB2_LIB.BASEBOARD_FAB2(SCH_1):GND    I32 @BASEBOARD_FAB2_LIB.BASEBOARD_FAB2(SCH_1):PAGE248

C9W8 CAP_A_0402V-0.1UF,16V,10%,X7R,A
     1 PVCCIO_CPU0 @BASEBOARD_FAB2_LIB.BASEBOARD_FAB2(SCH_1):PVCCIO_CPU0    I30 @BASEBOARD_FAB2_LIB.BASEBOARD_FAB2(SCH_1):PAGE248
     2    GND @BASEBOARD_FAB2_LIB.BASEBOARD_FAB2(SCH_1):GND    I30 @BASEBOARD_FAB2_LIB.BASEBOARD_FAB2(SCH_1):PAGE248

C9W10 CAP_0402LF-1000PF,50V,10%,X7R,A
     1 PWRGD_P2V5_BMC_STBY_R @BASEBOARD_FAB2_LIB.BASEBOARD_FAB2(SCH_1):PWRGD_P2V5_BMC_STBY_R    I84 @BASEBOARD_FAB2_LIB.BASEBOARD_FAB2(SCH_1):PAGE239
     2    GND @BASEBOARD_FAB2_LIB.BASEBOARD_FAB2(SCH_1):GND    I84 @BASEBOARD_FAB2_LIB.BASEBOARD_FAB2(SCH_1):PAGE239

C9W13 CAP_0805LF-22UF,4V,20%,X6S,C95A
     1 P2V5_AUX_BMC @BASEBOARD_FAB2_LIB.BASEBOARD_FAB2(SCH_1):P2V5_AUX_BMC    I81 @BASEBOARD_FAB2_LIB.BASEBOARD_FAB2(SCH_1):PAGE239
     2    GND @BASEBOARD_FAB2_LIB.BASEBOARD_FAB2(SCH_1):GND    I81 @BASEBOARD_FAB2_LIB.BASEBOARD_FAB2(SCH_1):PAGE239

C9W14 CAP_0603-10UF,6.3V,20%,X6S,E15A
     1 P3V3_STBY @BASEBOARD_FAB2_LIB.BASEBOARD_FAB2(SCH_1):P3V3_STBY    I46 @BASEBOARD_FAB2_LIB.BASEBOARD_FAB2(SCH_1):PAGE238
     2    GND @BASEBOARD_FAB2_LIB.BASEBOARD_FAB2(SCH_1):GND    I46 @BASEBOARD_FAB2_LIB.BASEBOARD_FAB2(SCH_1):PAGE238

C9W16 CAP_A_0603V-22.0UF,4V,20%,X6S,A
     1 P1V15_AUX_BMC @BASEBOARD_FAB2_LIB.BASEBOARD_FAB2(SCH_1):P1V15_AUX_BMC    I50 @BASEBOARD_FAB2_LIB.BASEBOARD_FAB2(SCH_1):PAGE238
     2    GND @BASEBOARD_FAB2_LIB.BASEBOARD_FAB2(SCH_1):GND    I50 @BASEBOARD_FAB2_LIB.BASEBOARD_FAB2(SCH_1):PAGE238

C9W17 CAP_0603-10UF,6.3V,20%,X6S,E15A
     1 P3V3_STBY @BASEBOARD_FAB2_LIB.BASEBOARD_FAB2(SCH_1):P3V3_STBY   I104 @BASEBOARD_FAB2_LIB.BASEBOARD_FAB2(SCH_1):PAGE239
     2    GND @BASEBOARD_FAB2_LIB.BASEBOARD_FAB2(SCH_1):GND   I104 @BASEBOARD_FAB2_LIB.BASEBOARD_FAB2(SCH_1):PAGE239

C9W19 CAP_A_0603V-22.0UF,4V,20%,X6S,A
     1 P1V2_AUX_BMC @BASEBOARD_FAB2_LIB.BASEBOARD_FAB2(SCH_1):P1V2_AUX_BMC   I111 @BASEBOARD_FAB2_LIB.BASEBOARD_FAB2(SCH_1):PAGE239
     2    GND @BASEBOARD_FAB2_LIB.BASEBOARD_FAB2(SCH_1):GND   I111 @BASEBOARD_FAB2_LIB.BASEBOARD_FAB2(SCH_1):PAGE239

C10W1 CAP_0805-10UF,16V,10%,X6S,C953A
     1 P12V_PUMP @BASEBOARD_FAB2_LIB.BASEBOARD_FAB2(SCH_1):P12V_PUMP     I3 @BASEBOARD_FAB2_LIB.BASEBOARD_FAB2(SCH_1):PAGE251
     2    GND @BASEBOARD_FAB2_LIB.BASEBOARD_FAB2(SCH_1):GND     I3 @BASEBOARD_FAB2_LIB.BASEBOARD_FAB2(SCH_1):PAGE251

C10W2 CAP_A_0402V-0.1UF,16V,10%,X7R,A
     1 P12V_PUMP @BASEBOARD_FAB2_LIB.BASEBOARD_FAB2(SCH_1):P12V_PUMP     I1 @BASEBOARD_FAB2_LIB.BASEBOARD_FAB2(SCH_1):PAGE251
     2    GND @BASEBOARD_FAB2_LIB.BASEBOARD_FAB2(SCH_1):GND     I1 @BASEBOARD_FAB2_LIB.BASEBOARD_FAB2(SCH_1):PAGE251

C10W3 CAP_A_0402V-0.01UF,25V,10%,X7RA
     1 PUMP_TACH0 @BASEBOARD_FAB2_LIB.BASEBOARD_FAB2(SCH_1):PUMP_TACH0    I16 @BASEBOARD_FAB2_LIB.BASEBOARD_FAB2(SCH_1):PAGE251
     2    GND @BASEBOARD_FAB2_LIB.BASEBOARD_FAB2(SCH_1):GND    I16 @BASEBOARD_FAB2_LIB.BASEBOARD_FAB2(SCH_1):PAGE251

C10W4 CAP_A_0402V-0.1UF,16V,10%,X7R,A
     1 P3V3_STBY @BASEBOARD_FAB2_LIB.BASEBOARD_FAB2(SCH_1):P3V3_STBY    I21 @BASEBOARD_FAB2_LIB.BASEBOARD_FAB2(SCH_1):PAGE251
     2    GND @BASEBOARD_FAB2_LIB.BASEBOARD_FAB2(SCH_1):GND    I21 @BASEBOARD_FAB2_LIB.BASEBOARD_FAB2(SCH_1):PAGE251

C10W5 CAP_A_0402V-0.01UF,25V,10%,X7RA
     1 PUMP_TACH1 @BASEBOARD_FAB2_LIB.BASEBOARD_FAB2(SCH_1):PUMP_TACH1    I29 @BASEBOARD_FAB2_LIB.BASEBOARD_FAB2(SCH_1):PAGE251
     2    GND @BASEBOARD_FAB2_LIB.BASEBOARD_FAB2(SCH_1):GND    I29 @BASEBOARD_FAB2_LIB.BASEBOARD_FAB2(SCH_1):PAGE251

C12W1 CAP_0402LF-47.0PF,50V,5%,COG,AA
     1 VR_PVDDQ_ABC_AIINSEN @BASEBOARD_FAB2_LIB.BASEBOARD_FAB2(SCH_1):VR_PVDDQ_ABC_AIINSEN     I8 @BASEBOARD_FAB2_LIB.BASEBOARD_FAB2(SCH_1):PAGE197
     2 VR_PVDDQ_ABC_VINSEN @BASEBOARD_FAB2_LIB.BASEBOARD_FAB2(SCH_1):VR_PVDDQ_ABC_VINSEN     I8 @BASEBOARD_FAB2_LIB.BASEBOARD_FAB2(SCH_1):PAGE197

C12W2 CAP_0402LF-47.0PF,50V,5%,COG,AA
     1 VR_PVDDQ_DEF_AIINSEN @BASEBOARD_FAB2_LIB.BASEBOARD_FAB2(SCH_1):VR_PVDDQ_DEF_AIINSEN     I1 @BASEBOARD_FAB2_LIB.BASEBOARD_FAB2(SCH_1):PAGE197
     2 VR_PVDDQ_DEF_VINSEN @BASEBOARD_FAB2_LIB.BASEBOARD_FAB2(SCH_1):VR_PVDDQ_DEF_VINSEN     I1 @BASEBOARD_FAB2_LIB.BASEBOARD_FAB2(SCH_1):PAGE197

C12W3 CAP_0402LF-47.0PF,50V,5%,COG,AA
     1 VR_PVDDQ_GHJ_AIINSEN @BASEBOARD_FAB2_LIB.BASEBOARD_FAB2(SCH_1):VR_PVDDQ_GHJ_AIINSEN    I42 @BASEBOARD_FAB2_LIB.BASEBOARD_FAB2(SCH_1):PAGE197
     2 VR_PVDDQ_GHJ_VINSEN @BASEBOARD_FAB2_LIB.BASEBOARD_FAB2(SCH_1):VR_PVDDQ_GHJ_VINSEN    I42 @BASEBOARD_FAB2_LIB.BASEBOARD_FAB2(SCH_1):PAGE197

C12W4 CAP_0402LF-47.0PF,50V,5%,COG,AA
     1 VR_PVDDQ_KLM_AIINSEN @BASEBOARD_FAB2_LIB.BASEBOARD_FAB2(SCH_1):VR_PVDDQ_KLM_AIINSEN    I18 @BASEBOARD_FAB2_LIB.BASEBOARD_FAB2(SCH_1):PAGE197
     2 VR_PVDDQ_KLM_VINSEN @BASEBOARD_FAB2_LIB.BASEBOARD_FAB2(SCH_1):VR_PVDDQ_KLM_VINSEN    I18 @BASEBOARD_FAB2_LIB.BASEBOARD_FAB2(SCH_1):PAGE197

C14W1 CAP_A_0402V-0.1UF,16V,10%,X7R,A
     1   P3V3 @BASEBOARD_FAB2_LIB.BASEBOARD_FAB2(SCH_1):P3V3    I13 @BASEBOARD_FAB2_LIB.BASEBOARD_FAB2(SCH_1):PAGE248
     2    GND @BASEBOARD_FAB2_LIB.BASEBOARD_FAB2(SCH_1):GND    I13 @BASEBOARD_FAB2_LIB.BASEBOARD_FAB2(SCH_1):PAGE248

C14W2 CAP_A_0402V-0.1UF,16V,10%,X7R,A
     1   P3V3 @BASEBOARD_FAB2_LIB.BASEBOARD_FAB2(SCH_1):P3V3    I17 @BASEBOARD_FAB2_LIB.BASEBOARD_FAB2(SCH_1):PAGE248
     2    GND @BASEBOARD_FAB2_LIB.BASEBOARD_FAB2(SCH_1):GND    I17 @BASEBOARD_FAB2_LIB.BASEBOARD_FAB2(SCH_1):PAGE248

C22W1 SC22U16V5MX-4-GP_SMD-BCG5-SC22A
     1 VR_FET_SW_P12V_STBY_PVDDQ_GHJ @BASEBOARD_FAB2_LIB.BASEBOARD_FAB2(SCH_1):VR_FET_SW_P12V_STBY_PVDDQ_GHJ   I246 @BASEBOARD_FAB2_LIB.BASEBOARD_FAB2(SCH_1):PAGE225
     2    GND @BASEBOARD_FAB2_LIB.BASEBOARD_FAB2(SCH_1):GND   I246 @BASEBOARD_FAB2_LIB.BASEBOARD_FAB2(SCH_1):PAGE225

C22W2 SC22U16V5MX-4-GP_SMD-BCG5-SC22A
     1 VR_FET_SW_P12V_STBY_PVDDQ_GHJ @BASEBOARD_FAB2_LIB.BASEBOARD_FAB2(SCH_1):VR_FET_SW_P12V_STBY_PVDDQ_GHJ   I247 @BASEBOARD_FAB2_LIB.BASEBOARD_FAB2(SCH_1):PAGE225
     2    GND @BASEBOARD_FAB2_LIB.BASEBOARD_FAB2(SCH_1):GND   I247 @BASEBOARD_FAB2_LIB.BASEBOARD_FAB2(SCH_1):PAGE225

C22W3 SC22U16V5MX-4-GP_SMD-BCG5-SC22A
     1 VR_FET_SW_P12V_STBY_PVDDQ_GHJ @BASEBOARD_FAB2_LIB.BASEBOARD_FAB2(SCH_1):VR_FET_SW_P12V_STBY_PVDDQ_GHJ   I249 @BASEBOARD_FAB2_LIB.BASEBOARD_FAB2(SCH_1):PAGE225
     2    GND @BASEBOARD_FAB2_LIB.BASEBOARD_FAB2(SCH_1):GND   I249 @BASEBOARD_FAB2_LIB.BASEBOARD_FAB2(SCH_1):PAGE225

C22W4 SC22U16V5MX-4-GP_SMD-BCG5-SC22A
     1 VR_FET_SW_P12V_STBY_PVDDQ_GHJ @BASEBOARD_FAB2_LIB.BASEBOARD_FAB2(SCH_1):VR_FET_SW_P12V_STBY_PVDDQ_GHJ   I251 @BASEBOARD_FAB2_LIB.BASEBOARD_FAB2(SCH_1):PAGE225
     2    GND @BASEBOARD_FAB2_LIB.BASEBOARD_FAB2(SCH_1):GND   I251 @BASEBOARD_FAB2_LIB.BASEBOARD_FAB2(SCH_1):PAGE225

C22W5 SC22U16V5MX-4-GP_SMD-BCG5-SC22A
     1 VR_FET_SW_P12V_STBY_PVPP_KLM @BASEBOARD_FAB2_LIB.BASEBOARD_FAB2(SCH_1):VR_FET_SW_P12V_STBY_PVPP_KLM   I222 @BASEBOARD_FAB2_LIB.BASEBOARD_FAB2(SCH_1):PAGE234
     2    GND @BASEBOARD_FAB2_LIB.BASEBOARD_FAB2(SCH_1):GND   I222 @BASEBOARD_FAB2_LIB.BASEBOARD_FAB2(SCH_1):PAGE234

C22W6 SC22U16V5MX-4-GP_SMD-BCG5-SC22A
     1 VR_FET_SW_P12V_STBY_PVPP_GHJ @BASEBOARD_FAB2_LIB.BASEBOARD_FAB2(SCH_1):VR_FET_SW_P12V_STBY_PVPP_GHJ   I278 @BASEBOARD_FAB2_LIB.BASEBOARD_FAB2(SCH_1):PAGE233
     2    GND @BASEBOARD_FAB2_LIB.BASEBOARD_FAB2(SCH_1):GND   I278 @BASEBOARD_FAB2_LIB.BASEBOARD_FAB2(SCH_1):PAGE233

C22W7 SC22U16V5MX-4-GP_SMD-BCG5-SC22A
     1 VR_FET_SW_P12V_STBY_PVPP_DEF @BASEBOARD_FAB2_LIB.BASEBOARD_FAB2(SCH_1):VR_FET_SW_P12V_STBY_PVPP_DEF   I311 @BASEBOARD_FAB2_LIB.BASEBOARD_FAB2(SCH_1):PAGE232
     2    GND @BASEBOARD_FAB2_LIB.BASEBOARD_FAB2(SCH_1):GND   I311 @BASEBOARD_FAB2_LIB.BASEBOARD_FAB2(SCH_1):PAGE232

C22W8 SC22U16V5MX-4-GP_SMD-BCG5-SC22A
     1 VR_FET_SW_P5V_STBY_PVIN @BASEBOARD_FAB2_LIB.BASEBOARD_FAB2(SCH_1):VR_FET_SW_P5V_STBY_PVIN    I96 @BASEBOARD_FAB2_LIB.BASEBOARD_FAB2(SCH_1):PAGE241
     2    GND @BASEBOARD_FAB2_LIB.BASEBOARD_FAB2(SCH_1):GND    I96 @BASEBOARD_FAB2_LIB.BASEBOARD_FAB2(SCH_1):PAGE241

C22W9 SC22U16V5MX-4-GP_SMD-BCG5-SC22A
     1 VR_FET_SW_P5V_STBY_PVIN @BASEBOARD_FAB2_LIB.BASEBOARD_FAB2(SCH_1):VR_FET_SW_P5V_STBY_PVIN    I95 @BASEBOARD_FAB2_LIB.BASEBOARD_FAB2(SCH_1):PAGE241
     2    GND @BASEBOARD_FAB2_LIB.BASEBOARD_FAB2(SCH_1):GND    I95 @BASEBOARD_FAB2_LIB.BASEBOARD_FAB2(SCH_1):PAGE241

C22W10 SC22U16V5MX-4-GP_SMD-BCG5-SC22A
     1 VR_FET_SW_P12V_STBY_PVPP_ABC @BASEBOARD_FAB2_LIB.BASEBOARD_FAB2(SCH_1):VR_FET_SW_P12V_STBY_PVPP_ABC   I225 @BASEBOARD_FAB2_LIB.BASEBOARD_FAB2(SCH_1):PAGE231
     2    GND @BASEBOARD_FAB2_LIB.BASEBOARD_FAB2(SCH_1):GND   I225 @BASEBOARD_FAB2_LIB.BASEBOARD_FAB2(SCH_1):PAGE231

C22W11 SC22U16V5MX-4-GP_SMD-BCG5-SC22A
     1 VR_FET_SW_P12V_STBY_P3V3_STBY @BASEBOARD_FAB2_LIB.BASEBOARD_FAB2(SCH_1):VR_FET_SW_P12V_STBY_P3V3_STBY   I182 @BASEBOARD_FAB2_LIB.BASEBOARD_FAB2(SCH_1):PAGE240
     2    GND @BASEBOARD_FAB2_LIB.BASEBOARD_FAB2(SCH_1):GND   I182 @BASEBOARD_FAB2_LIB.BASEBOARD_FAB2(SCH_1):PAGE240

C22W12 SC22U16V5MX-4-GP_SMD-BCG5-SC22A
     1 VR_FET_SW_P12V_STBY_P3V3_STBY @BASEBOARD_FAB2_LIB.BASEBOARD_FAB2(SCH_1):VR_FET_SW_P12V_STBY_P3V3_STBY   I186 @BASEBOARD_FAB2_LIB.BASEBOARD_FAB2(SCH_1):PAGE240
     2    GND @BASEBOARD_FAB2_LIB.BASEBOARD_FAB2(SCH_1):GND   I186 @BASEBOARD_FAB2_LIB.BASEBOARD_FAB2(SCH_1):PAGE240

C22W13 SC22U16V5MX-4-GP_SMD-BCG5-SC22A
     1 VR_FET_SW_P12V_STBY_PVCCIN_CPU0 @BASEBOARD_FAB2_LIB.BASEBOARD_FAB2(SCH_1):VR_FET_SW_P12V_STBY_PVCCIN_CPU0   I149 @BASEBOARD_FAB2_LIB.BASEBOARD_FAB2(SCH_1):PAGE214
     2    GND @BASEBOARD_FAB2_LIB.BASEBOARD_FAB2(SCH_1):GND   I149 @BASEBOARD_FAB2_LIB.BASEBOARD_FAB2(SCH_1):PAGE214

C22W14 SC22U16V5MX-4-GP_SMD-BCG5-SC22A
     1 VR_FET_SW_P12V_STBY_PVCCIN_CPU0 @BASEBOARD_FAB2_LIB.BASEBOARD_FAB2(SCH_1):VR_FET_SW_P12V_STBY_PVCCIN_CPU0   I152 @BASEBOARD_FAB2_LIB.BASEBOARD_FAB2(SCH_1):PAGE214
     2    GND @BASEBOARD_FAB2_LIB.BASEBOARD_FAB2(SCH_1):GND   I152 @BASEBOARD_FAB2_LIB.BASEBOARD_FAB2(SCH_1):PAGE214

C22W15 SC22U16V5MX-4-GP_SMD-BCG5-SC22A
     1 VR_FET_SW_P12V_STBY_PVCCIN_CPU0 @BASEBOARD_FAB2_LIB.BASEBOARD_FAB2(SCH_1):VR_FET_SW_P12V_STBY_PVCCIN_CPU0   I154 @BASEBOARD_FAB2_LIB.BASEBOARD_FAB2(SCH_1):PAGE214
     2    GND @BASEBOARD_FAB2_LIB.BASEBOARD_FAB2(SCH_1):GND   I154 @BASEBOARD_FAB2_LIB.BASEBOARD_FAB2(SCH_1):PAGE214

C22W16 SC22U16V5MX-4-GP_SMD-BCG5-SC22A
     1 VR_FET_SW_P12V_STBY_PVCCIN_CPU0 @BASEBOARD_FAB2_LIB.BASEBOARD_FAB2(SCH_1):VR_FET_SW_P12V_STBY_PVCCIN_CPU0   I160 @BASEBOARD_FAB2_LIB.BASEBOARD_FAB2(SCH_1):PAGE214
     2    GND @BASEBOARD_FAB2_LIB.BASEBOARD_FAB2(SCH_1):GND   I160 @BASEBOARD_FAB2_LIB.BASEBOARD_FAB2(SCH_1):PAGE214

C22W17 SC22U16V5MX-4-GP_SMD-BCG5-SC22A
     1 VR_FET_SW_P12V_STBY_PVCCIN_CPU0 @BASEBOARD_FAB2_LIB.BASEBOARD_FAB2(SCH_1):VR_FET_SW_P12V_STBY_PVCCIN_CPU0   I158 @BASEBOARD_FAB2_LIB.BASEBOARD_FAB2(SCH_1):PAGE214
     2    GND @BASEBOARD_FAB2_LIB.BASEBOARD_FAB2(SCH_1):GND   I158 @BASEBOARD_FAB2_LIB.BASEBOARD_FAB2(SCH_1):PAGE214

C22W18 SC22U16V5MX-4-GP_SMD-BCG5-SC22A
     1 VR_FET_SW_P12V_STBY_PVCCIN_CPU0 @BASEBOARD_FAB2_LIB.BASEBOARD_FAB2(SCH_1):VR_FET_SW_P12V_STBY_PVCCIN_CPU0   I156 @BASEBOARD_FAB2_LIB.BASEBOARD_FAB2(SCH_1):PAGE214
     2    GND @BASEBOARD_FAB2_LIB.BASEBOARD_FAB2(SCH_1):GND   I156 @BASEBOARD_FAB2_LIB.BASEBOARD_FAB2(SCH_1):PAGE214

C22W19 SC22U16V5MX-4-GP_SMD-BCG5-SC22A
     1 VR_FET_SW_P12V_STBY_PVCCIN_CPU0 @BASEBOARD_FAB2_LIB.BASEBOARD_FAB2(SCH_1):VR_FET_SW_P12V_STBY_PVCCIN_CPU0   I169 @BASEBOARD_FAB2_LIB.BASEBOARD_FAB2(SCH_1):PAGE214
     2    GND @BASEBOARD_FAB2_LIB.BASEBOARD_FAB2(SCH_1):GND   I169 @BASEBOARD_FAB2_LIB.BASEBOARD_FAB2(SCH_1):PAGE214

C22W20 SC22U16V5MX-4-GP_SMD-BCG5-SC22A
     1 VR_FET_SW_P12V_STBY_PVCCIN_CPU0 @BASEBOARD_FAB2_LIB.BASEBOARD_FAB2(SCH_1):VR_FET_SW_P12V_STBY_PVCCIN_CPU0   I168 @BASEBOARD_FAB2_LIB.BASEBOARD_FAB2(SCH_1):PAGE214
     2    GND @BASEBOARD_FAB2_LIB.BASEBOARD_FAB2(SCH_1):GND   I168 @BASEBOARD_FAB2_LIB.BASEBOARD_FAB2(SCH_1):PAGE214

C22W21 SC22U16V5MX-4-GP_SMD-BCG5-SC22A
     1 VR_FET_SW_P12V_STBY_PVCCIN_CPU0 @BASEBOARD_FAB2_LIB.BASEBOARD_FAB2(SCH_1):VR_FET_SW_P12V_STBY_PVCCIN_CPU0   I166 @BASEBOARD_FAB2_LIB.BASEBOARD_FAB2(SCH_1):PAGE214
     2    GND @BASEBOARD_FAB2_LIB.BASEBOARD_FAB2(SCH_1):GND   I166 @BASEBOARD_FAB2_LIB.BASEBOARD_FAB2(SCH_1):PAGE214

C22W22 SC22U16V5MX-4-GP_SMD-BCG5-SC22A
     1 VR_FET_SW_P12V_STBY_PVDDQ_DEF @BASEBOARD_FAB2_LIB.BASEBOARD_FAB2(SCH_1):VR_FET_SW_P12V_STBY_PVDDQ_DEF   I171 @BASEBOARD_FAB2_LIB.BASEBOARD_FAB2(SCH_1):PAGE236
     2    GND @BASEBOARD_FAB2_LIB.BASEBOARD_FAB2(SCH_1):GND   I171 @BASEBOARD_FAB2_LIB.BASEBOARD_FAB2(SCH_1):PAGE236

C22W23 SC22U16V5MX-4-GP_SMD-BCG5-SC22A
     1 VR_FET_SW_P12V_STBY_PVDDQ_DEF @BASEBOARD_FAB2_LIB.BASEBOARD_FAB2(SCH_1):VR_FET_SW_P12V_STBY_PVDDQ_DEF   I159 @BASEBOARD_FAB2_LIB.BASEBOARD_FAB2(SCH_1):PAGE236
     2    GND @BASEBOARD_FAB2_LIB.BASEBOARD_FAB2(SCH_1):GND   I159 @BASEBOARD_FAB2_LIB.BASEBOARD_FAB2(SCH_1):PAGE236

C22W24 SC22U16V5MX-4-GP_SMD-BCG5-SC22A
     1 VR_FET_SW_P12V_STBY_PVDDQ_DEF @BASEBOARD_FAB2_LIB.BASEBOARD_FAB2(SCH_1):VR_FET_SW_P12V_STBY_PVDDQ_DEF   I160 @BASEBOARD_FAB2_LIB.BASEBOARD_FAB2(SCH_1):PAGE236
     2    GND @BASEBOARD_FAB2_LIB.BASEBOARD_FAB2(SCH_1):GND   I160 @BASEBOARD_FAB2_LIB.BASEBOARD_FAB2(SCH_1):PAGE236

C22W25 SC22U16V5MX-4-GP_SMD-BCG5-SC22A
     1 VR_FET_SW_P12V_STBY_PVDDQ_DEF @BASEBOARD_FAB2_LIB.BASEBOARD_FAB2(SCH_1):VR_FET_SW_P12V_STBY_PVDDQ_DEF   I162 @BASEBOARD_FAB2_LIB.BASEBOARD_FAB2(SCH_1):PAGE236
     2    GND @BASEBOARD_FAB2_LIB.BASEBOARD_FAB2(SCH_1):GND   I162 @BASEBOARD_FAB2_LIB.BASEBOARD_FAB2(SCH_1):PAGE236

C22W26 SC22U16V5MX-4-GP_SMD-BCG5-SC22A
     1 VR_FET_SW_P12V_STBY_PVDDQ_DEF @BASEBOARD_FAB2_LIB.BASEBOARD_FAB2(SCH_1):VR_FET_SW_P12V_STBY_PVDDQ_DEF   I165 @BASEBOARD_FAB2_LIB.BASEBOARD_FAB2(SCH_1):PAGE236
     2    GND @BASEBOARD_FAB2_LIB.BASEBOARD_FAB2(SCH_1):GND   I165 @BASEBOARD_FAB2_LIB.BASEBOARD_FAB2(SCH_1):PAGE236

C22W27 SC22U16V5MX-4-GP_SMD-BCG5-SC22A
     1 VR_FET_SW_P12V_STBY_PVDDQ_DEF @BASEBOARD_FAB2_LIB.BASEBOARD_FAB2(SCH_1):VR_FET_SW_P12V_STBY_PVDDQ_DEF   I163 @BASEBOARD_FAB2_LIB.BASEBOARD_FAB2(SCH_1):PAGE236
     2    GND @BASEBOARD_FAB2_LIB.BASEBOARD_FAB2(SCH_1):GND   I163 @BASEBOARD_FAB2_LIB.BASEBOARD_FAB2(SCH_1):PAGE236

C22W28 SC22U16V5MX-4-GP_SMD-BCG5-SC22A
     1 VR_FET_SW_P12V_STBY_PVCCIO_CPU0 @BASEBOARD_FAB2_LIB.BASEBOARD_FAB2(SCH_1):VR_FET_SW_P12V_STBY_PVCCIO_CPU0   I136 @BASEBOARD_FAB2_LIB.BASEBOARD_FAB2(SCH_1):PAGE212
     2    GND @BASEBOARD_FAB2_LIB.BASEBOARD_FAB2(SCH_1):GND   I136 @BASEBOARD_FAB2_LIB.BASEBOARD_FAB2(SCH_1):PAGE212

C22W29 SC22U16V5MX-4-GP_SMD-BCG5-SC22A
     1 VR_FET_SW_P12V_STBY_PVCCIO_CPU0 @BASEBOARD_FAB2_LIB.BASEBOARD_FAB2(SCH_1):VR_FET_SW_P12V_STBY_PVCCIO_CPU0   I134 @BASEBOARD_FAB2_LIB.BASEBOARD_FAB2(SCH_1):PAGE212
     2    GND @BASEBOARD_FAB2_LIB.BASEBOARD_FAB2(SCH_1):GND   I134 @BASEBOARD_FAB2_LIB.BASEBOARD_FAB2(SCH_1):PAGE212

C22W30 SC22U16V5MX-4-GP_SMD-BCG5-SC22A
     1 VR_FET_SW_P12V_STBY_PVCCIO_CPU0 @BASEBOARD_FAB2_LIB.BASEBOARD_FAB2(SCH_1):VR_FET_SW_P12V_STBY_PVCCIO_CPU0   I132 @BASEBOARD_FAB2_LIB.BASEBOARD_FAB2(SCH_1):PAGE212
     2    GND @BASEBOARD_FAB2_LIB.BASEBOARD_FAB2(SCH_1):GND   I132 @BASEBOARD_FAB2_LIB.BASEBOARD_FAB2(SCH_1):PAGE212

C22W31 SC22U16V5MX-4-GP_SMD-BCG5-SC22A
     1 VR_FET_SW_P12V_STBY_PVCCIO_CPU0 @BASEBOARD_FAB2_LIB.BASEBOARD_FAB2(SCH_1):VR_FET_SW_P12V_STBY_PVCCIO_CPU0   I129 @BASEBOARD_FAB2_LIB.BASEBOARD_FAB2(SCH_1):PAGE212
     2    GND @BASEBOARD_FAB2_LIB.BASEBOARD_FAB2(SCH_1):GND   I129 @BASEBOARD_FAB2_LIB.BASEBOARD_FAB2(SCH_1):PAGE212

C22W32 SC22U16V5MX-4-GP_SMD-BCG5-SC22A
     1 VR_FET_SW_P12V_STBY_PVCCIO_CPU0 @BASEBOARD_FAB2_LIB.BASEBOARD_FAB2(SCH_1):VR_FET_SW_P12V_STBY_PVCCIO_CPU0   I126 @BASEBOARD_FAB2_LIB.BASEBOARD_FAB2(SCH_1):PAGE212
     2    GND @BASEBOARD_FAB2_LIB.BASEBOARD_FAB2(SCH_1):GND   I126 @BASEBOARD_FAB2_LIB.BASEBOARD_FAB2(SCH_1):PAGE212

C22W33 SC22U16V5MX-4-GP_SMD-BCG5-SC22A
     1 VR_FET_SW_P12V_STBY_PVCCIO_CPU0 @BASEBOARD_FAB2_LIB.BASEBOARD_FAB2(SCH_1):VR_FET_SW_P12V_STBY_PVCCIO_CPU0   I124 @BASEBOARD_FAB2_LIB.BASEBOARD_FAB2(SCH_1):PAGE212
     2    GND @BASEBOARD_FAB2_LIB.BASEBOARD_FAB2(SCH_1):GND   I124 @BASEBOARD_FAB2_LIB.BASEBOARD_FAB2(SCH_1):PAGE212

C22W34 SC22U16V5MX-4-GP_SMD-BCG5-SC22A
     1 P3V3_STBY @BASEBOARD_FAB2_LIB.BASEBOARD_FAB2(SCH_1):P3V3_STBY   I244 @BASEBOARD_FAB2_LIB.BASEBOARD_FAB2(SCH_1):PAGE139
     2    GND @BASEBOARD_FAB2_LIB.BASEBOARD_FAB2(SCH_1):GND   I244 @BASEBOARD_FAB2_LIB.BASEBOARD_FAB2(SCH_1):PAGE139

C22W35 SC22U16V5MX-4-GP_SMD-BCG5-SC22A
     1 P1V5_LAN @BASEBOARD_FAB2_LIB.BASEBOARD_FAB2(SCH_1):P1V5_LAN   I246 @BASEBOARD_FAB2_LIB.BASEBOARD_FAB2(SCH_1):PAGE139
     2    GND @BASEBOARD_FAB2_LIB.BASEBOARD_FAB2(SCH_1):GND   I246 @BASEBOARD_FAB2_LIB.BASEBOARD_FAB2(SCH_1):PAGE139

C25P80 CAP_A_0402V-0.1UF,16V,10%,X7R,A
     1 P5V_VGA_D @BASEBOARD_FAB2_LIB.BASEBOARD_FAB2(SCH_1):P5V_VGA_D   I134 @BASEBOARD_FAB2_LIB.BASEBOARD_FAB2(SCH_1):PAGE255
     2    GND @BASEBOARD_FAB2_LIB.BASEBOARD_FAB2(SCH_1):GND   I134 @BASEBOARD_FAB2_LIB.BASEBOARD_FAB2(SCH_1):PAGE255

C25P83 CAP_A_0402V-0.1UF,16V,10%,X7R,A
     1 P5V_VGA @BASEBOARD_FAB2_LIB.BASEBOARD_FAB2(SCH_1):P5V_VGA    I74 @BASEBOARD_FAB2_LIB.BASEBOARD_FAB2(SCH_1):PAGE255
     2    GND @BASEBOARD_FAB2_LIB.BASEBOARD_FAB2(SCH_1):GND    I74 @BASEBOARD_FAB2_LIB.BASEBOARD_FAB2(SCH_1):PAGE255

C25W1 CAP_0402-1.0UF,16V,10%,X6S,D97A
     1 P1V2_AUX_BMC @BASEBOARD_FAB2_LIB.BASEBOARD_FAB2(SCH_1):P1V2_AUX_BMC   I125 @BASEBOARD_FAB2_LIB.BASEBOARD_FAB2(SCH_1):PAGE151
     2    GND @BASEBOARD_FAB2_LIB.BASEBOARD_FAB2(SCH_1):GND   I125 @BASEBOARD_FAB2_LIB.BASEBOARD_FAB2(SCH_1):PAGE151

C25W2 CAP_0402-1.0UF,16V,10%,X6S,D97A
     1 P1V2_AUX_BMC @BASEBOARD_FAB2_LIB.BASEBOARD_FAB2(SCH_1):P1V2_AUX_BMC   I139 @BASEBOARD_FAB2_LIB.BASEBOARD_FAB2(SCH_1):PAGE151
     2    GND @BASEBOARD_FAB2_LIB.BASEBOARD_FAB2(SCH_1):GND   I139 @BASEBOARD_FAB2_LIB.BASEBOARD_FAB2(SCH_1):PAGE151

C25W3 CAP_0402-1.0UF,16V,10%,X6S,D97A
     1 P1V2_AUX_BMC @BASEBOARD_FAB2_LIB.BASEBOARD_FAB2(SCH_1):P1V2_AUX_BMC   I140 @BASEBOARD_FAB2_LIB.BASEBOARD_FAB2(SCH_1):PAGE151
     2    GND @BASEBOARD_FAB2_LIB.BASEBOARD_FAB2(SCH_1):GND   I140 @BASEBOARD_FAB2_LIB.BASEBOARD_FAB2(SCH_1):PAGE151

C25W4 CAP_0402-1.0UF,16V,10%,X6S,D97A
     1 P1V2_AUX_BMC @BASEBOARD_FAB2_LIB.BASEBOARD_FAB2(SCH_1):P1V2_AUX_BMC   I141 @BASEBOARD_FAB2_LIB.BASEBOARD_FAB2(SCH_1):PAGE151
     2    GND @BASEBOARD_FAB2_LIB.BASEBOARD_FAB2(SCH_1):GND   I141 @BASEBOARD_FAB2_LIB.BASEBOARD_FAB2(SCH_1):PAGE151

C25W5 CAP_0402-1.0UF,16V,10%,X6S,D97A
     1 P1V2_AUX_BMC @BASEBOARD_FAB2_LIB.BASEBOARD_FAB2(SCH_1):P1V2_AUX_BMC   I142 @BASEBOARD_FAB2_LIB.BASEBOARD_FAB2(SCH_1):PAGE151
     2    GND @BASEBOARD_FAB2_LIB.BASEBOARD_FAB2(SCH_1):GND   I142 @BASEBOARD_FAB2_LIB.BASEBOARD_FAB2(SCH_1):PAGE151

C25W6 CAP_0402-1.0UF,16V,10%,X6S,D97A
     1 P1V2_AUX_BMC @BASEBOARD_FAB2_LIB.BASEBOARD_FAB2(SCH_1):P1V2_AUX_BMC   I143 @BASEBOARD_FAB2_LIB.BASEBOARD_FAB2(SCH_1):PAGE151
     2    GND @BASEBOARD_FAB2_LIB.BASEBOARD_FAB2(SCH_1):GND   I143 @BASEBOARD_FAB2_LIB.BASEBOARD_FAB2(SCH_1):PAGE151

C25W7 CAP_A_0402V-0.1UF,16V,10%,X7R,A
     1 P3V3_STBY_BMC_ADCVREFP @BASEBOARD_FAB2_LIB.BASEBOARD_FAB2(SCH_1):P3V3_STBY_BMC_ADCVREFP   I161 @BASEBOARD_FAB2_LIB.BASEBOARD_FAB2(SCH_1):PAGE147
     2 VCC_ADCAV3V3 @BASEBOARD_FAB2_LIB.BASEBOARD_FAB2(SCH_1):VCC_ADCAV3V3   I161 @BASEBOARD_FAB2_LIB.BASEBOARD_FAB2(SCH_1):PAGE147

C25W8 CAP_A_0402V-0.1UF,16V,10%,X7R,A
     1 P3V3_STBY_BMC_ADCVREFN @BASEBOARD_FAB2_LIB.BASEBOARD_FAB2(SCH_1):P3V3_STBY_BMC_ADCVREFN   I162 @BASEBOARD_FAB2_LIB.BASEBOARD_FAB2(SCH_1):PAGE147
     2    GND @BASEBOARD_FAB2_LIB.BASEBOARD_FAB2(SCH_1):GND   I162 @BASEBOARD_FAB2_LIB.BASEBOARD_FAB2(SCH_1):PAGE147

C25W9 CAP_A_0402V-0.1UF,16V,10%,X7R,A
     1 P3V3_STBY_BMC_ADCVREFP @BASEBOARD_FAB2_LIB.BASEBOARD_FAB2(SCH_1):P3V3_STBY_BMC_ADCVREFP   I160 @BASEBOARD_FAB2_LIB.BASEBOARD_FAB2(SCH_1):PAGE147
     2 P3V3_STBY_BMC_ADCVREFN @BASEBOARD_FAB2_LIB.BASEBOARD_FAB2(SCH_1):P3V3_STBY_BMC_ADCVREFN   I160 @BASEBOARD_FAB2_LIB.BASEBOARD_FAB2(SCH_1):PAGE147

C25W10 CAP_A_0402V-0.01UF,25V,10%,X7RA
     1 P1V2_AUX_BMC @BASEBOARD_FAB2_LIB.BASEBOARD_FAB2(SCH_1):P1V2_AUX_BMC   I213 @BASEBOARD_FAB2_LIB.BASEBOARD_FAB2(SCH_1):PAGE151
     2 BMC_M_VREFCA @BASEBOARD_FAB2_LIB.BASEBOARD_FAB2(SCH_1):BMC_M_VREFCA   I213 @BASEBOARD_FAB2_LIB.BASEBOARD_FAB2(SCH_1):PAGE151

C25W11 CAP_A_0402V-0.01UF,25V,10%,X7RA
     1 BMC_M_VREFCA @BASEBOARD_FAB2_LIB.BASEBOARD_FAB2(SCH_1):BMC_M_VREFCA   I214 @BASEBOARD_FAB2_LIB.BASEBOARD_FAB2(SCH_1):PAGE151
     2    GND @BASEBOARD_FAB2_LIB.BASEBOARD_FAB2(SCH_1):GND   I214 @BASEBOARD_FAB2_LIB.BASEBOARD_FAB2(SCH_1):PAGE151

C25W12 CAP_A_0402V-1.0UF,6.3V,10%,X6SA
     1 BMC_M_VREFCA @BASEBOARD_FAB2_LIB.BASEBOARD_FAB2(SCH_1):BMC_M_VREFCA   I212 @BASEBOARD_FAB2_LIB.BASEBOARD_FAB2(SCH_1):PAGE151
     2    GND @BASEBOARD_FAB2_LIB.BASEBOARD_FAB2(SCH_1):GND   I212 @BASEBOARD_FAB2_LIB.BASEBOARD_FAB2(SCH_1):PAGE151

C25W13 CAP_A_0402V-0.1UF,16V,10%,X7R,A
     1 BMC_M_VREFCA @BASEBOARD_FAB2_LIB.BASEBOARD_FAB2(SCH_1):BMC_M_VREFCA   I217 @BASEBOARD_FAB2_LIB.BASEBOARD_FAB2(SCH_1):PAGE151
     2    GND @BASEBOARD_FAB2_LIB.BASEBOARD_FAB2(SCH_1):GND   I217 @BASEBOARD_FAB2_LIB.BASEBOARD_FAB2(SCH_1):PAGE151

C25W14 CAP_A_0402V-0.1UF,16V,10%,X7R,A
     1 P2V5_AUX_BMC @BASEBOARD_FAB2_LIB.BASEBOARD_FAB2(SCH_1):P2V5_AUX_BMC   I215 @BASEBOARD_FAB2_LIB.BASEBOARD_FAB2(SCH_1):PAGE151
     2    GND @BASEBOARD_FAB2_LIB.BASEBOARD_FAB2(SCH_1):GND   I215 @BASEBOARD_FAB2_LIB.BASEBOARD_FAB2(SCH_1):PAGE151

C25W15 CAP_A_0402V-0.1UF,16V,10%,X7R,A
     1 P2V5_AUX_BMC @BASEBOARD_FAB2_LIB.BASEBOARD_FAB2(SCH_1):P2V5_AUX_BMC   I216 @BASEBOARD_FAB2_LIB.BASEBOARD_FAB2(SCH_1):PAGE151
     2    GND @BASEBOARD_FAB2_LIB.BASEBOARD_FAB2(SCH_1):GND   I216 @BASEBOARD_FAB2_LIB.BASEBOARD_FAB2(SCH_1):PAGE151

C25W16 CAP_0402LF-100.0PF,50V,5%,COG,A
     1 P1V2_AUX_BMC @BASEBOARD_FAB2_LIB.BASEBOARD_FAB2(SCH_1):P1V2_AUX_BMC    I58 @BASEBOARD_FAB2_LIB.BASEBOARD_FAB2(SCH_1):PAGE151
     2    GND @BASEBOARD_FAB2_LIB.BASEBOARD_FAB2(SCH_1):GND    I58 @BASEBOARD_FAB2_LIB.BASEBOARD_FAB2(SCH_1):PAGE151

C25W17 SC1U16V3KX-2GP_SMD-BCG-SC1U16VA
     1 P1V2_AUX_BMC @BASEBOARD_FAB2_LIB.BASEBOARD_FAB2(SCH_1):P1V2_AUX_BMC   I120 @BASEBOARD_FAB2_LIB.BASEBOARD_FAB2(SCH_1):PAGE151
     2    GND @BASEBOARD_FAB2_LIB.BASEBOARD_FAB2(SCH_1):GND   I120 @BASEBOARD_FAB2_LIB.BASEBOARD_FAB2(SCH_1):PAGE151

C25W18 SC1U16V3KX-2GP_SMD-BCG-SC1U16VA
     1 P1V2_AUX_BMC @BASEBOARD_FAB2_LIB.BASEBOARD_FAB2(SCH_1):P1V2_AUX_BMC   I121 @BASEBOARD_FAB2_LIB.BASEBOARD_FAB2(SCH_1):PAGE151
     2    GND @BASEBOARD_FAB2_LIB.BASEBOARD_FAB2(SCH_1):GND   I121 @BASEBOARD_FAB2_LIB.BASEBOARD_FAB2(SCH_1):PAGE151

C25W19 CAP_0603-4.7UF,6.3V,10%,X6S,E1A
     1 P1V2_AUX_BMC @BASEBOARD_FAB2_LIB.BASEBOARD_FAB2(SCH_1):P1V2_AUX_BMC   I123 @BASEBOARD_FAB2_LIB.BASEBOARD_FAB2(SCH_1):PAGE151
     2    GND @BASEBOARD_FAB2_LIB.BASEBOARD_FAB2(SCH_1):GND   I123 @BASEBOARD_FAB2_LIB.BASEBOARD_FAB2(SCH_1):PAGE151

C25W20 CAP_A_0402V-0.1UF,16V,10%,X7R,A
     1 P2E_SSB_BMC_RX_DP @BASEBOARD_FAB2_LIB.BASEBOARD_FAB2(SCH_1):P2E_SSB_BMC_RX_DP   I158 @BASEBOARD_FAB2_LIB.BASEBOARD_FAB2(SCH_1):PAGE145
     2 P2E_SSB_BMC_RX_C_DP @BASEBOARD_FAB2_LIB.BASEBOARD_FAB2(SCH_1):P2E_SSB_BMC_RX_C_DP   I158 @BASEBOARD_FAB2_LIB.BASEBOARD_FAB2(SCH_1):PAGE145

C25W21 CAP_A_0402V-0.1UF,16V,10%,X7R,A
     1 P2E_SSB_BMC_RX_DN @BASEBOARD_FAB2_LIB.BASEBOARD_FAB2(SCH_1):P2E_SSB_BMC_RX_DN   I159 @BASEBOARD_FAB2_LIB.BASEBOARD_FAB2(SCH_1):PAGE145
     2 P2E_SSB_BMC_RX_C_DN @BASEBOARD_FAB2_LIB.BASEBOARD_FAB2(SCH_1):P2E_SSB_BMC_RX_C_DN   I159 @BASEBOARD_FAB2_LIB.BASEBOARD_FAB2(SCH_1):PAGE145

C25W22 CAP_A_0402V-0.1UF,16V,10%,X7R,A
     1 BMC_M_VREFCA @BASEBOARD_FAB2_LIB.BASEBOARD_FAB2(SCH_1):BMC_M_VREFCA    I67 @BASEBOARD_FAB2_LIB.BASEBOARD_FAB2(SCH_1):PAGE143
     2    GND @BASEBOARD_FAB2_LIB.BASEBOARD_FAB2(SCH_1):GND    I67 @BASEBOARD_FAB2_LIB.BASEBOARD_FAB2(SCH_1):PAGE143

C25W23 CAP_0402-1.0UF,16V,10%,X6S,D97A
     1 P1V15_AUX_BMC @BASEBOARD_FAB2_LIB.BASEBOARD_FAB2(SCH_1):P1V15_AUX_BMC   I103 @BASEBOARD_FAB2_LIB.BASEBOARD_FAB2(SCH_1):PAGE149
     2    GND @BASEBOARD_FAB2_LIB.BASEBOARD_FAB2(SCH_1):GND   I103 @BASEBOARD_FAB2_LIB.BASEBOARD_FAB2(SCH_1):PAGE149

C25W24 CAP_0402-1.0UF,16V,10%,X6S,D97A
     1 P1V15_AUX_BMC @BASEBOARD_FAB2_LIB.BASEBOARD_FAB2(SCH_1):P1V15_AUX_BMC   I104 @BASEBOARD_FAB2_LIB.BASEBOARD_FAB2(SCH_1):PAGE149
     2    GND @BASEBOARD_FAB2_LIB.BASEBOARD_FAB2(SCH_1):GND   I104 @BASEBOARD_FAB2_LIB.BASEBOARD_FAB2(SCH_1):PAGE149

C25W25 CAP_0402-1.0UF,16V,10%,X6S,D97A
     1 P1V15_AUX_BMC @BASEBOARD_FAB2_LIB.BASEBOARD_FAB2(SCH_1):P1V15_AUX_BMC   I105 @BASEBOARD_FAB2_LIB.BASEBOARD_FAB2(SCH_1):PAGE149
     2    GND @BASEBOARD_FAB2_LIB.BASEBOARD_FAB2(SCH_1):GND   I105 @BASEBOARD_FAB2_LIB.BASEBOARD_FAB2(SCH_1):PAGE149

C25W26 CAP_0402-1.0UF,16V,10%,X6S,D97A
     1 P1V15_AUX_BMC @BASEBOARD_FAB2_LIB.BASEBOARD_FAB2(SCH_1):P1V15_AUX_BMC   I106 @BASEBOARD_FAB2_LIB.BASEBOARD_FAB2(SCH_1):PAGE149
     2    GND @BASEBOARD_FAB2_LIB.BASEBOARD_FAB2(SCH_1):GND   I106 @BASEBOARD_FAB2_LIB.BASEBOARD_FAB2(SCH_1):PAGE149

C25W27 CAP_0402-1.0UF,16V,10%,X6S,D97A
     1 P1V15_AUX_BMC @BASEBOARD_FAB2_LIB.BASEBOARD_FAB2(SCH_1):P1V15_AUX_BMC   I107 @BASEBOARD_FAB2_LIB.BASEBOARD_FAB2(SCH_1):PAGE149
     2    GND @BASEBOARD_FAB2_LIB.BASEBOARD_FAB2(SCH_1):GND   I107 @BASEBOARD_FAB2_LIB.BASEBOARD_FAB2(SCH_1):PAGE149

C25W28 CAP_0402-1.0UF,16V,10%,X6S,D97A
     1 P1V15_AUX_BMC @BASEBOARD_FAB2_LIB.BASEBOARD_FAB2(SCH_1):P1V15_AUX_BMC   I108 @BASEBOARD_FAB2_LIB.BASEBOARD_FAB2(SCH_1):PAGE149
     2    GND @BASEBOARD_FAB2_LIB.BASEBOARD_FAB2(SCH_1):GND   I108 @BASEBOARD_FAB2_LIB.BASEBOARD_FAB2(SCH_1):PAGE149

C25W29 CAP_0603LF-10UF,4V,20%,X6S,E15A
     1 P1V15_AUX_BMC @BASEBOARD_FAB2_LIB.BASEBOARD_FAB2(SCH_1):P1V15_AUX_BMC   I129 @BASEBOARD_FAB2_LIB.BASEBOARD_FAB2(SCH_1):PAGE149
     2    GND @BASEBOARD_FAB2_LIB.BASEBOARD_FAB2(SCH_1):GND   I129 @BASEBOARD_FAB2_LIB.BASEBOARD_FAB2(SCH_1):PAGE149

C25W30 CAP_0603-4.7UF,6.3V,10%,X6S,E1A
     1 P1V15_AUX_BMC @BASEBOARD_FAB2_LIB.BASEBOARD_FAB2(SCH_1):P1V15_AUX_BMC     I1 @BASEBOARD_FAB2_LIB.BASEBOARD_FAB2(SCH_1):PAGE149
     2    GND @BASEBOARD_FAB2_LIB.BASEBOARD_FAB2(SCH_1):GND     I1 @BASEBOARD_FAB2_LIB.BASEBOARD_FAB2(SCH_1):PAGE149

C25W31 CAP_A_0402V-0.1UF,16V,10%,X7R,A
     1 VCC_ADCAV3V3 @BASEBOARD_FAB2_LIB.BASEBOARD_FAB2(SCH_1):VCC_ADCAV3V3   I119 @BASEBOARD_FAB2_LIB.BASEBOARD_FAB2(SCH_1):PAGE149
     2    GND @BASEBOARD_FAB2_LIB.BASEBOARD_FAB2(SCH_1):GND   I119 @BASEBOARD_FAB2_LIB.BASEBOARD_FAB2(SCH_1):PAGE149

C25W32 CAP_0402-1.0UF,16V,10%,X6S,D97A
     1 VCC_ADCAV3V3 @BASEBOARD_FAB2_LIB.BASEBOARD_FAB2(SCH_1):VCC_ADCAV3V3    I99 @BASEBOARD_FAB2_LIB.BASEBOARD_FAB2(SCH_1):PAGE149
     2    GND @BASEBOARD_FAB2_LIB.BASEBOARD_FAB2(SCH_1):GND    I99 @BASEBOARD_FAB2_LIB.BASEBOARD_FAB2(SCH_1):PAGE149

C25W33 CAP_0402-1.0UF,16V,10%,X6S,D97A
     1 VCC_ADCAV3V3 @BASEBOARD_FAB2_LIB.BASEBOARD_FAB2(SCH_1):VCC_ADCAV3V3   I102 @BASEBOARD_FAB2_LIB.BASEBOARD_FAB2(SCH_1):PAGE149
     2    GND @BASEBOARD_FAB2_LIB.BASEBOARD_FAB2(SCH_1):GND   I102 @BASEBOARD_FAB2_LIB.BASEBOARD_FAB2(SCH_1):PAGE149

C25W34 CAP_A_0402V-0.1UF,16V,10%,X7R,A
     1 VCC_DACAV3V3 @BASEBOARD_FAB2_LIB.BASEBOARD_FAB2(SCH_1):VCC_DACAV3V3   I120 @BASEBOARD_FAB2_LIB.BASEBOARD_FAB2(SCH_1):PAGE149
     2    GND @BASEBOARD_FAB2_LIB.BASEBOARD_FAB2(SCH_1):GND   I120 @BASEBOARD_FAB2_LIB.BASEBOARD_FAB2(SCH_1):PAGE149

C25W35 CAP_0402-1.0UF,16V,10%,X6S,D97A
     1 VCC_DACAV3V3 @BASEBOARD_FAB2_LIB.BASEBOARD_FAB2(SCH_1):VCC_DACAV3V3   I110 @BASEBOARD_FAB2_LIB.BASEBOARD_FAB2(SCH_1):PAGE149
     2    GND @BASEBOARD_FAB2_LIB.BASEBOARD_FAB2(SCH_1):GND   I110 @BASEBOARD_FAB2_LIB.BASEBOARD_FAB2(SCH_1):PAGE149

C25W36 CAP_0603-4.7UF,6.3V,10%,X6S,E1A
     1 VCC_DACAV3V3 @BASEBOARD_FAB2_LIB.BASEBOARD_FAB2(SCH_1):VCC_DACAV3V3    I46 @BASEBOARD_FAB2_LIB.BASEBOARD_FAB2(SCH_1):PAGE149
     2    GND @BASEBOARD_FAB2_LIB.BASEBOARD_FAB2(SCH_1):GND    I46 @BASEBOARD_FAB2_LIB.BASEBOARD_FAB2(SCH_1):PAGE149

C25W37 CAP_0402-1.0UF,16V,10%,X6S,D97A
     1 VCC_A_1V1 @BASEBOARD_FAB2_LIB.BASEBOARD_FAB2(SCH_1):VCC_A_1V1   I113 @BASEBOARD_FAB2_LIB.BASEBOARD_FAB2(SCH_1):PAGE149
     2    GND @BASEBOARD_FAB2_LIB.BASEBOARD_FAB2(SCH_1):GND   I113 @BASEBOARD_FAB2_LIB.BASEBOARD_FAB2(SCH_1):PAGE149

C25W38 CAP_A_0402V-0.1UF,16V,10%,X7R,A
     1 VCC_A_1V1 @BASEBOARD_FAB2_LIB.BASEBOARD_FAB2(SCH_1):VCC_A_1V1   I121 @BASEBOARD_FAB2_LIB.BASEBOARD_FAB2(SCH_1):PAGE149
     2    GND @BASEBOARD_FAB2_LIB.BASEBOARD_FAB2(SCH_1):GND   I121 @BASEBOARD_FAB2_LIB.BASEBOARD_FAB2(SCH_1):PAGE149

C25W39 CAP_0603-4.7UF,6.3V,10%,X6S,E1A
     1 VCC_A_1V1 @BASEBOARD_FAB2_LIB.BASEBOARD_FAB2(SCH_1):VCC_A_1V1    I25 @BASEBOARD_FAB2_LIB.BASEBOARD_FAB2(SCH_1):PAGE149
     2    GND @BASEBOARD_FAB2_LIB.BASEBOARD_FAB2(SCH_1):GND    I25 @BASEBOARD_FAB2_LIB.BASEBOARD_FAB2(SCH_1):PAGE149

C25W40 CAP_0402-1.0UF,16V,10%,X6S,D97A
     1 VCC_D_3V3 @BASEBOARD_FAB2_LIB.BASEBOARD_FAB2(SCH_1):VCC_D_3V3    I96 @BASEBOARD_FAB2_LIB.BASEBOARD_FAB2(SCH_1):PAGE149
     2    GND @BASEBOARD_FAB2_LIB.BASEBOARD_FAB2(SCH_1):GND    I96 @BASEBOARD_FAB2_LIB.BASEBOARD_FAB2(SCH_1):PAGE149

C25W41 CAP_0402-1.0UF,16V,10%,X6S,D97A
     1 VCC_D_3V3 @BASEBOARD_FAB2_LIB.BASEBOARD_FAB2(SCH_1):VCC_D_3V3    I97 @BASEBOARD_FAB2_LIB.BASEBOARD_FAB2(SCH_1):PAGE149
     2    GND @BASEBOARD_FAB2_LIB.BASEBOARD_FAB2(SCH_1):GND    I97 @BASEBOARD_FAB2_LIB.BASEBOARD_FAB2(SCH_1):PAGE149

C25W42 CAP_0402-1.0UF,16V,10%,X6S,D97A
     1 VCC_D_3V3 @BASEBOARD_FAB2_LIB.BASEBOARD_FAB2(SCH_1):VCC_D_3V3    I98 @BASEBOARD_FAB2_LIB.BASEBOARD_FAB2(SCH_1):PAGE149
     2    GND @BASEBOARD_FAB2_LIB.BASEBOARD_FAB2(SCH_1):GND    I98 @BASEBOARD_FAB2_LIB.BASEBOARD_FAB2(SCH_1):PAGE149

C25W43 CAP_0402-1.0UF,16V,10%,X6S,D97A
     1 VCC_D_3V3 @BASEBOARD_FAB2_LIB.BASEBOARD_FAB2(SCH_1):VCC_D_3V3   I100 @BASEBOARD_FAB2_LIB.BASEBOARD_FAB2(SCH_1):PAGE149
     2    GND @BASEBOARD_FAB2_LIB.BASEBOARD_FAB2(SCH_1):GND   I100 @BASEBOARD_FAB2_LIB.BASEBOARD_FAB2(SCH_1):PAGE149

C25W44 CAP_0402-1.0UF,16V,10%,X6S,D97A
     1 VCC_D_3V3 @BASEBOARD_FAB2_LIB.BASEBOARD_FAB2(SCH_1):VCC_D_3V3   I101 @BASEBOARD_FAB2_LIB.BASEBOARD_FAB2(SCH_1):PAGE149
     2    GND @BASEBOARD_FAB2_LIB.BASEBOARD_FAB2(SCH_1):GND   I101 @BASEBOARD_FAB2_LIB.BASEBOARD_FAB2(SCH_1):PAGE149

C25W45 CAP_A_0402V-0.1UF,16V,10%,X7R,A
     1 VCC_D_3V3 @BASEBOARD_FAB2_LIB.BASEBOARD_FAB2(SCH_1):VCC_D_3V3   I122 @BASEBOARD_FAB2_LIB.BASEBOARD_FAB2(SCH_1):PAGE149
     2    GND @BASEBOARD_FAB2_LIB.BASEBOARD_FAB2(SCH_1):GND   I122 @BASEBOARD_FAB2_LIB.BASEBOARD_FAB2(SCH_1):PAGE149

C25W46 CAP_0805-10UF,16V,10%,X6S,C953A
     1 VCC_D_3V3 @BASEBOARD_FAB2_LIB.BASEBOARD_FAB2(SCH_1):VCC_D_3V3    I51 @BASEBOARD_FAB2_LIB.BASEBOARD_FAB2(SCH_1):PAGE149
     2    GND @BASEBOARD_FAB2_LIB.BASEBOARD_FAB2(SCH_1):GND    I51 @BASEBOARD_FAB2_LIB.BASEBOARD_FAB2(SCH_1):PAGE149

C25W47 CAP_0603-4.7UF,6.3V,10%,X6S,E1A
     1 VCC_D_3V3 @BASEBOARD_FAB2_LIB.BASEBOARD_FAB2(SCH_1):VCC_D_3V3    I50 @BASEBOARD_FAB2_LIB.BASEBOARD_FAB2(SCH_1):PAGE149
     2    GND @BASEBOARD_FAB2_LIB.BASEBOARD_FAB2(SCH_1):GND    I50 @BASEBOARD_FAB2_LIB.BASEBOARD_FAB2(SCH_1):PAGE149

C25W48 CAP_0402-1.0UF,16V,10%,X6S,D97A
     1 P3V3_STBY @BASEBOARD_FAB2_LIB.BASEBOARD_FAB2(SCH_1):P3V3_STBY   I112 @BASEBOARD_FAB2_LIB.BASEBOARD_FAB2(SCH_1):PAGE149
     2    GND @BASEBOARD_FAB2_LIB.BASEBOARD_FAB2(SCH_1):GND   I112 @BASEBOARD_FAB2_LIB.BASEBOARD_FAB2(SCH_1):PAGE149

C25W49 CAP_A_0402V-0.1UF,16V,10%,X7R,A
     1 P3V3_STBY @BASEBOARD_FAB2_LIB.BASEBOARD_FAB2(SCH_1):P3V3_STBY   I123 @BASEBOARD_FAB2_LIB.BASEBOARD_FAB2(SCH_1):PAGE149
     2    GND @BASEBOARD_FAB2_LIB.BASEBOARD_FAB2(SCH_1):GND   I123 @BASEBOARD_FAB2_LIB.BASEBOARD_FAB2(SCH_1):PAGE149

C25W50 CAP_0603-4.7UF,6.3V,10%,X6S,E1A
     1 P3V3_STBY @BASEBOARD_FAB2_LIB.BASEBOARD_FAB2(SCH_1):P3V3_STBY    I31 @BASEBOARD_FAB2_LIB.BASEBOARD_FAB2(SCH_1):PAGE149
     2    GND @BASEBOARD_FAB2_LIB.BASEBOARD_FAB2(SCH_1):GND    I31 @BASEBOARD_FAB2_LIB.BASEBOARD_FAB2(SCH_1):PAGE149

C25W51 CAP_0402-1.0UF,16V,10%,X6S,D97A
     1 P1V2_AUX_BMC @BASEBOARD_FAB2_LIB.BASEBOARD_FAB2(SCH_1):P1V2_AUX_BMC   I114 @BASEBOARD_FAB2_LIB.BASEBOARD_FAB2(SCH_1):PAGE149
     2    GND @BASEBOARD_FAB2_LIB.BASEBOARD_FAB2(SCH_1):GND   I114 @BASEBOARD_FAB2_LIB.BASEBOARD_FAB2(SCH_1):PAGE149

C25W52 CAP_0402-1.0UF,16V,10%,X6S,D97A
     1 P1V2_AUX_BMC @BASEBOARD_FAB2_LIB.BASEBOARD_FAB2(SCH_1):P1V2_AUX_BMC   I118 @BASEBOARD_FAB2_LIB.BASEBOARD_FAB2(SCH_1):PAGE149
     2    GND @BASEBOARD_FAB2_LIB.BASEBOARD_FAB2(SCH_1):GND   I118 @BASEBOARD_FAB2_LIB.BASEBOARD_FAB2(SCH_1):PAGE149

C25W53 CAP_0402-1.0UF,16V,10%,X6S,D97A
     1 P1V2_AUX_BMC @BASEBOARD_FAB2_LIB.BASEBOARD_FAB2(SCH_1):P1V2_AUX_BMC    I92 @BASEBOARD_FAB2_LIB.BASEBOARD_FAB2(SCH_1):PAGE149
     2    GND @BASEBOARD_FAB2_LIB.BASEBOARD_FAB2(SCH_1):GND    I92 @BASEBOARD_FAB2_LIB.BASEBOARD_FAB2(SCH_1):PAGE149

C25W54 CAP_0402-1.0UF,16V,10%,X6S,D97A
     1 P1V2_AUX_BMC @BASEBOARD_FAB2_LIB.BASEBOARD_FAB2(SCH_1):P1V2_AUX_BMC    I95 @BASEBOARD_FAB2_LIB.BASEBOARD_FAB2(SCH_1):PAGE149
     2    GND @BASEBOARD_FAB2_LIB.BASEBOARD_FAB2(SCH_1):GND    I95 @BASEBOARD_FAB2_LIB.BASEBOARD_FAB2(SCH_1):PAGE149

C25W55 CAP_A_0402V-0.1UF,16V,10%,X7R,A
     1 P1V2_AUX_BMC @BASEBOARD_FAB2_LIB.BASEBOARD_FAB2(SCH_1):P1V2_AUX_BMC   I124 @BASEBOARD_FAB2_LIB.BASEBOARD_FAB2(SCH_1):PAGE149
     2    GND @BASEBOARD_FAB2_LIB.BASEBOARD_FAB2(SCH_1):GND   I124 @BASEBOARD_FAB2_LIB.BASEBOARD_FAB2(SCH_1):PAGE149

C25W56 CAP_0402-1.0UF,16V,10%,X6S,D97A
     1 VCC_PA_3V3 @BASEBOARD_FAB2_LIB.BASEBOARD_FAB2(SCH_1):VCC_PA_3V3    I93 @BASEBOARD_FAB2_LIB.BASEBOARD_FAB2(SCH_1):PAGE149
     2    GND @BASEBOARD_FAB2_LIB.BASEBOARD_FAB2(SCH_1):GND    I93 @BASEBOARD_FAB2_LIB.BASEBOARD_FAB2(SCH_1):PAGE149

C25W57 CAP_0402LF-100.0PF,50V,5%,COG,A
     1 VCC_PA_3V3 @BASEBOARD_FAB2_LIB.BASEBOARD_FAB2(SCH_1):VCC_PA_3V3   I130 @BASEBOARD_FAB2_LIB.BASEBOARD_FAB2(SCH_1):PAGE149
     2    GND @BASEBOARD_FAB2_LIB.BASEBOARD_FAB2(SCH_1):GND   I130 @BASEBOARD_FAB2_LIB.BASEBOARD_FAB2(SCH_1):PAGE149

C25W58 CAP_A_0402V-0.1UF,16V,10%,X7R,A
     1 VCC_PA_3V3 @BASEBOARD_FAB2_LIB.BASEBOARD_FAB2(SCH_1):VCC_PA_3V3   I125 @BASEBOARD_FAB2_LIB.BASEBOARD_FAB2(SCH_1):PAGE149
     2    GND @BASEBOARD_FAB2_LIB.BASEBOARD_FAB2(SCH_1):GND   I125 @BASEBOARD_FAB2_LIB.BASEBOARD_FAB2(SCH_1):PAGE149

C25W59 CAP_0603-4.7UF,6.3V,10%,X6S,E1A
     1 VCC_PA_3V3 @BASEBOARD_FAB2_LIB.BASEBOARD_FAB2(SCH_1):VCC_PA_3V3    I79 @BASEBOARD_FAB2_LIB.BASEBOARD_FAB2(SCH_1):PAGE149
     2    GND @BASEBOARD_FAB2_LIB.BASEBOARD_FAB2(SCH_1):GND    I79 @BASEBOARD_FAB2_LIB.BASEBOARD_FAB2(SCH_1):PAGE149

C25W60 CAP_0402-1.0UF,16V,10%,X6S,D97A
     1 P3V3_STBY @BASEBOARD_FAB2_LIB.BASEBOARD_FAB2(SCH_1):P3V3_STBY   I109 @BASEBOARD_FAB2_LIB.BASEBOARD_FAB2(SCH_1):PAGE149
     2    GND @BASEBOARD_FAB2_LIB.BASEBOARD_FAB2(SCH_1):GND   I109 @BASEBOARD_FAB2_LIB.BASEBOARD_FAB2(SCH_1):PAGE149

C25W61 CAP_A_0402V-0.1UF,16V,10%,X7R,A
     1 P3V3_STBY @BASEBOARD_FAB2_LIB.BASEBOARD_FAB2(SCH_1):P3V3_STBY   I126 @BASEBOARD_FAB2_LIB.BASEBOARD_FAB2(SCH_1):PAGE149
     2    GND @BASEBOARD_FAB2_LIB.BASEBOARD_FAB2(SCH_1):GND   I126 @BASEBOARD_FAB2_LIB.BASEBOARD_FAB2(SCH_1):PAGE149

C25W62 CAP_0603-4.7UF,6.3V,10%,X6S,E1A
     1 P3V3_STBY @BASEBOARD_FAB2_LIB.BASEBOARD_FAB2(SCH_1):P3V3_STBY    I40 @BASEBOARD_FAB2_LIB.BASEBOARD_FAB2(SCH_1):PAGE149
     2    GND @BASEBOARD_FAB2_LIB.BASEBOARD_FAB2(SCH_1):GND    I40 @BASEBOARD_FAB2_LIB.BASEBOARD_FAB2(SCH_1):PAGE149

C25W66 CAP_0402-1.0UF,16V,10%,X6S,D97A
     1 VCC_VA_3V3 @BASEBOARD_FAB2_LIB.BASEBOARD_FAB2(SCH_1):VCC_VA_3V3   I116 @BASEBOARD_FAB2_LIB.BASEBOARD_FAB2(SCH_1):PAGE149
     2    GND @BASEBOARD_FAB2_LIB.BASEBOARD_FAB2(SCH_1):GND   I116 @BASEBOARD_FAB2_LIB.BASEBOARD_FAB2(SCH_1):PAGE149

C25W67 CAP_0402-1.0UF,16V,10%,X6S,D97A
     1 VCC_VA_3V3 @BASEBOARD_FAB2_LIB.BASEBOARD_FAB2(SCH_1):VCC_VA_3V3   I117 @BASEBOARD_FAB2_LIB.BASEBOARD_FAB2(SCH_1):PAGE149
     2    GND @BASEBOARD_FAB2_LIB.BASEBOARD_FAB2(SCH_1):GND   I117 @BASEBOARD_FAB2_LIB.BASEBOARD_FAB2(SCH_1):PAGE149

C25W68 CAP_A_0402V-0.1UF,16V,10%,X7R,A
     1 VCC_VA_3V3 @BASEBOARD_FAB2_LIB.BASEBOARD_FAB2(SCH_1):VCC_VA_3V3   I128 @BASEBOARD_FAB2_LIB.BASEBOARD_FAB2(SCH_1):PAGE149
     2    GND @BASEBOARD_FAB2_LIB.BASEBOARD_FAB2(SCH_1):GND   I128 @BASEBOARD_FAB2_LIB.BASEBOARD_FAB2(SCH_1):PAGE149

C25W69 CAP_0603-4.7UF,6.3V,10%,X6S,E1A
     1 VCC_VA_3V3 @BASEBOARD_FAB2_LIB.BASEBOARD_FAB2(SCH_1):VCC_VA_3V3    I17 @BASEBOARD_FAB2_LIB.BASEBOARD_FAB2(SCH_1):PAGE149
     2    GND @BASEBOARD_FAB2_LIB.BASEBOARD_FAB2(SCH_1):GND    I17 @BASEBOARD_FAB2_LIB.BASEBOARD_FAB2(SCH_1):PAGE149

C25W70 CAP_0603-4.7UF,6.3V,10%,X6S,E1A
     1 P3V3_USB2A_ALG @BASEBOARD_FAB2_LIB.BASEBOARD_FAB2(SCH_1):P3V3_USB2A_ALG     I5 @BASEBOARD_FAB2_LIB.BASEBOARD_FAB2(SCH_1):PAGE149
     2    GND @BASEBOARD_FAB2_LIB.BASEBOARD_FAB2(SCH_1):GND     I5 @BASEBOARD_FAB2_LIB.BASEBOARD_FAB2(SCH_1):PAGE149

C25W71 CAP_0402-1.0UF,16V,10%,X6S,D97A
     1 P3V3_USB2A_ALG @BASEBOARD_FAB2_LIB.BASEBOARD_FAB2(SCH_1):P3V3_USB2A_ALG   I115 @BASEBOARD_FAB2_LIB.BASEBOARD_FAB2(SCH_1):PAGE149
     2    GND @BASEBOARD_FAB2_LIB.BASEBOARD_FAB2(SCH_1):GND   I115 @BASEBOARD_FAB2_LIB.BASEBOARD_FAB2(SCH_1):PAGE149

C25W72 CAP_0402LF-12.0PF,50V,5%,COG,AA
     1 BMC_VGA_BLUE @BASEBOARD_FAB2_LIB.BASEBOARD_FAB2(SCH_1):BMC_VGA_BLUE     I7 @BASEBOARD_FAB2_LIB.BASEBOARD_FAB2(SCH_1):PAGE255
     2    GND @BASEBOARD_FAB2_LIB.BASEBOARD_FAB2(SCH_1):GND     I7 @BASEBOARD_FAB2_LIB.BASEBOARD_FAB2(SCH_1):PAGE255

C25W73 CAP_0402LF-12.0PF,50V,5%,COG,AA
     1 BMC_VGA_GREEN @BASEBOARD_FAB2_LIB.BASEBOARD_FAB2(SCH_1):BMC_VGA_GREEN    I11 @BASEBOARD_FAB2_LIB.BASEBOARD_FAB2(SCH_1):PAGE255
     2    GND @BASEBOARD_FAB2_LIB.BASEBOARD_FAB2(SCH_1):GND    I11 @BASEBOARD_FAB2_LIB.BASEBOARD_FAB2(SCH_1):PAGE255

C25W74 CAP_0402LF-12.0PF,50V,5%,COG,AA
     1 BMC_VGA_RED @BASEBOARD_FAB2_LIB.BASEBOARD_FAB2(SCH_1):BMC_VGA_RED    I12 @BASEBOARD_FAB2_LIB.BASEBOARD_FAB2(SCH_1):PAGE255
     2    GND @BASEBOARD_FAB2_LIB.BASEBOARD_FAB2(SCH_1):GND    I12 @BASEBOARD_FAB2_LIB.BASEBOARD_FAB2(SCH_1):PAGE255

C25W75 CAP_0402LF-12.0PF,50V,5%,COG,AA
     1 V_IO_B_J @BASEBOARD_FAB2_LIB.BASEBOARD_FAB2(SCH_1):V_IO_B_J    I21 @BASEBOARD_FAB2_LIB.BASEBOARD_FAB2(SCH_1):PAGE255
     2    GND @BASEBOARD_FAB2_LIB.BASEBOARD_FAB2(SCH_1):GND    I21 @BASEBOARD_FAB2_LIB.BASEBOARD_FAB2(SCH_1):PAGE255

C25W76 CAP_0402LF-12.0PF,50V,5%,COG,AA
     1 V_IO_G_J @BASEBOARD_FAB2_LIB.BASEBOARD_FAB2(SCH_1):V_IO_G_J    I18 @BASEBOARD_FAB2_LIB.BASEBOARD_FAB2(SCH_1):PAGE255
     2    GND @BASEBOARD_FAB2_LIB.BASEBOARD_FAB2(SCH_1):GND    I18 @BASEBOARD_FAB2_LIB.BASEBOARD_FAB2(SCH_1):PAGE255

C25W77 CAP_0402LF-12.0PF,50V,5%,COG,AA
     1 V_IO_R_J @BASEBOARD_FAB2_LIB.BASEBOARD_FAB2(SCH_1):V_IO_R_J    I16 @BASEBOARD_FAB2_LIB.BASEBOARD_FAB2(SCH_1):PAGE255
     2    GND @BASEBOARD_FAB2_LIB.BASEBOARD_FAB2(SCH_1):GND    I16 @BASEBOARD_FAB2_LIB.BASEBOARD_FAB2(SCH_1):PAGE255

C25W78 CAP_0402LF-100.0PF,50V,5%,COG,A
     1 V_IBMC_5V_DDC_SCL_J @BASEBOARD_FAB2_LIB.BASEBOARD_FAB2(SCH_1):V_IBMC_5V_DDC_SCL_J    I35 @BASEBOARD_FAB2_LIB.BASEBOARD_FAB2(SCH_1):PAGE255
     2    GND @BASEBOARD_FAB2_LIB.BASEBOARD_FAB2(SCH_1):GND    I35 @BASEBOARD_FAB2_LIB.BASEBOARD_FAB2(SCH_1):PAGE255

C25W79 CAP_0402LF-100.0PF,50V,5%,COG,A
     1 V_IBMC_5V_DDC_SDA_J @BASEBOARD_FAB2_LIB.BASEBOARD_FAB2(SCH_1):V_IBMC_5V_DDC_SDA_J    I39 @BASEBOARD_FAB2_LIB.BASEBOARD_FAB2(SCH_1):PAGE255
     2    GND @BASEBOARD_FAB2_LIB.BASEBOARD_FAB2(SCH_1):GND    I39 @BASEBOARD_FAB2_LIB.BASEBOARD_FAB2(SCH_1):PAGE255

C25W81 CAP_0402LF-10.0PF,50V,5%,COG,AA
     1 V_IO_HSYNC_J @BASEBOARD_FAB2_LIB.BASEBOARD_FAB2(SCH_1):V_IO_HSYNC_J    I60 @BASEBOARD_FAB2_LIB.BASEBOARD_FAB2(SCH_1):PAGE255
     2    GND @BASEBOARD_FAB2_LIB.BASEBOARD_FAB2(SCH_1):GND    I60 @BASEBOARD_FAB2_LIB.BASEBOARD_FAB2(SCH_1):PAGE255

C25W82 CAP_0402LF-10.0PF,50V,5%,COG,AA
     1 V_IO_VSYNC_J @BASEBOARD_FAB2_LIB.BASEBOARD_FAB2(SCH_1):V_IO_VSYNC_J    I62 @BASEBOARD_FAB2_LIB.BASEBOARD_FAB2(SCH_1):PAGE255
     2    GND @BASEBOARD_FAB2_LIB.BASEBOARD_FAB2(SCH_1):GND    I62 @BASEBOARD_FAB2_LIB.BASEBOARD_FAB2(SCH_1):PAGE255

C25W90 CAP_A_0402V-0.1UF,16V,10%,X7R,A
     1 P5V_VGA_D @BASEBOARD_FAB2_LIB.BASEBOARD_FAB2(SCH_1):P5V_VGA_D   I118 @BASEBOARD_FAB2_LIB.BASEBOARD_FAB2(SCH_1):PAGE255
     2    GND @BASEBOARD_FAB2_LIB.BASEBOARD_FAB2(SCH_1):GND   I118 @BASEBOARD_FAB2_LIB.BASEBOARD_FAB2(SCH_1):PAGE255

C25W91 CAP_A_0402V-1.0UF,6.3V,10%,X6SA
     1 P3V3_STBY @BASEBOARD_FAB2_LIB.BASEBOARD_FAB2(SCH_1):P3V3_STBY    I26 @BASEBOARD_FAB2_LIB.BASEBOARD_FAB2(SCH_1):PAGE269
     2    GND @BASEBOARD_FAB2_LIB.BASEBOARD_FAB2(SCH_1):GND    I26 @BASEBOARD_FAB2_LIB.BASEBOARD_FAB2(SCH_1):PAGE269

C25W92 CAP_0402-1.0UF,16V,10%,X6S,D97A
     1 P3V3_STBY @BASEBOARD_FAB2_LIB.BASEBOARD_FAB2(SCH_1):P3V3_STBY    I23 @BASEBOARD_FAB2_LIB.BASEBOARD_FAB2(SCH_1):PAGE268
     2    GND @BASEBOARD_FAB2_LIB.BASEBOARD_FAB2(SCH_1):GND    I23 @BASEBOARD_FAB2_LIB.BASEBOARD_FAB2(SCH_1):PAGE268

C25W93 CAP_A_0402V-0.1UF,16V,10%,X7R,A
     1 P0V7_GTL2014_VREF_6 @BASEBOARD_FAB2_LIB.BASEBOARD_FAB2(SCH_1):P0V7_GTL2014_VREF_6    I27 @BASEBOARD_FAB2_LIB.BASEBOARD_FAB2(SCH_1):PAGE268
     2    GND @BASEBOARD_FAB2_LIB.BASEBOARD_FAB2(SCH_1):GND    I27 @BASEBOARD_FAB2_LIB.BASEBOARD_FAB2(SCH_1):PAGE268

C25W94 CAP_0402-1.0UF,16V,10%,X6S,D97A
     1 P3V3_STBY @BASEBOARD_FAB2_LIB.BASEBOARD_FAB2(SCH_1):P3V3_STBY    I32 @BASEBOARD_FAB2_LIB.BASEBOARD_FAB2(SCH_1):PAGE269
     2    GND @BASEBOARD_FAB2_LIB.BASEBOARD_FAB2(SCH_1):GND    I32 @BASEBOARD_FAB2_LIB.BASEBOARD_FAB2(SCH_1):PAGE269

C25W95 CAP_A_0402V-0.1UF,16V,10%,X7R,A
     1 P3V3_STBY @BASEBOARD_FAB2_LIB.BASEBOARD_FAB2(SCH_1):P3V3_STBY    I56 @BASEBOARD_FAB2_LIB.BASEBOARD_FAB2(SCH_1):PAGE269
     2    GND @BASEBOARD_FAB2_LIB.BASEBOARD_FAB2(SCH_1):GND    I56 @BASEBOARD_FAB2_LIB.BASEBOARD_FAB2(SCH_1):PAGE269

C25W96 CAP_A_0402V-0.1UF,16V,10%,X7R,A
     1 P3V3_STBY @BASEBOARD_FAB2_LIB.BASEBOARD_FAB2(SCH_1):P3V3_STBY     I9 @BASEBOARD_FAB2_LIB.BASEBOARD_FAB2(SCH_1):PAGE268
     2    GND @BASEBOARD_FAB2_LIB.BASEBOARD_FAB2(SCH_1):GND     I9 @BASEBOARD_FAB2_LIB.BASEBOARD_FAB2(SCH_1):PAGE268

C25W97 CAP_A_0402V-0.1UF,16V,10%,X7R,A
     1 P3V3_STBY @BASEBOARD_FAB2_LIB.BASEBOARD_FAB2(SCH_1):P3V3_STBY     I4 @BASEBOARD_FAB2_LIB.BASEBOARD_FAB2(SCH_1):PAGE268
     2    GND @BASEBOARD_FAB2_LIB.BASEBOARD_FAB2(SCH_1):GND     I4 @BASEBOARD_FAB2_LIB.BASEBOARD_FAB2(SCH_1):PAGE268

C25W98 CAP_0402-1.0UF,16V,10%,X6S,D97A
     1 P3V3_STBY @BASEBOARD_FAB2_LIB.BASEBOARD_FAB2(SCH_1):P3V3_STBY    I40 @BASEBOARD_FAB2_LIB.BASEBOARD_FAB2(SCH_1):PAGE268
     2    GND @BASEBOARD_FAB2_LIB.BASEBOARD_FAB2(SCH_1):GND    I40 @BASEBOARD_FAB2_LIB.BASEBOARD_FAB2(SCH_1):PAGE268

C25W99 CAP_A_0402V-0.1UF,16V,10%,X7R,A
     1 P3V3_STBY @BASEBOARD_FAB2_LIB.BASEBOARD_FAB2(SCH_1):P3V3_STBY    I62 @BASEBOARD_FAB2_LIB.BASEBOARD_FAB2(SCH_1):PAGE269
     2    GND @BASEBOARD_FAB2_LIB.BASEBOARD_FAB2(SCH_1):GND    I62 @BASEBOARD_FAB2_LIB.BASEBOARD_FAB2(SCH_1):PAGE269

C25W100 CAP_A_0402V-0.1UF,16V,10%,X7R,A
     1 P3V3_STBY @BASEBOARD_FAB2_LIB.BASEBOARD_FAB2(SCH_1):P3V3_STBY    I60 @BASEBOARD_FAB2_LIB.BASEBOARD_FAB2(SCH_1):PAGE268
     2    GND @BASEBOARD_FAB2_LIB.BASEBOARD_FAB2(SCH_1):GND    I60 @BASEBOARD_FAB2_LIB.BASEBOARD_FAB2(SCH_1):PAGE268

C25W101 CAP_A_0402V-0.1UF,16V,10%,X7R,A
     1 P3V3_STBY @BASEBOARD_FAB2_LIB.BASEBOARD_FAB2(SCH_1):P3V3_STBY    I79 @BASEBOARD_FAB2_LIB.BASEBOARD_FAB2(SCH_1):PAGE269
     2    GND @BASEBOARD_FAB2_LIB.BASEBOARD_FAB2(SCH_1):GND    I79 @BASEBOARD_FAB2_LIB.BASEBOARD_FAB2(SCH_1):PAGE269

C30W1 CAP_A_0402V-0.1UF,16V,10%,X7R,A
     1 USB3_P01_TXN @BASEBOARD_FAB2_LIB.BASEBOARD_FAB2(SCH_1):USB3_P01_TXN    I20 @BASEBOARD_FAB2_LIB.BASEBOARD_FAB2(SCH_1):PAGE253
     2 USB3_P01_C_TXN @BASEBOARD_FAB2_LIB.BASEBOARD_FAB2(SCH_1):USB3_P01_C_TXN    I20 @BASEBOARD_FAB2_LIB.BASEBOARD_FAB2(SCH_1):PAGE253

C30W2 CAP_A_0402V-0.1UF,16V,10%,X7R,A
     1 USB3_P01_TXP @BASEBOARD_FAB2_LIB.BASEBOARD_FAB2(SCH_1):USB3_P01_TXP    I19 @BASEBOARD_FAB2_LIB.BASEBOARD_FAB2(SCH_1):PAGE253
     2 USB3_P01_C_TXP @BASEBOARD_FAB2_LIB.BASEBOARD_FAB2(SCH_1):USB3_P01_C_TXP    I19 @BASEBOARD_FAB2_LIB.BASEBOARD_FAB2(SCH_1):PAGE253

C30W3 SC22U16V5MX-4-GP_SMD-BCG5-SC22A
     1 P5V_STBY_USBC @BASEBOARD_FAB2_LIB.BASEBOARD_FAB2(SCH_1):P5V_STBY_USBC    I35 @BASEBOARD_FAB2_LIB.BASEBOARD_FAB2(SCH_1):PAGE253
     2    GND @BASEBOARD_FAB2_LIB.BASEBOARD_FAB2(SCH_1):GND    I35 @BASEBOARD_FAB2_LIB.BASEBOARD_FAB2(SCH_1):PAGE253

C30W4 SC22U16V5MX-4-GP_SMD-BCG5-SC22A
     1 P5V_STBY_USBC @BASEBOARD_FAB2_LIB.BASEBOARD_FAB2(SCH_1):P5V_STBY_USBC    I36 @BASEBOARD_FAB2_LIB.BASEBOARD_FAB2(SCH_1):PAGE253
     2    GND @BASEBOARD_FAB2_LIB.BASEBOARD_FAB2(SCH_1):GND    I36 @BASEBOARD_FAB2_LIB.BASEBOARD_FAB2(SCH_1):PAGE253

C30W5 SC22U16V5MX-4-GP_SMD-BCG5-SC22A
     1 P5V_STBY_USBC @BASEBOARD_FAB2_LIB.BASEBOARD_FAB2(SCH_1):P5V_STBY_USBC    I38 @BASEBOARD_FAB2_LIB.BASEBOARD_FAB2(SCH_1):PAGE253
     2    GND @BASEBOARD_FAB2_LIB.BASEBOARD_FAB2(SCH_1):GND    I38 @BASEBOARD_FAB2_LIB.BASEBOARD_FAB2(SCH_1):PAGE253

C30W6 SC22U16V5MX-4-GP_SMD-BCG5-SC22A
     1 P5V_STBY_USBC @BASEBOARD_FAB2_LIB.BASEBOARD_FAB2(SCH_1):P5V_STBY_USBC    I37 @BASEBOARD_FAB2_LIB.BASEBOARD_FAB2(SCH_1):PAGE253
     2    GND @BASEBOARD_FAB2_LIB.BASEBOARD_FAB2(SCH_1):GND    I37 @BASEBOARD_FAB2_LIB.BASEBOARD_FAB2(SCH_1):PAGE253

C30W7 SC22U16V5MX-4-GP_SMD-BCG5-SC22A
     1 P5V_STBY_USBC @BASEBOARD_FAB2_LIB.BASEBOARD_FAB2(SCH_1):P5V_STBY_USBC    I42 @BASEBOARD_FAB2_LIB.BASEBOARD_FAB2(SCH_1):PAGE253
     2    GND @BASEBOARD_FAB2_LIB.BASEBOARD_FAB2(SCH_1):GND    I42 @BASEBOARD_FAB2_LIB.BASEBOARD_FAB2(SCH_1):PAGE253

C30W8 SC22U16V5MX-4-GP_SMD-BCG5-SC22A
     1 P5V_STBY_USBC @BASEBOARD_FAB2_LIB.BASEBOARD_FAB2(SCH_1):P5V_STBY_USBC    I41 @BASEBOARD_FAB2_LIB.BASEBOARD_FAB2(SCH_1):PAGE253
     2    GND @BASEBOARD_FAB2_LIB.BASEBOARD_FAB2(SCH_1):GND    I41 @BASEBOARD_FAB2_LIB.BASEBOARD_FAB2(SCH_1):PAGE253

C30W9 SC22U16V5MX-4-GP_SMD-BCG5-SC22A
     1 P5V_STBY_USBC @BASEBOARD_FAB2_LIB.BASEBOARD_FAB2(SCH_1):P5V_STBY_USBC    I40 @BASEBOARD_FAB2_LIB.BASEBOARD_FAB2(SCH_1):PAGE253
     2    GND @BASEBOARD_FAB2_LIB.BASEBOARD_FAB2(SCH_1):GND    I40 @BASEBOARD_FAB2_LIB.BASEBOARD_FAB2(SCH_1):PAGE253

C32W1 CAP_A_0402V-0.1UF,16V,10%,X7R,A
     1 P1V8_M2 @BASEBOARD_FAB2_LIB.BASEBOARD_FAB2(SCH_1):P1V8_M2   I188 @BASEBOARD_FAB2_LIB.BASEBOARD_FAB2(SCH_1):PAGE185
     2    GND @BASEBOARD_FAB2_LIB.BASEBOARD_FAB2(SCH_1):GND   I188 @BASEBOARD_FAB2_LIB.BASEBOARD_FAB2(SCH_1):PAGE185

C32W2 CAP_A_0402V-0.1UF,16V,10%,X7R,A
     1 P3V3_STBY @BASEBOARD_FAB2_LIB.BASEBOARD_FAB2(SCH_1):P3V3_STBY   I193 @BASEBOARD_FAB2_LIB.BASEBOARD_FAB2(SCH_1):PAGE185
     2    GND @BASEBOARD_FAB2_LIB.BASEBOARD_FAB2(SCH_1):GND   I193 @BASEBOARD_FAB2_LIB.BASEBOARD_FAB2(SCH_1):PAGE185

C32W3 CAP_A_0402V-0.1UF,16V,10%,X7R,A
     1 P1V8_M2 @BASEBOARD_FAB2_LIB.BASEBOARD_FAB2(SCH_1):P1V8_M2   I190 @BASEBOARD_FAB2_LIB.BASEBOARD_FAB2(SCH_1):PAGE185
     2    GND @BASEBOARD_FAB2_LIB.BASEBOARD_FAB2(SCH_1):GND   I190 @BASEBOARD_FAB2_LIB.BASEBOARD_FAB2(SCH_1):PAGE185

C32W4 CAP_A_0402V-0.1UF,16V,10%,X7R,A
     1 P3V3_STBY @BASEBOARD_FAB2_LIB.BASEBOARD_FAB2(SCH_1):P3V3_STBY   I196 @BASEBOARD_FAB2_LIB.BASEBOARD_FAB2(SCH_1):PAGE185
     2    GND @BASEBOARD_FAB2_LIB.BASEBOARD_FAB2(SCH_1):GND   I196 @BASEBOARD_FAB2_LIB.BASEBOARD_FAB2(SCH_1):PAGE185

C32W5 CAP_0402-1.0UF,16V,10%,X6S,D97A
     1 P1V8_M2 @BASEBOARD_FAB2_LIB.BASEBOARD_FAB2(SCH_1):P1V8_M2   I217 @BASEBOARD_FAB2_LIB.BASEBOARD_FAB2(SCH_1):PAGE185
     2    GND @BASEBOARD_FAB2_LIB.BASEBOARD_FAB2(SCH_1):GND   I217 @BASEBOARD_FAB2_LIB.BASEBOARD_FAB2(SCH_1):PAGE185

C826 CAP_0402-0.22UF,16V,10%,X7R,A3A
     1 P3E_CPU0_PE1_PCH_TXN<14> @BASEBOARD_FAB2_LIB.BASEBOARD_FAB2(SCH_1):P3E_CPU0_PE1_PCH_TXN(14)    I24 @BASEBOARD_FAB2_LIB.BASEBOARD_FAB2(SCH_1):PAGE244
     2 P3E_CPU0_PE1_PCH_CON_TXN<14> @BASEBOARD_FAB2_LIB.BASEBOARD_FAB2(SCH_1):P3E_CPU0_PE1_PCH_CON_TXN(14)    I24 @BASEBOARD_FAB2_LIB.BASEBOARD_FAB2(SCH_1):PAGE244

C827 CAP_0402-0.22UF,16V,10%,X7R,A3A
     1 P3E_CPU0_PE1_PCH_TXP<14> @BASEBOARD_FAB2_LIB.BASEBOARD_FAB2(SCH_1):P3E_CPU0_PE1_PCH_TXP(14)    I12 @BASEBOARD_FAB2_LIB.BASEBOARD_FAB2(SCH_1):PAGE244
     2 P3E_CPU0_PE1_PCH_CON_TXP<14> @BASEBOARD_FAB2_LIB.BASEBOARD_FAB2(SCH_1):P3E_CPU0_PE1_PCH_CON_TXP(14)    I12 @BASEBOARD_FAB2_LIB.BASEBOARD_FAB2(SCH_1):PAGE244

C828 CAP_0402-0.22UF,16V,10%,X7R,A3A
     1 P3E_CPU0_PE1_PCH_TXN<13> @BASEBOARD_FAB2_LIB.BASEBOARD_FAB2(SCH_1):P3E_CPU0_PE1_PCH_TXN(13)    I28 @BASEBOARD_FAB2_LIB.BASEBOARD_FAB2(SCH_1):PAGE244
     2 P3E_CPU0_PE1_PCH_CON_TXN<13> @BASEBOARD_FAB2_LIB.BASEBOARD_FAB2(SCH_1):P3E_CPU0_PE1_PCH_CON_TXN(13)    I28 @BASEBOARD_FAB2_LIB.BASEBOARD_FAB2(SCH_1):PAGE244

C829 CAP_0402-0.22UF,16V,10%,X7R,A3A
     1 P3E_CPU0_PE1_PCH_TXP<13> @BASEBOARD_FAB2_LIB.BASEBOARD_FAB2(SCH_1):P3E_CPU0_PE1_PCH_TXP(13)     I5 @BASEBOARD_FAB2_LIB.BASEBOARD_FAB2(SCH_1):PAGE244
     2 P3E_CPU0_PE1_PCH_CON_TXP<13> @BASEBOARD_FAB2_LIB.BASEBOARD_FAB2(SCH_1):P3E_CPU0_PE1_PCH_CON_TXP(13)     I5 @BASEBOARD_FAB2_LIB.BASEBOARD_FAB2(SCH_1):PAGE244

C830 CAP_0402-0.22UF,16V,10%,X7R,A3A
     1 P3E_CPU0_PE1_PCH_TXN<15> @BASEBOARD_FAB2_LIB.BASEBOARD_FAB2(SCH_1):P3E_CPU0_PE1_PCH_TXN(15)    I23 @BASEBOARD_FAB2_LIB.BASEBOARD_FAB2(SCH_1):PAGE244
     2 P3E_CPU0_PE1_PCH_CON_TXN<15> @BASEBOARD_FAB2_LIB.BASEBOARD_FAB2(SCH_1):P3E_CPU0_PE1_PCH_CON_TXN(15)    I23 @BASEBOARD_FAB2_LIB.BASEBOARD_FAB2(SCH_1):PAGE244

C831 CAP_0402-0.22UF,16V,10%,X7R,A3A
     1 P3E_CPU0_PE1_PCH_TXP<15> @BASEBOARD_FAB2_LIB.BASEBOARD_FAB2(SCH_1):P3E_CPU0_PE1_PCH_TXP(15)     I2 @BASEBOARD_FAB2_LIB.BASEBOARD_FAB2(SCH_1):PAGE244
     2 P3E_CPU0_PE1_PCH_CON_TXP<15> @BASEBOARD_FAB2_LIB.BASEBOARD_FAB2(SCH_1):P3E_CPU0_PE1_PCH_CON_TXP(15)     I2 @BASEBOARD_FAB2_LIB.BASEBOARD_FAB2(SCH_1):PAGE244

C832 CAP_0402-0.22UF,16V,10%,X7R,A3A
     1 P3E_CPU0_PE1_PCH_TXN<11> @BASEBOARD_FAB2_LIB.BASEBOARD_FAB2(SCH_1):P3E_CPU0_PE1_PCH_TXN(11)    I30 @BASEBOARD_FAB2_LIB.BASEBOARD_FAB2(SCH_1):PAGE244
     2 P3E_CPU0_PE1_PCH_CON_TXN<11> @BASEBOARD_FAB2_LIB.BASEBOARD_FAB2(SCH_1):P3E_CPU0_PE1_PCH_CON_TXN(11)    I30 @BASEBOARD_FAB2_LIB.BASEBOARD_FAB2(SCH_1):PAGE244

C833 CAP_0402-0.22UF,16V,10%,X7R,A3A
     1 P3E_CPU0_PE1_PCH_TXP<11> @BASEBOARD_FAB2_LIB.BASEBOARD_FAB2(SCH_1):P3E_CPU0_PE1_PCH_TXP(11)     I8 @BASEBOARD_FAB2_LIB.BASEBOARD_FAB2(SCH_1):PAGE244
     2 P3E_CPU0_PE1_PCH_CON_TXP<11> @BASEBOARD_FAB2_LIB.BASEBOARD_FAB2(SCH_1):P3E_CPU0_PE1_PCH_CON_TXP(11)     I8 @BASEBOARD_FAB2_LIB.BASEBOARD_FAB2(SCH_1):PAGE244

C834 CAP_0402-0.22UF,16V,10%,X7R,A3A
     1 P3E_CPU0_PE1_PCH_TXN<10> @BASEBOARD_FAB2_LIB.BASEBOARD_FAB2(SCH_1):P3E_CPU0_PE1_PCH_TXN(10)    I50 @BASEBOARD_FAB2_LIB.BASEBOARD_FAB2(SCH_1):PAGE244
     2 P3E_CPU0_PE1_PCH_CON_TXN<10> @BASEBOARD_FAB2_LIB.BASEBOARD_FAB2(SCH_1):P3E_CPU0_PE1_PCH_CON_TXN(10)    I50 @BASEBOARD_FAB2_LIB.BASEBOARD_FAB2(SCH_1):PAGE244

C835 CAP_0402-0.22UF,16V,10%,X7R,A3A
     1 P3E_CPU0_PE1_PCH_TXP<10> @BASEBOARD_FAB2_LIB.BASEBOARD_FAB2(SCH_1):P3E_CPU0_PE1_PCH_TXP(10)    I41 @BASEBOARD_FAB2_LIB.BASEBOARD_FAB2(SCH_1):PAGE244
     2 P3E_CPU0_PE1_PCH_CON_TXP<10> @BASEBOARD_FAB2_LIB.BASEBOARD_FAB2(SCH_1):P3E_CPU0_PE1_PCH_CON_TXP(10)    I41 @BASEBOARD_FAB2_LIB.BASEBOARD_FAB2(SCH_1):PAGE244

C840 CAP_0402-0.22UF,16V,10%,X7R,A3A
     1 P3E_CPU0_PE1_PCH_TXN<12> @BASEBOARD_FAB2_LIB.BASEBOARD_FAB2(SCH_1):P3E_CPU0_PE1_PCH_TXN(12)    I29 @BASEBOARD_FAB2_LIB.BASEBOARD_FAB2(SCH_1):PAGE244
     2 P3E_CPU0_PE1_PCH_CON_TXN<12> @BASEBOARD_FAB2_LIB.BASEBOARD_FAB2(SCH_1):P3E_CPU0_PE1_PCH_CON_TXN(12)    I29 @BASEBOARD_FAB2_LIB.BASEBOARD_FAB2(SCH_1):PAGE244

C841 CAP_0402-0.22UF,16V,10%,X7R,A3A
     1 P3E_CPU0_PE1_PCH_TXP<12> @BASEBOARD_FAB2_LIB.BASEBOARD_FAB2(SCH_1):P3E_CPU0_PE1_PCH_TXP(12)    I17 @BASEBOARD_FAB2_LIB.BASEBOARD_FAB2(SCH_1):PAGE244
     2 P3E_CPU0_PE1_PCH_CON_TXP<12> @BASEBOARD_FAB2_LIB.BASEBOARD_FAB2(SCH_1):P3E_CPU0_PE1_PCH_CON_TXP(12)    I17 @BASEBOARD_FAB2_LIB.BASEBOARD_FAB2(SCH_1):PAGE244

C842 CAP_0402-0.22UF,16V,10%,X7R,A3A
     1 P3E_CPU0_PE1_PCH_TXN<8> @BASEBOARD_FAB2_LIB.BASEBOARD_FAB2(SCH_1):P3E_CPU0_PE1_PCH_TXN(8)    I52 @BASEBOARD_FAB2_LIB.BASEBOARD_FAB2(SCH_1):PAGE244
     2 P3E_CPU0_PE1_PCH_CON_TXN<8> @BASEBOARD_FAB2_LIB.BASEBOARD_FAB2(SCH_1):P3E_CPU0_PE1_PCH_CON_TXN(8)    I52 @BASEBOARD_FAB2_LIB.BASEBOARD_FAB2(SCH_1):PAGE244

C843 CAP_0402-0.22UF,16V,10%,X7R,A3A
     1 P3E_CPU0_PE1_PCH_TXP<8> @BASEBOARD_FAB2_LIB.BASEBOARD_FAB2(SCH_1):P3E_CPU0_PE1_PCH_TXP(8)    I47 @BASEBOARD_FAB2_LIB.BASEBOARD_FAB2(SCH_1):PAGE244
     2 P3E_CPU0_PE1_PCH_CON_TXP<8> @BASEBOARD_FAB2_LIB.BASEBOARD_FAB2(SCH_1):P3E_CPU0_PE1_PCH_CON_TXP(8)    I47 @BASEBOARD_FAB2_LIB.BASEBOARD_FAB2(SCH_1):PAGE244

C844 CAP_0402-0.22UF,16V,10%,X7R,A3A
     1 P3E_CPU0_PE1_PCH_TXN<9> @BASEBOARD_FAB2_LIB.BASEBOARD_FAB2(SCH_1):P3E_CPU0_PE1_PCH_TXN(9)    I51 @BASEBOARD_FAB2_LIB.BASEBOARD_FAB2(SCH_1):PAGE244
     2 P3E_CPU0_PE1_PCH_CON_TXN<9> @BASEBOARD_FAB2_LIB.BASEBOARD_FAB2(SCH_1):P3E_CPU0_PE1_PCH_CON_TXN(9)    I51 @BASEBOARD_FAB2_LIB.BASEBOARD_FAB2(SCH_1):PAGE244

C845 CAP_0402-0.22UF,16V,10%,X7R,A3A
     1 P3E_CPU0_PE1_PCH_TXP<9> @BASEBOARD_FAB2_LIB.BASEBOARD_FAB2(SCH_1):P3E_CPU0_PE1_PCH_TXP(9)    I35 @BASEBOARD_FAB2_LIB.BASEBOARD_FAB2(SCH_1):PAGE244
     2 P3E_CPU0_PE1_PCH_CON_TXP<9> @BASEBOARD_FAB2_LIB.BASEBOARD_FAB2(SCH_1):P3E_CPU0_PE1_PCH_CON_TXP(9)    I35 @BASEBOARD_FAB2_LIB.BASEBOARD_FAB2(SCH_1):PAGE244

 CF1 SC22P50V2JN-4GP_SMD-BCG-SC22P5A
     1 VR_PVCCIN_CPU0_AIREF1 @BASEBOARD_FAB2_LIB.BASEBOARD_FAB2(SCH_1):VR_PVCCIN_CPU0_AIREF1   I168 @BASEBOARD_FAB2_LIB.BASEBOARD_FAB2(SCH_1):PAGE201
     2 ISENSE_PVCCIN_CPU0_PH1_IMON @BASEBOARD_FAB2_LIB.BASEBOARD_FAB2(SCH_1):ISENSE_PVCCIN_CPU0_PH1_IMON   I168 @BASEBOARD_FAB2_LIB.BASEBOARD_FAB2(SCH_1):PAGE201

 CF2 SC22P50V2JN-4GP_SMD-BCG-SC22P5A
     1 VR_PVCCIN_CPU0_AIREF2 @BASEBOARD_FAB2_LIB.BASEBOARD_FAB2(SCH_1):VR_PVCCIN_CPU0_AIREF2   I169 @BASEBOARD_FAB2_LIB.BASEBOARD_FAB2(SCH_1):PAGE201
     2 ISENSE_PVCCIN_CPU0_PH2_IMON @BASEBOARD_FAB2_LIB.BASEBOARD_FAB2(SCH_1):ISENSE_PVCCIN_CPU0_PH2_IMON   I169 @BASEBOARD_FAB2_LIB.BASEBOARD_FAB2(SCH_1):PAGE201

 CF3 SC22P50V2JN-4GP_SMD-BCG-SC22P5A
     1 VR_PVCCIN_CPU0_AIREF3 @BASEBOARD_FAB2_LIB.BASEBOARD_FAB2(SCH_1):VR_PVCCIN_CPU0_AIREF3   I170 @BASEBOARD_FAB2_LIB.BASEBOARD_FAB2(SCH_1):PAGE201
     2 ISENSE_PVCCIN_CPU0_PH3_IMON @BASEBOARD_FAB2_LIB.BASEBOARD_FAB2(SCH_1):ISENSE_PVCCIN_CPU0_PH3_IMON   I170 @BASEBOARD_FAB2_LIB.BASEBOARD_FAB2(SCH_1):PAGE201

 CF4 SC22P50V2JN-4GP_SMD-BCG-SC22P5A
     1 VR_PVCCIN_CPU0_AIREF4 @BASEBOARD_FAB2_LIB.BASEBOARD_FAB2(SCH_1):VR_PVCCIN_CPU0_AIREF4   I171 @BASEBOARD_FAB2_LIB.BASEBOARD_FAB2(SCH_1):PAGE201
     2 ISENSE_PVCCIN_CPU0_PH4_IMON @BASEBOARD_FAB2_LIB.BASEBOARD_FAB2(SCH_1):ISENSE_PVCCIN_CPU0_PH4_IMON   I171 @BASEBOARD_FAB2_LIB.BASEBOARD_FAB2(SCH_1):PAGE201

 CF5 SC22P50V2JN-4GP_SMD-BCG-SC22P5A
     1 VR_PVCCIN_CPU0_AIREF5 @BASEBOARD_FAB2_LIB.BASEBOARD_FAB2(SCH_1):VR_PVCCIN_CPU0_AIREF5   I172 @BASEBOARD_FAB2_LIB.BASEBOARD_FAB2(SCH_1):PAGE201
     2 ISENSE_PVCCIN_CPU0_PH5_IMON @BASEBOARD_FAB2_LIB.BASEBOARD_FAB2(SCH_1):ISENSE_PVCCIN_CPU0_PH5_IMON   I172 @BASEBOARD_FAB2_LIB.BASEBOARD_FAB2(SCH_1):PAGE201

 CF6 SC22P50V2JN-4GP_SMD-BCG-SC22P5A
     1 VR_PVSA_CPU0_BIREF1 @BASEBOARD_FAB2_LIB.BASEBOARD_FAB2(SCH_1):VR_PVSA_CPU0_BIREF1   I173 @BASEBOARD_FAB2_LIB.BASEBOARD_FAB2(SCH_1):PAGE201
     2 ISENSE_PVSA_CPU0_IMON @BASEBOARD_FAB2_LIB.BASEBOARD_FAB2(SCH_1):ISENSE_PVSA_CPU0_IMON   I173 @BASEBOARD_FAB2_LIB.BASEBOARD_FAB2(SCH_1):PAGE201

 CF7 SC22P50V2JN-4GP_SMD-BCG-SC22P5A
     1 VR_PVCCIN_CPU1_AIREF1 @BASEBOARD_FAB2_LIB.BASEBOARD_FAB2(SCH_1):VR_PVCCIN_CPU1_AIREF1   I137 @BASEBOARD_FAB2_LIB.BASEBOARD_FAB2(SCH_1):PAGE206
     2 ISENSE_PVCCIN_CPU1_PH1_IMON @BASEBOARD_FAB2_LIB.BASEBOARD_FAB2(SCH_1):ISENSE_PVCCIN_CPU1_PH1_IMON   I137 @BASEBOARD_FAB2_LIB.BASEBOARD_FAB2(SCH_1):PAGE206

 CF8 SC22P50V2JN-4GP_SMD-BCG-SC22P5A
     1 VR_PVCCIN_CPU1_AIREF2 @BASEBOARD_FAB2_LIB.BASEBOARD_FAB2(SCH_1):VR_PVCCIN_CPU1_AIREF2   I138 @BASEBOARD_FAB2_LIB.BASEBOARD_FAB2(SCH_1):PAGE206
     2 ISENSE_PVCCIN_CPU1_PH2_IMON @BASEBOARD_FAB2_LIB.BASEBOARD_FAB2(SCH_1):ISENSE_PVCCIN_CPU1_PH2_IMON   I138 @BASEBOARD_FAB2_LIB.BASEBOARD_FAB2(SCH_1):PAGE206

 CF9 SC22P50V2JN-4GP_SMD-BCG-SC22P5A
     1 VR_PVCCIN_CPU1_AIREF3 @BASEBOARD_FAB2_LIB.BASEBOARD_FAB2(SCH_1):VR_PVCCIN_CPU1_AIREF3   I139 @BASEBOARD_FAB2_LIB.BASEBOARD_FAB2(SCH_1):PAGE206
     2 ISENSE_PVCCIN_CPU1_PH3_IMON @BASEBOARD_FAB2_LIB.BASEBOARD_FAB2(SCH_1):ISENSE_PVCCIN_CPU1_PH3_IMON   I139 @BASEBOARD_FAB2_LIB.BASEBOARD_FAB2(SCH_1):PAGE206

CF10 SC22P50V2JN-4GP_SMD-BCG-SC22P5A
     1 VR_PVCCIN_CPU1_AIREF4 @BASEBOARD_FAB2_LIB.BASEBOARD_FAB2(SCH_1):VR_PVCCIN_CPU1_AIREF4   I140 @BASEBOARD_FAB2_LIB.BASEBOARD_FAB2(SCH_1):PAGE206
     2 ISENSE_PVCCIN_CPU1_PH4_IMON @BASEBOARD_FAB2_LIB.BASEBOARD_FAB2(SCH_1):ISENSE_PVCCIN_CPU1_PH4_IMON   I140 @BASEBOARD_FAB2_LIB.BASEBOARD_FAB2(SCH_1):PAGE206

CF11 SC22P50V2JN-4GP_SMD-BCG-SC22P5A
     1 VR_PVCCIN_CPU1_AIREF5 @BASEBOARD_FAB2_LIB.BASEBOARD_FAB2(SCH_1):VR_PVCCIN_CPU1_AIREF5   I141 @BASEBOARD_FAB2_LIB.BASEBOARD_FAB2(SCH_1):PAGE206
     2 ISENSE_PVCCIN_CPU1_PH5_IMON @BASEBOARD_FAB2_LIB.BASEBOARD_FAB2(SCH_1):ISENSE_PVCCIN_CPU1_PH5_IMON   I141 @BASEBOARD_FAB2_LIB.BASEBOARD_FAB2(SCH_1):PAGE206

CF12 SC22P50V2JN-4GP_SMD-BCG-SC22P5A
     1 VR_PVSA_CPU1_BIREF1 @BASEBOARD_FAB2_LIB.BASEBOARD_FAB2(SCH_1):VR_PVSA_CPU1_BIREF1   I142 @BASEBOARD_FAB2_LIB.BASEBOARD_FAB2(SCH_1):PAGE206
     2 ISENSE_PVSA_CPU1_IMON @BASEBOARD_FAB2_LIB.BASEBOARD_FAB2(SCH_1):ISENSE_PVSA_CPU1_IMON   I142 @BASEBOARD_FAB2_LIB.BASEBOARD_FAB2(SCH_1):PAGE206

CF13 SC22P50V2JN-4GP_SMD-BCG-SC22P5A
     1 VR_PVCCIO_CPU0_AIREF1 @BASEBOARD_FAB2_LIB.BASEBOARD_FAB2(SCH_1):VR_PVCCIO_CPU0_AIREF1    I95 @BASEBOARD_FAB2_LIB.BASEBOARD_FAB2(SCH_1):PAGE211
     2 ISENSE_PVCCIO_CPU0_PH1_IMON @BASEBOARD_FAB2_LIB.BASEBOARD_FAB2(SCH_1):ISENSE_PVCCIO_CPU0_PH1_IMON    I95 @BASEBOARD_FAB2_LIB.BASEBOARD_FAB2(SCH_1):PAGE211

CF14 SC22P50V2JN-4GP_SMD-BCG-SC22P5A
     1 VR_PVCCIO_CPU1_AIREF1 @BASEBOARD_FAB2_LIB.BASEBOARD_FAB2(SCH_1):VR_PVCCIO_CPU1_AIREF1    I98 @BASEBOARD_FAB2_LIB.BASEBOARD_FAB2(SCH_1):PAGE213
     2 ISENSE_PVCCIO_CPU1_PH1_IMON @BASEBOARD_FAB2_LIB.BASEBOARD_FAB2(SCH_1):ISENSE_PVCCIO_CPU1_PH1_IMON    I98 @BASEBOARD_FAB2_LIB.BASEBOARD_FAB2(SCH_1):PAGE213

CF15 SC22P50V2JN-4GP_SMD-BCG-SC22P5A
     1 VR_PVDDQ_ABC_AIREF1 @BASEBOARD_FAB2_LIB.BASEBOARD_FAB2(SCH_1):VR_PVDDQ_ABC_AIREF1    I16 @BASEBOARD_FAB2_LIB.BASEBOARD_FAB2(SCH_1):PAGE215
     2 ISENSE_PVDDQ_ABC_PH1_IMON @BASEBOARD_FAB2_LIB.BASEBOARD_FAB2(SCH_1):ISENSE_PVDDQ_ABC_PH1_IMON    I16 @BASEBOARD_FAB2_LIB.BASEBOARD_FAB2(SCH_1):PAGE215

CF16 SC22P50V2JN-4GP_SMD-BCG-SC22P5A
     1 VR_PVDDQ_ABC_AIREF2 @BASEBOARD_FAB2_LIB.BASEBOARD_FAB2(SCH_1):VR_PVDDQ_ABC_AIREF2    I26 @BASEBOARD_FAB2_LIB.BASEBOARD_FAB2(SCH_1):PAGE215
     2 ISENSE_PVDDQ_ABC_PH2_IMON @BASEBOARD_FAB2_LIB.BASEBOARD_FAB2(SCH_1):ISENSE_PVDDQ_ABC_PH2_IMON    I26 @BASEBOARD_FAB2_LIB.BASEBOARD_FAB2(SCH_1):PAGE215

CF17 SC22P50V2JN-4GP_SMD-BCG-SC22P5A
     1 VR_PVDDQ_DEF_AIREF1 @BASEBOARD_FAB2_LIB.BASEBOARD_FAB2(SCH_1):VR_PVDDQ_DEF_AIREF1    I17 @BASEBOARD_FAB2_LIB.BASEBOARD_FAB2(SCH_1):PAGE218
     2 ISENSE_PVDDQ_DEF_PH1_IMON @BASEBOARD_FAB2_LIB.BASEBOARD_FAB2(SCH_1):ISENSE_PVDDQ_DEF_PH1_IMON    I17 @BASEBOARD_FAB2_LIB.BASEBOARD_FAB2(SCH_1):PAGE218

CF18 SC22P50V2JN-4GP_SMD-BCG-SC22P5A
     1 VR_PVDDQ_DEF_AIREF2 @BASEBOARD_FAB2_LIB.BASEBOARD_FAB2(SCH_1):VR_PVDDQ_DEF_AIREF2    I20 @BASEBOARD_FAB2_LIB.BASEBOARD_FAB2(SCH_1):PAGE218
     2 ISENSE_PVDDQ_DEF_PH2_IMON @BASEBOARD_FAB2_LIB.BASEBOARD_FAB2(SCH_1):ISENSE_PVDDQ_DEF_PH2_IMON    I20 @BASEBOARD_FAB2_LIB.BASEBOARD_FAB2(SCH_1):PAGE218

CF19 SC22P50V2JN-4GP_SMD-BCG-SC22P5A
     1 VR_PVDDQ_GHJ_AIREF1 @BASEBOARD_FAB2_LIB.BASEBOARD_FAB2(SCH_1):VR_PVDDQ_GHJ_AIREF1    I15 @BASEBOARD_FAB2_LIB.BASEBOARD_FAB2(SCH_1):PAGE223
     2 ISENSE_PVDDQ_GHJ_PH1_IMON @BASEBOARD_FAB2_LIB.BASEBOARD_FAB2(SCH_1):ISENSE_PVDDQ_GHJ_PH1_IMON    I15 @BASEBOARD_FAB2_LIB.BASEBOARD_FAB2(SCH_1):PAGE223

CF20 SC22P50V2JN-4GP_SMD-BCG-SC22P5A
     1 VR_PVDDQ_GHJ_AIREF2 @BASEBOARD_FAB2_LIB.BASEBOARD_FAB2(SCH_1):VR_PVDDQ_GHJ_AIREF2    I17 @BASEBOARD_FAB2_LIB.BASEBOARD_FAB2(SCH_1):PAGE223
     2 ISENSE_PVDDQ_GHJ_PH2_IMON @BASEBOARD_FAB2_LIB.BASEBOARD_FAB2(SCH_1):ISENSE_PVDDQ_GHJ_PH2_IMON    I17 @BASEBOARD_FAB2_LIB.BASEBOARD_FAB2(SCH_1):PAGE223

CF21 SC22P50V2JN-4GP_SMD-BCG-SC22P5A
     1 VR_PVDDQ_KLM_AIREF1 @BASEBOARD_FAB2_LIB.BASEBOARD_FAB2(SCH_1):VR_PVDDQ_KLM_AIREF1    I15 @BASEBOARD_FAB2_LIB.BASEBOARD_FAB2(SCH_1):PAGE226
     2 ISENSE_PVDDQ_KLM_PH1_IMON @BASEBOARD_FAB2_LIB.BASEBOARD_FAB2(SCH_1):ISENSE_PVDDQ_KLM_PH1_IMON    I15 @BASEBOARD_FAB2_LIB.BASEBOARD_FAB2(SCH_1):PAGE226

CF22 SC22P50V2JN-4GP_SMD-BCG-SC22P5A
     1 VR_PVDDQ_KLM_AIREF2 @BASEBOARD_FAB2_LIB.BASEBOARD_FAB2(SCH_1):VR_PVDDQ_KLM_AIREF2    I17 @BASEBOARD_FAB2_LIB.BASEBOARD_FAB2(SCH_1):PAGE226
     2 ISENSE_PVDDQ_KLM_PH2_IMON @BASEBOARD_FAB2_LIB.BASEBOARD_FAB2(SCH_1):ISENSE_PVDDQ_KLM_PH2_IMON    I17 @BASEBOARD_FAB2_LIB.BASEBOARD_FAB2(SCH_1):PAGE226

CF23 SC22P50V2JN-4GP_SMD-BCG-SC22P5A
     1 VR_PVNN_PCH_AIREF1 @BASEBOARD_FAB2_LIB.BASEBOARD_FAB2(SCH_1):VR_PVNN_PCH_AIREF1   I239 @BASEBOARD_FAB2_LIB.BASEBOARD_FAB2(SCH_1):PAGE235
     2 ISENSE_PVNN_PCH_PH1_IMON @BASEBOARD_FAB2_LIB.BASEBOARD_FAB2(SCH_1):ISENSE_PVNN_PCH_PH1_IMON   I239 @BASEBOARD_FAB2_LIB.BASEBOARD_FAB2(SCH_1):PAGE235

CF24 SC22P50V2JN-4GP_SMD-BCG-SC22P5A
     1 VR_P1V05_PCH_BIREF1 @BASEBOARD_FAB2_LIB.BASEBOARD_FAB2(SCH_1):VR_P1V05_PCH_BIREF1   I240 @BASEBOARD_FAB2_LIB.BASEBOARD_FAB2(SCH_1):PAGE235
     2 ISENSE_P1V05_PCH_STBY_PH1_IMON @BASEBOARD_FAB2_LIB.BASEBOARD_FAB2(SCH_1):ISENSE_P1V05_PCH_STBY_PH1_IMON   I240 @BASEBOARD_FAB2_LIB.BASEBOARD_FAB2(SCH_1):PAGE235

CN8F1 CAP_A_0402V-1.0UF,6.3V,10%,X6SA
     1 P3V3_STBY @BASEBOARD_FAB2_LIB.BASEBOARD_FAB2(SCH_1):P3V3_STBY    I21 @BASEBOARD_FAB2_LIB.BASEBOARD_FAB2(SCH_1):PAGE246
     2    GND @BASEBOARD_FAB2_LIB.BASEBOARD_FAB2(SCH_1):GND    I21 @BASEBOARD_FAB2_LIB.BASEBOARD_FAB2(SCH_1):PAGE246

CN8F2 CAP_A_0402V-0.01UF,25V,10%,X7RA
     1 P3V3_STBY @BASEBOARD_FAB2_LIB.BASEBOARD_FAB2(SCH_1):P3V3_STBY    I22 @BASEBOARD_FAB2_LIB.BASEBOARD_FAB2(SCH_1):PAGE246
     2    GND @BASEBOARD_FAB2_LIB.BASEBOARD_FAB2(SCH_1):GND    I22 @BASEBOARD_FAB2_LIB.BASEBOARD_FAB2(SCH_1):PAGE246

CONX8 SMC-CONN60A-22-GP_CONN-G7-SMC-A
     1    GND @BASEBOARD_FAB2_LIB.BASEBOARD_FAB2(SCH_1):GND    I48 @BASEBOARD_FAB2_LIB.BASEBOARD_FAB2(SCH_1):PAGE245
     3 P3E_CPU0_PE2_SS_C_TXN<8> @BASEBOARD_FAB2_LIB.BASEBOARD_FAB2(SCH_1):P3E_CPU0_PE2_SS_C_TXN(8)    I48 @BASEBOARD_FAB2_LIB.BASEBOARD_FAB2(SCH_1):PAGE245
     5 P3E_CPU0_PE2_SS_C_TXP<8> @BASEBOARD_FAB2_LIB.BASEBOARD_FAB2(SCH_1):P3E_CPU0_PE2_SS_C_TXP(8)    I48 @BASEBOARD_FAB2_LIB.BASEBOARD_FAB2(SCH_1):PAGE245
     7    GND @BASEBOARD_FAB2_LIB.BASEBOARD_FAB2(SCH_1):GND    I48 @BASEBOARD_FAB2_LIB.BASEBOARD_FAB2(SCH_1):PAGE245
     2     NC     NC    I48 @BASEBOARD_FAB2_LIB.BASEBOARD_FAB2(SCH_1):PAGE245
     4    GND @BASEBOARD_FAB2_LIB.BASEBOARD_FAB2(SCH_1):GND    I48 @BASEBOARD_FAB2_LIB.BASEBOARD_FAB2(SCH_1):PAGE245
     6 P3E_CPU0_PE2_SS_RXN<8> @BASEBOARD_FAB2_LIB.BASEBOARD_FAB2(SCH_1):P3E_CPU0_PE2_SS_RXN(8)    I48 @BASEBOARD_FAB2_LIB.BASEBOARD_FAB2(SCH_1):PAGE245
     8 P3E_CPU0_PE2_SS_RXP<8> @BASEBOARD_FAB2_LIB.BASEBOARD_FAB2(SCH_1):P3E_CPU0_PE2_SS_RXP(8)    I48 @BASEBOARD_FAB2_LIB.BASEBOARD_FAB2(SCH_1):PAGE245
     9 P3E_CPU0_PE2_SS_C_TXN<9> @BASEBOARD_FAB2_LIB.BASEBOARD_FAB2(SCH_1):P3E_CPU0_PE2_SS_C_TXN(9)    I48 @BASEBOARD_FAB2_LIB.BASEBOARD_FAB2(SCH_1):PAGE245
    11 P3E_CPU0_PE2_SS_C_TXP<9> @BASEBOARD_FAB2_LIB.BASEBOARD_FAB2(SCH_1):P3E_CPU0_PE2_SS_C_TXP(9)    I48 @BASEBOARD_FAB2_LIB.BASEBOARD_FAB2(SCH_1):PAGE245
    13    GND @BASEBOARD_FAB2_LIB.BASEBOARD_FAB2(SCH_1):GND    I48 @BASEBOARD_FAB2_LIB.BASEBOARD_FAB2(SCH_1):PAGE245
    15 P3E_CPU0_PE2_SS_C_TXN<10> @BASEBOARD_FAB2_LIB.BASEBOARD_FAB2(SCH_1):P3E_CPU0_PE2_SS_C_TXN(10)    I48 @BASEBOARD_FAB2_LIB.BASEBOARD_FAB2(SCH_1):PAGE245
    17 P3E_CPU0_PE2_SS_C_TXP<10> @BASEBOARD_FAB2_LIB.BASEBOARD_FAB2(SCH_1):P3E_CPU0_PE2_SS_C_TXP(10)    I48 @BASEBOARD_FAB2_LIB.BASEBOARD_FAB2(SCH_1):PAGE245
    19    GND @BASEBOARD_FAB2_LIB.BASEBOARD_FAB2(SCH_1):GND    I48 @BASEBOARD_FAB2_LIB.BASEBOARD_FAB2(SCH_1):PAGE245
    21 P3E_CPU0_PE2_SS_C_TXP<11> @BASEBOARD_FAB2_LIB.BASEBOARD_FAB2(SCH_1):P3E_CPU0_PE2_SS_C_TXP(11)    I48 @BASEBOARD_FAB2_LIB.BASEBOARD_FAB2(SCH_1):PAGE245
    23 P3E_CPU0_PE2_SS_C_TXN<11> @BASEBOARD_FAB2_LIB.BASEBOARD_FAB2(SCH_1):P3E_CPU0_PE2_SS_C_TXN(11)    I48 @BASEBOARD_FAB2_LIB.BASEBOARD_FAB2(SCH_1):PAGE245
    25    GND @BASEBOARD_FAB2_LIB.BASEBOARD_FAB2(SCH_1):GND    I48 @BASEBOARD_FAB2_LIB.BASEBOARD_FAB2(SCH_1):PAGE245
    27 P3E_CPU0_PE2_SS_C_TXN<12> @BASEBOARD_FAB2_LIB.BASEBOARD_FAB2(SCH_1):P3E_CPU0_PE2_SS_C_TXN(12)    I48 @BASEBOARD_FAB2_LIB.BASEBOARD_FAB2(SCH_1):PAGE245
    29 P3E_CPU0_PE2_SS_C_TXP<12> @BASEBOARD_FAB2_LIB.BASEBOARD_FAB2(SCH_1):P3E_CPU0_PE2_SS_C_TXP(12)    I48 @BASEBOARD_FAB2_LIB.BASEBOARD_FAB2(SCH_1):PAGE245
    31    GND @BASEBOARD_FAB2_LIB.BASEBOARD_FAB2(SCH_1):GND    I48 @BASEBOARD_FAB2_LIB.BASEBOARD_FAB2(SCH_1):PAGE245
    33 P3E_CPU0_PE2_SS_C_TXN<13> @BASEBOARD_FAB2_LIB.BASEBOARD_FAB2(SCH_1):P3E_CPU0_PE2_SS_C_TXN(13)    I48 @BASEBOARD_FAB2_LIB.BASEBOARD_FAB2(SCH_1):PAGE245
    35 P3E_CPU0_PE2_SS_C_TXP<13> @BASEBOARD_FAB2_LIB.BASEBOARD_FAB2(SCH_1):P3E_CPU0_PE2_SS_C_TXP(13)    I48 @BASEBOARD_FAB2_LIB.BASEBOARD_FAB2(SCH_1):PAGE245
    37    GND @BASEBOARD_FAB2_LIB.BASEBOARD_FAB2(SCH_1):GND    I48 @BASEBOARD_FAB2_LIB.BASEBOARD_FAB2(SCH_1):PAGE245
    39 P3E_CPU0_PE2_SS_C_TXP<14> @BASEBOARD_FAB2_LIB.BASEBOARD_FAB2(SCH_1):P3E_CPU0_PE2_SS_C_TXP(14)    I48 @BASEBOARD_FAB2_LIB.BASEBOARD_FAB2(SCH_1):PAGE245
    41 P3E_CPU0_PE2_SS_C_TXN<14> @BASEBOARD_FAB2_LIB.BASEBOARD_FAB2(SCH_1):P3E_CPU0_PE2_SS_C_TXN(14)    I48 @BASEBOARD_FAB2_LIB.BASEBOARD_FAB2(SCH_1):PAGE245
    43    GND @BASEBOARD_FAB2_LIB.BASEBOARD_FAB2(SCH_1):GND    I48 @BASEBOARD_FAB2_LIB.BASEBOARD_FAB2(SCH_1):PAGE245
    45 P3E_CPU0_PE2_SS_C_TXN<15> @BASEBOARD_FAB2_LIB.BASEBOARD_FAB2(SCH_1):P3E_CPU0_PE2_SS_C_TXN(15)    I48 @BASEBOARD_FAB2_LIB.BASEBOARD_FAB2(SCH_1):PAGE245
    47 P3E_CPU0_PE2_SS_C_TXP<15> @BASEBOARD_FAB2_LIB.BASEBOARD_FAB2(SCH_1):P3E_CPU0_PE2_SS_C_TXP(15)    I48 @BASEBOARD_FAB2_LIB.BASEBOARD_FAB2(SCH_1):PAGE245
    49    GND @BASEBOARD_FAB2_LIB.BASEBOARD_FAB2(SCH_1):GND    I48 @BASEBOARD_FAB2_LIB.BASEBOARD_FAB2(SCH_1):PAGE245
    51 JTAG_RISER_TDI @BASEBOARD_FAB2_LIB.BASEBOARD_FAB2(SCH_1):JTAG_RISER_TDI    I48 @BASEBOARD_FAB2_LIB.BASEBOARD_FAB2(SCH_1):PAGE245
    53 JTAG_RISER_TDO @BASEBOARD_FAB2_LIB.BASEBOARD_FAB2(SCH_1):JTAG_RISER_TDO    I48 @BASEBOARD_FAB2_LIB.BASEBOARD_FAB2(SCH_1):PAGE245
    55    GND @BASEBOARD_FAB2_LIB.BASEBOARD_FAB2(SCH_1):GND    I48 @BASEBOARD_FAB2_LIB.BASEBOARD_FAB2(SCH_1):PAGE245
    57 USB2_P02_DN @BASEBOARD_FAB2_LIB.BASEBOARD_FAB2(SCH_1):USB2_P02_DN    I48 @BASEBOARD_FAB2_LIB.BASEBOARD_FAB2(SCH_1):PAGE245
    59 USB2_P02_DP @BASEBOARD_FAB2_LIB.BASEBOARD_FAB2(SCH_1):USB2_P02_DP    I48 @BASEBOARD_FAB2_LIB.BASEBOARD_FAB2(SCH_1):PAGE245
    10    GND @BASEBOARD_FAB2_LIB.BASEBOARD_FAB2(SCH_1):GND    I48 @BASEBOARD_FAB2_LIB.BASEBOARD_FAB2(SCH_1):PAGE245
    12 P3E_CPU0_PE2_SS_RXN<9> @BASEBOARD_FAB2_LIB.BASEBOARD_FAB2(SCH_1):P3E_CPU0_PE2_SS_RXN(9)    I48 @BASEBOARD_FAB2_LIB.BASEBOARD_FAB2(SCH_1):PAGE245
    14 P3E_CPU0_PE2_SS_RXP<9> @BASEBOARD_FAB2_LIB.BASEBOARD_FAB2(SCH_1):P3E_CPU0_PE2_SS_RXP(9)    I48 @BASEBOARD_FAB2_LIB.BASEBOARD_FAB2(SCH_1):PAGE245
    16    GND @BASEBOARD_FAB2_LIB.BASEBOARD_FAB2(SCH_1):GND    I48 @BASEBOARD_FAB2_LIB.BASEBOARD_FAB2(SCH_1):PAGE245
    18 P3E_CPU0_PE2_SS_RXN<10> @BASEBOARD_FAB2_LIB.BASEBOARD_FAB2(SCH_1):P3E_CPU0_PE2_SS_RXN(10)    I48 @BASEBOARD_FAB2_LIB.BASEBOARD_FAB2(SCH_1):PAGE245
    20 P3E_CPU0_PE2_SS_RXP<10> @BASEBOARD_FAB2_LIB.BASEBOARD_FAB2(SCH_1):P3E_CPU0_PE2_SS_RXP(10)    I48 @BASEBOARD_FAB2_LIB.BASEBOARD_FAB2(SCH_1):PAGE245
    22    GND @BASEBOARD_FAB2_LIB.BASEBOARD_FAB2(SCH_1):GND    I48 @BASEBOARD_FAB2_LIB.BASEBOARD_FAB2(SCH_1):PAGE245
    24 P3E_CPU0_PE2_SS_RXN<11> @BASEBOARD_FAB2_LIB.BASEBOARD_FAB2(SCH_1):P3E_CPU0_PE2_SS_RXN(11)    I48 @BASEBOARD_FAB2_LIB.BASEBOARD_FAB2(SCH_1):PAGE245
    26 P3E_CPU0_PE2_SS_RXP<11> @BASEBOARD_FAB2_LIB.BASEBOARD_FAB2(SCH_1):P3E_CPU0_PE2_SS_RXP(11)    I48 @BASEBOARD_FAB2_LIB.BASEBOARD_FAB2(SCH_1):PAGE245
    28    GND @BASEBOARD_FAB2_LIB.BASEBOARD_FAB2(SCH_1):GND    I48 @BASEBOARD_FAB2_LIB.BASEBOARD_FAB2(SCH_1):PAGE245
    30 P3E_CPU0_PE2_SS_RXN<12> @BASEBOARD_FAB2_LIB.BASEBOARD_FAB2(SCH_1):P3E_CPU0_PE2_SS_RXN(12)    I48 @BASEBOARD_FAB2_LIB.BASEBOARD_FAB2(SCH_1):PAGE245
    32 P3E_CPU0_PE2_SS_RXP<12> @BASEBOARD_FAB2_LIB.BASEBOARD_FAB2(SCH_1):P3E_CPU0_PE2_SS_RXP(12)    I48 @BASEBOARD_FAB2_LIB.BASEBOARD_FAB2(SCH_1):PAGE245
    34    GND @BASEBOARD_FAB2_LIB.BASEBOARD_FAB2(SCH_1):GND    I48 @BASEBOARD_FAB2_LIB.BASEBOARD_FAB2(SCH_1):PAGE245
    36 P3E_CPU0_PE2_SS_RXP<13> @BASEBOARD_FAB2_LIB.BASEBOARD_FAB2(SCH_1):P3E_CPU0_PE2_SS_RXP(13)    I48 @BASEBOARD_FAB2_LIB.BASEBOARD_FAB2(SCH_1):PAGE245
    38 P3E_CPU0_PE2_SS_RXN<13> @BASEBOARD_FAB2_LIB.BASEBOARD_FAB2(SCH_1):P3E_CPU0_PE2_SS_RXN(13)    I48 @BASEBOARD_FAB2_LIB.BASEBOARD_FAB2(SCH_1):PAGE245
    40    GND @BASEBOARD_FAB2_LIB.BASEBOARD_FAB2(SCH_1):GND    I48 @BASEBOARD_FAB2_LIB.BASEBOARD_FAB2(SCH_1):PAGE245
    42 P3E_CPU0_PE2_SS_RXN<14> @BASEBOARD_FAB2_LIB.BASEBOARD_FAB2(SCH_1):P3E_CPU0_PE2_SS_RXN(14)    I48 @BASEBOARD_FAB2_LIB.BASEBOARD_FAB2(SCH_1):PAGE245
    44 P3E_CPU0_PE2_SS_RXP<14> @BASEBOARD_FAB2_LIB.BASEBOARD_FAB2(SCH_1):P3E_CPU0_PE2_SS_RXP(14)    I48 @BASEBOARD_FAB2_LIB.BASEBOARD_FAB2(SCH_1):PAGE245
    46    GND @BASEBOARD_FAB2_LIB.BASEBOARD_FAB2(SCH_1):GND    I48 @BASEBOARD_FAB2_LIB.BASEBOARD_FAB2(SCH_1):PAGE245
    48 P3E_CPU0_PE2_SS_RXN<15> @BASEBOARD_FAB2_LIB.BASEBOARD_FAB2(SCH_1):P3E_CPU0_PE2_SS_RXN(15)    I48 @BASEBOARD_FAB2_LIB.BASEBOARD_FAB2(SCH_1):PAGE245
    50 P3E_CPU0_PE2_SS_RXP<15> @BASEBOARD_FAB2_LIB.BASEBOARD_FAB2(SCH_1):P3E_CPU0_PE2_SS_RXP(15)    I48 @BASEBOARD_FAB2_LIB.BASEBOARD_FAB2(SCH_1):PAGE245
    52    GND @BASEBOARD_FAB2_LIB.BASEBOARD_FAB2(SCH_1):GND    I48 @BASEBOARD_FAB2_LIB.BASEBOARD_FAB2(SCH_1):PAGE245
    54 JTAG_RISER_TMS @BASEBOARD_FAB2_LIB.BASEBOARD_FAB2(SCH_1):JTAG_RISER_TMS    I48 @BASEBOARD_FAB2_LIB.BASEBOARD_FAB2(SCH_1):PAGE245
    56 JTAG_RISER_TCK @BASEBOARD_FAB2_LIB.BASEBOARD_FAB2(SCH_1):JTAG_RISER_TCK    I48 @BASEBOARD_FAB2_LIB.BASEBOARD_FAB2(SCH_1):PAGE245
    58    GND @BASEBOARD_FAB2_LIB.BASEBOARD_FAB2(SCH_1):GND    I48 @BASEBOARD_FAB2_LIB.BASEBOARD_FAB2(SCH_1):PAGE245
    60 JTAG_RISER_TRST @BASEBOARD_FAB2_LIB.BASEBOARD_FAB2(SCH_1):JTAG_RISER_TRST    I48 @BASEBOARD_FAB2_LIB.BASEBOARD_FAB2(SCH_1):PAGE245
   NP1     NC     NC    I48 @BASEBOARD_FAB2_LIB.BASEBOARD_FAB2(SCH_1):PAGE245
   NP2     NC     NC    I48 @BASEBOARD_FAB2_LIB.BASEBOARD_FAB2(SCH_1):PAGE245
  PTH1    GND @BASEBOARD_FAB2_LIB.BASEBOARD_FAB2(SCH_1):GND    I48 @BASEBOARD_FAB2_LIB.BASEBOARD_FAB2(SCH_1):PAGE245
  PTH2    GND @BASEBOARD_FAB2_LIB.BASEBOARD_FAB2(SCH_1):GND    I48 @BASEBOARD_FAB2_LIB.BASEBOARD_FAB2(SCH_1):PAGE245

CR1B1 DIODE_SM-SDMK0340L,EMPTY,H7179A
     1 P5V_STBY @BASEBOARD_FAB2_LIB.BASEBOARD_FAB2(SCH_1):P5V_STBY    I64 @BASEBOARD_FAB2_LIB.BASEBOARD_FAB2(SCH_1):PAGE161
     2 FAN_PWM_OUT_SYS1_R @BASEBOARD_FAB2_LIB.BASEBOARD_FAB2(SCH_1):FAN_PWM_OUT_SYS1_R    I64 @BASEBOARD_FAB2_LIB.BASEBOARD_FAB2(SCH_1):PAGE161

CR1B2 DIODE_SM-SDMK0340L,IC,H71799-0A
     1 FAN_TACH2_CPU1_D1 @BASEBOARD_FAB2_LIB.BASEBOARD_FAB2(SCH_1):FAN_TACH2_CPU1_D1    I62 @BASEBOARD_FAB2_LIB.BASEBOARD_FAB2(SCH_1):PAGE161
     2 FAN_TACH2_CPU1_D2 @BASEBOARD_FAB2_LIB.BASEBOARD_FAB2(SCH_1):FAN_TACH2_CPU1_D2    I62 @BASEBOARD_FAB2_LIB.BASEBOARD_FAB2(SCH_1):PAGE161

CR1E1 DIODE_SM-SDMK0340L,EMPTY,H7179A
     1 P5V_STBY @BASEBOARD_FAB2_LIB.BASEBOARD_FAB2(SCH_1):P5V_STBY    I50 @BASEBOARD_FAB2_LIB.BASEBOARD_FAB2(SCH_1):PAGE161
     2 FAN_PWM_OUT_SYS0_R @BASEBOARD_FAB2_LIB.BASEBOARD_FAB2(SCH_1):FAN_PWM_OUT_SYS0_R    I50 @BASEBOARD_FAB2_LIB.BASEBOARD_FAB2(SCH_1):PAGE161

CR1F1 DIODE_SM-SDMK0340L,IC,H71799-0A
     1 FAN_TACH0_CPU0_D1 @BASEBOARD_FAB2_LIB.BASEBOARD_FAB2(SCH_1):FAN_TACH0_CPU0_D1    I42 @BASEBOARD_FAB2_LIB.BASEBOARD_FAB2(SCH_1):PAGE161
     2 FAN_TACH0_CPU0_D2 @BASEBOARD_FAB2_LIB.BASEBOARD_FAB2(SCH_1):FAN_TACH0_CPU0_D2    I42 @BASEBOARD_FAB2_LIB.BASEBOARD_FAB2(SCH_1):PAGE161

CR1F3 DIODE_SM-SDMK0340L,IC,H71799-0A
     1 FM_MATED_IN_D2_N @BASEBOARD_FAB2_LIB.BASEBOARD_FAB2(SCH_1):FM_MATED_IN_D2_N    I37 @BASEBOARD_FAB2_LIB.BASEBOARD_FAB2(SCH_1):PAGE181
     2 FM_MATED_IN_D1_N @BASEBOARD_FAB2_LIB.BASEBOARD_FAB2(SCH_1):FM_MATED_IN_D1_N    I37 @BASEBOARD_FAB2_LIB.BASEBOARD_FAB2(SCH_1):PAGE181

CR1F4 DIODE_SM-SDMK0340L,IC,H71799-0A
     1 FM_MATED_IN_D1_N @BASEBOARD_FAB2_LIB.BASEBOARD_FAB2(SCH_1):FM_MATED_IN_D1_N     I5 @BASEBOARD_FAB2_LIB.BASEBOARD_FAB2(SCH_1):PAGE181
     2 FM_MATED_IN_N @BASEBOARD_FAB2_LIB.BASEBOARD_FAB2(SCH_1):FM_MATED_IN_N     I5 @BASEBOARD_FAB2_LIB.BASEBOARD_FAB2(SCH_1):PAGE181

CR1F5 DIODE_SM-MBRS340T3G,EMPTY,C819A
     1 P12V_STBY @BASEBOARD_FAB2_LIB.BASEBOARD_FAB2(SCH_1):P12V_STBY   I220 @BASEBOARD_FAB2_LIB.BASEBOARD_FAB2(SCH_1):PAGE200
     2    GND @BASEBOARD_FAB2_LIB.BASEBOARD_FAB2(SCH_1):GND   I220 @BASEBOARD_FAB2_LIB.BASEBOARD_FAB2(SCH_1):PAGE200

CR1L1 DIODE_SM-1N4148W,IC,D89194-001
     1 FM_DB_UART_SEL1_N @BASEBOARD_FAB2_LIB.BASEBOARD_FAB2(SCH_1):FM_DB_UART_SEL1_N     I2 @BASEBOARD_FAB2_LIB.BASEBOARD_FAB2(SCH_1):PAGE168
     2 FM_DB_UART_SEL0_N @BASEBOARD_FAB2_LIB.BASEBOARD_FAB2(SCH_1):FM_DB_UART_SEL0_N     I2 @BASEBOARD_FAB2_LIB.BASEBOARD_FAB2(SCH_1):PAGE168

CR1L2 DIODE_SM-1N4148W,IC,D89194-001
     1 FM_DB_UART_SEL2_N @BASEBOARD_FAB2_LIB.BASEBOARD_FAB2(SCH_1):FM_DB_UART_SEL2_N     I3 @BASEBOARD_FAB2_LIB.BASEBOARD_FAB2(SCH_1):PAGE168
     2 FM_DB_UART_SEL1_N @BASEBOARD_FAB2_LIB.BASEBOARD_FAB2(SCH_1):FM_DB_UART_SEL1_N     I3 @BASEBOARD_FAB2_LIB.BASEBOARD_FAB2(SCH_1):PAGE168

CR1L3 DIODE_SM-1N4148W,IC,D89194-001
     1 FM_DB_UART_SEL3_N @BASEBOARD_FAB2_LIB.BASEBOARD_FAB2(SCH_1):FM_DB_UART_SEL3_N     I4 @BASEBOARD_FAB2_LIB.BASEBOARD_FAB2(SCH_1):PAGE168
     2 FM_DB_UART_SEL2_N @BASEBOARD_FAB2_LIB.BASEBOARD_FAB2(SCH_1):FM_DB_UART_SEL2_N     I4 @BASEBOARD_FAB2_LIB.BASEBOARD_FAB2(SCH_1):PAGE168

CR1L4 DIODE_SM-1N4148W,IC,D89194-001
     1 FM_DB_UART_SEL4_N @BASEBOARD_FAB2_LIB.BASEBOARD_FAB2(SCH_1):FM_DB_UART_SEL4_N     I5 @BASEBOARD_FAB2_LIB.BASEBOARD_FAB2(SCH_1):PAGE168
     2 FM_DB_UART_SEL3_N @BASEBOARD_FAB2_LIB.BASEBOARD_FAB2(SCH_1):FM_DB_UART_SEL3_N     I5 @BASEBOARD_FAB2_LIB.BASEBOARD_FAB2(SCH_1):PAGE168

CR1M2 DIODEAC_DUAL_ARRAY_SM9-ESD3V3UA
     1 USB2_P01_ESD_DP @BASEBOARD_FAB2_LIB.BASEBOARD_FAB2(SCH_1):USB2_P01_ESD_DP    I98 @BASEBOARD_FAB2_LIB.BASEBOARD_FAB2(SCH_1):PAGE176
     2 USB2_P01_ESD_DN @BASEBOARD_FAB2_LIB.BASEBOARD_FAB2(SCH_1):USB2_P01_ESD_DN    I98 @BASEBOARD_FAB2_LIB.BASEBOARD_FAB2(SCH_1):PAGE176
     4 TP_USB_ESD_AC2 @BASEBOARD_FAB2_LIB.BASEBOARD_FAB2(SCH_1):TP_USB_ESD_AC2    I98 @BASEBOARD_FAB2_LIB.BASEBOARD_FAB2(SCH_1):PAGE176
     5 TP_USB_ESD_AC3 @BASEBOARD_FAB2_LIB.BASEBOARD_FAB2(SCH_1):TP_USB_ESD_AC3    I98 @BASEBOARD_FAB2_LIB.BASEBOARD_FAB2(SCH_1):PAGE176
     3    GND @BASEBOARD_FAB2_LIB.BASEBOARD_FAB2(SCH_1):GND    I98 @BASEBOARD_FAB2_LIB.BASEBOARD_FAB2(SCH_1):PAGE176
     9 USB2_P01_ESD_DP @BASEBOARD_FAB2_LIB.BASEBOARD_FAB2(SCH_1):USB2_P01_ESD_DP    I98 @BASEBOARD_FAB2_LIB.BASEBOARD_FAB2(SCH_1):PAGE176
     8 USB2_P01_ESD_DN @BASEBOARD_FAB2_LIB.BASEBOARD_FAB2(SCH_1):USB2_P01_ESD_DN    I98 @BASEBOARD_FAB2_LIB.BASEBOARD_FAB2(SCH_1):PAGE176
     7 TP_USB_ESD_OUT2 @BASEBOARD_FAB2_LIB.BASEBOARD_FAB2(SCH_1):TP_USB_ESD_OUT2    I98 @BASEBOARD_FAB2_LIB.BASEBOARD_FAB2(SCH_1):PAGE176
     6 TP_USB_ESD_OUT3 @BASEBOARD_FAB2_LIB.BASEBOARD_FAB2(SCH_1):TP_USB_ESD_OUT3    I98 @BASEBOARD_FAB2_LIB.BASEBOARD_FAB2(SCH_1):PAGE176

CR2U1 DIODE2A_DUAL_SMLF-BAS70-05,DIOA
     3 P3V3_RTC_STBY @BASEBOARD_FAB2_LIB.BASEBOARD_FAB2(SCH_1):P3V3_RTC_STBY    I53 @BASEBOARD_FAB2_LIB.BASEBOARD_FAB2(SCH_1):PAGE196
     1 P3V3_STBY @BASEBOARD_FAB2_LIB.BASEBOARD_FAB2(SCH_1):P3V3_STBY    I53 @BASEBOARD_FAB2_LIB.BASEBOARD_FAB2(SCH_1):PAGE196
     2 A_P3V_BAT_R @BASEBOARD_FAB2_LIB.BASEBOARD_FAB2(SCH_1):A_P3V_BAT_R    I53 @BASEBOARD_FAB2_LIB.BASEBOARD_FAB2(SCH_1):PAGE196

CR3U1 DIODE_SMLF-1N5819HW,IC,D55839-A
     1 P3V3_STBY_PLD_D @BASEBOARD_FAB2_LIB.BASEBOARD_FAB2(SCH_1):P3V3_STBY_PLD_D    I49 @BASEBOARD_FAB2_LIB.BASEBOARD_FAB2(SCH_1):PAGE189
     2 P3V3_STBY @BASEBOARD_FAB2_LIB.BASEBOARD_FAB2(SCH_1):P3V3_STBY    I49 @BASEBOARD_FAB2_LIB.BASEBOARD_FAB2(SCH_1):PAGE189

CR3W1 DIODE_SMLF-BAT54WS,IC,C73510-0A
     1 BMC_SELF_HW_D_RST @BASEBOARD_FAB2_LIB.BASEBOARD_FAB2(SCH_1):BMC_SELF_HW_D_RST    I55 @BASEBOARD_FAB2_LIB.BASEBOARD_FAB2(SCH_1):PAGE249
     2 BMC_SELF_HW_RST @BASEBOARD_FAB2_LIB.BASEBOARD_FAB2(SCH_1):BMC_SELF_HW_RST    I55 @BASEBOARD_FAB2_LIB.BASEBOARD_FAB2(SCH_1):PAGE249

CR6W1 DIODE_SMLF-BAT54WS,IC,C73510-0A
     1 FM_CPU_CATERR_LVT3_N @BASEBOARD_FAB2_LIB.BASEBOARD_FAB2(SCH_1):FM_CPU_CATERR_LVT3_N   I157 @BASEBOARD_FAB2_LIB.BASEBOARD_FAB2(SCH_1):PAGE247
     2 FM_CPU_CATERR_MSMI_LVT3_N @BASEBOARD_FAB2_LIB.BASEBOARD_FAB2(SCH_1):FM_CPU_CATERR_MSMI_LVT3_N   I157 @BASEBOARD_FAB2_LIB.BASEBOARD_FAB2(SCH_1):PAGE247

CR6W2 DIODE_SMLF-BAT54WS,IC,C73510-0A
     1 FM_CPU_MSMI_LVT3_N @BASEBOARD_FAB2_LIB.BASEBOARD_FAB2(SCH_1):FM_CPU_MSMI_LVT3_N   I158 @BASEBOARD_FAB2_LIB.BASEBOARD_FAB2(SCH_1):PAGE247
     2 FM_CPU_CATERR_MSMI_LVT3_N @BASEBOARD_FAB2_LIB.BASEBOARD_FAB2(SCH_1):FM_CPU_CATERR_MSMI_LVT3_N   I158 @BASEBOARD_FAB2_LIB.BASEBOARD_FAB2(SCH_1):PAGE247

CR7E1 DIODE_SMLF-BAT54WS,IC,C73510-0A
     1 PWRGD_P3V3_STBY @BASEBOARD_FAB2_LIB.BASEBOARD_FAB2(SCH_1):PWRGD_P3V3_STBY   I103 @BASEBOARD_FAB2_LIB.BASEBOARD_FAB2(SCH_1):PAGE196
     2 PWRGD_DSW_PWROK @BASEBOARD_FAB2_LIB.BASEBOARD_FAB2(SCH_1):PWRGD_DSW_PWROK   I103 @BASEBOARD_FAB2_LIB.BASEBOARD_FAB2(SCH_1):PAGE196

CR8E1 DIODE_SMLF-BAT54WS,IC,C73510-0A
     1 PWRGD_P12V_HSC @BASEBOARD_FAB2_LIB.BASEBOARD_FAB2(SCH_1):PWRGD_P12V_HSC   I128 @BASEBOARD_FAB2_LIB.BASEBOARD_FAB2(SCH_1):PAGE196
     2 PWRGD_P12V_HSC_DLY @BASEBOARD_FAB2_LIB.BASEBOARD_FAB2(SCH_1):PWRGD_P12V_HSC_DLY   I128 @BASEBOARD_FAB2_LIB.BASEBOARD_FAB2(SCH_1):PAGE196

CR9P1 DIODE_SMLF-BAT54WS,IC,C73510-0A
     1 IRQ_UV_DETECT_N @BASEBOARD_FAB2_LIB.BASEBOARD_FAB2(SCH_1):IRQ_UV_DETECT_N   I214 @BASEBOARD_FAB2_LIB.BASEBOARD_FAB2(SCH_1):PAGE200
     2 FM_DISABLE_FAN_N @BASEBOARD_FAB2_LIB.BASEBOARD_FAB2(SCH_1):FM_DISABLE_FAN_N   I214 @BASEBOARD_FAB2_LIB.BASEBOARD_FAB2(SCH_1):PAGE200

CR9P2 DIODE_SMLF-BAT54WS,IC,C73510-0A
     1 FM_UV_ADR_TRIGGER_N @BASEBOARD_FAB2_LIB.BASEBOARD_FAB2(SCH_1):FM_UV_ADR_TRIGGER_N   I213 @BASEBOARD_FAB2_LIB.BASEBOARD_FAB2(SCH_1):PAGE200
     2 FM_DISABLE_FAN_N @BASEBOARD_FAB2_LIB.BASEBOARD_FAB2(SCH_1):FM_DISABLE_FAN_N   I213 @BASEBOARD_FAB2_LIB.BASEBOARD_FAB2(SCH_1):PAGE200

CR9W1 DIODE_SMLF-BAT54WS,IC,C73510-0A
     1 SPA_5V_SIN_SW @BASEBOARD_FAB2_LIB.BASEBOARD_FAB2(SCH_1):SPA_5V_SIN_SW   I202 @BASEBOARD_FAB2_LIB.BASEBOARD_FAB2(SCH_1):PAGE155
     2 SPA_5V_SIN_SW_D @BASEBOARD_FAB2_LIB.BASEBOARD_FAB2(SCH_1):SPA_5V_SIN_SW_D   I202 @BASEBOARD_FAB2_LIB.BASEBOARD_FAB2(SCH_1):PAGE155

CR10W1 DIODE_SM-SDMK0340L,IC,H71799-0A
     1 PUMP_TACH_D @BASEBOARD_FAB2_LIB.BASEBOARD_FAB2(SCH_1):PUMP_TACH_D    I12 @BASEBOARD_FAB2_LIB.BASEBOARD_FAB2(SCH_1):PAGE251
     2 PUMP_TACH_R @BASEBOARD_FAB2_LIB.BASEBOARD_FAB2(SCH_1):PUMP_TACH_R    I12 @BASEBOARD_FAB2_LIB.BASEBOARD_FAB2(SCH_1):PAGE251

CR10W2 DIODE_SM-SDMK0340L,EMPTY,H7179A
     1 P5V_STBY @BASEBOARD_FAB2_LIB.BASEBOARD_FAB2(SCH_1):P5V_STBY    I10 @BASEBOARD_FAB2_LIB.BASEBOARD_FAB2(SCH_1):PAGE251
     2 PUMP_PWM_OUT_R @BASEBOARD_FAB2_LIB.BASEBOARD_FAB2(SCH_1):PUMP_PWM_OUT_R    I10 @BASEBOARD_FAB2_LIB.BASEBOARD_FAB2(SCH_1):PAGE251

CR10W3 DIODE_SM-SDMK0340L,IC,H71799-0A
     1 PUMP_TACH1_D @BASEBOARD_FAB2_LIB.BASEBOARD_FAB2(SCH_1):PUMP_TACH1_D    I26 @BASEBOARD_FAB2_LIB.BASEBOARD_FAB2(SCH_1):PAGE251
     2 PUMP_TACH1_R @BASEBOARD_FAB2_LIB.BASEBOARD_FAB2(SCH_1):PUMP_TACH1_R    I26 @BASEBOARD_FAB2_LIB.BASEBOARD_FAB2(SCH_1):PAGE251

CR25W1 DIODEAC_DUAL_ARRAY_SM9-ESD3V3UA
     1 V_IO_B_J @BASEBOARD_FAB2_LIB.BASEBOARD_FAB2(SCH_1):V_IO_B_J   I129 @BASEBOARD_FAB2_LIB.BASEBOARD_FAB2(SCH_1):PAGE255
     2 V_IO_G_J @BASEBOARD_FAB2_LIB.BASEBOARD_FAB2(SCH_1):V_IO_G_J   I129 @BASEBOARD_FAB2_LIB.BASEBOARD_FAB2(SCH_1):PAGE255
     4 V_IO_R_J @BASEBOARD_FAB2_LIB.BASEBOARD_FAB2(SCH_1):V_IO_R_J   I129 @BASEBOARD_FAB2_LIB.BASEBOARD_FAB2(SCH_1):PAGE255
     5     NC     NC   I129 @BASEBOARD_FAB2_LIB.BASEBOARD_FAB2(SCH_1):PAGE255
     3    GND @BASEBOARD_FAB2_LIB.BASEBOARD_FAB2(SCH_1):GND   I129 @BASEBOARD_FAB2_LIB.BASEBOARD_FAB2(SCH_1):PAGE255
     9 V_IO_B_J @BASEBOARD_FAB2_LIB.BASEBOARD_FAB2(SCH_1):V_IO_B_J   I129 @BASEBOARD_FAB2_LIB.BASEBOARD_FAB2(SCH_1):PAGE255
     8 V_IO_G_J @BASEBOARD_FAB2_LIB.BASEBOARD_FAB2(SCH_1):V_IO_G_J   I129 @BASEBOARD_FAB2_LIB.BASEBOARD_FAB2(SCH_1):PAGE255
     7 V_IO_R_J @BASEBOARD_FAB2_LIB.BASEBOARD_FAB2(SCH_1):V_IO_R_J   I129 @BASEBOARD_FAB2_LIB.BASEBOARD_FAB2(SCH_1):PAGE255
     6     NC     NC   I129 @BASEBOARD_FAB2_LIB.BASEBOARD_FAB2(SCH_1):PAGE255

CR25W2 DIODEAC_DUAL_ARRAY_SM9-ESD3V3UA
     1 V_IBMC_5V_DDC_SDA_J @BASEBOARD_FAB2_LIB.BASEBOARD_FAB2(SCH_1):V_IBMC_5V_DDC_SDA_J   I131 @BASEBOARD_FAB2_LIB.BASEBOARD_FAB2(SCH_1):PAGE255
     2 V_IBMC_5V_DDC_SCL_J @BASEBOARD_FAB2_LIB.BASEBOARD_FAB2(SCH_1):V_IBMC_5V_DDC_SCL_J   I131 @BASEBOARD_FAB2_LIB.BASEBOARD_FAB2(SCH_1):PAGE255
     4 V_IO_VSYNC_J @BASEBOARD_FAB2_LIB.BASEBOARD_FAB2(SCH_1):V_IO_VSYNC_J   I131 @BASEBOARD_FAB2_LIB.BASEBOARD_FAB2(SCH_1):PAGE255
     5 V_IO_HSYNC_J @BASEBOARD_FAB2_LIB.BASEBOARD_FAB2(SCH_1):V_IO_HSYNC_J   I131 @BASEBOARD_FAB2_LIB.BASEBOARD_FAB2(SCH_1):PAGE255
     3    GND @BASEBOARD_FAB2_LIB.BASEBOARD_FAB2(SCH_1):GND   I131 @BASEBOARD_FAB2_LIB.BASEBOARD_FAB2(SCH_1):PAGE255
     9 V_IBMC_5V_DDC_SDA_J @BASEBOARD_FAB2_LIB.BASEBOARD_FAB2(SCH_1):V_IBMC_5V_DDC_SDA_J   I131 @BASEBOARD_FAB2_LIB.BASEBOARD_FAB2(SCH_1):PAGE255
     8 V_IBMC_5V_DDC_SCL_J @BASEBOARD_FAB2_LIB.BASEBOARD_FAB2(SCH_1):V_IBMC_5V_DDC_SCL_J   I131 @BASEBOARD_FAB2_LIB.BASEBOARD_FAB2(SCH_1):PAGE255
     7 V_IO_VSYNC_J @BASEBOARD_FAB2_LIB.BASEBOARD_FAB2(SCH_1):V_IO_VSYNC_J   I131 @BASEBOARD_FAB2_LIB.BASEBOARD_FAB2(SCH_1):PAGE255
     6 V_IO_HSYNC_J @BASEBOARD_FAB2_LIB.BASEBOARD_FAB2(SCH_1):V_IO_HSYNC_J   I131 @BASEBOARD_FAB2_LIB.BASEBOARD_FAB2(SCH_1):PAGE255

CR30W1 DIODEAC_DUAL_ARRAY_SM9-ESD3V3UA
     1 USB3_P01_FB_TXN @BASEBOARD_FAB2_LIB.BASEBOARD_FAB2(SCH_1):USB3_P01_FB_TXN     I5 @BASEBOARD_FAB2_LIB.BASEBOARD_FAB2(SCH_1):PAGE253
     2 USB3_P01_FB_TXP @BASEBOARD_FAB2_LIB.BASEBOARD_FAB2(SCH_1):USB3_P01_FB_TXP     I5 @BASEBOARD_FAB2_LIB.BASEBOARD_FAB2(SCH_1):PAGE253
     4 USB3_P01_FB_RXN @BASEBOARD_FAB2_LIB.BASEBOARD_FAB2(SCH_1):USB3_P01_FB_RXN     I5 @BASEBOARD_FAB2_LIB.BASEBOARD_FAB2(SCH_1):PAGE253
     5 USB3_P01_FB_RXP @BASEBOARD_FAB2_LIB.BASEBOARD_FAB2(SCH_1):USB3_P01_FB_RXP     I5 @BASEBOARD_FAB2_LIB.BASEBOARD_FAB2(SCH_1):PAGE253
     3    GND @BASEBOARD_FAB2_LIB.BASEBOARD_FAB2(SCH_1):GND     I5 @BASEBOARD_FAB2_LIB.BASEBOARD_FAB2(SCH_1):PAGE253
     9 USB3_P01_FB_TXN @BASEBOARD_FAB2_LIB.BASEBOARD_FAB2(SCH_1):USB3_P01_FB_TXN     I5 @BASEBOARD_FAB2_LIB.BASEBOARD_FAB2(SCH_1):PAGE253
     8 USB3_P01_FB_TXP @BASEBOARD_FAB2_LIB.BASEBOARD_FAB2(SCH_1):USB3_P01_FB_TXP     I5 @BASEBOARD_FAB2_LIB.BASEBOARD_FAB2(SCH_1):PAGE253
     7 USB3_P01_FB_RXN @BASEBOARD_FAB2_LIB.BASEBOARD_FAB2(SCH_1):USB3_P01_FB_RXN     I5 @BASEBOARD_FAB2_LIB.BASEBOARD_FAB2(SCH_1):PAGE253
     6 USB3_P01_FB_RXP @BASEBOARD_FAB2_LIB.BASEBOARD_FAB2(SCH_1):USB3_P01_FB_RXP     I5 @BASEBOARD_FAB2_LIB.BASEBOARD_FAB2(SCH_1):PAGE253

 CT1 CAP_A_0402V-0.1UF,16V,10%,X7R,A
     1 VR_PVCCIN_CPU0_AIREF1 @BASEBOARD_FAB2_LIB.BASEBOARD_FAB2(SCH_1):VR_PVCCIN_CPU0_AIREF1    I70 @BASEBOARD_FAB2_LIB.BASEBOARD_FAB2(SCH_1):PAGE202
     2    GND @BASEBOARD_FAB2_LIB.BASEBOARD_FAB2(SCH_1):GND    I70 @BASEBOARD_FAB2_LIB.BASEBOARD_FAB2(SCH_1):PAGE202

 CT2 CAP_0402LF-1000PF,50V,10%,X7R,A
     1 A_TSENSE_PVCCIN_CPU0 @BASEBOARD_FAB2_LIB.BASEBOARD_FAB2(SCH_1):A_TSENSE_PVCCIN_CPU0    I78 @BASEBOARD_FAB2_LIB.BASEBOARD_FAB2(SCH_1):PAGE202
     2    GND @BASEBOARD_FAB2_LIB.BASEBOARD_FAB2(SCH_1):GND    I78 @BASEBOARD_FAB2_LIB.BASEBOARD_FAB2(SCH_1):PAGE202

 CT3 CAP_0402LF-1000PF,50V,10%,X7R,A
     1 VR_PVCCIN_CPU0_PHASE1 @BASEBOARD_FAB2_LIB.BASEBOARD_FAB2(SCH_1):VR_PVCCIN_CPU0_PHASE1    I97 @BASEBOARD_FAB2_LIB.BASEBOARD_FAB2(SCH_1):PAGE202
     2 VR_PVCCIN_CPU0_PHASE1_RC @BASEBOARD_FAB2_LIB.BASEBOARD_FAB2(SCH_1):VR_PVCCIN_CPU0_PHASE1_RC    I97 @BASEBOARD_FAB2_LIB.BASEBOARD_FAB2(SCH_1):PAGE202

 CT4 CAP_0402LF-1000PF,50V,10%,X7R,A
     1 A_TSENSE_PVCCIN_CPU0 @BASEBOARD_FAB2_LIB.BASEBOARD_FAB2(SCH_1):A_TSENSE_PVCCIN_CPU0    I87 @BASEBOARD_FAB2_LIB.BASEBOARD_FAB2(SCH_1):PAGE202
     2    GND @BASEBOARD_FAB2_LIB.BASEBOARD_FAB2(SCH_1):GND    I87 @BASEBOARD_FAB2_LIB.BASEBOARD_FAB2(SCH_1):PAGE202

 CT5 CAP_0402LF-1000PF,50V,10%,X7R,A
     1 VR_PVCCIN_CPU0_PHASE2 @BASEBOARD_FAB2_LIB.BASEBOARD_FAB2(SCH_1):VR_PVCCIN_CPU0_PHASE2    I98 @BASEBOARD_FAB2_LIB.BASEBOARD_FAB2(SCH_1):PAGE202
     2 VR_PVCCIN_CPU0_PHASE2_RC @BASEBOARD_FAB2_LIB.BASEBOARD_FAB2(SCH_1):VR_PVCCIN_CPU0_PHASE2_RC    I98 @BASEBOARD_FAB2_LIB.BASEBOARD_FAB2(SCH_1):PAGE202

 CT6 CAP_A_0402V-0.1UF,16V,10%,X7R,A
     1 VR_PVCCIN_CPU0_AIREF2 @BASEBOARD_FAB2_LIB.BASEBOARD_FAB2(SCH_1):VR_PVCCIN_CPU0_AIREF2    I81 @BASEBOARD_FAB2_LIB.BASEBOARD_FAB2(SCH_1):PAGE202
     2    GND @BASEBOARD_FAB2_LIB.BASEBOARD_FAB2(SCH_1):GND    I81 @BASEBOARD_FAB2_LIB.BASEBOARD_FAB2(SCH_1):PAGE202

 CT7 CAP_A_0402V-0.1UF,16V,10%,X7R,A
     1 VR_PVDDQ_KLM_AIREF1 @BASEBOARD_FAB2_LIB.BASEBOARD_FAB2(SCH_1):VR_PVDDQ_KLM_AIREF1   I109 @BASEBOARD_FAB2_LIB.BASEBOARD_FAB2(SCH_1):PAGE227
     2    GND @BASEBOARD_FAB2_LIB.BASEBOARD_FAB2(SCH_1):GND   I109 @BASEBOARD_FAB2_LIB.BASEBOARD_FAB2(SCH_1):PAGE227

 CT8 CAP_0402LF-1000PF,50V,10%,X7R,A
     1 A_TSENSE_PVDDQ_KLM @BASEBOARD_FAB2_LIB.BASEBOARD_FAB2(SCH_1):A_TSENSE_PVDDQ_KLM   I114 @BASEBOARD_FAB2_LIB.BASEBOARD_FAB2(SCH_1):PAGE227
     2    GND @BASEBOARD_FAB2_LIB.BASEBOARD_FAB2(SCH_1):GND   I114 @BASEBOARD_FAB2_LIB.BASEBOARD_FAB2(SCH_1):PAGE227

 CT9 CAP_0402LF-1000PF,50V,10%,X7R,A
     1 VR_PVDDQ_KLM_PH1_SW @BASEBOARD_FAB2_LIB.BASEBOARD_FAB2(SCH_1):VR_PVDDQ_KLM_PH1_SW   I134 @BASEBOARD_FAB2_LIB.BASEBOARD_FAB2(SCH_1):PAGE227
     2 VR_PVDDQ_KLM_PH1_RC @BASEBOARD_FAB2_LIB.BASEBOARD_FAB2(SCH_1):VR_PVDDQ_KLM_PH1_RC   I134 @BASEBOARD_FAB2_LIB.BASEBOARD_FAB2(SCH_1):PAGE227

CT10 CAP_0402LF-1000PF,50V,10%,X7R,A
     1 A_TSENSE_PVDDQ_KLM @BASEBOARD_FAB2_LIB.BASEBOARD_FAB2(SCH_1):A_TSENSE_PVDDQ_KLM   I119 @BASEBOARD_FAB2_LIB.BASEBOARD_FAB2(SCH_1):PAGE227
     2    GND @BASEBOARD_FAB2_LIB.BASEBOARD_FAB2(SCH_1):GND   I119 @BASEBOARD_FAB2_LIB.BASEBOARD_FAB2(SCH_1):PAGE227

CT11 CAP_0402LF-1000PF,50V,10%,X7R,A
     1 VR_PVDDQ_KLM_PH2_SW @BASEBOARD_FAB2_LIB.BASEBOARD_FAB2(SCH_1):VR_PVDDQ_KLM_PH2_SW   I135 @BASEBOARD_FAB2_LIB.BASEBOARD_FAB2(SCH_1):PAGE227
     2 VR_PVDDQ_KLM_PH2_RC @BASEBOARD_FAB2_LIB.BASEBOARD_FAB2(SCH_1):VR_PVDDQ_KLM_PH2_RC   I135 @BASEBOARD_FAB2_LIB.BASEBOARD_FAB2(SCH_1):PAGE227

CT12 CAP_A_0402V-0.1UF,16V,10%,X7R,A
     1 VR_PVDDQ_KLM_AIREF2 @BASEBOARD_FAB2_LIB.BASEBOARD_FAB2(SCH_1):VR_PVDDQ_KLM_AIREF2   I122 @BASEBOARD_FAB2_LIB.BASEBOARD_FAB2(SCH_1):PAGE227
     2    GND @BASEBOARD_FAB2_LIB.BASEBOARD_FAB2(SCH_1):GND   I122 @BASEBOARD_FAB2_LIB.BASEBOARD_FAB2(SCH_1):PAGE227

CT13 CAP_A_0402V-0.1UF,16V,10%,X7R,A
     1 VR_PVCCIN_CPU1_AIREF5 @BASEBOARD_FAB2_LIB.BASEBOARD_FAB2(SCH_1):VR_PVCCIN_CPU1_AIREF5    I62 @BASEBOARD_FAB2_LIB.BASEBOARD_FAB2(SCH_1):PAGE209
     2    GND @BASEBOARD_FAB2_LIB.BASEBOARD_FAB2(SCH_1):GND    I62 @BASEBOARD_FAB2_LIB.BASEBOARD_FAB2(SCH_1):PAGE209

CT14 CAP_0402LF-1000PF,50V,10%,X7R,A
     1 VR_PVCCIN_CPU1_PHASE5 @BASEBOARD_FAB2_LIB.BASEBOARD_FAB2(SCH_1):VR_PVCCIN_CPU1_PHASE5    I73 @BASEBOARD_FAB2_LIB.BASEBOARD_FAB2(SCH_1):PAGE209
     2 VR_PVCCIN_CPU1_PHASE5_RC @BASEBOARD_FAB2_LIB.BASEBOARD_FAB2(SCH_1):VR_PVCCIN_CPU1_PHASE5_RC    I73 @BASEBOARD_FAB2_LIB.BASEBOARD_FAB2(SCH_1):PAGE209

CT15 CAP_0402LF-1000PF,50V,10%,X7R,A
     1 A_TSENSE_PVCCIN_CPU1 @BASEBOARD_FAB2_LIB.BASEBOARD_FAB2(SCH_1):A_TSENSE_PVCCIN_CPU1    I67 @BASEBOARD_FAB2_LIB.BASEBOARD_FAB2(SCH_1):PAGE209
     2    GND @BASEBOARD_FAB2_LIB.BASEBOARD_FAB2(SCH_1):GND    I67 @BASEBOARD_FAB2_LIB.BASEBOARD_FAB2(SCH_1):PAGE209

CT16 CAP_A_0402V-0.1UF,16V,10%,X7R,A
     1 VR_PVCCIN_CPU1_AIREF3 @BASEBOARD_FAB2_LIB.BASEBOARD_FAB2(SCH_1):VR_PVCCIN_CPU1_AIREF3    I80 @BASEBOARD_FAB2_LIB.BASEBOARD_FAB2(SCH_1):PAGE208
     2    GND @BASEBOARD_FAB2_LIB.BASEBOARD_FAB2(SCH_1):GND    I80 @BASEBOARD_FAB2_LIB.BASEBOARD_FAB2(SCH_1):PAGE208

CT18 CAP_0402LF-1000PF,50V,10%,X7R,A
     1 VR_PVCCIN_CPU1_PHASE3 @BASEBOARD_FAB2_LIB.BASEBOARD_FAB2(SCH_1):VR_PVCCIN_CPU1_PHASE3   I104 @BASEBOARD_FAB2_LIB.BASEBOARD_FAB2(SCH_1):PAGE208
     2 VR_PVCCIN_CPU1_PHASE3_RC @BASEBOARD_FAB2_LIB.BASEBOARD_FAB2(SCH_1):VR_PVCCIN_CPU1_PHASE3_RC   I104 @BASEBOARD_FAB2_LIB.BASEBOARD_FAB2(SCH_1):PAGE208

CT19 CAP_0402LF-1000PF,50V,10%,X7R,A
     1 A_TSENSE_PVCCIN_CPU1 @BASEBOARD_FAB2_LIB.BASEBOARD_FAB2(SCH_1):A_TSENSE_PVCCIN_CPU1    I90 @BASEBOARD_FAB2_LIB.BASEBOARD_FAB2(SCH_1):PAGE208
     2    GND @BASEBOARD_FAB2_LIB.BASEBOARD_FAB2(SCH_1):GND    I90 @BASEBOARD_FAB2_LIB.BASEBOARD_FAB2(SCH_1):PAGE208

CT20 CAP_0402LF-1000PF,50V,10%,X7R,A
     1 VR_PVCCIN_CPU1_PHASE4 @BASEBOARD_FAB2_LIB.BASEBOARD_FAB2(SCH_1):VR_PVCCIN_CPU1_PHASE4   I105 @BASEBOARD_FAB2_LIB.BASEBOARD_FAB2(SCH_1):PAGE208
     2 VR_PVCCIN_CPU1_PHASE4_RC @BASEBOARD_FAB2_LIB.BASEBOARD_FAB2(SCH_1):VR_PVCCIN_CPU1_PHASE4_RC   I105 @BASEBOARD_FAB2_LIB.BASEBOARD_FAB2(SCH_1):PAGE208

CT21 CAP_A_0402V-0.1UF,16V,10%,X7R,A
     1 VR_PVCCIN_CPU1_AIREF4 @BASEBOARD_FAB2_LIB.BASEBOARD_FAB2(SCH_1):VR_PVCCIN_CPU1_AIREF4    I87 @BASEBOARD_FAB2_LIB.BASEBOARD_FAB2(SCH_1):PAGE208
     2    GND @BASEBOARD_FAB2_LIB.BASEBOARD_FAB2(SCH_1):GND    I87 @BASEBOARD_FAB2_LIB.BASEBOARD_FAB2(SCH_1):PAGE208

CT22 CAP_0402LF-1000PF,50V,10%,X7R,A
     1 A_TSENSE_PVCCIN_CPU1 @BASEBOARD_FAB2_LIB.BASEBOARD_FAB2(SCH_1):A_TSENSE_PVCCIN_CPU1    I74 @BASEBOARD_FAB2_LIB.BASEBOARD_FAB2(SCH_1):PAGE207
     2    GND @BASEBOARD_FAB2_LIB.BASEBOARD_FAB2(SCH_1):GND    I74 @BASEBOARD_FAB2_LIB.BASEBOARD_FAB2(SCH_1):PAGE207

CT23 CAP_0402LF-1000PF,50V,10%,X7R,A
     1 VR_PVCCIN_CPU1_PHASE1 @BASEBOARD_FAB2_LIB.BASEBOARD_FAB2(SCH_1):VR_PVCCIN_CPU1_PHASE1    I95 @BASEBOARD_FAB2_LIB.BASEBOARD_FAB2(SCH_1):PAGE207
     2 VR_PVCCIN_CPU1_PHASE1_RC @BASEBOARD_FAB2_LIB.BASEBOARD_FAB2(SCH_1):VR_PVCCIN_CPU1_PHASE1_RC    I95 @BASEBOARD_FAB2_LIB.BASEBOARD_FAB2(SCH_1):PAGE207

CT24 CAP_A_0402V-0.1UF,16V,10%,X7R,A
     1 VR_PVCCIN_CPU1_AIREF1 @BASEBOARD_FAB2_LIB.BASEBOARD_FAB2(SCH_1):VR_PVCCIN_CPU1_AIREF1    I71 @BASEBOARD_FAB2_LIB.BASEBOARD_FAB2(SCH_1):PAGE207
     2    GND @BASEBOARD_FAB2_LIB.BASEBOARD_FAB2(SCH_1):GND    I71 @BASEBOARD_FAB2_LIB.BASEBOARD_FAB2(SCH_1):PAGE207

CT25 CAP_A_0402V-0.1UF,16V,10%,X7R,A
     1 VR_PVCCIN_CPU1_AIREF2 @BASEBOARD_FAB2_LIB.BASEBOARD_FAB2(SCH_1):VR_PVCCIN_CPU1_AIREF2    I81 @BASEBOARD_FAB2_LIB.BASEBOARD_FAB2(SCH_1):PAGE207
     2    GND @BASEBOARD_FAB2_LIB.BASEBOARD_FAB2(SCH_1):GND    I81 @BASEBOARD_FAB2_LIB.BASEBOARD_FAB2(SCH_1):PAGE207

CT26 CAP_0402LF-1000PF,50V,10%,X7R,A
     1 A_TSENSE_PVCCIN_CPU1 @BASEBOARD_FAB2_LIB.BASEBOARD_FAB2(SCH_1):A_TSENSE_PVCCIN_CPU1    I82 @BASEBOARD_FAB2_LIB.BASEBOARD_FAB2(SCH_1):PAGE207
     2    GND @BASEBOARD_FAB2_LIB.BASEBOARD_FAB2(SCH_1):GND    I82 @BASEBOARD_FAB2_LIB.BASEBOARD_FAB2(SCH_1):PAGE207

CT27 CAP_0402LF-1000PF,50V,10%,X7R,A
     1 VR_PVCCIN_CPU1_PHASE2 @BASEBOARD_FAB2_LIB.BASEBOARD_FAB2(SCH_1):VR_PVCCIN_CPU1_PHASE2    I96 @BASEBOARD_FAB2_LIB.BASEBOARD_FAB2(SCH_1):PAGE207
     2 VR_PVCCIN_CPU1_PHASE2_RC @BASEBOARD_FAB2_LIB.BASEBOARD_FAB2(SCH_1):VR_PVCCIN_CPU1_PHASE2_RC    I96 @BASEBOARD_FAB2_LIB.BASEBOARD_FAB2(SCH_1):PAGE207

CT28 CAP_0402LF-1000PF,50V,10%,X7R,A
     1 A_TSENSE_PVDDQ_GHJ @BASEBOARD_FAB2_LIB.BASEBOARD_FAB2(SCH_1):A_TSENSE_PVDDQ_GHJ   I122 @BASEBOARD_FAB2_LIB.BASEBOARD_FAB2(SCH_1):PAGE224
     2    GND @BASEBOARD_FAB2_LIB.BASEBOARD_FAB2(SCH_1):GND   I122 @BASEBOARD_FAB2_LIB.BASEBOARD_FAB2(SCH_1):PAGE224

CT29 CAP_0402LF-1000PF,50V,10%,X7R,A
     1 VR_PVDDQ_GHJ_PH1_SW @BASEBOARD_FAB2_LIB.BASEBOARD_FAB2(SCH_1):VR_PVDDQ_GHJ_PH1_SW   I140 @BASEBOARD_FAB2_LIB.BASEBOARD_FAB2(SCH_1):PAGE224
     2 VR_PVDDQ_GHJ_PH1_SW_RC @BASEBOARD_FAB2_LIB.BASEBOARD_FAB2(SCH_1):VR_PVDDQ_GHJ_PH1_SW_RC   I140 @BASEBOARD_FAB2_LIB.BASEBOARD_FAB2(SCH_1):PAGE224

CT30 CAP_A_0402V-0.1UF,16V,10%,X7R,A
     1 VR_PVDDQ_GHJ_AIREF1 @BASEBOARD_FAB2_LIB.BASEBOARD_FAB2(SCH_1):VR_PVDDQ_GHJ_AIREF1   I117 @BASEBOARD_FAB2_LIB.BASEBOARD_FAB2(SCH_1):PAGE224
     2    GND @BASEBOARD_FAB2_LIB.BASEBOARD_FAB2(SCH_1):GND   I117 @BASEBOARD_FAB2_LIB.BASEBOARD_FAB2(SCH_1):PAGE224

CT31 CAP_A_0402V-0.1UF,16V,10%,X7R,A
     1 VR_PVDDQ_GHJ_AIREF2 @BASEBOARD_FAB2_LIB.BASEBOARD_FAB2(SCH_1):VR_PVDDQ_GHJ_AIREF2   I124 @BASEBOARD_FAB2_LIB.BASEBOARD_FAB2(SCH_1):PAGE224
     2    GND @BASEBOARD_FAB2_LIB.BASEBOARD_FAB2(SCH_1):GND   I124 @BASEBOARD_FAB2_LIB.BASEBOARD_FAB2(SCH_1):PAGE224

CT32 CAP_0402LF-1000PF,50V,10%,X7R,A
     1 A_TSENSE_PVDDQ_GHJ @BASEBOARD_FAB2_LIB.BASEBOARD_FAB2(SCH_1):A_TSENSE_PVDDQ_GHJ   I130 @BASEBOARD_FAB2_LIB.BASEBOARD_FAB2(SCH_1):PAGE224
     2    GND @BASEBOARD_FAB2_LIB.BASEBOARD_FAB2(SCH_1):GND   I130 @BASEBOARD_FAB2_LIB.BASEBOARD_FAB2(SCH_1):PAGE224

CT33 CAP_0402LF-1000PF,50V,10%,X7R,A
     1 VR_PVDDQ_GHJ_PH2_SW @BASEBOARD_FAB2_LIB.BASEBOARD_FAB2(SCH_1):VR_PVDDQ_GHJ_PH2_SW   I141 @BASEBOARD_FAB2_LIB.BASEBOARD_FAB2(SCH_1):PAGE224
     2 VR_PVDDQ_GHJ_PH2_SW_RC @BASEBOARD_FAB2_LIB.BASEBOARD_FAB2(SCH_1):VR_PVDDQ_GHJ_PH2_SW_RC   I141 @BASEBOARD_FAB2_LIB.BASEBOARD_FAB2(SCH_1):PAGE224

CT34 CAP_0402LF-1000PF,50V,10%,X7R,A
     1 A_TSENSE_PVCCIN_CPU0 @BASEBOARD_FAB2_LIB.BASEBOARD_FAB2(SCH_1):A_TSENSE_PVCCIN_CPU0    I88 @BASEBOARD_FAB2_LIB.BASEBOARD_FAB2(SCH_1):PAGE204
     2    GND @BASEBOARD_FAB2_LIB.BASEBOARD_FAB2(SCH_1):GND    I88 @BASEBOARD_FAB2_LIB.BASEBOARD_FAB2(SCH_1):PAGE204

CT35 CAP_0402LF-1000PF,50V,10%,X7R,A
     1 VR_PVCCIN_CPU0_PHASE5 @BASEBOARD_FAB2_LIB.BASEBOARD_FAB2(SCH_1):VR_PVCCIN_CPU0_PHASE5    I97 @BASEBOARD_FAB2_LIB.BASEBOARD_FAB2(SCH_1):PAGE204
     2 VR_PVCCIN_CPU0_PHASE5_RC @BASEBOARD_FAB2_LIB.BASEBOARD_FAB2(SCH_1):VR_PVCCIN_CPU0_PHASE5_RC    I97 @BASEBOARD_FAB2_LIB.BASEBOARD_FAB2(SCH_1):PAGE204

CT36 CAP_A_0402V-0.1UF,16V,10%,X7R,A
     1 VR_PVCCIN_CPU0_AIREF5 @BASEBOARD_FAB2_LIB.BASEBOARD_FAB2(SCH_1):VR_PVCCIN_CPU0_AIREF5    I85 @BASEBOARD_FAB2_LIB.BASEBOARD_FAB2(SCH_1):PAGE204
     2    GND @BASEBOARD_FAB2_LIB.BASEBOARD_FAB2(SCH_1):GND    I85 @BASEBOARD_FAB2_LIB.BASEBOARD_FAB2(SCH_1):PAGE204

CT37 CAP_0402LF-1000PF,50V,10%,X7R,A
     1 A_TSENSE_PVCCIN_CPU0 @BASEBOARD_FAB2_LIB.BASEBOARD_FAB2(SCH_1):A_TSENSE_PVCCIN_CPU0    I99 @BASEBOARD_FAB2_LIB.BASEBOARD_FAB2(SCH_1):PAGE203
     2    GND @BASEBOARD_FAB2_LIB.BASEBOARD_FAB2(SCH_1):GND    I99 @BASEBOARD_FAB2_LIB.BASEBOARD_FAB2(SCH_1):PAGE203

CT38 CAP_0402LF-1000PF,50V,10%,X7R,A
     1 VR_PVCCIN_CPU0_PHASE3 @BASEBOARD_FAB2_LIB.BASEBOARD_FAB2(SCH_1):VR_PVCCIN_CPU0_PHASE3   I118 @BASEBOARD_FAB2_LIB.BASEBOARD_FAB2(SCH_1):PAGE203
     2 VR_PVCCIN_CPU0_PHASE3_RC @BASEBOARD_FAB2_LIB.BASEBOARD_FAB2(SCH_1):VR_PVCCIN_CPU0_PHASE3_RC   I118 @BASEBOARD_FAB2_LIB.BASEBOARD_FAB2(SCH_1):PAGE203

CT39 CAP_A_0402V-0.1UF,16V,10%,X7R,A
     1 VR_PVCCIN_CPU0_AIREF3 @BASEBOARD_FAB2_LIB.BASEBOARD_FAB2(SCH_1):VR_PVCCIN_CPU0_AIREF3    I96 @BASEBOARD_FAB2_LIB.BASEBOARD_FAB2(SCH_1):PAGE203
     2    GND @BASEBOARD_FAB2_LIB.BASEBOARD_FAB2(SCH_1):GND    I96 @BASEBOARD_FAB2_LIB.BASEBOARD_FAB2(SCH_1):PAGE203

CT40 CAP_A_0402V-0.1UF,16V,10%,X7R,A
     1 VR_PVCCIN_CPU0_AIREF4 @BASEBOARD_FAB2_LIB.BASEBOARD_FAB2(SCH_1):VR_PVCCIN_CPU0_AIREF4    I93 @BASEBOARD_FAB2_LIB.BASEBOARD_FAB2(SCH_1):PAGE203
     2    GND @BASEBOARD_FAB2_LIB.BASEBOARD_FAB2(SCH_1):GND    I93 @BASEBOARD_FAB2_LIB.BASEBOARD_FAB2(SCH_1):PAGE203

CT41 CAP_0402LF-1000PF,50V,10%,X7R,A
     1 VR_PVCCIN_CPU0_PHASE4 @BASEBOARD_FAB2_LIB.BASEBOARD_FAB2(SCH_1):VR_PVCCIN_CPU0_PHASE4   I119 @BASEBOARD_FAB2_LIB.BASEBOARD_FAB2(SCH_1):PAGE203
     2 VR_PVCCIN_CPU0_PHASE4_RC @BASEBOARD_FAB2_LIB.BASEBOARD_FAB2(SCH_1):VR_PVCCIN_CPU0_PHASE4_RC   I119 @BASEBOARD_FAB2_LIB.BASEBOARD_FAB2(SCH_1):PAGE203

CT42 CAP_0402LF-1000PF,50V,10%,X7R,A
     1 A_TSENSE_PVCCIN_CPU0 @BASEBOARD_FAB2_LIB.BASEBOARD_FAB2(SCH_1):A_TSENSE_PVCCIN_CPU0   I108 @BASEBOARD_FAB2_LIB.BASEBOARD_FAB2(SCH_1):PAGE203
     2    GND @BASEBOARD_FAB2_LIB.BASEBOARD_FAB2(SCH_1):GND   I108 @BASEBOARD_FAB2_LIB.BASEBOARD_FAB2(SCH_1):PAGE203

CT43 CAP_0402LF-1000PF,50V,10%,X7R,A
     1 A_TSENSE_PVDDQ_DEF @BASEBOARD_FAB2_LIB.BASEBOARD_FAB2(SCH_1):A_TSENSE_PVDDQ_DEF   I124 @BASEBOARD_FAB2_LIB.BASEBOARD_FAB2(SCH_1):PAGE219
     2    GND @BASEBOARD_FAB2_LIB.BASEBOARD_FAB2(SCH_1):GND   I124 @BASEBOARD_FAB2_LIB.BASEBOARD_FAB2(SCH_1):PAGE219

CT44 CAP_0402LF-1000PF,50V,10%,X7R,A
     1 VR_PVDDQ_DEF_PH1_SW @BASEBOARD_FAB2_LIB.BASEBOARD_FAB2(SCH_1):VR_PVDDQ_DEF_PH1_SW   I137 @BASEBOARD_FAB2_LIB.BASEBOARD_FAB2(SCH_1):PAGE219
     2 VR_PVDDQ_DEF_PH1_SW_RC @BASEBOARD_FAB2_LIB.BASEBOARD_FAB2(SCH_1):VR_PVDDQ_DEF_PH1_SW_RC   I137 @BASEBOARD_FAB2_LIB.BASEBOARD_FAB2(SCH_1):PAGE219

CT45 CAP_A_0402V-0.1UF,16V,10%,X7R,A
     1 VR_PVDDQ_DEF_AIREF1 @BASEBOARD_FAB2_LIB.BASEBOARD_FAB2(SCH_1):VR_PVDDQ_DEF_AIREF1   I116 @BASEBOARD_FAB2_LIB.BASEBOARD_FAB2(SCH_1):PAGE219
     2    GND @BASEBOARD_FAB2_LIB.BASEBOARD_FAB2(SCH_1):GND   I116 @BASEBOARD_FAB2_LIB.BASEBOARD_FAB2(SCH_1):PAGE219

CT46 CAP_A_0402V-0.1UF,16V,10%,X7R,A
     1 VR_PVDDQ_DEF_AIREF2 @BASEBOARD_FAB2_LIB.BASEBOARD_FAB2(SCH_1):VR_PVDDQ_DEF_AIREF2   I113 @BASEBOARD_FAB2_LIB.BASEBOARD_FAB2(SCH_1):PAGE219
     2    GND @BASEBOARD_FAB2_LIB.BASEBOARD_FAB2(SCH_1):GND   I113 @BASEBOARD_FAB2_LIB.BASEBOARD_FAB2(SCH_1):PAGE219

CT47 CAP_0402LF-1000PF,50V,10%,X7R,A
     1 VR_PVDDQ_DEF_PH2_SW @BASEBOARD_FAB2_LIB.BASEBOARD_FAB2(SCH_1):VR_PVDDQ_DEF_PH2_SW   I138 @BASEBOARD_FAB2_LIB.BASEBOARD_FAB2(SCH_1):PAGE219
     2 VR_PVDDQ_DEF_PH2_SW_RC @BASEBOARD_FAB2_LIB.BASEBOARD_FAB2(SCH_1):VR_PVDDQ_DEF_PH2_SW_RC   I138 @BASEBOARD_FAB2_LIB.BASEBOARD_FAB2(SCH_1):PAGE219

CT48 CAP_0402LF-1000PF,50V,10%,X7R,A
     1 A_TSENSE_PVDDQ_DEF @BASEBOARD_FAB2_LIB.BASEBOARD_FAB2(SCH_1):A_TSENSE_PVDDQ_DEF   I119 @BASEBOARD_FAB2_LIB.BASEBOARD_FAB2(SCH_1):PAGE219
     2    GND @BASEBOARD_FAB2_LIB.BASEBOARD_FAB2(SCH_1):GND   I119 @BASEBOARD_FAB2_LIB.BASEBOARD_FAB2(SCH_1):PAGE219

CT49 CAP_0402LF-1000PF,50V,10%,X7R,A
     1 A_TSENSE_PVDDQ_ABC @BASEBOARD_FAB2_LIB.BASEBOARD_FAB2(SCH_1):A_TSENSE_PVDDQ_ABC   I118 @BASEBOARD_FAB2_LIB.BASEBOARD_FAB2(SCH_1):PAGE216
     2    GND @BASEBOARD_FAB2_LIB.BASEBOARD_FAB2(SCH_1):GND   I118 @BASEBOARD_FAB2_LIB.BASEBOARD_FAB2(SCH_1):PAGE216

CT50 CAP_0402LF-1000PF,50V,10%,X7R,A
     1 VR_PVDDQ_ABC_PH1_SW @BASEBOARD_FAB2_LIB.BASEBOARD_FAB2(SCH_1):VR_PVDDQ_ABC_PH1_SW   I135 @BASEBOARD_FAB2_LIB.BASEBOARD_FAB2(SCH_1):PAGE216
     2 VR_PVDDQ_ABC_PH1_SW_RC @BASEBOARD_FAB2_LIB.BASEBOARD_FAB2(SCH_1):VR_PVDDQ_ABC_PH1_SW_RC   I135 @BASEBOARD_FAB2_LIB.BASEBOARD_FAB2(SCH_1):PAGE216

CT51 CAP_A_0402V-0.1UF,16V,10%,X7R,A
     1 VR_PVDDQ_ABC_AIREF1 @BASEBOARD_FAB2_LIB.BASEBOARD_FAB2(SCH_1):VR_PVDDQ_ABC_AIREF1   I108 @BASEBOARD_FAB2_LIB.BASEBOARD_FAB2(SCH_1):PAGE216
     2    GND @BASEBOARD_FAB2_LIB.BASEBOARD_FAB2(SCH_1):GND   I108 @BASEBOARD_FAB2_LIB.BASEBOARD_FAB2(SCH_1):PAGE216

CT52 CAP_A_0402V-0.1UF,16V,10%,X7R,A
     1 VR_PVDDQ_ABC_AIREF2 @BASEBOARD_FAB2_LIB.BASEBOARD_FAB2(SCH_1):VR_PVDDQ_ABC_AIREF2   I111 @BASEBOARD_FAB2_LIB.BASEBOARD_FAB2(SCH_1):PAGE216
     2    GND @BASEBOARD_FAB2_LIB.BASEBOARD_FAB2(SCH_1):GND   I111 @BASEBOARD_FAB2_LIB.BASEBOARD_FAB2(SCH_1):PAGE216

CT53 CAP_0402LF-1000PF,50V,10%,X7R,A
     1 VR_PVDDQ_ABC_PH2_SW @BASEBOARD_FAB2_LIB.BASEBOARD_FAB2(SCH_1):VR_PVDDQ_ABC_PH2_SW   I136 @BASEBOARD_FAB2_LIB.BASEBOARD_FAB2(SCH_1):PAGE216
     2 VR_PVDDQ_ABC_PH2_SW_RC @BASEBOARD_FAB2_LIB.BASEBOARD_FAB2(SCH_1):VR_PVDDQ_ABC_PH2_SW_RC   I136 @BASEBOARD_FAB2_LIB.BASEBOARD_FAB2(SCH_1):PAGE216

CT54 CAP_0402LF-1000PF,50V,10%,X7R,A
     1 A_TSENSE_PVDDQ_ABC @BASEBOARD_FAB2_LIB.BASEBOARD_FAB2(SCH_1):A_TSENSE_PVDDQ_ABC   I121 @BASEBOARD_FAB2_LIB.BASEBOARD_FAB2(SCH_1):PAGE216
     2    GND @BASEBOARD_FAB2_LIB.BASEBOARD_FAB2(SCH_1):GND   I121 @BASEBOARD_FAB2_LIB.BASEBOARD_FAB2(SCH_1):PAGE216

CT55 CAP_0402LF-1000PF,50V,10%,X7R,A
     1 A_TSENSE_PVSA_CPU1 @BASEBOARD_FAB2_LIB.BASEBOARD_FAB2(SCH_1):A_TSENSE_PVSA_CPU1    I60 @BASEBOARD_FAB2_LIB.BASEBOARD_FAB2(SCH_1):PAGE210
     2    GND @BASEBOARD_FAB2_LIB.BASEBOARD_FAB2(SCH_1):GND    I60 @BASEBOARD_FAB2_LIB.BASEBOARD_FAB2(SCH_1):PAGE210

CT56 CAP_0402LF-1000PF,50V,10%,X7R,A
     1 VR_PVSA_CPU1_PHASE_SW @BASEBOARD_FAB2_LIB.BASEBOARD_FAB2(SCH_1):VR_PVSA_CPU1_PHASE_SW    I66 @BASEBOARD_FAB2_LIB.BASEBOARD_FAB2(SCH_1):PAGE210
     2 VR_PVSA_CPU1_PHASE_SW_RC @BASEBOARD_FAB2_LIB.BASEBOARD_FAB2(SCH_1):VR_PVSA_CPU1_PHASE_SW_RC    I66 @BASEBOARD_FAB2_LIB.BASEBOARD_FAB2(SCH_1):PAGE210

CT57 CAP_A_0402V-0.1UF,16V,10%,X7R,A
     1 VR_PVSA_CPU1_BIREF1 @BASEBOARD_FAB2_LIB.BASEBOARD_FAB2(SCH_1):VR_PVSA_CPU1_BIREF1    I55 @BASEBOARD_FAB2_LIB.BASEBOARD_FAB2(SCH_1):PAGE210
     2    GND @BASEBOARD_FAB2_LIB.BASEBOARD_FAB2(SCH_1):GND    I55 @BASEBOARD_FAB2_LIB.BASEBOARD_FAB2(SCH_1):PAGE210

CT58 CAP_0402LF-1000PF,50V,10%,X7R,A
     1 A_TSENSE_PVSA_CPU0 @BASEBOARD_FAB2_LIB.BASEBOARD_FAB2(SCH_1):A_TSENSE_PVSA_CPU0    I65 @BASEBOARD_FAB2_LIB.BASEBOARD_FAB2(SCH_1):PAGE205
     2    GND @BASEBOARD_FAB2_LIB.BASEBOARD_FAB2(SCH_1):GND    I65 @BASEBOARD_FAB2_LIB.BASEBOARD_FAB2(SCH_1):PAGE205

CT59 CAP_0402LF-1000PF,50V,10%,X7R,A
     1 VR_PVSA_CPU0_PHASE_SW @BASEBOARD_FAB2_LIB.BASEBOARD_FAB2(SCH_1):VR_PVSA_CPU0_PHASE_SW    I76 @BASEBOARD_FAB2_LIB.BASEBOARD_FAB2(SCH_1):PAGE205
     2 VR_PVSA_CPU0_PHASE_SW_RC @BASEBOARD_FAB2_LIB.BASEBOARD_FAB2(SCH_1):VR_PVSA_CPU0_PHASE_SW_RC    I76 @BASEBOARD_FAB2_LIB.BASEBOARD_FAB2(SCH_1):PAGE205

CT60 CAP_A_0402V-0.1UF,16V,10%,X7R,A
     1 VR_PVSA_CPU0_BIREF1 @BASEBOARD_FAB2_LIB.BASEBOARD_FAB2(SCH_1):VR_PVSA_CPU0_BIREF1    I69 @BASEBOARD_FAB2_LIB.BASEBOARD_FAB2(SCH_1):PAGE205
     2    GND @BASEBOARD_FAB2_LIB.BASEBOARD_FAB2(SCH_1):GND    I69 @BASEBOARD_FAB2_LIB.BASEBOARD_FAB2(SCH_1):PAGE205

CT61 CAP_0402LF-1000PF,50V,10%,X7R,A
     1 A_TSENSE_PVCCIO_CPU1 @BASEBOARD_FAB2_LIB.BASEBOARD_FAB2(SCH_1):A_TSENSE_PVCCIO_CPU1   I134 @BASEBOARD_FAB2_LIB.BASEBOARD_FAB2(SCH_1):PAGE214
     2    GND @BASEBOARD_FAB2_LIB.BASEBOARD_FAB2(SCH_1):GND   I134 @BASEBOARD_FAB2_LIB.BASEBOARD_FAB2(SCH_1):PAGE214

CT62 CAP_0402LF-1000PF,50V,10%,X7R,A
     1 VR_PVCCIO_CPU1_PH1_SW @BASEBOARD_FAB2_LIB.BASEBOARD_FAB2(SCH_1):VR_PVCCIO_CPU1_PH1_SW   I143 @BASEBOARD_FAB2_LIB.BASEBOARD_FAB2(SCH_1):PAGE214
     2 VR_PVCCIO_CPU1_PH1_SW_RC @BASEBOARD_FAB2_LIB.BASEBOARD_FAB2(SCH_1):VR_PVCCIO_CPU1_PH1_SW_RC   I143 @BASEBOARD_FAB2_LIB.BASEBOARD_FAB2(SCH_1):PAGE214

CT63 CAP_A_0402V-0.1UF,16V,10%,X7R,A
     1 VR_PVCCIO_CPU1_AIREF1 @BASEBOARD_FAB2_LIB.BASEBOARD_FAB2(SCH_1):VR_PVCCIO_CPU1_AIREF1   I137 @BASEBOARD_FAB2_LIB.BASEBOARD_FAB2(SCH_1):PAGE214
     2    GND @BASEBOARD_FAB2_LIB.BASEBOARD_FAB2(SCH_1):GND   I137 @BASEBOARD_FAB2_LIB.BASEBOARD_FAB2(SCH_1):PAGE214

CT64 CAP_0402LF-1000PF,50V,10%,X7R,A
     1 A_TSENSE_PVNN_PCH_TMON @BASEBOARD_FAB2_LIB.BASEBOARD_FAB2(SCH_1):A_TSENSE_PVNN_PCH_TMON   I136 @BASEBOARD_FAB2_LIB.BASEBOARD_FAB2(SCH_1):PAGE236
     2    GND @BASEBOARD_FAB2_LIB.BASEBOARD_FAB2(SCH_1):GND   I136 @BASEBOARD_FAB2_LIB.BASEBOARD_FAB2(SCH_1):PAGE236

CT65 CAP_0402LF-1000PF,50V,10%,X7R,A
     1 VR_PVNN_PCH_PH1_PHASE_SW @BASEBOARD_FAB2_LIB.BASEBOARD_FAB2(SCH_1):VR_PVNN_PCH_PH1_PHASE_SW   I149 @BASEBOARD_FAB2_LIB.BASEBOARD_FAB2(SCH_1):PAGE236
     2 VR_PVNN_PCH_PH1_PHASE_SW_RC @BASEBOARD_FAB2_LIB.BASEBOARD_FAB2(SCH_1):VR_PVNN_PCH_PH1_PHASE_SW_RC   I149 @BASEBOARD_FAB2_LIB.BASEBOARD_FAB2(SCH_1):PAGE236

CT66 CAP_A_0402V-0.1UF,16V,10%,X7R,A
     1 VR_PVNN_PCH_AIREF1 @BASEBOARD_FAB2_LIB.BASEBOARD_FAB2(SCH_1):VR_PVNN_PCH_AIREF1   I127 @BASEBOARD_FAB2_LIB.BASEBOARD_FAB2(SCH_1):PAGE236
     2    GND @BASEBOARD_FAB2_LIB.BASEBOARD_FAB2(SCH_1):GND   I127 @BASEBOARD_FAB2_LIB.BASEBOARD_FAB2(SCH_1):PAGE236

CT67 CAP_A_0402V-0.1UF,16V,10%,X7R,A
     1 VR_P1V05_PCH_BIREF1 @BASEBOARD_FAB2_LIB.BASEBOARD_FAB2(SCH_1):VR_P1V05_PCH_BIREF1   I124 @BASEBOARD_FAB2_LIB.BASEBOARD_FAB2(SCH_1):PAGE236
     2    GND @BASEBOARD_FAB2_LIB.BASEBOARD_FAB2(SCH_1):GND   I124 @BASEBOARD_FAB2_LIB.BASEBOARD_FAB2(SCH_1):PAGE236

CT68 CAP_0402LF-1000PF,50V,10%,X7R,A
     1 VR_P1V05_PCH_STBY_PH1_PHASE_SW @BASEBOARD_FAB2_LIB.BASEBOARD_FAB2(SCH_1):VR_P1V05_PCH_STBY_PH1_PHASE_SW   I150 @BASEBOARD_FAB2_LIB.BASEBOARD_FAB2(SCH_1):PAGE236
     2 VR_P1V05_PCH_STBY_PH1_SW_RC @BASEBOARD_FAB2_LIB.BASEBOARD_FAB2(SCH_1):VR_P1V05_PCH_STBY_PH1_SW_RC   I150 @BASEBOARD_FAB2_LIB.BASEBOARD_FAB2(SCH_1):PAGE236

CT69 CAP_0402LF-1000PF,50V,10%,X7R,A
     1 A_TSENSE_P1V05_PCH_STBY_TMON @BASEBOARD_FAB2_LIB.BASEBOARD_FAB2(SCH_1):A_TSENSE_P1V05_PCH_STBY_TMON   I134 @BASEBOARD_FAB2_LIB.BASEBOARD_FAB2(SCH_1):PAGE236
     2    GND @BASEBOARD_FAB2_LIB.BASEBOARD_FAB2(SCH_1):GND   I134 @BASEBOARD_FAB2_LIB.BASEBOARD_FAB2(SCH_1):PAGE236

CT70 CAP_A_0402V-0.1UF,16V,10%,X7R,A
     1 VR_PVCCIO_CPU0_AIREF1 @BASEBOARD_FAB2_LIB.BASEBOARD_FAB2(SCH_1):VR_PVCCIO_CPU0_AIREF1   I106 @BASEBOARD_FAB2_LIB.BASEBOARD_FAB2(SCH_1):PAGE212
     2    GND @BASEBOARD_FAB2_LIB.BASEBOARD_FAB2(SCH_1):GND   I106 @BASEBOARD_FAB2_LIB.BASEBOARD_FAB2(SCH_1):PAGE212

CT71 CAP_0402LF-1000PF,50V,10%,X7R,A
     1 A_TSENSE_PVCCIO_CPU0 @BASEBOARD_FAB2_LIB.BASEBOARD_FAB2(SCH_1):A_TSENSE_PVCCIO_CPU0   I109 @BASEBOARD_FAB2_LIB.BASEBOARD_FAB2(SCH_1):PAGE212
     2    GND @BASEBOARD_FAB2_LIB.BASEBOARD_FAB2(SCH_1):GND   I109 @BASEBOARD_FAB2_LIB.BASEBOARD_FAB2(SCH_1):PAGE212

CT72 CAP_0402LF-1000PF,50V,10%,X7R,A
     1 VR_PVCCIO_CPU0_PH1_SW @BASEBOARD_FAB2_LIB.BASEBOARD_FAB2(SCH_1):VR_PVCCIO_CPU0_PH1_SW   I118 @BASEBOARD_FAB2_LIB.BASEBOARD_FAB2(SCH_1):PAGE212
     2 VR_PVCCIO_CPU0_PH1_SW_RC @BASEBOARD_FAB2_LIB.BASEBOARD_FAB2(SCH_1):VR_PVCCIO_CPU0_PH1_SW_RC   I118 @BASEBOARD_FAB2_LIB.BASEBOARD_FAB2(SCH_1):PAGE212

CTI7 CAP_0402LF-1000PF,50V,10%,X7R,A
     1 A_TSENSE_PVCCIN_CPU1 @BASEBOARD_FAB2_LIB.BASEBOARD_FAB2(SCH_1):A_TSENSE_PVCCIN_CPU1    I82 @BASEBOARD_FAB2_LIB.BASEBOARD_FAB2(SCH_1):PAGE208
     2    GND @BASEBOARD_FAB2_LIB.BASEBOARD_FAB2(SCH_1):GND    I82 @BASEBOARD_FAB2_LIB.BASEBOARD_FAB2(SCH_1):PAGE208

D25W8 RB551V30-GP_DISCRET-G-RB551V30A
     K P5V_VGA_D @BASEBOARD_FAB2_LIB.BASEBOARD_FAB2(SCH_1):P5V_VGA_D   I128 @BASEBOARD_FAB2_LIB.BASEBOARD_FAB2(SCH_1):PAGE255
     A    P5V @BASEBOARD_FAB2_LIB.BASEBOARD_FAB2(SCH_1):P5V   I128 @BASEBOARD_FAB2_LIB.BASEBOARD_FAB2(SCH_1):PAGE255

DS9A1 LED_1NC-BLUE,IC,C96565-012
     1 FP_ID_LED_P5V_STBY_N @BASEBOARD_FAB2_LIB.BASEBOARD_FAB2(SCH_1):FP_ID_LED_P5V_STBY_N    I50 @BASEBOARD_FAB2_LIB.BASEBOARD_FAB2(SCH_1):PAGE175
     2 FP_ID_LED_XOR_R @BASEBOARD_FAB2_LIB.BASEBOARD_FAB2(SCH_1):FP_ID_LED_XOR_R    I50 @BASEBOARD_FAB2_LIB.BASEBOARD_FAB2(SCH_1):PAGE175

DS9A2 LED_1NCLF-GREEN,IC,C96565-011
     1 FP_LED_HDD_ACTIVITY_AND_N @BASEBOARD_FAB2_LIB.BASEBOARD_FAB2(SCH_1):FP_LED_HDD_ACTIVITY_AND_N    I42 @BASEBOARD_FAB2_LIB.BASEBOARD_FAB2(SCH_1):PAGE177
     2 FP_LED_HDD_ACTIVITY_AND_R_N @BASEBOARD_FAB2_LIB.BASEBOARD_FAB2(SCH_1):FP_LED_HDD_ACTIVITY_AND_R_N    I42 @BASEBOARD_FAB2_LIB.BASEBOARD_FAB2(SCH_1):PAGE177

DS9A3 LED_1NCLF-YELLOW,IC,C96565-003
     1 FM_SPEAKER_PCH_N @BASEBOARD_FAB2_LIB.BASEBOARD_FAB2(SCH_1):FM_SPEAKER_PCH_N    I67 @BASEBOARD_FAB2_LIB.BASEBOARD_FAB2(SCH_1):PAGE175
     2 FM_BEEP_LED_P @BASEBOARD_FAB2_LIB.BASEBOARD_FAB2(SCH_1):FM_BEEP_LED_P    I67 @BASEBOARD_FAB2_LIB.BASEBOARD_FAB2(SCH_1):PAGE175

DS9A4 LED_A1LF-GREEN,IC,D14725-022
     2 FM_UARTSW_LSB_N @BASEBOARD_FAB2_LIB.BASEBOARD_FAB2(SCH_1):FM_UARTSW_LSB_N   I130 @BASEBOARD_FAB2_LIB.BASEBOARD_FAB2(SCH_1):PAGE158
     1 FM_UARTSW_LSB_R_N @BASEBOARD_FAB2_LIB.BASEBOARD_FAB2(SCH_1):FM_UARTSW_LSB_R_N   I130 @BASEBOARD_FAB2_LIB.BASEBOARD_FAB2(SCH_1):PAGE158

DS9A5 LED_A1LF-GREEN,IC,C97278-010
     2 FM_PWR_LED_K @BASEBOARD_FAB2_LIB.BASEBOARD_FAB2(SCH_1):FM_PWR_LED_K   I179 @BASEBOARD_FAB2_LIB.BASEBOARD_FAB2(SCH_1):PAGE119
     1 FM_PWR_LED_A @BASEBOARD_FAB2_LIB.BASEBOARD_FAB2(SCH_1):FM_PWR_LED_A   I179 @BASEBOARD_FAB2_LIB.BASEBOARD_FAB2(SCH_1):PAGE119

DS9A6 LED_A1LF-GREEN,IC,C97278-010
     2    GND @BASEBOARD_FAB2_LIB.BASEBOARD_FAB2(SCH_1):GND    I31 @BASEBOARD_FAB2_LIB.BASEBOARD_FAB2(SCH_1):PAGE177
     1 LED_P5V_STBY @BASEBOARD_FAB2_LIB.BASEBOARD_FAB2(SCH_1):LED_P5V_STBY    I31 @BASEBOARD_FAB2_LIB.BASEBOARD_FAB2(SCH_1):PAGE177

DS9A7 LED_A1LF-GREEN,IC,D14725-022
     2 FM_UARTSW_MSB_N @BASEBOARD_FAB2_LIB.BASEBOARD_FAB2(SCH_1):FM_UARTSW_MSB_N   I134 @BASEBOARD_FAB2_LIB.BASEBOARD_FAB2(SCH_1):PAGE158
     1 FM_UARTSW_MSB_R_N @BASEBOARD_FAB2_LIB.BASEBOARD_FAB2(SCH_1):FM_UARTSW_MSB_R_N   I134 @BASEBOARD_FAB2_LIB.BASEBOARD_FAB2(SCH_1):PAGE158

DS9E1 LED_A1LF-GREEN,IC,C97278-010
     2 FM_HEARTBEAT_LED_K @BASEBOARD_FAB2_LIB.BASEBOARD_FAB2(SCH_1):FM_HEARTBEAT_LED_K   I144 @BASEBOARD_FAB2_LIB.BASEBOARD_FAB2(SCH_1):PAGE151
     1 FM_HEARTBEAT_LED_A @BASEBOARD_FAB2_LIB.BASEBOARD_FAB2(SCH_1):FM_HEARTBEAT_LED_A   I144 @BASEBOARD_FAB2_LIB.BASEBOARD_FAB2(SCH_1):PAGE151

DS9F1 LED_A1-RED,IC,D14725-005
     2 FM_RED_LED_CATHODE @BASEBOARD_FAB2_LIB.BASEBOARD_FAB2(SCH_1):FM_RED_LED_CATHODE    I71 @BASEBOARD_FAB2_LIB.BASEBOARD_FAB2(SCH_1):PAGE177
     1 FM_RED_LED_ANODE @BASEBOARD_FAB2_LIB.BASEBOARD_FAB2(SCH_1):FM_RED_LED_ANODE    I71 @BASEBOARD_FAB2_LIB.BASEBOARD_FAB2(SCH_1):PAGE177

EU1A1 IR354XX_SM-IR35411,IC,H73688-0A
    33 VR_PVDDQ_KLM_PH2_BOOT_R @BASEBOARD_FAB2_LIB.BASEBOARD_FAB2(SCH_1):VR_PVDDQ_KLM_PH2_BOOT_R   I102 @BASEBOARD_FAB2_LIB.BASEBOARD_FAB2(SCH_1):PAGE227
    35 P5V_STBY @BASEBOARD_FAB2_LIB.BASEBOARD_FAB2(SCH_1):P5V_STBY   I102 @BASEBOARD_FAB2_LIB.BASEBOARD_FAB2(SCH_1):PAGE227
    41 TP_PVDDQ_KLM_PH2_GL_1 @BASEBOARD_FAB2_LIB.BASEBOARD_FAB2(SCH_1):TP_PVDDQ_KLM_PH2_GL_1   I102 @BASEBOARD_FAB2_LIB.BASEBOARD_FAB2(SCH_1):PAGE227
     6 TP_PVDDQ_KLM_PH2_GL_0 @BASEBOARD_FAB2_LIB.BASEBOARD_FAB2(SCH_1):TP_PVDDQ_KLM_PH2_GL_0   I102 @BASEBOARD_FAB2_LIB.BASEBOARD_FAB2(SCH_1):PAGE227
    38 ISENSE_PVDDQ_KLM_PH2_IMON @BASEBOARD_FAB2_LIB.BASEBOARD_FAB2(SCH_1):ISENSE_PVDDQ_KLM_PH2_IMON   I102 @BASEBOARD_FAB2_LIB.BASEBOARD_FAB2(SCH_1):PAGE227
     2    GND @BASEBOARD_FAB2_LIB.BASEBOARD_FAB2(SCH_1):GND   I102 @BASEBOARD_FAB2_LIB.BASEBOARD_FAB2(SCH_1):PAGE227
    31     NC     NC   I102 @BASEBOARD_FAB2_LIB.BASEBOARD_FAB2(SCH_1):PAGE227
    37 VR_PVDDQ_KLM_PH2_OCSET @BASEBOARD_FAB2_LIB.BASEBOARD_FAB2(SCH_1):VR_PVDDQ_KLM_PH2_OCSET   I102 @BASEBOARD_FAB2_LIB.BASEBOARD_FAB2(SCH_1):PAGE227
    40    GND @BASEBOARD_FAB2_LIB.BASEBOARD_FAB2(SCH_1):GND   I102 @BASEBOARD_FAB2_LIB.BASEBOARD_FAB2(SCH_1):PAGE227
     7    GND @BASEBOARD_FAB2_LIB.BASEBOARD_FAB2(SCH_1):GND   I102 @BASEBOARD_FAB2_LIB.BASEBOARD_FAB2(SCH_1):PAGE227
     5    GND @BASEBOARD_FAB2_LIB.BASEBOARD_FAB2(SCH_1):GND   I102 @BASEBOARD_FAB2_LIB.BASEBOARD_FAB2(SCH_1):PAGE227
    32 VR_PVDDQ_KLM_PH2_PHASE @BASEBOARD_FAB2_LIB.BASEBOARD_FAB2(SCH_1):VR_PVDDQ_KLM_PH2_PHASE   I102 @BASEBOARD_FAB2_LIB.BASEBOARD_FAB2(SCH_1):PAGE227
    34 VR_PVDDQ_KLM_PWM2 @BASEBOARD_FAB2_LIB.BASEBOARD_FAB2(SCH_1):VR_PVDDQ_KLM_PWM2   I102 @BASEBOARD_FAB2_LIB.BASEBOARD_FAB2(SCH_1):PAGE227
    39 VR_PVDDQ_KLM_AIREF2 @BASEBOARD_FAB2_LIB.BASEBOARD_FAB2(SCH_1):VR_PVDDQ_KLM_AIREF2   I102 @BASEBOARD_FAB2_LIB.BASEBOARD_FAB2(SCH_1):PAGE227
    10 VR_PVDDQ_KLM_PH2_SW @BASEBOARD_FAB2_LIB.BASEBOARD_FAB2(SCH_1):VR_PVDDQ_KLM_PH2_SW   I102 @BASEBOARD_FAB2_LIB.BASEBOARD_FAB2(SCH_1):PAGE227
    36 A_TSENSE_PVDDQ_KLM @BASEBOARD_FAB2_LIB.BASEBOARD_FAB2(SCH_1):A_TSENSE_PVDDQ_KLM   I102 @BASEBOARD_FAB2_LIB.BASEBOARD_FAB2(SCH_1):PAGE227
     3 VR_PVDDQ_KLM_PH2_VCIN @BASEBOARD_FAB2_LIB.BASEBOARD_FAB2(SCH_1):VR_PVDDQ_KLM_PH2_VCIN   I102 @BASEBOARD_FAB2_LIB.BASEBOARD_FAB2(SCH_1):PAGE227
     4 P5V_STBY @BASEBOARD_FAB2_LIB.BASEBOARD_FAB2(SCH_1):P5V_STBY   I102 @BASEBOARD_FAB2_LIB.BASEBOARD_FAB2(SCH_1):PAGE227
    30 VR_FET_SW_P12V_STBY_PVDDQ_KLM @BASEBOARD_FAB2_LIB.BASEBOARD_FAB2(SCH_1):VR_FET_SW_P12V_STBY_PVDDQ_KLM   I102 @BASEBOARD_FAB2_LIB.BASEBOARD_FAB2(SCH_1):PAGE227
    25 VR_FET_SW_P12V_STBY_PVDDQ_KLM @BASEBOARD_FAB2_LIB.BASEBOARD_FAB2(SCH_1):VR_FET_SW_P12V_STBY_PVDDQ_KLM   I102 @BASEBOARD_FAB2_LIB.BASEBOARD_FAB2(SCH_1):PAGE227
     1 PVDDQ_KLM @BASEBOARD_FAB2_LIB.BASEBOARD_FAB2(SCH_1):PVDDQ_KLM   I102 @BASEBOARD_FAB2_LIB.BASEBOARD_FAB2(SCH_1):PAGE227

EU1A2 IR354XX_SM-IR35411,IC,H73688-0A
    33 VR_PVDDQ_KLM_PH1_BOOT_R @BASEBOARD_FAB2_LIB.BASEBOARD_FAB2(SCH_1):VR_PVDDQ_KLM_PH1_BOOT_R   I101 @BASEBOARD_FAB2_LIB.BASEBOARD_FAB2(SCH_1):PAGE227
    35 P5V_STBY @BASEBOARD_FAB2_LIB.BASEBOARD_FAB2(SCH_1):P5V_STBY   I101 @BASEBOARD_FAB2_LIB.BASEBOARD_FAB2(SCH_1):PAGE227
    41 TP_PVDDQ_KLM_PH1_GL_1 @BASEBOARD_FAB2_LIB.BASEBOARD_FAB2(SCH_1):TP_PVDDQ_KLM_PH1_GL_1   I101 @BASEBOARD_FAB2_LIB.BASEBOARD_FAB2(SCH_1):PAGE227
     6 TP_PVDDQ_KLM_PH1_GL_0 @BASEBOARD_FAB2_LIB.BASEBOARD_FAB2(SCH_1):TP_PVDDQ_KLM_PH1_GL_0   I101 @BASEBOARD_FAB2_LIB.BASEBOARD_FAB2(SCH_1):PAGE227
    38 ISENSE_PVDDQ_KLM_PH1_IMON @BASEBOARD_FAB2_LIB.BASEBOARD_FAB2(SCH_1):ISENSE_PVDDQ_KLM_PH1_IMON   I101 @BASEBOARD_FAB2_LIB.BASEBOARD_FAB2(SCH_1):PAGE227
     2    GND @BASEBOARD_FAB2_LIB.BASEBOARD_FAB2(SCH_1):GND   I101 @BASEBOARD_FAB2_LIB.BASEBOARD_FAB2(SCH_1):PAGE227
    31     NC     NC   I101 @BASEBOARD_FAB2_LIB.BASEBOARD_FAB2(SCH_1):PAGE227
    37 VR_PVDDQ_KLM_PH1_OCSET @BASEBOARD_FAB2_LIB.BASEBOARD_FAB2(SCH_1):VR_PVDDQ_KLM_PH1_OCSET   I101 @BASEBOARD_FAB2_LIB.BASEBOARD_FAB2(SCH_1):PAGE227
    40    GND @BASEBOARD_FAB2_LIB.BASEBOARD_FAB2(SCH_1):GND   I101 @BASEBOARD_FAB2_LIB.BASEBOARD_FAB2(SCH_1):PAGE227
     7    GND @BASEBOARD_FAB2_LIB.BASEBOARD_FAB2(SCH_1):GND   I101 @BASEBOARD_FAB2_LIB.BASEBOARD_FAB2(SCH_1):PAGE227
     5    GND @BASEBOARD_FAB2_LIB.BASEBOARD_FAB2(SCH_1):GND   I101 @BASEBOARD_FAB2_LIB.BASEBOARD_FAB2(SCH_1):PAGE227
    32 VR_PVDDQ_KLM_PH1_PHASE @BASEBOARD_FAB2_LIB.BASEBOARD_FAB2(SCH_1):VR_PVDDQ_KLM_PH1_PHASE   I101 @BASEBOARD_FAB2_LIB.BASEBOARD_FAB2(SCH_1):PAGE227
    34 VR_PVDDQ_KLM_PWM1 @BASEBOARD_FAB2_LIB.BASEBOARD_FAB2(SCH_1):VR_PVDDQ_KLM_PWM1   I101 @BASEBOARD_FAB2_LIB.BASEBOARD_FAB2(SCH_1):PAGE227
    39 VR_PVDDQ_KLM_AIREF1 @BASEBOARD_FAB2_LIB.BASEBOARD_FAB2(SCH_1):VR_PVDDQ_KLM_AIREF1   I101 @BASEBOARD_FAB2_LIB.BASEBOARD_FAB2(SCH_1):PAGE227
    10 VR_PVDDQ_KLM_PH1_SW @BASEBOARD_FAB2_LIB.BASEBOARD_FAB2(SCH_1):VR_PVDDQ_KLM_PH1_SW   I101 @BASEBOARD_FAB2_LIB.BASEBOARD_FAB2(SCH_1):PAGE227
    36 A_TSENSE_PVDDQ_KLM @BASEBOARD_FAB2_LIB.BASEBOARD_FAB2(SCH_1):A_TSENSE_PVDDQ_KLM   I101 @BASEBOARD_FAB2_LIB.BASEBOARD_FAB2(SCH_1):PAGE227
     3 VR_PVDDQ_KLM_PH1_VCIN @BASEBOARD_FAB2_LIB.BASEBOARD_FAB2(SCH_1):VR_PVDDQ_KLM_PH1_VCIN   I101 @BASEBOARD_FAB2_LIB.BASEBOARD_FAB2(SCH_1):PAGE227
     4 P5V_STBY @BASEBOARD_FAB2_LIB.BASEBOARD_FAB2(SCH_1):P5V_STBY   I101 @BASEBOARD_FAB2_LIB.BASEBOARD_FAB2(SCH_1):PAGE227
    30 VR_FET_SW_P12V_STBY_PVDDQ_KLM @BASEBOARD_FAB2_LIB.BASEBOARD_FAB2(SCH_1):VR_FET_SW_P12V_STBY_PVDDQ_KLM   I101 @BASEBOARD_FAB2_LIB.BASEBOARD_FAB2(SCH_1):PAGE227
    25 VR_FET_SW_P12V_STBY_PVDDQ_KLM @BASEBOARD_FAB2_LIB.BASEBOARD_FAB2(SCH_1):VR_FET_SW_P12V_STBY_PVDDQ_KLM   I101 @BASEBOARD_FAB2_LIB.BASEBOARD_FAB2(SCH_1):PAGE227
     1 PVDDQ_KLM @BASEBOARD_FAB2_LIB.BASEBOARD_FAB2(SCH_1):PVDDQ_KLM   I101 @BASEBOARD_FAB2_LIB.BASEBOARD_FAB2(SCH_1):PAGE227

EU1B1 PXM1310B_QFN-IC,H89186-001
     1     NC     NC    I69 @BASEBOARD_FAB2_LIB.BASEBOARD_FAB2(SCH_1):PAGE226
     2     NC     NC    I69 @BASEBOARD_FAB2_LIB.BASEBOARD_FAB2(SCH_1):PAGE226
     3     NC     NC    I69 @BASEBOARD_FAB2_LIB.BASEBOARD_FAB2(SCH_1):PAGE226
     4 VR_PVDDQ_KLM_PWM2 @BASEBOARD_FAB2_LIB.BASEBOARD_FAB2(SCH_1):VR_PVDDQ_KLM_PWM2    I69 @BASEBOARD_FAB2_LIB.BASEBOARD_FAB2(SCH_1):PAGE226
     5 VR_PVDDQ_KLM_PWM1 @BASEBOARD_FAB2_LIB.BASEBOARD_FAB2(SCH_1):VR_PVDDQ_KLM_PWM1    I69 @BASEBOARD_FAB2_LIB.BASEBOARD_FAB2(SCH_1):PAGE226
     6 SMB_VR_STBY_LVC3_SDA @BASEBOARD_FAB2_LIB.BASEBOARD_FAB2(SCH_1):SMB_VR_STBY_LVC3_SDA    I69 @BASEBOARD_FAB2_LIB.BASEBOARD_FAB2(SCH_1):PAGE226
     7 SMB_VR_STBY_LVC3_SCL @BASEBOARD_FAB2_LIB.BASEBOARD_FAB2(SCH_1):SMB_VR_STBY_LVC3_SCL    I69 @BASEBOARD_FAB2_LIB.BASEBOARD_FAB2(SCH_1):PAGE226
     8     NC     NC    I69 @BASEBOARD_FAB2_LIB.BASEBOARD_FAB2(SCH_1):PAGE226
     9 PWRGD_PVDDQ_KLM_R @BASEBOARD_FAB2_LIB.BASEBOARD_FAB2(SCH_1):PWRGD_PVDDQ_KLM_R    I69 @BASEBOARD_FAB2_LIB.BASEBOARD_FAB2(SCH_1):PAGE226
    10 VR_PVDDQ_KLM_VREN @BASEBOARD_FAB2_LIB.BASEBOARD_FAB2(SCH_1):VR_PVDDQ_KLM_VREN    I69 @BASEBOARD_FAB2_LIB.BASEBOARD_FAB2(SCH_1):PAGE226
    11 IRQ_PVDDQ_KLM_VRHOT_LVT3_R_N @BASEBOARD_FAB2_LIB.BASEBOARD_FAB2(SCH_1):IRQ_PVDDQ_KLM_VRHOT_LVT3_R_N    I69 @BASEBOARD_FAB2_LIB.BASEBOARD_FAB2(SCH_1):PAGE226
    12     NC     NC    I69 @BASEBOARD_FAB2_LIB.BASEBOARD_FAB2(SCH_1):PAGE226
    13 PU_VR_PVDDQ_KLM_FAULT1 @BASEBOARD_FAB2_LIB.BASEBOARD_FAB2(SCH_1):PU_VR_PVDDQ_KLM_FAULT1    I69 @BASEBOARD_FAB2_LIB.BASEBOARD_FAB2(SCH_1):PAGE226
    14 NC_PVDDQ_KLM_GP1 @BASEBOARD_FAB2_LIB.BASEBOARD_FAB2(SCH_1):NC_PVDDQ_KLM_GP1    I69 @BASEBOARD_FAB2_LIB.BASEBOARD_FAB2(SCH_1):PAGE226
    15 SVID_CLK_PVDDQ_KLM @BASEBOARD_FAB2_LIB.BASEBOARD_FAB2(SCH_1):SVID_CLK_PVDDQ_KLM    I69 @BASEBOARD_FAB2_LIB.BASEBOARD_FAB2(SCH_1):PAGE226
    16 SVID_VDIO_PVDDQ_KLM @BASEBOARD_FAB2_LIB.BASEBOARD_FAB2(SCH_1):SVID_VDIO_PVDDQ_KLM    I69 @BASEBOARD_FAB2_LIB.BASEBOARD_FAB2(SCH_1):PAGE226
    17 SVID_ALERT_PVDDQ_KLM @BASEBOARD_FAB2_LIB.BASEBOARD_FAB2(SCH_1):SVID_ALERT_PVDDQ_KLM    I69 @BASEBOARD_FAB2_LIB.BASEBOARD_FAB2(SCH_1):PAGE226
    18 NC_PVDDQ_KLM_GP0 @BASEBOARD_FAB2_LIB.BASEBOARD_FAB2(SCH_1):NC_PVDDQ_KLM_GP0    I69 @BASEBOARD_FAB2_LIB.BASEBOARD_FAB2(SCH_1):PAGE226
    19 VR_PVDDQ_KLM_AVSP @BASEBOARD_FAB2_LIB.BASEBOARD_FAB2(SCH_1):VR_PVDDQ_KLM_AVSP    I69 @BASEBOARD_FAB2_LIB.BASEBOARD_FAB2(SCH_1):PAGE226
    20 VSENSE_PVDDQ_KLM_N @BASEBOARD_FAB2_LIB.BASEBOARD_FAB2(SCH_1):VSENSE_PVDDQ_KLM_N    I69 @BASEBOARD_FAB2_LIB.BASEBOARD_FAB2(SCH_1):PAGE226
    21 VR_PVDDQ_KLM_AIREF1 @BASEBOARD_FAB2_LIB.BASEBOARD_FAB2(SCH_1):VR_PVDDQ_KLM_AIREF1    I69 @BASEBOARD_FAB2_LIB.BASEBOARD_FAB2(SCH_1):PAGE226
    22 ISENSE_PVDDQ_KLM_PH1_IMON @BASEBOARD_FAB2_LIB.BASEBOARD_FAB2(SCH_1):ISENSE_PVDDQ_KLM_PH1_IMON    I69 @BASEBOARD_FAB2_LIB.BASEBOARD_FAB2(SCH_1):PAGE226
    23 VR_PVDDQ_KLM_AIREF2 @BASEBOARD_FAB2_LIB.BASEBOARD_FAB2(SCH_1):VR_PVDDQ_KLM_AIREF2    I69 @BASEBOARD_FAB2_LIB.BASEBOARD_FAB2(SCH_1):PAGE226
    24 ISENSE_PVDDQ_KLM_PH2_IMON @BASEBOARD_FAB2_LIB.BASEBOARD_FAB2(SCH_1):ISENSE_PVDDQ_KLM_PH2_IMON    I69 @BASEBOARD_FAB2_LIB.BASEBOARD_FAB2(SCH_1):PAGE226
    25     NC     NC    I69 @BASEBOARD_FAB2_LIB.BASEBOARD_FAB2(SCH_1):PAGE226
    26     NC     NC    I69 @BASEBOARD_FAB2_LIB.BASEBOARD_FAB2(SCH_1):PAGE226
    27    GND @BASEBOARD_FAB2_LIB.BASEBOARD_FAB2(SCH_1):GND    I69 @BASEBOARD_FAB2_LIB.BASEBOARD_FAB2(SCH_1):PAGE226
    28     NC     NC    I69 @BASEBOARD_FAB2_LIB.BASEBOARD_FAB2(SCH_1):PAGE226
    29     NC     NC    I69 @BASEBOARD_FAB2_LIB.BASEBOARD_FAB2(SCH_1):PAGE226
    30     NC     NC    I69 @BASEBOARD_FAB2_LIB.BASEBOARD_FAB2(SCH_1):PAGE226
    31     NC     NC    I69 @BASEBOARD_FAB2_LIB.BASEBOARD_FAB2(SCH_1):PAGE226
    32    GND @BASEBOARD_FAB2_LIB.BASEBOARD_FAB2(SCH_1):GND    I69 @BASEBOARD_FAB2_LIB.BASEBOARD_FAB2(SCH_1):PAGE226
    33 VR_PVDDQ_KLM_XADDR2 @BASEBOARD_FAB2_LIB.BASEBOARD_FAB2(SCH_1):VR_PVDDQ_KLM_XADDR2    I69 @BASEBOARD_FAB2_LIB.BASEBOARD_FAB2(SCH_1):PAGE226
    34     NC     NC    I69 @BASEBOARD_FAB2_LIB.BASEBOARD_FAB2(SCH_1):PAGE226
    35 A_TSENSE_PVDDQ_KLM @BASEBOARD_FAB2_LIB.BASEBOARD_FAB2(SCH_1):A_TSENSE_PVDDQ_KLM    I69 @BASEBOARD_FAB2_LIB.BASEBOARD_FAB2(SCH_1):PAGE226
    36 VR_PVDDQ_KLM_XADDR1 @BASEBOARD_FAB2_LIB.BASEBOARD_FAB2(SCH_1):VR_PVDDQ_KLM_XADDR1    I69 @BASEBOARD_FAB2_LIB.BASEBOARD_FAB2(SCH_1):PAGE226
    37 VR_PVDDQ_KLM_VINSEN @BASEBOARD_FAB2_LIB.BASEBOARD_FAB2(SCH_1):VR_PVDDQ_KLM_VINSEN    I69 @BASEBOARD_FAB2_LIB.BASEBOARD_FAB2(SCH_1):PAGE226
    38 VR_PVDDQ_KLM_AIINSEN @BASEBOARD_FAB2_LIB.BASEBOARD_FAB2(SCH_1):VR_PVDDQ_KLM_AIINSEN    I69 @BASEBOARD_FAB2_LIB.BASEBOARD_FAB2(SCH_1):PAGE226
    39 VR_PVDDQ_KLM_VDD @BASEBOARD_FAB2_LIB.BASEBOARD_FAB2(SCH_1):VR_PVDDQ_KLM_VDD    I69 @BASEBOARD_FAB2_LIB.BASEBOARD_FAB2(SCH_1):PAGE226
    40 VR_PVDDQ_KLM_VD12 @BASEBOARD_FAB2_LIB.BASEBOARD_FAB2(SCH_1):VR_PVDDQ_KLM_VD12    I69 @BASEBOARD_FAB2_LIB.BASEBOARD_FAB2(SCH_1):PAGE226
    41    GND @BASEBOARD_FAB2_LIB.BASEBOARD_FAB2(SCH_1):GND    I69 @BASEBOARD_FAB2_LIB.BASEBOARD_FAB2(SCH_1):PAGE226

EU1C1 IR354XX_SM-IR35412,IC,H73684-0A
    33 VR_PVSA_CPU1_BOOT_R @BASEBOARD_FAB2_LIB.BASEBOARD_FAB2(SCH_1):VR_PVSA_CPU1_BOOT_R    I51 @BASEBOARD_FAB2_LIB.BASEBOARD_FAB2(SCH_1):PAGE210
    35 P5V_STBY @BASEBOARD_FAB2_LIB.BASEBOARD_FAB2(SCH_1):P5V_STBY    I51 @BASEBOARD_FAB2_LIB.BASEBOARD_FAB2(SCH_1):PAGE210
    41 TP_PVSA_CPU1_GL_1 @BASEBOARD_FAB2_LIB.BASEBOARD_FAB2(SCH_1):TP_PVSA_CPU1_GL_1    I51 @BASEBOARD_FAB2_LIB.BASEBOARD_FAB2(SCH_1):PAGE210
     6 TP_PVSA_CPU1_GL_0 @BASEBOARD_FAB2_LIB.BASEBOARD_FAB2(SCH_1):TP_PVSA_CPU1_GL_0    I51 @BASEBOARD_FAB2_LIB.BASEBOARD_FAB2(SCH_1):PAGE210
    38 ISENSE_PVSA_CPU1_IMON @BASEBOARD_FAB2_LIB.BASEBOARD_FAB2(SCH_1):ISENSE_PVSA_CPU1_IMON    I51 @BASEBOARD_FAB2_LIB.BASEBOARD_FAB2(SCH_1):PAGE210
     2    GND @BASEBOARD_FAB2_LIB.BASEBOARD_FAB2(SCH_1):GND    I51 @BASEBOARD_FAB2_LIB.BASEBOARD_FAB2(SCH_1):PAGE210
    31     NC     NC    I51 @BASEBOARD_FAB2_LIB.BASEBOARD_FAB2(SCH_1):PAGE210
    37 VR_PVSA_CPU1_OCSET @BASEBOARD_FAB2_LIB.BASEBOARD_FAB2(SCH_1):VR_PVSA_CPU1_OCSET    I51 @BASEBOARD_FAB2_LIB.BASEBOARD_FAB2(SCH_1):PAGE210
    40    GND @BASEBOARD_FAB2_LIB.BASEBOARD_FAB2(SCH_1):GND    I51 @BASEBOARD_FAB2_LIB.BASEBOARD_FAB2(SCH_1):PAGE210
     7    GND @BASEBOARD_FAB2_LIB.BASEBOARD_FAB2(SCH_1):GND    I51 @BASEBOARD_FAB2_LIB.BASEBOARD_FAB2(SCH_1):PAGE210
     5    GND @BASEBOARD_FAB2_LIB.BASEBOARD_FAB2(SCH_1):GND    I51 @BASEBOARD_FAB2_LIB.BASEBOARD_FAB2(SCH_1):PAGE210
    32 VR_PVSA_CPU1_PHASE @BASEBOARD_FAB2_LIB.BASEBOARD_FAB2(SCH_1):VR_PVSA_CPU1_PHASE    I51 @BASEBOARD_FAB2_LIB.BASEBOARD_FAB2(SCH_1):PAGE210
    34 VR_PVSA_CPU1_PWM @BASEBOARD_FAB2_LIB.BASEBOARD_FAB2(SCH_1):VR_PVSA_CPU1_PWM    I51 @BASEBOARD_FAB2_LIB.BASEBOARD_FAB2(SCH_1):PAGE210
    39 VR_PVSA_CPU1_BIREF1 @BASEBOARD_FAB2_LIB.BASEBOARD_FAB2(SCH_1):VR_PVSA_CPU1_BIREF1    I51 @BASEBOARD_FAB2_LIB.BASEBOARD_FAB2(SCH_1):PAGE210
    10 VR_PVSA_CPU1_PHASE_SW @BASEBOARD_FAB2_LIB.BASEBOARD_FAB2(SCH_1):VR_PVSA_CPU1_PHASE_SW    I51 @BASEBOARD_FAB2_LIB.BASEBOARD_FAB2(SCH_1):PAGE210
    36 A_TSENSE_PVSA_CPU1 @BASEBOARD_FAB2_LIB.BASEBOARD_FAB2(SCH_1):A_TSENSE_PVSA_CPU1    I51 @BASEBOARD_FAB2_LIB.BASEBOARD_FAB2(SCH_1):PAGE210
     3 VR_PVSA_CPU1_VCIN @BASEBOARD_FAB2_LIB.BASEBOARD_FAB2(SCH_1):VR_PVSA_CPU1_VCIN    I51 @BASEBOARD_FAB2_LIB.BASEBOARD_FAB2(SCH_1):PAGE210
     4 P5V_STBY @BASEBOARD_FAB2_LIB.BASEBOARD_FAB2(SCH_1):P5V_STBY    I51 @BASEBOARD_FAB2_LIB.BASEBOARD_FAB2(SCH_1):PAGE210
    30 VR_FET_SW_P12V_STBY_PVCCIN_CPU1 @BASEBOARD_FAB2_LIB.BASEBOARD_FAB2(SCH_1):VR_FET_SW_P12V_STBY_PVCCIN_CPU1    I51 @BASEBOARD_FAB2_LIB.BASEBOARD_FAB2(SCH_1):PAGE210
    25 VR_FET_SW_P12V_STBY_PVCCIN_CPU1 @BASEBOARD_FAB2_LIB.BASEBOARD_FAB2(SCH_1):VR_FET_SW_P12V_STBY_PVCCIN_CPU1    I51 @BASEBOARD_FAB2_LIB.BASEBOARD_FAB2(SCH_1):PAGE210
     1 PVSA_CPU1 @BASEBOARD_FAB2_LIB.BASEBOARD_FAB2(SCH_1):PVSA_CPU1    I51 @BASEBOARD_FAB2_LIB.BASEBOARD_FAB2(SCH_1):PAGE210

EU1C2 PXE1610B_QFN-IC,H79206-001
     1 VR_PVSA_CPU1_PWM @BASEBOARD_FAB2_LIB.BASEBOARD_FAB2(SCH_1):VR_PVSA_CPU1_PWM   I130 @BASEBOARD_FAB2_LIB.BASEBOARD_FAB2(SCH_1):PAGE206
     2     NC     NC   I130 @BASEBOARD_FAB2_LIB.BASEBOARD_FAB2(SCH_1):PAGE206
     3 VR_PVCCIN_CPU1_PWM5 @BASEBOARD_FAB2_LIB.BASEBOARD_FAB2(SCH_1):VR_PVCCIN_CPU1_PWM5   I130 @BASEBOARD_FAB2_LIB.BASEBOARD_FAB2(SCH_1):PAGE206
     4 VR_PVCCIN_CPU1_PWM4 @BASEBOARD_FAB2_LIB.BASEBOARD_FAB2(SCH_1):VR_PVCCIN_CPU1_PWM4   I130 @BASEBOARD_FAB2_LIB.BASEBOARD_FAB2(SCH_1):PAGE206
     5 VR_PVCCIN_CPU1_PWM3 @BASEBOARD_FAB2_LIB.BASEBOARD_FAB2(SCH_1):VR_PVCCIN_CPU1_PWM3   I130 @BASEBOARD_FAB2_LIB.BASEBOARD_FAB2(SCH_1):PAGE206
     6 VR_PVCCIN_CPU1_PWM2 @BASEBOARD_FAB2_LIB.BASEBOARD_FAB2(SCH_1):VR_PVCCIN_CPU1_PWM2   I130 @BASEBOARD_FAB2_LIB.BASEBOARD_FAB2(SCH_1):PAGE206
     7 VR_PVCCIN_CPU1_PWM1 @BASEBOARD_FAB2_LIB.BASEBOARD_FAB2(SCH_1):VR_PVCCIN_CPU1_PWM1   I130 @BASEBOARD_FAB2_LIB.BASEBOARD_FAB2(SCH_1):PAGE206
     8 SMB_VR_STBY_LVC3_SDA @BASEBOARD_FAB2_LIB.BASEBOARD_FAB2(SCH_1):SMB_VR_STBY_LVC3_SDA   I130 @BASEBOARD_FAB2_LIB.BASEBOARD_FAB2(SCH_1):PAGE206
     9 SMB_VR_STBY_LVC3_SCL @BASEBOARD_FAB2_LIB.BASEBOARD_FAB2(SCH_1):SMB_VR_STBY_LVC3_SCL   I130 @BASEBOARD_FAB2_LIB.BASEBOARD_FAB2(SCH_1):PAGE206
    10     NC     NC   I130 @BASEBOARD_FAB2_LIB.BASEBOARD_FAB2(SCH_1):PAGE206
    11 VR_VRRDY_PVCCIN_CPU1 @BASEBOARD_FAB2_LIB.BASEBOARD_FAB2(SCH_1):VR_VRRDY_PVCCIN_CPU1   I130 @BASEBOARD_FAB2_LIB.BASEBOARD_FAB2(SCH_1):PAGE206
    12 VR_PVCCIN_CPU1_VREN @BASEBOARD_FAB2_LIB.BASEBOARD_FAB2(SCH_1):VR_PVCCIN_CPU1_VREN   I130 @BASEBOARD_FAB2_LIB.BASEBOARD_FAB2(SCH_1):PAGE206
    13 IRQ_PVCCIN_CPU1_VRHOT_LVC3_R_N @BASEBOARD_FAB2_LIB.BASEBOARD_FAB2(SCH_1):IRQ_PVCCIN_CPU1_VRHOT_LVC3_R_N   I130 @BASEBOARD_FAB2_LIB.BASEBOARD_FAB2(SCH_1):PAGE206
    14 FM_PVCCIN_CPU1_PWR_IN_ALERT_N @BASEBOARD_FAB2_LIB.BASEBOARD_FAB2(SCH_1):FM_PVCCIN_CPU1_PWR_IN_ALERT_N   I130 @BASEBOARD_FAB2_LIB.BASEBOARD_FAB2(SCH_1):PAGE206
    15 PWRGD_PVSA_CPU1_R @BASEBOARD_FAB2_LIB.BASEBOARD_FAB2(SCH_1):PWRGD_PVSA_CPU1_R   I130 @BASEBOARD_FAB2_LIB.BASEBOARD_FAB2(SCH_1):PAGE206
    16     NC     NC   I130 @BASEBOARD_FAB2_LIB.BASEBOARD_FAB2(SCH_1):PAGE206
    17 SVID_VCLK_PVCCIN_CPU1 @BASEBOARD_FAB2_LIB.BASEBOARD_FAB2(SCH_1):SVID_VCLK_PVCCIN_CPU1   I130 @BASEBOARD_FAB2_LIB.BASEBOARD_FAB2(SCH_1):PAGE206
    18 SVID_VDIO_PVCCIN_CPU1 @BASEBOARD_FAB2_LIB.BASEBOARD_FAB2(SCH_1):SVID_VDIO_PVCCIN_CPU1   I130 @BASEBOARD_FAB2_LIB.BASEBOARD_FAB2(SCH_1):PAGE206
    19 SVID_VALERT_VCCIN_CPU1 @BASEBOARD_FAB2_LIB.BASEBOARD_FAB2(SCH_1):SVID_VALERT_VCCIN_CPU1   I130 @BASEBOARD_FAB2_LIB.BASEBOARD_FAB2(SCH_1):PAGE206
    20 PU_VR_PVCCIN_CPU1_FLT1_SMBALT_N @BASEBOARD_FAB2_LIB.BASEBOARD_FAB2(SCH_1):PU_VR_PVCCIN_CPU1_FLT1_SMBALT_N_IMON   I130 @BASEBOARD_FAB2_LIB.BASEBOARD_FAB2(SCH_1):PAGE206
    21 VSENSE_PVCCIN_CPU1_AVSP @BASEBOARD_FAB2_LIB.BASEBOARD_FAB2(SCH_1):VSENSE_PVCCIN_CPU1_AVSP   I130 @BASEBOARD_FAB2_LIB.BASEBOARD_FAB2(SCH_1):PAGE206
    22 VSENSE_PVCCIN_CPU1_N @BASEBOARD_FAB2_LIB.BASEBOARD_FAB2(SCH_1):VSENSE_PVCCIN_CPU1_N   I130 @BASEBOARD_FAB2_LIB.BASEBOARD_FAB2(SCH_1):PAGE206
    23 VR_PVCCIN_CPU1_AIREF1 @BASEBOARD_FAB2_LIB.BASEBOARD_FAB2(SCH_1):VR_PVCCIN_CPU1_AIREF1   I130 @BASEBOARD_FAB2_LIB.BASEBOARD_FAB2(SCH_1):PAGE206
    24 ISENSE_PVCCIN_CPU1_PH1_IMON @BASEBOARD_FAB2_LIB.BASEBOARD_FAB2(SCH_1):ISENSE_PVCCIN_CPU1_PH1_IMON   I130 @BASEBOARD_FAB2_LIB.BASEBOARD_FAB2(SCH_1):PAGE206
    25 VR_PVCCIN_CPU1_AIREF2 @BASEBOARD_FAB2_LIB.BASEBOARD_FAB2(SCH_1):VR_PVCCIN_CPU1_AIREF2   I130 @BASEBOARD_FAB2_LIB.BASEBOARD_FAB2(SCH_1):PAGE206
    26 ISENSE_PVCCIN_CPU1_PH2_IMON @BASEBOARD_FAB2_LIB.BASEBOARD_FAB2(SCH_1):ISENSE_PVCCIN_CPU1_PH2_IMON   I130 @BASEBOARD_FAB2_LIB.BASEBOARD_FAB2(SCH_1):PAGE206
    27 VR_PVCCIN_CPU1_AIREF3 @BASEBOARD_FAB2_LIB.BASEBOARD_FAB2(SCH_1):VR_PVCCIN_CPU1_AIREF3   I130 @BASEBOARD_FAB2_LIB.BASEBOARD_FAB2(SCH_1):PAGE206
    28 ISENSE_PVCCIN_CPU1_PH3_IMON @BASEBOARD_FAB2_LIB.BASEBOARD_FAB2(SCH_1):ISENSE_PVCCIN_CPU1_PH3_IMON   I130 @BASEBOARD_FAB2_LIB.BASEBOARD_FAB2(SCH_1):PAGE206
    29 VR_PVCCIN_CPU1_AIREF4 @BASEBOARD_FAB2_LIB.BASEBOARD_FAB2(SCH_1):VR_PVCCIN_CPU1_AIREF4   I130 @BASEBOARD_FAB2_LIB.BASEBOARD_FAB2(SCH_1):PAGE206
    30 ISENSE_PVCCIN_CPU1_PH4_IMON @BASEBOARD_FAB2_LIB.BASEBOARD_FAB2(SCH_1):ISENSE_PVCCIN_CPU1_PH4_IMON   I130 @BASEBOARD_FAB2_LIB.BASEBOARD_FAB2(SCH_1):PAGE206
    31 VR_PVCCIN_CPU1_AIREF5 @BASEBOARD_FAB2_LIB.BASEBOARD_FAB2(SCH_1):VR_PVCCIN_CPU1_AIREF5   I130 @BASEBOARD_FAB2_LIB.BASEBOARD_FAB2(SCH_1):PAGE206
    32 ISENSE_PVCCIN_CPU1_PH5_IMON @BASEBOARD_FAB2_LIB.BASEBOARD_FAB2(SCH_1):ISENSE_PVCCIN_CPU1_PH5_IMON   I130 @BASEBOARD_FAB2_LIB.BASEBOARD_FAB2(SCH_1):PAGE206
    33     NC     NC   I130 @BASEBOARD_FAB2_LIB.BASEBOARD_FAB2(SCH_1):PAGE206
    34     NC     NC   I130 @BASEBOARD_FAB2_LIB.BASEBOARD_FAB2(SCH_1):PAGE206
    35 VSENSE_PVSA_CPU1_BVSP @BASEBOARD_FAB2_LIB.BASEBOARD_FAB2(SCH_1):VSENSE_PVSA_CPU1_BVSP   I130 @BASEBOARD_FAB2_LIB.BASEBOARD_FAB2(SCH_1):PAGE206
    36 VSENSE_PVSA_CPU1_N @BASEBOARD_FAB2_LIB.BASEBOARD_FAB2(SCH_1):VSENSE_PVSA_CPU1_N   I130 @BASEBOARD_FAB2_LIB.BASEBOARD_FAB2(SCH_1):PAGE206
    37 VR_PVSA_CPU1_BIREF1 @BASEBOARD_FAB2_LIB.BASEBOARD_FAB2(SCH_1):VR_PVSA_CPU1_BIREF1   I130 @BASEBOARD_FAB2_LIB.BASEBOARD_FAB2(SCH_1):PAGE206
    38 ISENSE_PVSA_CPU1_IMON @BASEBOARD_FAB2_LIB.BASEBOARD_FAB2(SCH_1):ISENSE_PVSA_CPU1_IMON   I130 @BASEBOARD_FAB2_LIB.BASEBOARD_FAB2(SCH_1):PAGE206
    39 PU_VR_PVCCIN_CPU1_IMON @BASEBOARD_FAB2_LIB.BASEBOARD_FAB2(SCH_1):PU_VR_PVCCIN_CPU1_IMON   I130 @BASEBOARD_FAB2_LIB.BASEBOARD_FAB2(SCH_1):PAGE206
    40     NC     NC   I130 @BASEBOARD_FAB2_LIB.BASEBOARD_FAB2(SCH_1):PAGE206
    41 VR_PVCCIN_CPU1_XADDR2 @BASEBOARD_FAB2_LIB.BASEBOARD_FAB2(SCH_1):VR_PVCCIN_CPU1_XADDR2   I130 @BASEBOARD_FAB2_LIB.BASEBOARD_FAB2(SCH_1):PAGE206
    42 A_TSENSE_PVSA_CPU1 @BASEBOARD_FAB2_LIB.BASEBOARD_FAB2(SCH_1):A_TSENSE_PVSA_CPU1   I130 @BASEBOARD_FAB2_LIB.BASEBOARD_FAB2(SCH_1):PAGE206
    43 A_TSENSE_PVCCIN_CPU1 @BASEBOARD_FAB2_LIB.BASEBOARD_FAB2(SCH_1):A_TSENSE_PVCCIN_CPU1   I130 @BASEBOARD_FAB2_LIB.BASEBOARD_FAB2(SCH_1):PAGE206
    44 VR_PVCCIN_CPU1_XADDR1 @BASEBOARD_FAB2_LIB.BASEBOARD_FAB2(SCH_1):VR_PVCCIN_CPU1_XADDR1   I130 @BASEBOARD_FAB2_LIB.BASEBOARD_FAB2(SCH_1):PAGE206
    45 VR_PVCCIN_CPU1_AVINSEN @BASEBOARD_FAB2_LIB.BASEBOARD_FAB2(SCH_1):VR_PVCCIN_CPU1_AVINSEN   I130 @BASEBOARD_FAB2_LIB.BASEBOARD_FAB2(SCH_1):PAGE206
    46     NC     NC   I130 @BASEBOARD_FAB2_LIB.BASEBOARD_FAB2(SCH_1):PAGE206
    47 VR_PVCCIN_CPU1_VDD @BASEBOARD_FAB2_LIB.BASEBOARD_FAB2(SCH_1):VR_PVCCIN_CPU1_VDD   I130 @BASEBOARD_FAB2_LIB.BASEBOARD_FAB2(SCH_1):PAGE206
    48 VR_PVCCIN_CPU1_VD12 @BASEBOARD_FAB2_LIB.BASEBOARD_FAB2(SCH_1):VR_PVCCIN_CPU1_VD12   I130 @BASEBOARD_FAB2_LIB.BASEBOARD_FAB2(SCH_1):PAGE206
    49    GND @BASEBOARD_FAB2_LIB.BASEBOARD_FAB2(SCH_1):GND   I130 @BASEBOARD_FAB2_LIB.BASEBOARD_FAB2(SCH_1):PAGE206

EU1C3 IR354XX_SM-IR35411,IC,H73688-0A
    33 VR_PVCCIN_CPU1_PH5_BOOT_R @BASEBOARD_FAB2_LIB.BASEBOARD_FAB2(SCH_1):VR_PVCCIN_CPU1_PH5_BOOT_R    I56 @BASEBOARD_FAB2_LIB.BASEBOARD_FAB2(SCH_1):PAGE209
    35 P5V_STBY @BASEBOARD_FAB2_LIB.BASEBOARD_FAB2(SCH_1):P5V_STBY    I56 @BASEBOARD_FAB2_LIB.BASEBOARD_FAB2(SCH_1):PAGE209
    41 TP_PVCCIN_CPU1_PH5_GL_1 @BASEBOARD_FAB2_LIB.BASEBOARD_FAB2(SCH_1):TP_PVCCIN_CPU1_PH5_GL_1    I56 @BASEBOARD_FAB2_LIB.BASEBOARD_FAB2(SCH_1):PAGE209
     6 TP_PVCCIN_CPU1_PH5_GL_0 @BASEBOARD_FAB2_LIB.BASEBOARD_FAB2(SCH_1):TP_PVCCIN_CPU1_PH5_GL_0    I56 @BASEBOARD_FAB2_LIB.BASEBOARD_FAB2(SCH_1):PAGE209
    38 ISENSE_PVCCIN_CPU1_PH5_IMON @BASEBOARD_FAB2_LIB.BASEBOARD_FAB2(SCH_1):ISENSE_PVCCIN_CPU1_PH5_IMON    I56 @BASEBOARD_FAB2_LIB.BASEBOARD_FAB2(SCH_1):PAGE209
     2    GND @BASEBOARD_FAB2_LIB.BASEBOARD_FAB2(SCH_1):GND    I56 @BASEBOARD_FAB2_LIB.BASEBOARD_FAB2(SCH_1):PAGE209
    31     NC     NC    I56 @BASEBOARD_FAB2_LIB.BASEBOARD_FAB2(SCH_1):PAGE209
    37 VR_PVCCIN_CPU1_PH5_OCSET @BASEBOARD_FAB2_LIB.BASEBOARD_FAB2(SCH_1):VR_PVCCIN_CPU1_PH5_OCSET    I56 @BASEBOARD_FAB2_LIB.BASEBOARD_FAB2(SCH_1):PAGE209
    40    GND @BASEBOARD_FAB2_LIB.BASEBOARD_FAB2(SCH_1):GND    I56 @BASEBOARD_FAB2_LIB.BASEBOARD_FAB2(SCH_1):PAGE209
     7    GND @BASEBOARD_FAB2_LIB.BASEBOARD_FAB2(SCH_1):GND    I56 @BASEBOARD_FAB2_LIB.BASEBOARD_FAB2(SCH_1):PAGE209
     5    GND @BASEBOARD_FAB2_LIB.BASEBOARD_FAB2(SCH_1):GND    I56 @BASEBOARD_FAB2_LIB.BASEBOARD_FAB2(SCH_1):PAGE209
    32 VR_PVCCIN_CPU1_PH5_PHASE @BASEBOARD_FAB2_LIB.BASEBOARD_FAB2(SCH_1):VR_PVCCIN_CPU1_PH5_PHASE    I56 @BASEBOARD_FAB2_LIB.BASEBOARD_FAB2(SCH_1):PAGE209
    34 VR_PVCCIN_CPU1_PWM5 @BASEBOARD_FAB2_LIB.BASEBOARD_FAB2(SCH_1):VR_PVCCIN_CPU1_PWM5    I56 @BASEBOARD_FAB2_LIB.BASEBOARD_FAB2(SCH_1):PAGE209
    39 VR_PVCCIN_CPU1_AIREF5 @BASEBOARD_FAB2_LIB.BASEBOARD_FAB2(SCH_1):VR_PVCCIN_CPU1_AIREF5    I56 @BASEBOARD_FAB2_LIB.BASEBOARD_FAB2(SCH_1):PAGE209
    10 VR_PVCCIN_CPU1_PHASE5 @BASEBOARD_FAB2_LIB.BASEBOARD_FAB2(SCH_1):VR_PVCCIN_CPU1_PHASE5    I56 @BASEBOARD_FAB2_LIB.BASEBOARD_FAB2(SCH_1):PAGE209
    36 A_TSENSE_PVCCIN_CPU1 @BASEBOARD_FAB2_LIB.BASEBOARD_FAB2(SCH_1):A_TSENSE_PVCCIN_CPU1    I56 @BASEBOARD_FAB2_LIB.BASEBOARD_FAB2(SCH_1):PAGE209
     3 VR_PVCCIN_CPU1_PH5_VCIN @BASEBOARD_FAB2_LIB.BASEBOARD_FAB2(SCH_1):VR_PVCCIN_CPU1_PH5_VCIN    I56 @BASEBOARD_FAB2_LIB.BASEBOARD_FAB2(SCH_1):PAGE209
     4 P5V_STBY @BASEBOARD_FAB2_LIB.BASEBOARD_FAB2(SCH_1):P5V_STBY    I56 @BASEBOARD_FAB2_LIB.BASEBOARD_FAB2(SCH_1):PAGE209
    30 VR_FET_SW_P12V_STBY_PVCCIN_CPU1 @BASEBOARD_FAB2_LIB.BASEBOARD_FAB2(SCH_1):VR_FET_SW_P12V_STBY_PVCCIN_CPU1    I56 @BASEBOARD_FAB2_LIB.BASEBOARD_FAB2(SCH_1):PAGE209
    25 VR_FET_SW_P12V_STBY_PVCCIN_CPU1 @BASEBOARD_FAB2_LIB.BASEBOARD_FAB2(SCH_1):VR_FET_SW_P12V_STBY_PVCCIN_CPU1    I56 @BASEBOARD_FAB2_LIB.BASEBOARD_FAB2(SCH_1):PAGE209
     1 PVCCIN_CPU1 @BASEBOARD_FAB2_LIB.BASEBOARD_FAB2(SCH_1):PVCCIN_CPU1    I56 @BASEBOARD_FAB2_LIB.BASEBOARD_FAB2(SCH_1):PAGE209

EU1D1 IR354XX_SM-IR35411,IC,H73688-0A
    33 VR_PVCCIN_CPU1_PH4_BOOT_R @BASEBOARD_FAB2_LIB.BASEBOARD_FAB2(SCH_1):VR_PVCCIN_CPU1_PH4_BOOT_R    I71 @BASEBOARD_FAB2_LIB.BASEBOARD_FAB2(SCH_1):PAGE208
    35 P5V_STBY @BASEBOARD_FAB2_LIB.BASEBOARD_FAB2(SCH_1):P5V_STBY    I71 @BASEBOARD_FAB2_LIB.BASEBOARD_FAB2(SCH_1):PAGE208
    41 TP_PVCCIN_CPU1_PH4_GL_1 @BASEBOARD_FAB2_LIB.BASEBOARD_FAB2(SCH_1):TP_PVCCIN_CPU1_PH4_GL_1    I71 @BASEBOARD_FAB2_LIB.BASEBOARD_FAB2(SCH_1):PAGE208
     6 TP_PVCCIN_CPU1_PH4_GL_0 @BASEBOARD_FAB2_LIB.BASEBOARD_FAB2(SCH_1):TP_PVCCIN_CPU1_PH4_GL_0    I71 @BASEBOARD_FAB2_LIB.BASEBOARD_FAB2(SCH_1):PAGE208
    38 ISENSE_PVCCIN_CPU1_PH4_IMON @BASEBOARD_FAB2_LIB.BASEBOARD_FAB2(SCH_1):ISENSE_PVCCIN_CPU1_PH4_IMON    I71 @BASEBOARD_FAB2_LIB.BASEBOARD_FAB2(SCH_1):PAGE208
     2    GND @BASEBOARD_FAB2_LIB.BASEBOARD_FAB2(SCH_1):GND    I71 @BASEBOARD_FAB2_LIB.BASEBOARD_FAB2(SCH_1):PAGE208
    31     NC     NC    I71 @BASEBOARD_FAB2_LIB.BASEBOARD_FAB2(SCH_1):PAGE208
    37 VR_PVCCIN_CPU1_PH4_OCSET @BASEBOARD_FAB2_LIB.BASEBOARD_FAB2(SCH_1):VR_PVCCIN_CPU1_PH4_OCSET    I71 @BASEBOARD_FAB2_LIB.BASEBOARD_FAB2(SCH_1):PAGE208
    40    GND @BASEBOARD_FAB2_LIB.BASEBOARD_FAB2(SCH_1):GND    I71 @BASEBOARD_FAB2_LIB.BASEBOARD_FAB2(SCH_1):PAGE208
     7    GND @BASEBOARD_FAB2_LIB.BASEBOARD_FAB2(SCH_1):GND    I71 @BASEBOARD_FAB2_LIB.BASEBOARD_FAB2(SCH_1):PAGE208
     5    GND @BASEBOARD_FAB2_LIB.BASEBOARD_FAB2(SCH_1):GND    I71 @BASEBOARD_FAB2_LIB.BASEBOARD_FAB2(SCH_1):PAGE208
    32 VR_PVCCIN_CPU1_PH4_PHASE @BASEBOARD_FAB2_LIB.BASEBOARD_FAB2(SCH_1):VR_PVCCIN_CPU1_PH4_PHASE    I71 @BASEBOARD_FAB2_LIB.BASEBOARD_FAB2(SCH_1):PAGE208
    34 VR_PVCCIN_CPU1_PWM4 @BASEBOARD_FAB2_LIB.BASEBOARD_FAB2(SCH_1):VR_PVCCIN_CPU1_PWM4    I71 @BASEBOARD_FAB2_LIB.BASEBOARD_FAB2(SCH_1):PAGE208
    39 VR_PVCCIN_CPU1_AIREF4 @BASEBOARD_FAB2_LIB.BASEBOARD_FAB2(SCH_1):VR_PVCCIN_CPU1_AIREF4    I71 @BASEBOARD_FAB2_LIB.BASEBOARD_FAB2(SCH_1):PAGE208
    10 VR_PVCCIN_CPU1_PHASE4 @BASEBOARD_FAB2_LIB.BASEBOARD_FAB2(SCH_1):VR_PVCCIN_CPU1_PHASE4    I71 @BASEBOARD_FAB2_LIB.BASEBOARD_FAB2(SCH_1):PAGE208
    36 A_TSENSE_PVCCIN_CPU1 @BASEBOARD_FAB2_LIB.BASEBOARD_FAB2(SCH_1):A_TSENSE_PVCCIN_CPU1    I71 @BASEBOARD_FAB2_LIB.BASEBOARD_FAB2(SCH_1):PAGE208
     3 VR_PVCCIN_CPU1_PH4_VCIN @BASEBOARD_FAB2_LIB.BASEBOARD_FAB2(SCH_1):VR_PVCCIN_CPU1_PH4_VCIN    I71 @BASEBOARD_FAB2_LIB.BASEBOARD_FAB2(SCH_1):PAGE208
     4 P5V_STBY @BASEBOARD_FAB2_LIB.BASEBOARD_FAB2(SCH_1):P5V_STBY    I71 @BASEBOARD_FAB2_LIB.BASEBOARD_FAB2(SCH_1):PAGE208
    30 VR_FET_SW_P12V_STBY_PVCCIN_CPU1 @BASEBOARD_FAB2_LIB.BASEBOARD_FAB2(SCH_1):VR_FET_SW_P12V_STBY_PVCCIN_CPU1    I71 @BASEBOARD_FAB2_LIB.BASEBOARD_FAB2(SCH_1):PAGE208
    25 VR_FET_SW_P12V_STBY_PVCCIN_CPU1 @BASEBOARD_FAB2_LIB.BASEBOARD_FAB2(SCH_1):VR_FET_SW_P12V_STBY_PVCCIN_CPU1    I71 @BASEBOARD_FAB2_LIB.BASEBOARD_FAB2(SCH_1):PAGE208
     1 PVCCIN_CPU1 @BASEBOARD_FAB2_LIB.BASEBOARD_FAB2(SCH_1):PVCCIN_CPU1    I71 @BASEBOARD_FAB2_LIB.BASEBOARD_FAB2(SCH_1):PAGE208

EU1D2 ADM1278_SM-IC,G99251-001
     7 FM_P12V_HSC_ADR1 @BASEBOARD_FAB2_LIB.BASEBOARD_FAB2(SCH_1):FM_P12V_HSC_ADR1    I10 @BASEBOARD_FAB2_LIB.BASEBOARD_FAB2(SCH_1):PAGE199
     8 FM_P12V_HSC_ADR2 @BASEBOARD_FAB2_LIB.BASEBOARD_FAB2(SCH_1):FM_P12V_HSC_ADR2    I10 @BASEBOARD_FAB2_LIB.BASEBOARD_FAB2(SCH_1):PAGE199
    19 A_HSC_CSOUT @BASEBOARD_FAB2_LIB.BASEBOARD_FAB2(SCH_1):A_HSC_CSOUT    I10 @BASEBOARD_FAB2_LIB.BASEBOARD_FAB2(SCH_1):PAGE199
    12 FM_P12V_HOTSWAP0_EN @BASEBOARD_FAB2_LIB.BASEBOARD_FAB2(SCH_1):FM_P12V_HOTSWAP0_EN    I10 @BASEBOARD_FAB2_LIB.BASEBOARD_FAB2(SCH_1):PAGE199
    33 AGND_HSC @BASEBOARD_FAB2_LIB.BASEBOARD_FAB2(SCH_1):AGND_HSC    I10 @BASEBOARD_FAB2_LIB.BASEBOARD_FAB2(SCH_1):PAGE199
     6 IRQ_HSC_FAULT_R_N @BASEBOARD_FAB2_LIB.BASEBOARD_FAB2(SCH_1):IRQ_HSC_FAULT_R_N    I10 @BASEBOARD_FAB2_LIB.BASEBOARD_FAB2(SCH_1):PAGE199
    24 A_HSC_GATE @BASEBOARD_FAB2_LIB.BASEBOARD_FAB2(SCH_1):A_HSC_GATE    I10 @BASEBOARD_FAB2_LIB.BASEBOARD_FAB2(SCH_1):PAGE199
    22 AGND_HSC @BASEBOARD_FAB2_LIB.BASEBOARD_FAB2(SCH_1):AGND_HSC    I10 @BASEBOARD_FAB2_LIB.BASEBOARD_FAB2(SCH_1):PAGE199
    13 IRQ_SML1_PMBUS_ALERT_R_N @BASEBOARD_FAB2_LIB.BASEBOARD_FAB2(SCH_1):IRQ_SML1_PMBUS_ALERT_R_N    I10 @BASEBOARD_FAB2_LIB.BASEBOARD_FAB2(SCH_1):PAGE199
    14 TP_HSC_ALERT2_N @BASEBOARD_FAB2_LIB.BASEBOARD_FAB2(SCH_1):TP_HSC_ALERT2_N    I10 @BASEBOARD_FAB2_LIB.BASEBOARD_FAB2(SCH_1):PAGE199
    27 A_HSC_HSN @BASEBOARD_FAB2_LIB.BASEBOARD_FAB2(SCH_1):A_HSC_HSN    I10 @BASEBOARD_FAB2_LIB.BASEBOARD_FAB2(SCH_1):PAGE199
    28 A_HSC_HSP @BASEBOARD_FAB2_LIB.BASEBOARD_FAB2(SCH_1):A_HSC_HSP    I10 @BASEBOARD_FAB2_LIB.BASEBOARD_FAB2(SCH_1):PAGE199
     3 A_HSC_ISET @BASEBOARD_FAB2_LIB.BASEBOARD_FAB2(SCH_1):A_HSC_ISET    I10 @BASEBOARD_FAB2_LIB.BASEBOARD_FAB2(SCH_1):PAGE199
     4 A_HSC_ISTART @BASEBOARD_FAB2_LIB.BASEBOARD_FAB2(SCH_1):A_HSC_ISTART    I10 @BASEBOARD_FAB2_LIB.BASEBOARD_FAB2(SCH_1):PAGE199
    10 TP_HSC_MCLK @BASEBOARD_FAB2_LIB.BASEBOARD_FAB2(SCH_1):TP_HSC_MCLK    I10 @BASEBOARD_FAB2_LIB.BASEBOARD_FAB2(SCH_1):PAGE199
    11 TP_HSC_MDAT @BASEBOARD_FAB2_LIB.BASEBOARD_FAB2(SCH_1):TP_HSC_MDAT    I10 @BASEBOARD_FAB2_LIB.BASEBOARD_FAB2(SCH_1):PAGE199
    26 A_HSC_MON @BASEBOARD_FAB2_LIB.BASEBOARD_FAB2(SCH_1):A_HSC_MON    I10 @BASEBOARD_FAB2_LIB.BASEBOARD_FAB2(SCH_1):PAGE199
    29 A_HSC_MOP @BASEBOARD_FAB2_LIB.BASEBOARD_FAB2(SCH_1):A_HSC_MOP    I10 @BASEBOARD_FAB2_LIB.BASEBOARD_FAB2(SCH_1):PAGE199
    32 A_HSC_OV @BASEBOARD_FAB2_LIB.BASEBOARD_FAB2(SCH_1):A_HSC_OV    I10 @BASEBOARD_FAB2_LIB.BASEBOARD_FAB2(SCH_1):PAGE199
    23    GND @BASEBOARD_FAB2_LIB.BASEBOARD_FAB2(SCH_1):GND    I10 @BASEBOARD_FAB2_LIB.BASEBOARD_FAB2(SCH_1):PAGE199
     1 A_HSC_PSET @BASEBOARD_FAB2_LIB.BASEBOARD_FAB2(SCH_1):A_HSC_PSET    I10 @BASEBOARD_FAB2_LIB.BASEBOARD_FAB2(SCH_1):PAGE199
    21 A_HSC_PWGIN @BASEBOARD_FAB2_LIB.BASEBOARD_FAB2(SCH_1):A_HSC_PWGIN    I10 @BASEBOARD_FAB2_LIB.BASEBOARD_FAB2(SCH_1):PAGE199
    18 PWRGD_P12V_R @BASEBOARD_FAB2_LIB.BASEBOARD_FAB2(SCH_1):PWRGD_P12V_R    I10 @BASEBOARD_FAB2_LIB.BASEBOARD_FAB2(SCH_1):PAGE199
    17 PD_HSC_RETRY_N @BASEBOARD_FAB2_LIB.BASEBOARD_FAB2(SCH_1):PD_HSC_RETRY_N    I10 @BASEBOARD_FAB2_LIB.BASEBOARD_FAB2(SCH_1):PAGE199
    16 SMB_3V3SB_HSC_SCL_R @BASEBOARD_FAB2_LIB.BASEBOARD_FAB2(SCH_1):SMB_3V3SB_HSC_SCL_R    I10 @BASEBOARD_FAB2_LIB.BASEBOARD_FAB2(SCH_1):PAGE199
    15 SMB_3V3SB_HSC_SDA_R @BASEBOARD_FAB2_LIB.BASEBOARD_FAB2(SCH_1):SMB_3V3SB_HSC_SDA_R    I10 @BASEBOARD_FAB2_LIB.BASEBOARD_FAB2(SCH_1):PAGE199
     9 TP_HSC_SPISSN @BASEBOARD_FAB2_LIB.BASEBOARD_FAB2(SCH_1):TP_HSC_SPISSN    I10 @BASEBOARD_FAB2_LIB.BASEBOARD_FAB2(SCH_1):PAGE199
    25 A_HSC_TEMP @BASEBOARD_FAB2_LIB.BASEBOARD_FAB2(SCH_1):A_HSC_TEMP    I10 @BASEBOARD_FAB2_LIB.BASEBOARD_FAB2(SCH_1):PAGE199
     5 A_HSC_TIMER @BASEBOARD_FAB2_LIB.BASEBOARD_FAB2(SCH_1):A_HSC_TIMER    I10 @BASEBOARD_FAB2_LIB.BASEBOARD_FAB2(SCH_1):PAGE199
    31 A_HSC_UV @BASEBOARD_FAB2_LIB.BASEBOARD_FAB2(SCH_1):A_HSC_UV    I10 @BASEBOARD_FAB2_LIB.BASEBOARD_FAB2(SCH_1):PAGE199
     2 A_HSC_VCAP @BASEBOARD_FAB2_LIB.BASEBOARD_FAB2(SCH_1):A_HSC_VCAP    I10 @BASEBOARD_FAB2_LIB.BASEBOARD_FAB2(SCH_1):PAGE199
    30 P12V_HSC_VCC @BASEBOARD_FAB2_LIB.BASEBOARD_FAB2(SCH_1):P12V_HSC_VCC    I10 @BASEBOARD_FAB2_LIB.BASEBOARD_FAB2(SCH_1):PAGE199
    20 A_HSC_VOUT @BASEBOARD_FAB2_LIB.BASEBOARD_FAB2(SCH_1):A_HSC_VOUT    I10 @BASEBOARD_FAB2_LIB.BASEBOARD_FAB2(SCH_1):PAGE199

EU1D3 IR354XX_SM-IR35411,IC,H73688-0A
    33 VR_PVCCIN_CPU1_PH3_BOOT_R @BASEBOARD_FAB2_LIB.BASEBOARD_FAB2(SCH_1):VR_PVCCIN_CPU1_PH3_BOOT_R    I27 @BASEBOARD_FAB2_LIB.BASEBOARD_FAB2(SCH_1):PAGE208
    35 P5V_STBY @BASEBOARD_FAB2_LIB.BASEBOARD_FAB2(SCH_1):P5V_STBY    I27 @BASEBOARD_FAB2_LIB.BASEBOARD_FAB2(SCH_1):PAGE208
    41 TP_PVCCIN_CPU1_PH3_GL_1 @BASEBOARD_FAB2_LIB.BASEBOARD_FAB2(SCH_1):TP_PVCCIN_CPU1_PH3_GL_1    I27 @BASEBOARD_FAB2_LIB.BASEBOARD_FAB2(SCH_1):PAGE208
     6 TP_PVCCIN_CPU1_PH3_GL_0 @BASEBOARD_FAB2_LIB.BASEBOARD_FAB2(SCH_1):TP_PVCCIN_CPU1_PH3_GL_0    I27 @BASEBOARD_FAB2_LIB.BASEBOARD_FAB2(SCH_1):PAGE208
    38 ISENSE_PVCCIN_CPU1_PH3_IMON @BASEBOARD_FAB2_LIB.BASEBOARD_FAB2(SCH_1):ISENSE_PVCCIN_CPU1_PH3_IMON    I27 @BASEBOARD_FAB2_LIB.BASEBOARD_FAB2(SCH_1):PAGE208
     2    GND @BASEBOARD_FAB2_LIB.BASEBOARD_FAB2(SCH_1):GND    I27 @BASEBOARD_FAB2_LIB.BASEBOARD_FAB2(SCH_1):PAGE208
    31     NC     NC    I27 @BASEBOARD_FAB2_LIB.BASEBOARD_FAB2(SCH_1):PAGE208
    37 VR_PVCCIN_CPU1_PH3_OCSET @BASEBOARD_FAB2_LIB.BASEBOARD_FAB2(SCH_1):VR_PVCCIN_CPU1_PH3_OCSET    I27 @BASEBOARD_FAB2_LIB.BASEBOARD_FAB2(SCH_1):PAGE208
    40    GND @BASEBOARD_FAB2_LIB.BASEBOARD_FAB2(SCH_1):GND    I27 @BASEBOARD_FAB2_LIB.BASEBOARD_FAB2(SCH_1):PAGE208
     7    GND @BASEBOARD_FAB2_LIB.BASEBOARD_FAB2(SCH_1):GND    I27 @BASEBOARD_FAB2_LIB.BASEBOARD_FAB2(SCH_1):PAGE208
     5    GND @BASEBOARD_FAB2_LIB.BASEBOARD_FAB2(SCH_1):GND    I27 @BASEBOARD_FAB2_LIB.BASEBOARD_FAB2(SCH_1):PAGE208
    32 VR_PVCCIN_CPU1_PH3_PHASE @BASEBOARD_FAB2_LIB.BASEBOARD_FAB2(SCH_1):VR_PVCCIN_CPU1_PH3_PHASE    I27 @BASEBOARD_FAB2_LIB.BASEBOARD_FAB2(SCH_1):PAGE208
    34 VR_PVCCIN_CPU1_PWM3 @BASEBOARD_FAB2_LIB.BASEBOARD_FAB2(SCH_1):VR_PVCCIN_CPU1_PWM3    I27 @BASEBOARD_FAB2_LIB.BASEBOARD_FAB2(SCH_1):PAGE208
    39 VR_PVCCIN_CPU1_AIREF3 @BASEBOARD_FAB2_LIB.BASEBOARD_FAB2(SCH_1):VR_PVCCIN_CPU1_AIREF3    I27 @BASEBOARD_FAB2_LIB.BASEBOARD_FAB2(SCH_1):PAGE208
    10 VR_PVCCIN_CPU1_PHASE3 @BASEBOARD_FAB2_LIB.BASEBOARD_FAB2(SCH_1):VR_PVCCIN_CPU1_PHASE3    I27 @BASEBOARD_FAB2_LIB.BASEBOARD_FAB2(SCH_1):PAGE208
    36 A_TSENSE_PVCCIN_CPU1 @BASEBOARD_FAB2_LIB.BASEBOARD_FAB2(SCH_1):A_TSENSE_PVCCIN_CPU1    I27 @BASEBOARD_FAB2_LIB.BASEBOARD_FAB2(SCH_1):PAGE208
     3 VR_PVCCIN_CPU1_PH3_VCIN @BASEBOARD_FAB2_LIB.BASEBOARD_FAB2(SCH_1):VR_PVCCIN_CPU1_PH3_VCIN    I27 @BASEBOARD_FAB2_LIB.BASEBOARD_FAB2(SCH_1):PAGE208
     4 P5V_STBY @BASEBOARD_FAB2_LIB.BASEBOARD_FAB2(SCH_1):P5V_STBY    I27 @BASEBOARD_FAB2_LIB.BASEBOARD_FAB2(SCH_1):PAGE208
    30 VR_FET_SW_P12V_STBY_PVCCIN_CPU1 @BASEBOARD_FAB2_LIB.BASEBOARD_FAB2(SCH_1):VR_FET_SW_P12V_STBY_PVCCIN_CPU1    I27 @BASEBOARD_FAB2_LIB.BASEBOARD_FAB2(SCH_1):PAGE208
    25 VR_FET_SW_P12V_STBY_PVCCIN_CPU1 @BASEBOARD_FAB2_LIB.BASEBOARD_FAB2(SCH_1):VR_FET_SW_P12V_STBY_PVCCIN_CPU1    I27 @BASEBOARD_FAB2_LIB.BASEBOARD_FAB2(SCH_1):PAGE208
     1 PVCCIN_CPU1 @BASEBOARD_FAB2_LIB.BASEBOARD_FAB2(SCH_1):PVCCIN_CPU1    I27 @BASEBOARD_FAB2_LIB.BASEBOARD_FAB2(SCH_1):PAGE208

EU1D4 IR354XX_SM-IR35411,IC,H73688-0A
    33 VR_PVCCIN_CPU1_PH2_BOOT_R @BASEBOARD_FAB2_LIB.BASEBOARD_FAB2(SCH_1):VR_PVCCIN_CPU1_PH2_BOOT_R   I113 @BASEBOARD_FAB2_LIB.BASEBOARD_FAB2(SCH_1):PAGE207
    35 P5V_STBY @BASEBOARD_FAB2_LIB.BASEBOARD_FAB2(SCH_1):P5V_STBY   I113 @BASEBOARD_FAB2_LIB.BASEBOARD_FAB2(SCH_1):PAGE207
    41 TP_PVCCINC_CPU1_PH2_GL_1 @BASEBOARD_FAB2_LIB.BASEBOARD_FAB2(SCH_1):TP_PVCCINC_CPU1_PH2_GL_1   I113 @BASEBOARD_FAB2_LIB.BASEBOARD_FAB2(SCH_1):PAGE207
     6 TP_PVCCINC_CPU1_PH2_GL_0 @BASEBOARD_FAB2_LIB.BASEBOARD_FAB2(SCH_1):TP_PVCCINC_CPU1_PH2_GL_0   I113 @BASEBOARD_FAB2_LIB.BASEBOARD_FAB2(SCH_1):PAGE207
    38 ISENSE_PVCCIN_CPU1_PH2_IMON @BASEBOARD_FAB2_LIB.BASEBOARD_FAB2(SCH_1):ISENSE_PVCCIN_CPU1_PH2_IMON   I113 @BASEBOARD_FAB2_LIB.BASEBOARD_FAB2(SCH_1):PAGE207
     2    GND @BASEBOARD_FAB2_LIB.BASEBOARD_FAB2(SCH_1):GND   I113 @BASEBOARD_FAB2_LIB.BASEBOARD_FAB2(SCH_1):PAGE207
    31     NC     NC   I113 @BASEBOARD_FAB2_LIB.BASEBOARD_FAB2(SCH_1):PAGE207
    37 VR_PVCCIN_CPU1_PH2_OCSET @BASEBOARD_FAB2_LIB.BASEBOARD_FAB2(SCH_1):VR_PVCCIN_CPU1_PH2_OCSET   I113 @BASEBOARD_FAB2_LIB.BASEBOARD_FAB2(SCH_1):PAGE207
    40    GND @BASEBOARD_FAB2_LIB.BASEBOARD_FAB2(SCH_1):GND   I113 @BASEBOARD_FAB2_LIB.BASEBOARD_FAB2(SCH_1):PAGE207
     7    GND @BASEBOARD_FAB2_LIB.BASEBOARD_FAB2(SCH_1):GND   I113 @BASEBOARD_FAB2_LIB.BASEBOARD_FAB2(SCH_1):PAGE207
     5    GND @BASEBOARD_FAB2_LIB.BASEBOARD_FAB2(SCH_1):GND   I113 @BASEBOARD_FAB2_LIB.BASEBOARD_FAB2(SCH_1):PAGE207
    32 VR_PVCCIN_CPU1_PH2_PHASE @BASEBOARD_FAB2_LIB.BASEBOARD_FAB2(SCH_1):VR_PVCCIN_CPU1_PH2_PHASE   I113 @BASEBOARD_FAB2_LIB.BASEBOARD_FAB2(SCH_1):PAGE207
    34 VR_PVCCIN_CPU1_PWM2 @BASEBOARD_FAB2_LIB.BASEBOARD_FAB2(SCH_1):VR_PVCCIN_CPU1_PWM2   I113 @BASEBOARD_FAB2_LIB.BASEBOARD_FAB2(SCH_1):PAGE207
    39 VR_PVCCIN_CPU1_AIREF2 @BASEBOARD_FAB2_LIB.BASEBOARD_FAB2(SCH_1):VR_PVCCIN_CPU1_AIREF2   I113 @BASEBOARD_FAB2_LIB.BASEBOARD_FAB2(SCH_1):PAGE207
    10 VR_PVCCIN_CPU1_PHASE2 @BASEBOARD_FAB2_LIB.BASEBOARD_FAB2(SCH_1):VR_PVCCIN_CPU1_PHASE2   I113 @BASEBOARD_FAB2_LIB.BASEBOARD_FAB2(SCH_1):PAGE207
    36 A_TSENSE_PVCCIN_CPU1 @BASEBOARD_FAB2_LIB.BASEBOARD_FAB2(SCH_1):A_TSENSE_PVCCIN_CPU1   I113 @BASEBOARD_FAB2_LIB.BASEBOARD_FAB2(SCH_1):PAGE207
     3 VR_PVCCIN_CPU1_PH2_VCIN @BASEBOARD_FAB2_LIB.BASEBOARD_FAB2(SCH_1):VR_PVCCIN_CPU1_PH2_VCIN   I113 @BASEBOARD_FAB2_LIB.BASEBOARD_FAB2(SCH_1):PAGE207
     4 P5V_STBY @BASEBOARD_FAB2_LIB.BASEBOARD_FAB2(SCH_1):P5V_STBY   I113 @BASEBOARD_FAB2_LIB.BASEBOARD_FAB2(SCH_1):PAGE207
    30 VR_FET_SW_P12V_STBY_PVCCIN_CPU1 @BASEBOARD_FAB2_LIB.BASEBOARD_FAB2(SCH_1):VR_FET_SW_P12V_STBY_PVCCIN_CPU1   I113 @BASEBOARD_FAB2_LIB.BASEBOARD_FAB2(SCH_1):PAGE207
    25 VR_FET_SW_P12V_STBY_PVCCIN_CPU1 @BASEBOARD_FAB2_LIB.BASEBOARD_FAB2(SCH_1):VR_FET_SW_P12V_STBY_PVCCIN_CPU1   I113 @BASEBOARD_FAB2_LIB.BASEBOARD_FAB2(SCH_1):PAGE207
     1 PVCCIN_CPU1 @BASEBOARD_FAB2_LIB.BASEBOARD_FAB2(SCH_1):PVCCIN_CPU1   I113 @BASEBOARD_FAB2_LIB.BASEBOARD_FAB2(SCH_1):PAGE207

EU1E1 MOSFETN_1D3S_SOT5-IC,G68777-001
     1 P12V_STBY @BASEBOARD_FAB2_LIB.BASEBOARD_FAB2(SCH_1):P12V_STBY    I59 @BASEBOARD_FAB2_LIB.BASEBOARD_FAB2(SCH_1):PAGE200
     2 P12V_STBY @BASEBOARD_FAB2_LIB.BASEBOARD_FAB2(SCH_1):P12V_STBY    I59 @BASEBOARD_FAB2_LIB.BASEBOARD_FAB2(SCH_1):PAGE200
     3 P12V_STBY @BASEBOARD_FAB2_LIB.BASEBOARD_FAB2(SCH_1):P12V_STBY    I59 @BASEBOARD_FAB2_LIB.BASEBOARD_FAB2(SCH_1):PAGE200
     5 P12V_MB0_SW @BASEBOARD_FAB2_LIB.BASEBOARD_FAB2(SCH_1):P12V_MB0_SW    I59 @BASEBOARD_FAB2_LIB.BASEBOARD_FAB2(SCH_1):PAGE200
     4 A_HSC_GATE3_R @BASEBOARD_FAB2_LIB.BASEBOARD_FAB2(SCH_1):A_HSC_GATE3_R    I59 @BASEBOARD_FAB2_LIB.BASEBOARD_FAB2(SCH_1):PAGE200

EU1E2 IR354XX_SM-IR35411,IC,H73688-0A
    33 VR_PVCCIN_CPU1_PH1_BOOT_R @BASEBOARD_FAB2_LIB.BASEBOARD_FAB2(SCH_1):VR_PVCCIN_CPU1_PH1_BOOT_R    I20 @BASEBOARD_FAB2_LIB.BASEBOARD_FAB2(SCH_1):PAGE207
    35 P5V_STBY @BASEBOARD_FAB2_LIB.BASEBOARD_FAB2(SCH_1):P5V_STBY    I20 @BASEBOARD_FAB2_LIB.BASEBOARD_FAB2(SCH_1):PAGE207
    41 TP_PVCCINC_CPU1_PH1_GL_1 @BASEBOARD_FAB2_LIB.BASEBOARD_FAB2(SCH_1):TP_PVCCINC_CPU1_PH1_GL_1    I20 @BASEBOARD_FAB2_LIB.BASEBOARD_FAB2(SCH_1):PAGE207
     6 TP_PVCCINC_CPU1_PH1_GL_0 @BASEBOARD_FAB2_LIB.BASEBOARD_FAB2(SCH_1):TP_PVCCINC_CPU1_PH1_GL_0    I20 @BASEBOARD_FAB2_LIB.BASEBOARD_FAB2(SCH_1):PAGE207
    38 ISENSE_PVCCIN_CPU1_PH1_IMON @BASEBOARD_FAB2_LIB.BASEBOARD_FAB2(SCH_1):ISENSE_PVCCIN_CPU1_PH1_IMON    I20 @BASEBOARD_FAB2_LIB.BASEBOARD_FAB2(SCH_1):PAGE207
     2    GND @BASEBOARD_FAB2_LIB.BASEBOARD_FAB2(SCH_1):GND    I20 @BASEBOARD_FAB2_LIB.BASEBOARD_FAB2(SCH_1):PAGE207
    31     NC     NC    I20 @BASEBOARD_FAB2_LIB.BASEBOARD_FAB2(SCH_1):PAGE207
    37 VR_PVCCIN_CPU1_PH1_OCSET @BASEBOARD_FAB2_LIB.BASEBOARD_FAB2(SCH_1):VR_PVCCIN_CPU1_PH1_OCSET    I20 @BASEBOARD_FAB2_LIB.BASEBOARD_FAB2(SCH_1):PAGE207
    40    GND @BASEBOARD_FAB2_LIB.BASEBOARD_FAB2(SCH_1):GND    I20 @BASEBOARD_FAB2_LIB.BASEBOARD_FAB2(SCH_1):PAGE207
     7    GND @BASEBOARD_FAB2_LIB.BASEBOARD_FAB2(SCH_1):GND    I20 @BASEBOARD_FAB2_LIB.BASEBOARD_FAB2(SCH_1):PAGE207
     5    GND @BASEBOARD_FAB2_LIB.BASEBOARD_FAB2(SCH_1):GND    I20 @BASEBOARD_FAB2_LIB.BASEBOARD_FAB2(SCH_1):PAGE207
    32 VR_PVCCIN_CPU1_PH1_PHASE @BASEBOARD_FAB2_LIB.BASEBOARD_FAB2(SCH_1):VR_PVCCIN_CPU1_PH1_PHASE    I20 @BASEBOARD_FAB2_LIB.BASEBOARD_FAB2(SCH_1):PAGE207
    34 VR_PVCCIN_CPU1_PWM1 @BASEBOARD_FAB2_LIB.BASEBOARD_FAB2(SCH_1):VR_PVCCIN_CPU1_PWM1    I20 @BASEBOARD_FAB2_LIB.BASEBOARD_FAB2(SCH_1):PAGE207
    39 VR_PVCCIN_CPU1_AIREF1 @BASEBOARD_FAB2_LIB.BASEBOARD_FAB2(SCH_1):VR_PVCCIN_CPU1_AIREF1    I20 @BASEBOARD_FAB2_LIB.BASEBOARD_FAB2(SCH_1):PAGE207
    10 VR_PVCCIN_CPU1_PHASE1 @BASEBOARD_FAB2_LIB.BASEBOARD_FAB2(SCH_1):VR_PVCCIN_CPU1_PHASE1    I20 @BASEBOARD_FAB2_LIB.BASEBOARD_FAB2(SCH_1):PAGE207
    36 A_TSENSE_PVCCIN_CPU1 @BASEBOARD_FAB2_LIB.BASEBOARD_FAB2(SCH_1):A_TSENSE_PVCCIN_CPU1    I20 @BASEBOARD_FAB2_LIB.BASEBOARD_FAB2(SCH_1):PAGE207
     3 VR_PVCCIN_CPU1_PH1_VCIN @BASEBOARD_FAB2_LIB.BASEBOARD_FAB2(SCH_1):VR_PVCCIN_CPU1_PH1_VCIN    I20 @BASEBOARD_FAB2_LIB.BASEBOARD_FAB2(SCH_1):PAGE207
     4 P5V_STBY @BASEBOARD_FAB2_LIB.BASEBOARD_FAB2(SCH_1):P5V_STBY    I20 @BASEBOARD_FAB2_LIB.BASEBOARD_FAB2(SCH_1):PAGE207
    30 VR_FET_SW_P12V_STBY_PVCCIN_CPU1 @BASEBOARD_FAB2_LIB.BASEBOARD_FAB2(SCH_1):VR_FET_SW_P12V_STBY_PVCCIN_CPU1    I20 @BASEBOARD_FAB2_LIB.BASEBOARD_FAB2(SCH_1):PAGE207
    25 VR_FET_SW_P12V_STBY_PVCCIN_CPU1 @BASEBOARD_FAB2_LIB.BASEBOARD_FAB2(SCH_1):VR_FET_SW_P12V_STBY_PVCCIN_CPU1    I20 @BASEBOARD_FAB2_LIB.BASEBOARD_FAB2(SCH_1):PAGE207
     1 PVCCIN_CPU1 @BASEBOARD_FAB2_LIB.BASEBOARD_FAB2(SCH_1):PVCCIN_CPU1    I20 @BASEBOARD_FAB2_LIB.BASEBOARD_FAB2(SCH_1):PAGE207

EU1E3 MOSFETN_1D3S_SOT5-IC,G68777-001
     1 P12V_STBY @BASEBOARD_FAB2_LIB.BASEBOARD_FAB2(SCH_1):P12V_STBY    I54 @BASEBOARD_FAB2_LIB.BASEBOARD_FAB2(SCH_1):PAGE200
     2 P12V_STBY @BASEBOARD_FAB2_LIB.BASEBOARD_FAB2(SCH_1):P12V_STBY    I54 @BASEBOARD_FAB2_LIB.BASEBOARD_FAB2(SCH_1):PAGE200
     3 P12V_STBY @BASEBOARD_FAB2_LIB.BASEBOARD_FAB2(SCH_1):P12V_STBY    I54 @BASEBOARD_FAB2_LIB.BASEBOARD_FAB2(SCH_1):PAGE200
     5 P12V_MB0_SW @BASEBOARD_FAB2_LIB.BASEBOARD_FAB2(SCH_1):P12V_MB0_SW    I54 @BASEBOARD_FAB2_LIB.BASEBOARD_FAB2(SCH_1):PAGE200
     4 A_HSC_GATE1_R @BASEBOARD_FAB2_LIB.BASEBOARD_FAB2(SCH_1):A_HSC_GATE1_R    I54 @BASEBOARD_FAB2_LIB.BASEBOARD_FAB2(SCH_1):PAGE200

EU1F1 IR354XX_SM-IR35411,IC,H73688-0A
    33 VR_PVDDQ_GHJ_PH2_BOOT_R @BASEBOARD_FAB2_LIB.BASEBOARD_FAB2(SCH_1):VR_PVDDQ_GHJ_PH2_BOOT_R   I111 @BASEBOARD_FAB2_LIB.BASEBOARD_FAB2(SCH_1):PAGE224
    35 P5V_STBY @BASEBOARD_FAB2_LIB.BASEBOARD_FAB2(SCH_1):P5V_STBY   I111 @BASEBOARD_FAB2_LIB.BASEBOARD_FAB2(SCH_1):PAGE224
    41 TP_PVDDQ_GHJ_PH2_GL_1 @BASEBOARD_FAB2_LIB.BASEBOARD_FAB2(SCH_1):TP_PVDDQ_GHJ_PH2_GL_1   I111 @BASEBOARD_FAB2_LIB.BASEBOARD_FAB2(SCH_1):PAGE224
     6 TP_PVDDQ_GHJ_PH2_GL_0 @BASEBOARD_FAB2_LIB.BASEBOARD_FAB2(SCH_1):TP_PVDDQ_GHJ_PH2_GL_0   I111 @BASEBOARD_FAB2_LIB.BASEBOARD_FAB2(SCH_1):PAGE224
    38 ISENSE_PVDDQ_GHJ_PH2_IMON @BASEBOARD_FAB2_LIB.BASEBOARD_FAB2(SCH_1):ISENSE_PVDDQ_GHJ_PH2_IMON   I111 @BASEBOARD_FAB2_LIB.BASEBOARD_FAB2(SCH_1):PAGE224
     2    GND @BASEBOARD_FAB2_LIB.BASEBOARD_FAB2(SCH_1):GND   I111 @BASEBOARD_FAB2_LIB.BASEBOARD_FAB2(SCH_1):PAGE224
    31     NC     NC   I111 @BASEBOARD_FAB2_LIB.BASEBOARD_FAB2(SCH_1):PAGE224
    37 VR_PVDDQ_GHJ_PH2_OCSET @BASEBOARD_FAB2_LIB.BASEBOARD_FAB2(SCH_1):VR_PVDDQ_GHJ_PH2_OCSET   I111 @BASEBOARD_FAB2_LIB.BASEBOARD_FAB2(SCH_1):PAGE224
    40    GND @BASEBOARD_FAB2_LIB.BASEBOARD_FAB2(SCH_1):GND   I111 @BASEBOARD_FAB2_LIB.BASEBOARD_FAB2(SCH_1):PAGE224
     7    GND @BASEBOARD_FAB2_LIB.BASEBOARD_FAB2(SCH_1):GND   I111 @BASEBOARD_FAB2_LIB.BASEBOARD_FAB2(SCH_1):PAGE224
     5    GND @BASEBOARD_FAB2_LIB.BASEBOARD_FAB2(SCH_1):GND   I111 @BASEBOARD_FAB2_LIB.BASEBOARD_FAB2(SCH_1):PAGE224
    32 VR_PVDDQ_GHJ_PH2_PHASE @BASEBOARD_FAB2_LIB.BASEBOARD_FAB2(SCH_1):VR_PVDDQ_GHJ_PH2_PHASE   I111 @BASEBOARD_FAB2_LIB.BASEBOARD_FAB2(SCH_1):PAGE224
    34 VR_PVDDQ_GHJ_PWM2 @BASEBOARD_FAB2_LIB.BASEBOARD_FAB2(SCH_1):VR_PVDDQ_GHJ_PWM2   I111 @BASEBOARD_FAB2_LIB.BASEBOARD_FAB2(SCH_1):PAGE224
    39 VR_PVDDQ_GHJ_AIREF2 @BASEBOARD_FAB2_LIB.BASEBOARD_FAB2(SCH_1):VR_PVDDQ_GHJ_AIREF2   I111 @BASEBOARD_FAB2_LIB.BASEBOARD_FAB2(SCH_1):PAGE224
    10 VR_PVDDQ_GHJ_PH2_SW @BASEBOARD_FAB2_LIB.BASEBOARD_FAB2(SCH_1):VR_PVDDQ_GHJ_PH2_SW   I111 @BASEBOARD_FAB2_LIB.BASEBOARD_FAB2(SCH_1):PAGE224
    36 A_TSENSE_PVDDQ_GHJ @BASEBOARD_FAB2_LIB.BASEBOARD_FAB2(SCH_1):A_TSENSE_PVDDQ_GHJ   I111 @BASEBOARD_FAB2_LIB.BASEBOARD_FAB2(SCH_1):PAGE224
     3 VR_PVDDQ_GHJ_PH2_VCIN @BASEBOARD_FAB2_LIB.BASEBOARD_FAB2(SCH_1):VR_PVDDQ_GHJ_PH2_VCIN   I111 @BASEBOARD_FAB2_LIB.BASEBOARD_FAB2(SCH_1):PAGE224
     4 P5V_STBY @BASEBOARD_FAB2_LIB.BASEBOARD_FAB2(SCH_1):P5V_STBY   I111 @BASEBOARD_FAB2_LIB.BASEBOARD_FAB2(SCH_1):PAGE224
    30 VR_FET_SW_P12V_STBY_PVDDQ_GHJ @BASEBOARD_FAB2_LIB.BASEBOARD_FAB2(SCH_1):VR_FET_SW_P12V_STBY_PVDDQ_GHJ   I111 @BASEBOARD_FAB2_LIB.BASEBOARD_FAB2(SCH_1):PAGE224
    25 VR_FET_SW_P12V_STBY_PVDDQ_GHJ @BASEBOARD_FAB2_LIB.BASEBOARD_FAB2(SCH_1):VR_FET_SW_P12V_STBY_PVDDQ_GHJ   I111 @BASEBOARD_FAB2_LIB.BASEBOARD_FAB2(SCH_1):PAGE224
     1 PVDDQ_GHJ @BASEBOARD_FAB2_LIB.BASEBOARD_FAB2(SCH_1):PVDDQ_GHJ   I111 @BASEBOARD_FAB2_LIB.BASEBOARD_FAB2(SCH_1):PAGE224

EU1G1 IR354XX_SM-IR35411,IC,H73688-0A
    33 VR_PVDDQ_GHJ_PH1_BOOT_R @BASEBOARD_FAB2_LIB.BASEBOARD_FAB2(SCH_1):VR_PVDDQ_GHJ_PH1_BOOT_R   I110 @BASEBOARD_FAB2_LIB.BASEBOARD_FAB2(SCH_1):PAGE224
    35 P5V_STBY @BASEBOARD_FAB2_LIB.BASEBOARD_FAB2(SCH_1):P5V_STBY   I110 @BASEBOARD_FAB2_LIB.BASEBOARD_FAB2(SCH_1):PAGE224
    41 TP_PVDDQ_GHJ_PH1_GL_1 @BASEBOARD_FAB2_LIB.BASEBOARD_FAB2(SCH_1):TP_PVDDQ_GHJ_PH1_GL_1   I110 @BASEBOARD_FAB2_LIB.BASEBOARD_FAB2(SCH_1):PAGE224
     6 TP_PVDDQ_GHJ_PH1_GL_0 @BASEBOARD_FAB2_LIB.BASEBOARD_FAB2(SCH_1):TP_PVDDQ_GHJ_PH1_GL_0   I110 @BASEBOARD_FAB2_LIB.BASEBOARD_FAB2(SCH_1):PAGE224
    38 ISENSE_PVDDQ_GHJ_PH1_IMON @BASEBOARD_FAB2_LIB.BASEBOARD_FAB2(SCH_1):ISENSE_PVDDQ_GHJ_PH1_IMON   I110 @BASEBOARD_FAB2_LIB.BASEBOARD_FAB2(SCH_1):PAGE224
     2    GND @BASEBOARD_FAB2_LIB.BASEBOARD_FAB2(SCH_1):GND   I110 @BASEBOARD_FAB2_LIB.BASEBOARD_FAB2(SCH_1):PAGE224
    31     NC     NC   I110 @BASEBOARD_FAB2_LIB.BASEBOARD_FAB2(SCH_1):PAGE224
    37 VR_PVDDQ_GHJ_PH1_OCSET @BASEBOARD_FAB2_LIB.BASEBOARD_FAB2(SCH_1):VR_PVDDQ_GHJ_PH1_OCSET   I110 @BASEBOARD_FAB2_LIB.BASEBOARD_FAB2(SCH_1):PAGE224
    40    GND @BASEBOARD_FAB2_LIB.BASEBOARD_FAB2(SCH_1):GND   I110 @BASEBOARD_FAB2_LIB.BASEBOARD_FAB2(SCH_1):PAGE224
     7    GND @BASEBOARD_FAB2_LIB.BASEBOARD_FAB2(SCH_1):GND   I110 @BASEBOARD_FAB2_LIB.BASEBOARD_FAB2(SCH_1):PAGE224
     5    GND @BASEBOARD_FAB2_LIB.BASEBOARD_FAB2(SCH_1):GND   I110 @BASEBOARD_FAB2_LIB.BASEBOARD_FAB2(SCH_1):PAGE224
    32 VR_PVDDQ_GHJ_PH1_PHASE @BASEBOARD_FAB2_LIB.BASEBOARD_FAB2(SCH_1):VR_PVDDQ_GHJ_PH1_PHASE   I110 @BASEBOARD_FAB2_LIB.BASEBOARD_FAB2(SCH_1):PAGE224
    34 VR_PVDDQ_GHJ_PWM1 @BASEBOARD_FAB2_LIB.BASEBOARD_FAB2(SCH_1):VR_PVDDQ_GHJ_PWM1   I110 @BASEBOARD_FAB2_LIB.BASEBOARD_FAB2(SCH_1):PAGE224
    39 VR_PVDDQ_GHJ_AIREF1 @BASEBOARD_FAB2_LIB.BASEBOARD_FAB2(SCH_1):VR_PVDDQ_GHJ_AIREF1   I110 @BASEBOARD_FAB2_LIB.BASEBOARD_FAB2(SCH_1):PAGE224
    10 VR_PVDDQ_GHJ_PH1_SW @BASEBOARD_FAB2_LIB.BASEBOARD_FAB2(SCH_1):VR_PVDDQ_GHJ_PH1_SW   I110 @BASEBOARD_FAB2_LIB.BASEBOARD_FAB2(SCH_1):PAGE224
    36 A_TSENSE_PVDDQ_GHJ @BASEBOARD_FAB2_LIB.BASEBOARD_FAB2(SCH_1):A_TSENSE_PVDDQ_GHJ   I110 @BASEBOARD_FAB2_LIB.BASEBOARD_FAB2(SCH_1):PAGE224
     3 VR_PVDDQ_GHJ_PH1_VCIN @BASEBOARD_FAB2_LIB.BASEBOARD_FAB2(SCH_1):VR_PVDDQ_GHJ_PH1_VCIN   I110 @BASEBOARD_FAB2_LIB.BASEBOARD_FAB2(SCH_1):PAGE224
     4 P5V_STBY @BASEBOARD_FAB2_LIB.BASEBOARD_FAB2(SCH_1):P5V_STBY   I110 @BASEBOARD_FAB2_LIB.BASEBOARD_FAB2(SCH_1):PAGE224
    30 VR_FET_SW_P12V_STBY_PVDDQ_GHJ @BASEBOARD_FAB2_LIB.BASEBOARD_FAB2(SCH_1):VR_FET_SW_P12V_STBY_PVDDQ_GHJ   I110 @BASEBOARD_FAB2_LIB.BASEBOARD_FAB2(SCH_1):PAGE224
    25 VR_FET_SW_P12V_STBY_PVDDQ_GHJ @BASEBOARD_FAB2_LIB.BASEBOARD_FAB2(SCH_1):VR_FET_SW_P12V_STBY_PVDDQ_GHJ   I110 @BASEBOARD_FAB2_LIB.BASEBOARD_FAB2(SCH_1):PAGE224
     1 PVDDQ_GHJ @BASEBOARD_FAB2_LIB.BASEBOARD_FAB2(SCH_1):PVDDQ_GHJ   I110 @BASEBOARD_FAB2_LIB.BASEBOARD_FAB2(SCH_1):PAGE224

EU1G2 PXM1310B_QFN-IC,H89186-001
     1     NC     NC    I69 @BASEBOARD_FAB2_LIB.BASEBOARD_FAB2(SCH_1):PAGE223
     2     NC     NC    I69 @BASEBOARD_FAB2_LIB.BASEBOARD_FAB2(SCH_1):PAGE223
     3     NC     NC    I69 @BASEBOARD_FAB2_LIB.BASEBOARD_FAB2(SCH_1):PAGE223
     4 VR_PVDDQ_GHJ_PWM2 @BASEBOARD_FAB2_LIB.BASEBOARD_FAB2(SCH_1):VR_PVDDQ_GHJ_PWM2    I69 @BASEBOARD_FAB2_LIB.BASEBOARD_FAB2(SCH_1):PAGE223
     5 VR_PVDDQ_GHJ_PWM1 @BASEBOARD_FAB2_LIB.BASEBOARD_FAB2(SCH_1):VR_PVDDQ_GHJ_PWM1    I69 @BASEBOARD_FAB2_LIB.BASEBOARD_FAB2(SCH_1):PAGE223
     6 SMB_VR_STBY_LVC3_SDA @BASEBOARD_FAB2_LIB.BASEBOARD_FAB2(SCH_1):SMB_VR_STBY_LVC3_SDA    I69 @BASEBOARD_FAB2_LIB.BASEBOARD_FAB2(SCH_1):PAGE223
     7 SMB_VR_STBY_LVC3_SCL @BASEBOARD_FAB2_LIB.BASEBOARD_FAB2(SCH_1):SMB_VR_STBY_LVC3_SCL    I69 @BASEBOARD_FAB2_LIB.BASEBOARD_FAB2(SCH_1):PAGE223
     8     NC     NC    I69 @BASEBOARD_FAB2_LIB.BASEBOARD_FAB2(SCH_1):PAGE223
     9 PWRGD_PVDDQ_GHJ_R @BASEBOARD_FAB2_LIB.BASEBOARD_FAB2(SCH_1):PWRGD_PVDDQ_GHJ_R    I69 @BASEBOARD_FAB2_LIB.BASEBOARD_FAB2(SCH_1):PAGE223
    10 VR_PVDDQ_GHJ_VREN @BASEBOARD_FAB2_LIB.BASEBOARD_FAB2(SCH_1):VR_PVDDQ_GHJ_VREN    I69 @BASEBOARD_FAB2_LIB.BASEBOARD_FAB2(SCH_1):PAGE223
    11 IRQ_PVDDQ_GHJ_VRHOT_LVT3_R_N @BASEBOARD_FAB2_LIB.BASEBOARD_FAB2(SCH_1):IRQ_PVDDQ_GHJ_VRHOT_LVT3_R_N    I69 @BASEBOARD_FAB2_LIB.BASEBOARD_FAB2(SCH_1):PAGE223
    12     NC     NC    I69 @BASEBOARD_FAB2_LIB.BASEBOARD_FAB2(SCH_1):PAGE223
    13 PU_VR_PVDDQ_GHJ_FAULT1 @BASEBOARD_FAB2_LIB.BASEBOARD_FAB2(SCH_1):PU_VR_PVDDQ_GHJ_FAULT1    I69 @BASEBOARD_FAB2_LIB.BASEBOARD_FAB2(SCH_1):PAGE223
    14 TP_PVDDQ_GHJ_MP1 @BASEBOARD_FAB2_LIB.BASEBOARD_FAB2(SCH_1):TP_PVDDQ_GHJ_MP1    I69 @BASEBOARD_FAB2_LIB.BASEBOARD_FAB2(SCH_1):PAGE223
    15 SVID_CLK_PVDDQ_GHJ @BASEBOARD_FAB2_LIB.BASEBOARD_FAB2(SCH_1):SVID_CLK_PVDDQ_GHJ    I69 @BASEBOARD_FAB2_LIB.BASEBOARD_FAB2(SCH_1):PAGE223
    16 SVID_VDIO_PVDDQ_GHJ @BASEBOARD_FAB2_LIB.BASEBOARD_FAB2(SCH_1):SVID_VDIO_PVDDQ_GHJ    I69 @BASEBOARD_FAB2_LIB.BASEBOARD_FAB2(SCH_1):PAGE223
    17 SVID_ALERT_PVDDQ_GHJ @BASEBOARD_FAB2_LIB.BASEBOARD_FAB2(SCH_1):SVID_ALERT_PVDDQ_GHJ    I69 @BASEBOARD_FAB2_LIB.BASEBOARD_FAB2(SCH_1):PAGE223
    18 TP_PVDDQ_GHJ_MP2 @BASEBOARD_FAB2_LIB.BASEBOARD_FAB2(SCH_1):TP_PVDDQ_GHJ_MP2    I69 @BASEBOARD_FAB2_LIB.BASEBOARD_FAB2(SCH_1):PAGE223
    19 VR_PVDDQ_GHJ_AVSP @BASEBOARD_FAB2_LIB.BASEBOARD_FAB2(SCH_1):VR_PVDDQ_GHJ_AVSP    I69 @BASEBOARD_FAB2_LIB.BASEBOARD_FAB2(SCH_1):PAGE223
    20 VSENSE_PVDDQ_GHJ_N @BASEBOARD_FAB2_LIB.BASEBOARD_FAB2(SCH_1):VSENSE_PVDDQ_GHJ_N    I69 @BASEBOARD_FAB2_LIB.BASEBOARD_FAB2(SCH_1):PAGE223
    21 VR_PVDDQ_GHJ_AIREF1 @BASEBOARD_FAB2_LIB.BASEBOARD_FAB2(SCH_1):VR_PVDDQ_GHJ_AIREF1    I69 @BASEBOARD_FAB2_LIB.BASEBOARD_FAB2(SCH_1):PAGE223
    22 ISENSE_PVDDQ_GHJ_PH1_IMON @BASEBOARD_FAB2_LIB.BASEBOARD_FAB2(SCH_1):ISENSE_PVDDQ_GHJ_PH1_IMON    I69 @BASEBOARD_FAB2_LIB.BASEBOARD_FAB2(SCH_1):PAGE223
    23 VR_PVDDQ_GHJ_AIREF2 @BASEBOARD_FAB2_LIB.BASEBOARD_FAB2(SCH_1):VR_PVDDQ_GHJ_AIREF2    I69 @BASEBOARD_FAB2_LIB.BASEBOARD_FAB2(SCH_1):PAGE223
    24 ISENSE_PVDDQ_GHJ_PH2_IMON @BASEBOARD_FAB2_LIB.BASEBOARD_FAB2(SCH_1):ISENSE_PVDDQ_GHJ_PH2_IMON    I69 @BASEBOARD_FAB2_LIB.BASEBOARD_FAB2(SCH_1):PAGE223
    25     NC     NC    I69 @BASEBOARD_FAB2_LIB.BASEBOARD_FAB2(SCH_1):PAGE223
    26     NC     NC    I69 @BASEBOARD_FAB2_LIB.BASEBOARD_FAB2(SCH_1):PAGE223
    27    GND @BASEBOARD_FAB2_LIB.BASEBOARD_FAB2(SCH_1):GND    I69 @BASEBOARD_FAB2_LIB.BASEBOARD_FAB2(SCH_1):PAGE223
    28     NC     NC    I69 @BASEBOARD_FAB2_LIB.BASEBOARD_FAB2(SCH_1):PAGE223
    29     NC     NC    I69 @BASEBOARD_FAB2_LIB.BASEBOARD_FAB2(SCH_1):PAGE223
    30     NC     NC    I69 @BASEBOARD_FAB2_LIB.BASEBOARD_FAB2(SCH_1):PAGE223
    31     NC     NC    I69 @BASEBOARD_FAB2_LIB.BASEBOARD_FAB2(SCH_1):PAGE223
    32    GND @BASEBOARD_FAB2_LIB.BASEBOARD_FAB2(SCH_1):GND    I69 @BASEBOARD_FAB2_LIB.BASEBOARD_FAB2(SCH_1):PAGE223
    33 VR_PVDDQ_GHJ_XADDR2 @BASEBOARD_FAB2_LIB.BASEBOARD_FAB2(SCH_1):VR_PVDDQ_GHJ_XADDR2    I69 @BASEBOARD_FAB2_LIB.BASEBOARD_FAB2(SCH_1):PAGE223
    34     NC     NC    I69 @BASEBOARD_FAB2_LIB.BASEBOARD_FAB2(SCH_1):PAGE223
    35 A_TSENSE_PVDDQ_GHJ @BASEBOARD_FAB2_LIB.BASEBOARD_FAB2(SCH_1):A_TSENSE_PVDDQ_GHJ    I69 @BASEBOARD_FAB2_LIB.BASEBOARD_FAB2(SCH_1):PAGE223
    36 VR_PVDDQ_GHJ_XADDR1 @BASEBOARD_FAB2_LIB.BASEBOARD_FAB2(SCH_1):VR_PVDDQ_GHJ_XADDR1    I69 @BASEBOARD_FAB2_LIB.BASEBOARD_FAB2(SCH_1):PAGE223
    37 VR_PVDDQ_GHJ_VINSEN @BASEBOARD_FAB2_LIB.BASEBOARD_FAB2(SCH_1):VR_PVDDQ_GHJ_VINSEN    I69 @BASEBOARD_FAB2_LIB.BASEBOARD_FAB2(SCH_1):PAGE223
    38 VR_PVDDQ_GHJ_AIINSEN @BASEBOARD_FAB2_LIB.BASEBOARD_FAB2(SCH_1):VR_PVDDQ_GHJ_AIINSEN    I69 @BASEBOARD_FAB2_LIB.BASEBOARD_FAB2(SCH_1):PAGE223
    39 VR_PVDDQ_GHJ_VDD @BASEBOARD_FAB2_LIB.BASEBOARD_FAB2(SCH_1):VR_PVDDQ_GHJ_VDD    I69 @BASEBOARD_FAB2_LIB.BASEBOARD_FAB2(SCH_1):PAGE223
    40 VR_PVDDQ_GHJ_VD12 @BASEBOARD_FAB2_LIB.BASEBOARD_FAB2(SCH_1):VR_PVDDQ_GHJ_VD12    I69 @BASEBOARD_FAB2_LIB.BASEBOARD_FAB2(SCH_1):PAGE223
    41    GND @BASEBOARD_FAB2_LIB.BASEBOARD_FAB2(SCH_1):GND    I69 @BASEBOARD_FAB2_LIB.BASEBOARD_FAB2(SCH_1):PAGE223

EU2T1 SLG55021_SM-IC,G56246-001
     4    GND @BASEBOARD_FAB2_LIB.BASEBOARD_FAB2(SCH_1):GND     I1 @BASEBOARD_FAB2_LIB.BASEBOARD_FAB2(SCH_1):PAGE198
     9    GND @BASEBOARD_FAB2_LIB.BASEBOARD_FAB2(SCH_1):GND     I1 @BASEBOARD_FAB2_LIB.BASEBOARD_FAB2(SCH_1):PAGE198
     1 P5V_STBY @BASEBOARD_FAB2_LIB.BASEBOARD_FAB2(SCH_1):P5V_STBY     I1 @BASEBOARD_FAB2_LIB.BASEBOARD_FAB2(SCH_1):PAGE198
     2 FM_P3V3_CPLD_EN @BASEBOARD_FAB2_LIB.BASEBOARD_FAB2(SCH_1):FM_P3V3_CPLD_EN     I1 @BASEBOARD_FAB2_LIB.BASEBOARD_FAB2(SCH_1):PAGE198
     3 P5V_STBY @BASEBOARD_FAB2_LIB.BASEBOARD_FAB2(SCH_1):P5V_STBY     I1 @BASEBOARD_FAB2_LIB.BASEBOARD_FAB2(SCH_1):PAGE198
     5 P3V3_STBY @BASEBOARD_FAB2_LIB.BASEBOARD_FAB2(SCH_1):P3V3_STBY     I1 @BASEBOARD_FAB2_LIB.BASEBOARD_FAB2(SCH_1):PAGE198
     6   P3V3 @BASEBOARD_FAB2_LIB.BASEBOARD_FAB2(SCH_1):P3V3     I1 @BASEBOARD_FAB2_LIB.BASEBOARD_FAB2(SCH_1):PAGE198
     7 P3V3_SWITCH_G @BASEBOARD_FAB2_LIB.BASEBOARD_FAB2(SCH_1):P3V3_SWITCH_G     I1 @BASEBOARD_FAB2_LIB.BASEBOARD_FAB2(SCH_1):PAGE198
     8 TP_SLG55021_P3V3_8 @BASEBOARD_FAB2_LIB.BASEBOARD_FAB2(SCH_1):TP_SLG55021_P3V3_8     I1 @BASEBOARD_FAB2_LIB.BASEBOARD_FAB2(SCH_1):PAGE198

EU3P1 PXE1110B_QFN-IC,H89187-001
     1     NC     NC    I93 @BASEBOARD_FAB2_LIB.BASEBOARD_FAB2(SCH_1):PAGE211
     2     NC     NC    I93 @BASEBOARD_FAB2_LIB.BASEBOARD_FAB2(SCH_1):PAGE211
     3     NC     NC    I93 @BASEBOARD_FAB2_LIB.BASEBOARD_FAB2(SCH_1):PAGE211
     4     NC     NC    I93 @BASEBOARD_FAB2_LIB.BASEBOARD_FAB2(SCH_1):PAGE211
     5 VR_PVCCIO_CPU0_PWM1 @BASEBOARD_FAB2_LIB.BASEBOARD_FAB2(SCH_1):VR_PVCCIO_CPU0_PWM1    I93 @BASEBOARD_FAB2_LIB.BASEBOARD_FAB2(SCH_1):PAGE211
     6 SMB_VR_STBY_LVC3_SDA @BASEBOARD_FAB2_LIB.BASEBOARD_FAB2(SCH_1):SMB_VR_STBY_LVC3_SDA    I93 @BASEBOARD_FAB2_LIB.BASEBOARD_FAB2(SCH_1):PAGE211
     7 SMB_VR_STBY_LVC3_SCL @BASEBOARD_FAB2_LIB.BASEBOARD_FAB2(SCH_1):SMB_VR_STBY_LVC3_SCL    I93 @BASEBOARD_FAB2_LIB.BASEBOARD_FAB2(SCH_1):PAGE211
     8     NC     NC    I93 @BASEBOARD_FAB2_LIB.BASEBOARD_FAB2(SCH_1):PAGE211
     9 PWRGD_PVCCIO_CPU0_R @BASEBOARD_FAB2_LIB.BASEBOARD_FAB2(SCH_1):PWRGD_PVCCIO_CPU0_R    I93 @BASEBOARD_FAB2_LIB.BASEBOARD_FAB2(SCH_1):PAGE211
    10 VR_PVCCIO_CPU0_EN @BASEBOARD_FAB2_LIB.BASEBOARD_FAB2(SCH_1):VR_PVCCIO_CPU0_EN    I93 @BASEBOARD_FAB2_LIB.BASEBOARD_FAB2(SCH_1):PAGE211
    11 IRQ_PVCCIO_CPU0_VRHOT_N @BASEBOARD_FAB2_LIB.BASEBOARD_FAB2(SCH_1):IRQ_PVCCIO_CPU0_VRHOT_N    I93 @BASEBOARD_FAB2_LIB.BASEBOARD_FAB2(SCH_1):PAGE211
    12     NC     NC    I93 @BASEBOARD_FAB2_LIB.BASEBOARD_FAB2(SCH_1):PAGE211
    13     NC     NC    I93 @BASEBOARD_FAB2_LIB.BASEBOARD_FAB2(SCH_1):PAGE211
    14     NC     NC    I93 @BASEBOARD_FAB2_LIB.BASEBOARD_FAB2(SCH_1):PAGE211
    15 SVID_CLK_PVCCIO_CPU0 @BASEBOARD_FAB2_LIB.BASEBOARD_FAB2(SCH_1):SVID_CLK_PVCCIO_CPU0    I93 @BASEBOARD_FAB2_LIB.BASEBOARD_FAB2(SCH_1):PAGE211
    16 SVID_VDIO_PVCCIO_CPU0 @BASEBOARD_FAB2_LIB.BASEBOARD_FAB2(SCH_1):SVID_VDIO_PVCCIO_CPU0    I93 @BASEBOARD_FAB2_LIB.BASEBOARD_FAB2(SCH_1):PAGE211
    17 SVID_ALERT_PVCCIO_CPU0 @BASEBOARD_FAB2_LIB.BASEBOARD_FAB2(SCH_1):SVID_ALERT_PVCCIO_CPU0    I93 @BASEBOARD_FAB2_LIB.BASEBOARD_FAB2(SCH_1):PAGE211
    18     NC     NC    I93 @BASEBOARD_FAB2_LIB.BASEBOARD_FAB2(SCH_1):PAGE211
    19 VR_PVCCIO_CPU0_AVSP @BASEBOARD_FAB2_LIB.BASEBOARD_FAB2(SCH_1):VR_PVCCIO_CPU0_AVSP    I93 @BASEBOARD_FAB2_LIB.BASEBOARD_FAB2(SCH_1):PAGE211
    20 VSENSE_PVCCIO_CPU0_AVSN @BASEBOARD_FAB2_LIB.BASEBOARD_FAB2(SCH_1):VSENSE_PVCCIO_CPU0_AVSN    I93 @BASEBOARD_FAB2_LIB.BASEBOARD_FAB2(SCH_1):PAGE211
    21 VR_PVCCIO_CPU0_AIREF1 @BASEBOARD_FAB2_LIB.BASEBOARD_FAB2(SCH_1):VR_PVCCIO_CPU0_AIREF1    I93 @BASEBOARD_FAB2_LIB.BASEBOARD_FAB2(SCH_1):PAGE211
    22 ISENSE_PVCCIO_CPU0_PH1_IMON @BASEBOARD_FAB2_LIB.BASEBOARD_FAB2(SCH_1):ISENSE_PVCCIO_CPU0_PH1_IMON    I93 @BASEBOARD_FAB2_LIB.BASEBOARD_FAB2(SCH_1):PAGE211
    23    GND @BASEBOARD_FAB2_LIB.BASEBOARD_FAB2(SCH_1):GND    I93 @BASEBOARD_FAB2_LIB.BASEBOARD_FAB2(SCH_1):PAGE211
    24     NC     NC    I93 @BASEBOARD_FAB2_LIB.BASEBOARD_FAB2(SCH_1):PAGE211
    25     NC     NC    I93 @BASEBOARD_FAB2_LIB.BASEBOARD_FAB2(SCH_1):PAGE211
    26    GND @BASEBOARD_FAB2_LIB.BASEBOARD_FAB2(SCH_1):GND    I93 @BASEBOARD_FAB2_LIB.BASEBOARD_FAB2(SCH_1):PAGE211
    27    GND @BASEBOARD_FAB2_LIB.BASEBOARD_FAB2(SCH_1):GND    I93 @BASEBOARD_FAB2_LIB.BASEBOARD_FAB2(SCH_1):PAGE211
    28     NC     NC    I93 @BASEBOARD_FAB2_LIB.BASEBOARD_FAB2(SCH_1):PAGE211
    29     NC     NC    I93 @BASEBOARD_FAB2_LIB.BASEBOARD_FAB2(SCH_1):PAGE211
    30     NC     NC    I93 @BASEBOARD_FAB2_LIB.BASEBOARD_FAB2(SCH_1):PAGE211
    31     NC     NC    I93 @BASEBOARD_FAB2_LIB.BASEBOARD_FAB2(SCH_1):PAGE211
    32 PU_VR_PVCCIO_CPU0_FAULT1 @BASEBOARD_FAB2_LIB.BASEBOARD_FAB2(SCH_1):PU_VR_PVCCIO_CPU0_FAULT1    I93 @BASEBOARD_FAB2_LIB.BASEBOARD_FAB2(SCH_1):PAGE211
    33 VR_PVCCIO_CPU0_XADDR2 @BASEBOARD_FAB2_LIB.BASEBOARD_FAB2(SCH_1):VR_PVCCIO_CPU0_XADDR2    I93 @BASEBOARD_FAB2_LIB.BASEBOARD_FAB2(SCH_1):PAGE211
    34     NC     NC    I93 @BASEBOARD_FAB2_LIB.BASEBOARD_FAB2(SCH_1):PAGE211
    35 A_TSENSE_PVCCIO_CPU0 @BASEBOARD_FAB2_LIB.BASEBOARD_FAB2(SCH_1):A_TSENSE_PVCCIO_CPU0    I93 @BASEBOARD_FAB2_LIB.BASEBOARD_FAB2(SCH_1):PAGE211
    36 VR_PVCCIO_CPU0_XADDR1 @BASEBOARD_FAB2_LIB.BASEBOARD_FAB2(SCH_1):VR_PVCCIO_CPU0_XADDR1    I93 @BASEBOARD_FAB2_LIB.BASEBOARD_FAB2(SCH_1):PAGE211
    37 VR_PVCCIO_CPU0_VINSEN @BASEBOARD_FAB2_LIB.BASEBOARD_FAB2(SCH_1):VR_PVCCIO_CPU0_VINSEN    I93 @BASEBOARD_FAB2_LIB.BASEBOARD_FAB2(SCH_1):PAGE211
    38     NC     NC    I93 @BASEBOARD_FAB2_LIB.BASEBOARD_FAB2(SCH_1):PAGE211
    39 VR_PVCCIO_CPU0_VDD @BASEBOARD_FAB2_LIB.BASEBOARD_FAB2(SCH_1):VR_PVCCIO_CPU0_VDD    I93 @BASEBOARD_FAB2_LIB.BASEBOARD_FAB2(SCH_1):PAGE211
    40 VR_PVCCIO_CPU0_VD12 @BASEBOARD_FAB2_LIB.BASEBOARD_FAB2(SCH_1):VR_PVCCIO_CPU0_VD12    I93 @BASEBOARD_FAB2_LIB.BASEBOARD_FAB2(SCH_1):PAGE211
    41    GND @BASEBOARD_FAB2_LIB.BASEBOARD_FAB2(SCH_1):GND    I93 @BASEBOARD_FAB2_LIB.BASEBOARD_FAB2(SCH_1):PAGE211

EU4A1 MIC5166_DFN-IC,H55101-001
     7 FM_PVTT_DEF_EN_R @BASEBOARD_FAB2_LIB.BASEBOARD_FAB2(SCH_1):FM_PVTT_DEF_EN_R    I13 @BASEBOARD_FAB2_LIB.BASEBOARD_FAB2(SCH_1):PAGE222
    10 PVDDQ_DEF @BASEBOARD_FAB2_LIB.BASEBOARD_FAB2(SCH_1):PVDDQ_DEF    I13 @BASEBOARD_FAB2_LIB.BASEBOARD_FAB2(SCH_1):PAGE222
     1 VR_PVTT_DEF_VREF @BASEBOARD_FAB2_LIB.BASEBOARD_FAB2(SCH_1):VR_PVTT_DEF_VREF    I13 @BASEBOARD_FAB2_LIB.BASEBOARD_FAB2(SCH_1):PAGE222
     2 VR_PVTT_DEF_BIAS @BASEBOARD_FAB2_LIB.BASEBOARD_FAB2(SCH_1):VR_PVTT_DEF_BIAS    I13 @BASEBOARD_FAB2_LIB.BASEBOARD_FAB2(SCH_1):PAGE222
     3    GND @BASEBOARD_FAB2_LIB.BASEBOARD_FAB2(SCH_1):GND    I13 @BASEBOARD_FAB2_LIB.BASEBOARD_FAB2(SCH_1):PAGE222
     5 PWRGD_PVTT_DEF_CPU0_R @BASEBOARD_FAB2_LIB.BASEBOARD_FAB2(SCH_1):PWRGD_PVTT_DEF_CPU0_R    I13 @BASEBOARD_FAB2_LIB.BASEBOARD_FAB2(SCH_1):PAGE222
     4 VSENSE_PVDDQ_DEF_VTT @BASEBOARD_FAB2_LIB.BASEBOARD_FAB2(SCH_1):VSENSE_PVDDQ_DEF_VTT    I13 @BASEBOARD_FAB2_LIB.BASEBOARD_FAB2(SCH_1):PAGE222
     6 VR_PVTT_DEF_SNS @BASEBOARD_FAB2_LIB.BASEBOARD_FAB2(SCH_1):VR_PVTT_DEF_SNS    I13 @BASEBOARD_FAB2_LIB.BASEBOARD_FAB2(SCH_1):PAGE222
     8    GND @BASEBOARD_FAB2_LIB.BASEBOARD_FAB2(SCH_1):GND    I13 @BASEBOARD_FAB2_LIB.BASEBOARD_FAB2(SCH_1):PAGE222
     9 PVTT_DEF @BASEBOARD_FAB2_LIB.BASEBOARD_FAB2(SCH_1):PVTT_DEF    I13 @BASEBOARD_FAB2_LIB.BASEBOARD_FAB2(SCH_1):PAGE222
    11    GND @BASEBOARD_FAB2_LIB.BASEBOARD_FAB2(SCH_1):GND    I13 @BASEBOARD_FAB2_LIB.BASEBOARD_FAB2(SCH_1):PAGE222

EU4A2 MIC5166_DFN-IC,H55101-001
     7 FM_PVTT_KLM_EN_R @BASEBOARD_FAB2_LIB.BASEBOARD_FAB2(SCH_1):FM_PVTT_KLM_EN_R    I37 @BASEBOARD_FAB2_LIB.BASEBOARD_FAB2(SCH_1):PAGE230
    10 PVDDQ_KLM @BASEBOARD_FAB2_LIB.BASEBOARD_FAB2(SCH_1):PVDDQ_KLM    I37 @BASEBOARD_FAB2_LIB.BASEBOARD_FAB2(SCH_1):PAGE230
     1 VR_PVTT_KLM_VREF @BASEBOARD_FAB2_LIB.BASEBOARD_FAB2(SCH_1):VR_PVTT_KLM_VREF    I37 @BASEBOARD_FAB2_LIB.BASEBOARD_FAB2(SCH_1):PAGE230
     2 VR_PVTT_KLM_BIAS @BASEBOARD_FAB2_LIB.BASEBOARD_FAB2(SCH_1):VR_PVTT_KLM_BIAS    I37 @BASEBOARD_FAB2_LIB.BASEBOARD_FAB2(SCH_1):PAGE230
     3    GND @BASEBOARD_FAB2_LIB.BASEBOARD_FAB2(SCH_1):GND    I37 @BASEBOARD_FAB2_LIB.BASEBOARD_FAB2(SCH_1):PAGE230
     5 PWRGD_PVTT_KLM_CPU1_R @BASEBOARD_FAB2_LIB.BASEBOARD_FAB2(SCH_1):PWRGD_PVTT_KLM_CPU1_R    I37 @BASEBOARD_FAB2_LIB.BASEBOARD_FAB2(SCH_1):PAGE230
     4 VSENSE_PVDDQ_KLM_VTT @BASEBOARD_FAB2_LIB.BASEBOARD_FAB2(SCH_1):VSENSE_PVDDQ_KLM_VTT    I37 @BASEBOARD_FAB2_LIB.BASEBOARD_FAB2(SCH_1):PAGE230
     6 VR_PVTT_KLM_SNS @BASEBOARD_FAB2_LIB.BASEBOARD_FAB2(SCH_1):VR_PVTT_KLM_SNS    I37 @BASEBOARD_FAB2_LIB.BASEBOARD_FAB2(SCH_1):PAGE230
     8    GND @BASEBOARD_FAB2_LIB.BASEBOARD_FAB2(SCH_1):GND    I37 @BASEBOARD_FAB2_LIB.BASEBOARD_FAB2(SCH_1):PAGE230
     9 PVTT_KLM @BASEBOARD_FAB2_LIB.BASEBOARD_FAB2(SCH_1):PVTT_KLM    I37 @BASEBOARD_FAB2_LIB.BASEBOARD_FAB2(SCH_1):PAGE230
    11    GND @BASEBOARD_FAB2_LIB.BASEBOARD_FAB2(SCH_1):GND    I37 @BASEBOARD_FAB2_LIB.BASEBOARD_FAB2(SCH_1):PAGE230

EU4A3 NCP3232L_SM-IC,H86355-001
     5 AGND_PVPP_KLM @BASEBOARD_FAB2_LIB.BASEBOARD_FAB2(SCH_1):AGND_PVPP_KLM   I184 @BASEBOARD_FAB2_LIB.BASEBOARD_FAB2(SCH_1):PAGE234
    36 VR_PVPP_KLM_BOOT @BASEBOARD_FAB2_LIB.BASEBOARD_FAB2(SCH_1):VR_PVPP_KLM_BOOT   I184 @BASEBOARD_FAB2_LIB.BASEBOARD_FAB2(SCH_1):PAGE234
     3 VR_COMP_PVPP_KLM_3 @BASEBOARD_FAB2_LIB.BASEBOARD_FAB2(SCH_1):VR_COMP_PVPP_KLM_3   I184 @BASEBOARD_FAB2_LIB.BASEBOARD_FAB2(SCH_1):PAGE234
    40 FM_PVPP_PVDDQ_CPU1_EN_KLM @BASEBOARD_FAB2_LIB.BASEBOARD_FAB2(SCH_1):FM_PVPP_PVDDQ_CPU1_EN_KLM   I184 @BASEBOARD_FAB2_LIB.BASEBOARD_FAB2(SCH_1):PAGE234
     2 VR_FB_PVPP_KLM @BASEBOARD_FAB2_LIB.BASEBOARD_FAB2(SCH_1):VR_FB_PVPP_KLM   I184 @BASEBOARD_FAB2_LIB.BASEBOARD_FAB2(SCH_1):PAGE234
    41    GND @BASEBOARD_FAB2_LIB.BASEBOARD_FAB2(SCH_1):GND   I184 @BASEBOARD_FAB2_LIB.BASEBOARD_FAB2(SCH_1):PAGE234
     4 VR_PVPP_KLM_ISET @BASEBOARD_FAB2_LIB.BASEBOARD_FAB2(SCH_1):VR_PVPP_KLM_ISET   I184 @BASEBOARD_FAB2_LIB.BASEBOARD_FAB2(SCH_1):PAGE234
     6 AGND_PVPP_KLM @BASEBOARD_FAB2_LIB.BASEBOARD_FAB2(SCH_1):AGND_PVPP_KLM   I184 @BASEBOARD_FAB2_LIB.BASEBOARD_FAB2(SCH_1):PAGE234
     7 PWRGD_PVPP_KLM_R @BASEBOARD_FAB2_LIB.BASEBOARD_FAB2(SCH_1):PWRGD_PVPP_KLM_R   I184 @BASEBOARD_FAB2_LIB.BASEBOARD_FAB2(SCH_1):PAGE234
    37    GND @BASEBOARD_FAB2_LIB.BASEBOARD_FAB2(SCH_1):GND   I184 @BASEBOARD_FAB2_LIB.BASEBOARD_FAB2(SCH_1):PAGE234
    28    GND @BASEBOARD_FAB2_LIB.BASEBOARD_FAB2(SCH_1):GND   I184 @BASEBOARD_FAB2_LIB.BASEBOARD_FAB2(SCH_1):PAGE234
    27    GND @BASEBOARD_FAB2_LIB.BASEBOARD_FAB2(SCH_1):GND   I184 @BASEBOARD_FAB2_LIB.BASEBOARD_FAB2(SCH_1):PAGE234
    26    GND @BASEBOARD_FAB2_LIB.BASEBOARD_FAB2(SCH_1):GND   I184 @BASEBOARD_FAB2_LIB.BASEBOARD_FAB2(SCH_1):PAGE234
    25    GND @BASEBOARD_FAB2_LIB.BASEBOARD_FAB2(SCH_1):GND   I184 @BASEBOARD_FAB2_LIB.BASEBOARD_FAB2(SCH_1):PAGE234
    24    GND @BASEBOARD_FAB2_LIB.BASEBOARD_FAB2(SCH_1):GND   I184 @BASEBOARD_FAB2_LIB.BASEBOARD_FAB2(SCH_1):PAGE234
    23    GND @BASEBOARD_FAB2_LIB.BASEBOARD_FAB2(SCH_1):GND   I184 @BASEBOARD_FAB2_LIB.BASEBOARD_FAB2(SCH_1):PAGE234
    22    GND @BASEBOARD_FAB2_LIB.BASEBOARD_FAB2(SCH_1):GND   I184 @BASEBOARD_FAB2_LIB.BASEBOARD_FAB2(SCH_1):PAGE234
    21    GND @BASEBOARD_FAB2_LIB.BASEBOARD_FAB2(SCH_1):GND   I184 @BASEBOARD_FAB2_LIB.BASEBOARD_FAB2(SCH_1):PAGE234
    20    GND @BASEBOARD_FAB2_LIB.BASEBOARD_FAB2(SCH_1):GND   I184 @BASEBOARD_FAB2_LIB.BASEBOARD_FAB2(SCH_1):PAGE234
    19    GND @BASEBOARD_FAB2_LIB.BASEBOARD_FAB2(SCH_1):GND   I184 @BASEBOARD_FAB2_LIB.BASEBOARD_FAB2(SCH_1):PAGE234
    18    GND @BASEBOARD_FAB2_LIB.BASEBOARD_FAB2(SCH_1):GND   I184 @BASEBOARD_FAB2_LIB.BASEBOARD_FAB2(SCH_1):PAGE234
    17    GND @BASEBOARD_FAB2_LIB.BASEBOARD_FAB2(SCH_1):GND   I184 @BASEBOARD_FAB2_LIB.BASEBOARD_FAB2(SCH_1):PAGE234
    16    GND @BASEBOARD_FAB2_LIB.BASEBOARD_FAB2(SCH_1):GND   I184 @BASEBOARD_FAB2_LIB.BASEBOARD_FAB2(SCH_1):PAGE234
     1 VR_PVPP_KLM_SS @BASEBOARD_FAB2_LIB.BASEBOARD_FAB2(SCH_1):VR_PVPP_KLM_SS   I184 @BASEBOARD_FAB2_LIB.BASEBOARD_FAB2(SCH_1):PAGE234
    38 VR_VB_PVPP_KLM @BASEBOARD_FAB2_LIB.BASEBOARD_FAB2(SCH_1):VR_VB_PVPP_KLM   I184 @BASEBOARD_FAB2_LIB.BASEBOARD_FAB2(SCH_1):PAGE234
    39 VR_FET_SW_P12V_STBY_PVPP_KLM @BASEBOARD_FAB2_LIB.BASEBOARD_FAB2(SCH_1):VR_FET_SW_P12V_STBY_PVPP_KLM   I184 @BASEBOARD_FAB2_LIB.BASEBOARD_FAB2(SCH_1):PAGE234
    42 VR_FET_SW_P12V_STBY_PVPP_KLM @BASEBOARD_FAB2_LIB.BASEBOARD_FAB2(SCH_1):VR_FET_SW_P12V_STBY_PVPP_KLM   I184 @BASEBOARD_FAB2_LIB.BASEBOARD_FAB2(SCH_1):PAGE234
    14 VR_FET_SW_P12V_STBY_PVPP_KLM @BASEBOARD_FAB2_LIB.BASEBOARD_FAB2(SCH_1):VR_FET_SW_P12V_STBY_PVPP_KLM   I184 @BASEBOARD_FAB2_LIB.BASEBOARD_FAB2(SCH_1):PAGE234
    13 VR_FET_SW_P12V_STBY_PVPP_KLM @BASEBOARD_FAB2_LIB.BASEBOARD_FAB2(SCH_1):VR_FET_SW_P12V_STBY_PVPP_KLM   I184 @BASEBOARD_FAB2_LIB.BASEBOARD_FAB2(SCH_1):PAGE234
    12 VR_FET_SW_P12V_STBY_PVPP_KLM @BASEBOARD_FAB2_LIB.BASEBOARD_FAB2(SCH_1):VR_FET_SW_P12V_STBY_PVPP_KLM   I184 @BASEBOARD_FAB2_LIB.BASEBOARD_FAB2(SCH_1):PAGE234
    11 VR_FET_SW_P12V_STBY_PVPP_KLM @BASEBOARD_FAB2_LIB.BASEBOARD_FAB2(SCH_1):VR_FET_SW_P12V_STBY_PVPP_KLM   I184 @BASEBOARD_FAB2_LIB.BASEBOARD_FAB2(SCH_1):PAGE234
    10 VR_FET_SW_P12V_STBY_PVPP_KLM @BASEBOARD_FAB2_LIB.BASEBOARD_FAB2(SCH_1):VR_FET_SW_P12V_STBY_PVPP_KLM   I184 @BASEBOARD_FAB2_LIB.BASEBOARD_FAB2(SCH_1):PAGE234
     9 VR_FET_SW_P12V_STBY_PVPP_KLM @BASEBOARD_FAB2_LIB.BASEBOARD_FAB2(SCH_1):VR_FET_SW_P12V_STBY_PVPP_KLM   I184 @BASEBOARD_FAB2_LIB.BASEBOARD_FAB2(SCH_1):PAGE234
     8 VR_FET_SW_P12V_STBY_PVPP_KLM @BASEBOARD_FAB2_LIB.BASEBOARD_FAB2(SCH_1):VR_FET_SW_P12V_STBY_PVPP_KLM   I184 @BASEBOARD_FAB2_LIB.BASEBOARD_FAB2(SCH_1):PAGE234
    35 VR_PVPP_KLM_PHASE @BASEBOARD_FAB2_LIB.BASEBOARD_FAB2(SCH_1):VR_PVPP_KLM_PHASE   I184 @BASEBOARD_FAB2_LIB.BASEBOARD_FAB2(SCH_1):PAGE234
    43 VR_PVPP_KLM_PHASE @BASEBOARD_FAB2_LIB.BASEBOARD_FAB2(SCH_1):VR_PVPP_KLM_PHASE   I184 @BASEBOARD_FAB2_LIB.BASEBOARD_FAB2(SCH_1):PAGE234
    34 VR_PVPP_KLM_PHASE @BASEBOARD_FAB2_LIB.BASEBOARD_FAB2(SCH_1):VR_PVPP_KLM_PHASE   I184 @BASEBOARD_FAB2_LIB.BASEBOARD_FAB2(SCH_1):PAGE234
    33 VR_PVPP_KLM_PHASE @BASEBOARD_FAB2_LIB.BASEBOARD_FAB2(SCH_1):VR_PVPP_KLM_PHASE   I184 @BASEBOARD_FAB2_LIB.BASEBOARD_FAB2(SCH_1):PAGE234
    32 VR_PVPP_KLM_PHASE @BASEBOARD_FAB2_LIB.BASEBOARD_FAB2(SCH_1):VR_PVPP_KLM_PHASE   I184 @BASEBOARD_FAB2_LIB.BASEBOARD_FAB2(SCH_1):PAGE234
    31 VR_PVPP_KLM_PHASE @BASEBOARD_FAB2_LIB.BASEBOARD_FAB2(SCH_1):VR_PVPP_KLM_PHASE   I184 @BASEBOARD_FAB2_LIB.BASEBOARD_FAB2(SCH_1):PAGE234
    30 VR_PVPP_KLM_PHASE @BASEBOARD_FAB2_LIB.BASEBOARD_FAB2(SCH_1):VR_PVPP_KLM_PHASE   I184 @BASEBOARD_FAB2_LIB.BASEBOARD_FAB2(SCH_1):PAGE234
    29 VR_PVPP_KLM_PHASE @BASEBOARD_FAB2_LIB.BASEBOARD_FAB2(SCH_1):VR_PVPP_KLM_PHASE   I184 @BASEBOARD_FAB2_LIB.BASEBOARD_FAB2(SCH_1):PAGE234
    15 VR_PVPP_KLM_PHASE @BASEBOARD_FAB2_LIB.BASEBOARD_FAB2(SCH_1):VR_PVPP_KLM_PHASE   I184 @BASEBOARD_FAB2_LIB.BASEBOARD_FAB2(SCH_1):PAGE234

EU4C1 IR354XX_SM-IR35412,IC,H73684-0A
    33 VR_PVSA_CPU0_BOOT_R @BASEBOARD_FAB2_LIB.BASEBOARD_FAB2(SCH_1):VR_PVSA_CPU0_BOOT_R    I46 @BASEBOARD_FAB2_LIB.BASEBOARD_FAB2(SCH_1):PAGE205
    35 P5V_STBY @BASEBOARD_FAB2_LIB.BASEBOARD_FAB2(SCH_1):P5V_STBY    I46 @BASEBOARD_FAB2_LIB.BASEBOARD_FAB2(SCH_1):PAGE205
    41 TP_PVSA_CPU0_GL_1 @BASEBOARD_FAB2_LIB.BASEBOARD_FAB2(SCH_1):TP_PVSA_CPU0_GL_1    I46 @BASEBOARD_FAB2_LIB.BASEBOARD_FAB2(SCH_1):PAGE205
     6 TP_PVSA_CPU0_GL_0 @BASEBOARD_FAB2_LIB.BASEBOARD_FAB2(SCH_1):TP_PVSA_CPU0_GL_0    I46 @BASEBOARD_FAB2_LIB.BASEBOARD_FAB2(SCH_1):PAGE205
    38 ISENSE_PVSA_CPU0_IMON @BASEBOARD_FAB2_LIB.BASEBOARD_FAB2(SCH_1):ISENSE_PVSA_CPU0_IMON    I46 @BASEBOARD_FAB2_LIB.BASEBOARD_FAB2(SCH_1):PAGE205
     2    GND @BASEBOARD_FAB2_LIB.BASEBOARD_FAB2(SCH_1):GND    I46 @BASEBOARD_FAB2_LIB.BASEBOARD_FAB2(SCH_1):PAGE205
    31     NC     NC    I46 @BASEBOARD_FAB2_LIB.BASEBOARD_FAB2(SCH_1):PAGE205
    37 VR_PVSA_CPU0_OCSET @BASEBOARD_FAB2_LIB.BASEBOARD_FAB2(SCH_1):VR_PVSA_CPU0_OCSET    I46 @BASEBOARD_FAB2_LIB.BASEBOARD_FAB2(SCH_1):PAGE205
    40    GND @BASEBOARD_FAB2_LIB.BASEBOARD_FAB2(SCH_1):GND    I46 @BASEBOARD_FAB2_LIB.BASEBOARD_FAB2(SCH_1):PAGE205
     7    GND @BASEBOARD_FAB2_LIB.BASEBOARD_FAB2(SCH_1):GND    I46 @BASEBOARD_FAB2_LIB.BASEBOARD_FAB2(SCH_1):PAGE205
     5    GND @BASEBOARD_FAB2_LIB.BASEBOARD_FAB2(SCH_1):GND    I46 @BASEBOARD_FAB2_LIB.BASEBOARD_FAB2(SCH_1):PAGE205
    32 VR_PVSA_CPU0_PHASE @BASEBOARD_FAB2_LIB.BASEBOARD_FAB2(SCH_1):VR_PVSA_CPU0_PHASE    I46 @BASEBOARD_FAB2_LIB.BASEBOARD_FAB2(SCH_1):PAGE205
    34 VR_PVSA_CPU0_PWM @BASEBOARD_FAB2_LIB.BASEBOARD_FAB2(SCH_1):VR_PVSA_CPU0_PWM    I46 @BASEBOARD_FAB2_LIB.BASEBOARD_FAB2(SCH_1):PAGE205
    39 VR_PVSA_CPU0_BIREF1 @BASEBOARD_FAB2_LIB.BASEBOARD_FAB2(SCH_1):VR_PVSA_CPU0_BIREF1    I46 @BASEBOARD_FAB2_LIB.BASEBOARD_FAB2(SCH_1):PAGE205
    10 VR_PVSA_CPU0_PHASE_SW @BASEBOARD_FAB2_LIB.BASEBOARD_FAB2(SCH_1):VR_PVSA_CPU0_PHASE_SW    I46 @BASEBOARD_FAB2_LIB.BASEBOARD_FAB2(SCH_1):PAGE205
    36 A_TSENSE_PVSA_CPU0 @BASEBOARD_FAB2_LIB.BASEBOARD_FAB2(SCH_1):A_TSENSE_PVSA_CPU0    I46 @BASEBOARD_FAB2_LIB.BASEBOARD_FAB2(SCH_1):PAGE205
     3 VR_PVSA_CPU0_VCIN @BASEBOARD_FAB2_LIB.BASEBOARD_FAB2(SCH_1):VR_PVSA_CPU0_VCIN    I46 @BASEBOARD_FAB2_LIB.BASEBOARD_FAB2(SCH_1):PAGE205
     4 P5V_STBY @BASEBOARD_FAB2_LIB.BASEBOARD_FAB2(SCH_1):P5V_STBY    I46 @BASEBOARD_FAB2_LIB.BASEBOARD_FAB2(SCH_1):PAGE205
    30 VR_FET_SW_P12V_STBY_PVCCIN_CPU0 @BASEBOARD_FAB2_LIB.BASEBOARD_FAB2(SCH_1):VR_FET_SW_P12V_STBY_PVCCIN_CPU0    I46 @BASEBOARD_FAB2_LIB.BASEBOARD_FAB2(SCH_1):PAGE205
    25 VR_FET_SW_P12V_STBY_PVCCIN_CPU0 @BASEBOARD_FAB2_LIB.BASEBOARD_FAB2(SCH_1):VR_FET_SW_P12V_STBY_PVCCIN_CPU0    I46 @BASEBOARD_FAB2_LIB.BASEBOARD_FAB2(SCH_1):PAGE205
     1 PVSA_CPU0 @BASEBOARD_FAB2_LIB.BASEBOARD_FAB2(SCH_1):PVSA_CPU0    I46 @BASEBOARD_FAB2_LIB.BASEBOARD_FAB2(SCH_1):PAGE205

EU4C2 IR354XX_SM-IR35411,IC,H73688-0A
    33 VR_PVCCIN_CPU0_PH5_BOOT_R @BASEBOARD_FAB2_LIB.BASEBOARD_FAB2(SCH_1):VR_PVCCIN_CPU0_PH5_BOOT_R    I71 @BASEBOARD_FAB2_LIB.BASEBOARD_FAB2(SCH_1):PAGE204
    35 P5V_STBY @BASEBOARD_FAB2_LIB.BASEBOARD_FAB2(SCH_1):P5V_STBY    I71 @BASEBOARD_FAB2_LIB.BASEBOARD_FAB2(SCH_1):PAGE204
    41 TP_PVCCIN_CPU0_PH5_GL_1 @BASEBOARD_FAB2_LIB.BASEBOARD_FAB2(SCH_1):TP_PVCCIN_CPU0_PH5_GL_1    I71 @BASEBOARD_FAB2_LIB.BASEBOARD_FAB2(SCH_1):PAGE204
     6 TP_PVCCIN_CPU0_PH5_GL_0 @BASEBOARD_FAB2_LIB.BASEBOARD_FAB2(SCH_1):TP_PVCCIN_CPU0_PH5_GL_0    I71 @BASEBOARD_FAB2_LIB.BASEBOARD_FAB2(SCH_1):PAGE204
    38 ISENSE_PVCCIN_CPU0_PH5_IMON @BASEBOARD_FAB2_LIB.BASEBOARD_FAB2(SCH_1):ISENSE_PVCCIN_CPU0_PH5_IMON    I71 @BASEBOARD_FAB2_LIB.BASEBOARD_FAB2(SCH_1):PAGE204
     2    GND @BASEBOARD_FAB2_LIB.BASEBOARD_FAB2(SCH_1):GND    I71 @BASEBOARD_FAB2_LIB.BASEBOARD_FAB2(SCH_1):PAGE204
    31     NC     NC    I71 @BASEBOARD_FAB2_LIB.BASEBOARD_FAB2(SCH_1):PAGE204
    37 VR_PVCCIN_CPU0_PH5_OCSET @BASEBOARD_FAB2_LIB.BASEBOARD_FAB2(SCH_1):VR_PVCCIN_CPU0_PH5_OCSET    I71 @BASEBOARD_FAB2_LIB.BASEBOARD_FAB2(SCH_1):PAGE204
    40    GND @BASEBOARD_FAB2_LIB.BASEBOARD_FAB2(SCH_1):GND    I71 @BASEBOARD_FAB2_LIB.BASEBOARD_FAB2(SCH_1):PAGE204
     7    GND @BASEBOARD_FAB2_LIB.BASEBOARD_FAB2(SCH_1):GND    I71 @BASEBOARD_FAB2_LIB.BASEBOARD_FAB2(SCH_1):PAGE204
     5    GND @BASEBOARD_FAB2_LIB.BASEBOARD_FAB2(SCH_1):GND    I71 @BASEBOARD_FAB2_LIB.BASEBOARD_FAB2(SCH_1):PAGE204
    32 VR_PVCCIN_CPU0_PH5_PHASE @BASEBOARD_FAB2_LIB.BASEBOARD_FAB2(SCH_1):VR_PVCCIN_CPU0_PH5_PHASE    I71 @BASEBOARD_FAB2_LIB.BASEBOARD_FAB2(SCH_1):PAGE204
    34 VR_PVCCIN_CPU0_PWM5 @BASEBOARD_FAB2_LIB.BASEBOARD_FAB2(SCH_1):VR_PVCCIN_CPU0_PWM5    I71 @BASEBOARD_FAB2_LIB.BASEBOARD_FAB2(SCH_1):PAGE204
    39 VR_PVCCIN_CPU0_AIREF5 @BASEBOARD_FAB2_LIB.BASEBOARD_FAB2(SCH_1):VR_PVCCIN_CPU0_AIREF5    I71 @BASEBOARD_FAB2_LIB.BASEBOARD_FAB2(SCH_1):PAGE204
    10 VR_PVCCIN_CPU0_PHASE5 @BASEBOARD_FAB2_LIB.BASEBOARD_FAB2(SCH_1):VR_PVCCIN_CPU0_PHASE5    I71 @BASEBOARD_FAB2_LIB.BASEBOARD_FAB2(SCH_1):PAGE204
    36 A_TSENSE_PVCCIN_CPU0 @BASEBOARD_FAB2_LIB.BASEBOARD_FAB2(SCH_1):A_TSENSE_PVCCIN_CPU0    I71 @BASEBOARD_FAB2_LIB.BASEBOARD_FAB2(SCH_1):PAGE204
     3 VR_PVCCIN_CPU0_PH5_VCIN @BASEBOARD_FAB2_LIB.BASEBOARD_FAB2(SCH_1):VR_PVCCIN_CPU0_PH5_VCIN    I71 @BASEBOARD_FAB2_LIB.BASEBOARD_FAB2(SCH_1):PAGE204
     4 P5V_STBY @BASEBOARD_FAB2_LIB.BASEBOARD_FAB2(SCH_1):P5V_STBY    I71 @BASEBOARD_FAB2_LIB.BASEBOARD_FAB2(SCH_1):PAGE204
    30 VR_FET_SW_P12V_STBY_PVCCIN_CPU0 @BASEBOARD_FAB2_LIB.BASEBOARD_FAB2(SCH_1):VR_FET_SW_P12V_STBY_PVCCIN_CPU0    I71 @BASEBOARD_FAB2_LIB.BASEBOARD_FAB2(SCH_1):PAGE204
    25 VR_FET_SW_P12V_STBY_PVCCIN_CPU0 @BASEBOARD_FAB2_LIB.BASEBOARD_FAB2(SCH_1):VR_FET_SW_P12V_STBY_PVCCIN_CPU0    I71 @BASEBOARD_FAB2_LIB.BASEBOARD_FAB2(SCH_1):PAGE204
     1 PVCCIN_CPU0 @BASEBOARD_FAB2_LIB.BASEBOARD_FAB2(SCH_1):PVCCIN_CPU0    I71 @BASEBOARD_FAB2_LIB.BASEBOARD_FAB2(SCH_1):PAGE204

EU4D1 IR354XX_SM-IR35411,IC,H73688-0A
    33 VR_PVCCIN_CPU0_PH4_BOOT_R @BASEBOARD_FAB2_LIB.BASEBOARD_FAB2(SCH_1):VR_PVCCIN_CPU0_PH4_BOOT_R    I71 @BASEBOARD_FAB2_LIB.BASEBOARD_FAB2(SCH_1):PAGE203
    35 P5V_STBY @BASEBOARD_FAB2_LIB.BASEBOARD_FAB2(SCH_1):P5V_STBY    I71 @BASEBOARD_FAB2_LIB.BASEBOARD_FAB2(SCH_1):PAGE203
    41 TP_PVCCIN_CPU0_PH4_GL_1 @BASEBOARD_FAB2_LIB.BASEBOARD_FAB2(SCH_1):TP_PVCCIN_CPU0_PH4_GL_1    I71 @BASEBOARD_FAB2_LIB.BASEBOARD_FAB2(SCH_1):PAGE203
     6 TP_PVCCIN_CPU0_PH4_GL_0 @BASEBOARD_FAB2_LIB.BASEBOARD_FAB2(SCH_1):TP_PVCCIN_CPU0_PH4_GL_0    I71 @BASEBOARD_FAB2_LIB.BASEBOARD_FAB2(SCH_1):PAGE203
    38 ISENSE_PVCCIN_CPU0_PH4_IMON @BASEBOARD_FAB2_LIB.BASEBOARD_FAB2(SCH_1):ISENSE_PVCCIN_CPU0_PH4_IMON    I71 @BASEBOARD_FAB2_LIB.BASEBOARD_FAB2(SCH_1):PAGE203
     2    GND @BASEBOARD_FAB2_LIB.BASEBOARD_FAB2(SCH_1):GND    I71 @BASEBOARD_FAB2_LIB.BASEBOARD_FAB2(SCH_1):PAGE203
    31     NC     NC    I71 @BASEBOARD_FAB2_LIB.BASEBOARD_FAB2(SCH_1):PAGE203
    37 VR_PVCCIN_CPU0_PH4_OCSET @BASEBOARD_FAB2_LIB.BASEBOARD_FAB2(SCH_1):VR_PVCCIN_CPU0_PH4_OCSET    I71 @BASEBOARD_FAB2_LIB.BASEBOARD_FAB2(SCH_1):PAGE203
    40    GND @BASEBOARD_FAB2_LIB.BASEBOARD_FAB2(SCH_1):GND    I71 @BASEBOARD_FAB2_LIB.BASEBOARD_FAB2(SCH_1):PAGE203
     7    GND @BASEBOARD_FAB2_LIB.BASEBOARD_FAB2(SCH_1):GND    I71 @BASEBOARD_FAB2_LIB.BASEBOARD_FAB2(SCH_1):PAGE203
     5    GND @BASEBOARD_FAB2_LIB.BASEBOARD_FAB2(SCH_1):GND    I71 @BASEBOARD_FAB2_LIB.BASEBOARD_FAB2(SCH_1):PAGE203
    32 VR_PVCCIN_CPU0_PH4_PHASE @BASEBOARD_FAB2_LIB.BASEBOARD_FAB2(SCH_1):VR_PVCCIN_CPU0_PH4_PHASE    I71 @BASEBOARD_FAB2_LIB.BASEBOARD_FAB2(SCH_1):PAGE203
    34 VR_PVCCIN_CPU0_PWM4 @BASEBOARD_FAB2_LIB.BASEBOARD_FAB2(SCH_1):VR_PVCCIN_CPU0_PWM4    I71 @BASEBOARD_FAB2_LIB.BASEBOARD_FAB2(SCH_1):PAGE203
    39 VR_PVCCIN_CPU0_AIREF4 @BASEBOARD_FAB2_LIB.BASEBOARD_FAB2(SCH_1):VR_PVCCIN_CPU0_AIREF4    I71 @BASEBOARD_FAB2_LIB.BASEBOARD_FAB2(SCH_1):PAGE203
    10 VR_PVCCIN_CPU0_PHASE4 @BASEBOARD_FAB2_LIB.BASEBOARD_FAB2(SCH_1):VR_PVCCIN_CPU0_PHASE4    I71 @BASEBOARD_FAB2_LIB.BASEBOARD_FAB2(SCH_1):PAGE203
    36 A_TSENSE_PVCCIN_CPU0 @BASEBOARD_FAB2_LIB.BASEBOARD_FAB2(SCH_1):A_TSENSE_PVCCIN_CPU0    I71 @BASEBOARD_FAB2_LIB.BASEBOARD_FAB2(SCH_1):PAGE203
     3 VR_PVCCIN_CPU0_PH4_VCIN @BASEBOARD_FAB2_LIB.BASEBOARD_FAB2(SCH_1):VR_PVCCIN_CPU0_PH4_VCIN    I71 @BASEBOARD_FAB2_LIB.BASEBOARD_FAB2(SCH_1):PAGE203
     4 P5V_STBY @BASEBOARD_FAB2_LIB.BASEBOARD_FAB2(SCH_1):P5V_STBY    I71 @BASEBOARD_FAB2_LIB.BASEBOARD_FAB2(SCH_1):PAGE203
    30 VR_FET_SW_P12V_STBY_PVCCIN_CPU0 @BASEBOARD_FAB2_LIB.BASEBOARD_FAB2(SCH_1):VR_FET_SW_P12V_STBY_PVCCIN_CPU0    I71 @BASEBOARD_FAB2_LIB.BASEBOARD_FAB2(SCH_1):PAGE203
    25 VR_FET_SW_P12V_STBY_PVCCIN_CPU0 @BASEBOARD_FAB2_LIB.BASEBOARD_FAB2(SCH_1):VR_FET_SW_P12V_STBY_PVCCIN_CPU0    I71 @BASEBOARD_FAB2_LIB.BASEBOARD_FAB2(SCH_1):PAGE203
     1 PVCCIN_CPU0 @BASEBOARD_FAB2_LIB.BASEBOARD_FAB2(SCH_1):PVCCIN_CPU0    I71 @BASEBOARD_FAB2_LIB.BASEBOARD_FAB2(SCH_1):PAGE203

EU4D2 NB3W1200L_LCC-IC,H13585-001
     1 P3V3_DB1200_A @BASEBOARD_FAB2_LIB.BASEBOARD_FAB2(SCH_1):P3V3_DB1200_A     I1 @BASEBOARD_FAB2_LIB.BASEBOARD_FAB2(SCH_1):PAGE102
     2    GND @BASEBOARD_FAB2_LIB.BASEBOARD_FAB2(SCH_1):GND     I1 @BASEBOARD_FAB2_LIB.BASEBOARD_FAB2(SCH_1):PAGE102
     3     NC     NC     I1 @BASEBOARD_FAB2_LIB.BASEBOARD_FAB2(SCH_1):PAGE102
     4 FM_100M_N @BASEBOARD_FAB2_LIB.BASEBOARD_FAB2(SCH_1):FM_100M_N     I1 @BASEBOARD_FAB2_LIB.BASEBOARD_FAB2(SCH_1):PAGE102
     5 FM_HBW_BYPASS_LOWBW_N @BASEBOARD_FAB2_LIB.BASEBOARD_FAB2(SCH_1):FM_HBW_BYPASS_LOWBW_N     I1 @BASEBOARD_FAB2_LIB.BASEBOARD_FAB2(SCH_1):PAGE102
     6 FM_DB1200_PWRGD_R @BASEBOARD_FAB2_LIB.BASEBOARD_FAB2(SCH_1):FM_DB1200_PWRGD_R     I1 @BASEBOARD_FAB2_LIB.BASEBOARD_FAB2(SCH_1):PAGE102
     7    GND @BASEBOARD_FAB2_LIB.BASEBOARD_FAB2(SCH_1):GND     I1 @BASEBOARD_FAB2_LIB.BASEBOARD_FAB2(SCH_1):PAGE102
     8 P3V3_DB1200_R @BASEBOARD_FAB2_LIB.BASEBOARD_FAB2(SCH_1):P3V3_DB1200_R     I1 @BASEBOARD_FAB2_LIB.BASEBOARD_FAB2(SCH_1):PAGE102
     9 CLK_100M_DB1200_DP @BASEBOARD_FAB2_LIB.BASEBOARD_FAB2(SCH_1):CLK_100M_DB1200_DP     I1 @BASEBOARD_FAB2_LIB.BASEBOARD_FAB2(SCH_1):PAGE102
    10 CLK_100M_DB1200_DN @BASEBOARD_FAB2_LIB.BASEBOARD_FAB2(SCH_1):CLK_100M_DB1200_DN     I1 @BASEBOARD_FAB2_LIB.BASEBOARD_FAB2(SCH_1):PAGE102
    11 FM_DB1200_SMB_SA0 @BASEBOARD_FAB2_LIB.BASEBOARD_FAB2(SCH_1):FM_DB1200_SMB_SA0     I1 @BASEBOARD_FAB2_LIB.BASEBOARD_FAB2(SCH_1):PAGE102
    12 SMB_HOST_STBY_LVC3_SDA_R2 @BASEBOARD_FAB2_LIB.BASEBOARD_FAB2(SCH_1):SMB_HOST_STBY_LVC3_SDA_R2     I1 @BASEBOARD_FAB2_LIB.BASEBOARD_FAB2(SCH_1):PAGE102
    13 SMB_HOST_STBY_LVC3_SCL_R2 @BASEBOARD_FAB2_LIB.BASEBOARD_FAB2(SCH_1):SMB_HOST_STBY_LVC3_SCL_R2     I1 @BASEBOARD_FAB2_LIB.BASEBOARD_FAB2(SCH_1):PAGE102
    14 FM_DB1200_SMB_SA1 @BASEBOARD_FAB2_LIB.BASEBOARD_FAB2(SCH_1):FM_DB1200_SMB_SA1     I1 @BASEBOARD_FAB2_LIB.BASEBOARD_FAB2(SCH_1):PAGE102
    15     NC     NC     I1 @BASEBOARD_FAB2_LIB.BASEBOARD_FAB2(SCH_1):PAGE102
    16     NC     NC     I1 @BASEBOARD_FAB2_LIB.BASEBOARD_FAB2(SCH_1):PAGE102
    17 CLK_100M_CPU0_BCLK0_R_DP @BASEBOARD_FAB2_LIB.BASEBOARD_FAB2(SCH_1):CLK_100M_CPU0_BCLK0_R_DP     I1 @BASEBOARD_FAB2_LIB.BASEBOARD_FAB2(SCH_1):PAGE102
    18 CLK_100M_CPU0_BCLK0_R_DN @BASEBOARD_FAB2_LIB.BASEBOARD_FAB2(SCH_1):CLK_100M_CPU0_BCLK0_R_DN     I1 @BASEBOARD_FAB2_LIB.BASEBOARD_FAB2(SCH_1):PAGE102
    19 FM_DB1200ZL_BCLKS_EN_N @BASEBOARD_FAB2_LIB.BASEBOARD_FAB2(SCH_1):FM_DB1200ZL_BCLKS_EN_N     I1 @BASEBOARD_FAB2_LIB.BASEBOARD_FAB2(SCH_1):PAGE102
    20 FM_DB1200ZL_BCLKS_EN_N @BASEBOARD_FAB2_LIB.BASEBOARD_FAB2(SCH_1):FM_DB1200ZL_BCLKS_EN_N     I1 @BASEBOARD_FAB2_LIB.BASEBOARD_FAB2(SCH_1):PAGE102
    21 CLK_100M_CPU0_BCLK1_R_DP @BASEBOARD_FAB2_LIB.BASEBOARD_FAB2(SCH_1):CLK_100M_CPU0_BCLK1_R_DP     I1 @BASEBOARD_FAB2_LIB.BASEBOARD_FAB2(SCH_1):PAGE102
    22 CLK_100M_CPU0_BCLK1_R_DN @BASEBOARD_FAB2_LIB.BASEBOARD_FAB2(SCH_1):CLK_100M_CPU0_BCLK1_R_DN     I1 @BASEBOARD_FAB2_LIB.BASEBOARD_FAB2(SCH_1):PAGE102
    23    GND @BASEBOARD_FAB2_LIB.BASEBOARD_FAB2(SCH_1):GND     I1 @BASEBOARD_FAB2_LIB.BASEBOARD_FAB2(SCH_1):PAGE102
    24 P3V3_DB1200 @BASEBOARD_FAB2_LIB.BASEBOARD_FAB2(SCH_1):P3V3_DB1200     I1 @BASEBOARD_FAB2_LIB.BASEBOARD_FAB2(SCH_1):PAGE102
    25 P3V3_DB1200 @BASEBOARD_FAB2_LIB.BASEBOARD_FAB2(SCH_1):P3V3_DB1200     I1 @BASEBOARD_FAB2_LIB.BASEBOARD_FAB2(SCH_1):PAGE102
    26 CLK_100M_CPU0_BCLK2_R_DP @BASEBOARD_FAB2_LIB.BASEBOARD_FAB2(SCH_1):CLK_100M_CPU0_BCLK2_R_DP     I1 @BASEBOARD_FAB2_LIB.BASEBOARD_FAB2(SCH_1):PAGE102
    27 CLK_100M_CPU0_BCLK2_R_DN @BASEBOARD_FAB2_LIB.BASEBOARD_FAB2(SCH_1):CLK_100M_CPU0_BCLK2_R_DN     I1 @BASEBOARD_FAB2_LIB.BASEBOARD_FAB2(SCH_1):PAGE102
    28 FM_DB1200ZL_BCLKS_EN_N @BASEBOARD_FAB2_LIB.BASEBOARD_FAB2(SCH_1):FM_DB1200ZL_BCLKS_EN_N     I1 @BASEBOARD_FAB2_LIB.BASEBOARD_FAB2(SCH_1):PAGE102
    29 FM_CPU0_MCP_CLK_EN_N @BASEBOARD_FAB2_LIB.BASEBOARD_FAB2(SCH_1):FM_CPU0_MCP_CLK_EN_N     I1 @BASEBOARD_FAB2_LIB.BASEBOARD_FAB2(SCH_1):PAGE102
    30 CLK_100M_CPU0_PE_REFCLK_R_DP @BASEBOARD_FAB2_LIB.BASEBOARD_FAB2(SCH_1):CLK_100M_CPU0_PE_REFCLK_R_DP     I1 @BASEBOARD_FAB2_LIB.BASEBOARD_FAB2(SCH_1):PAGE102
    31 CLK_100M_CPU0_PE_REFCLK_R_DN @BASEBOARD_FAB2_LIB.BASEBOARD_FAB2(SCH_1):CLK_100M_CPU0_PE_REFCLK_R_DN     I1 @BASEBOARD_FAB2_LIB.BASEBOARD_FAB2(SCH_1):PAGE102
    32 P3V3_DB1200 @BASEBOARD_FAB2_LIB.BASEBOARD_FAB2(SCH_1):P3V3_DB1200     I1 @BASEBOARD_FAB2_LIB.BASEBOARD_FAB2(SCH_1):PAGE102
    33    GND @BASEBOARD_FAB2_LIB.BASEBOARD_FAB2(SCH_1):GND     I1 @BASEBOARD_FAB2_LIB.BASEBOARD_FAB2(SCH_1):PAGE102
    34 CLK_100M_CPU0_RC_REFCLK0_R_DP @BASEBOARD_FAB2_LIB.BASEBOARD_FAB2(SCH_1):CLK_100M_CPU0_RC_REFCLK0_R_DP     I1 @BASEBOARD_FAB2_LIB.BASEBOARD_FAB2(SCH_1):PAGE102
    35 CLK_100M_CPU0_RC_REFCLK0_R_DN @BASEBOARD_FAB2_LIB.BASEBOARD_FAB2(SCH_1):CLK_100M_CPU0_RC_REFCLK0_R_DN     I1 @BASEBOARD_FAB2_LIB.BASEBOARD_FAB2(SCH_1):PAGE102
    36 FM_CPU0_MCP_CLK_EN_N @BASEBOARD_FAB2_LIB.BASEBOARD_FAB2(SCH_1):FM_CPU0_MCP_CLK_EN_N     I1 @BASEBOARD_FAB2_LIB.BASEBOARD_FAB2(SCH_1):PAGE102
    37 FM_CPU0_MCP_CLK_EN_N @BASEBOARD_FAB2_LIB.BASEBOARD_FAB2(SCH_1):FM_CPU0_MCP_CLK_EN_N     I1 @BASEBOARD_FAB2_LIB.BASEBOARD_FAB2(SCH_1):PAGE102
    38 CLK_100M_CPU0_RC_REFCLK1_R_DP @BASEBOARD_FAB2_LIB.BASEBOARD_FAB2(SCH_1):CLK_100M_CPU0_RC_REFCLK1_R_DP     I1 @BASEBOARD_FAB2_LIB.BASEBOARD_FAB2(SCH_1):PAGE102
    39 CLK_100M_CPU0_RC_REFCLK1_R_DN @BASEBOARD_FAB2_LIB.BASEBOARD_FAB2(SCH_1):CLK_100M_CPU0_RC_REFCLK1_R_DN     I1 @BASEBOARD_FAB2_LIB.BASEBOARD_FAB2(SCH_1):PAGE102
    40 P3V3_DB1200 @BASEBOARD_FAB2_LIB.BASEBOARD_FAB2(SCH_1):P3V3_DB1200     I1 @BASEBOARD_FAB2_LIB.BASEBOARD_FAB2(SCH_1):PAGE102
    41    GND @BASEBOARD_FAB2_LIB.BASEBOARD_FAB2(SCH_1):GND     I1 @BASEBOARD_FAB2_LIB.BASEBOARD_FAB2(SCH_1):PAGE102
    42 CLK_100M_CPU1_BCLK0_R_DP @BASEBOARD_FAB2_LIB.BASEBOARD_FAB2(SCH_1):CLK_100M_CPU1_BCLK0_R_DP     I1 @BASEBOARD_FAB2_LIB.BASEBOARD_FAB2(SCH_1):PAGE102
    43 CLK_100M_CPU1_BCLK0_R_DN @BASEBOARD_FAB2_LIB.BASEBOARD_FAB2(SCH_1):CLK_100M_CPU1_BCLK0_R_DN     I1 @BASEBOARD_FAB2_LIB.BASEBOARD_FAB2(SCH_1):PAGE102
    44 FM_DB1200ZL_BCLKS_EN_N @BASEBOARD_FAB2_LIB.BASEBOARD_FAB2(SCH_1):FM_DB1200ZL_BCLKS_EN_N     I1 @BASEBOARD_FAB2_LIB.BASEBOARD_FAB2(SCH_1):PAGE102
    45 FM_DB1200ZL_BCLKS_EN_N @BASEBOARD_FAB2_LIB.BASEBOARD_FAB2(SCH_1):FM_DB1200ZL_BCLKS_EN_N     I1 @BASEBOARD_FAB2_LIB.BASEBOARD_FAB2(SCH_1):PAGE102
    46 CLK_100M_CPU1_BCLK1_R_DP @BASEBOARD_FAB2_LIB.BASEBOARD_FAB2(SCH_1):CLK_100M_CPU1_BCLK1_R_DP     I1 @BASEBOARD_FAB2_LIB.BASEBOARD_FAB2(SCH_1):PAGE102
    47 CLK_100M_CPU1_BCLK1_R_DN @BASEBOARD_FAB2_LIB.BASEBOARD_FAB2(SCH_1):CLK_100M_CPU1_BCLK1_R_DN     I1 @BASEBOARD_FAB2_LIB.BASEBOARD_FAB2(SCH_1):PAGE102
    48    GND @BASEBOARD_FAB2_LIB.BASEBOARD_FAB2(SCH_1):GND     I1 @BASEBOARD_FAB2_LIB.BASEBOARD_FAB2(SCH_1):PAGE102
    49 P3V3_DB1200 @BASEBOARD_FAB2_LIB.BASEBOARD_FAB2(SCH_1):P3V3_DB1200     I1 @BASEBOARD_FAB2_LIB.BASEBOARD_FAB2(SCH_1):PAGE102
    50 CLK_100M_CPU1_BCLK2_R_DP @BASEBOARD_FAB2_LIB.BASEBOARD_FAB2(SCH_1):CLK_100M_CPU1_BCLK2_R_DP     I1 @BASEBOARD_FAB2_LIB.BASEBOARD_FAB2(SCH_1):PAGE102
    51 CLK_100M_CPU1_BCLK2_R_DN @BASEBOARD_FAB2_LIB.BASEBOARD_FAB2(SCH_1):CLK_100M_CPU1_BCLK2_R_DN     I1 @BASEBOARD_FAB2_LIB.BASEBOARD_FAB2(SCH_1):PAGE102
    52 FM_DB1200ZL_BCLKS_EN_N @BASEBOARD_FAB2_LIB.BASEBOARD_FAB2(SCH_1):FM_DB1200ZL_BCLKS_EN_N     I1 @BASEBOARD_FAB2_LIB.BASEBOARD_FAB2(SCH_1):PAGE102
    53 FM_CPU1_MCP_CLK_EN_N @BASEBOARD_FAB2_LIB.BASEBOARD_FAB2(SCH_1):FM_CPU1_MCP_CLK_EN_N     I1 @BASEBOARD_FAB2_LIB.BASEBOARD_FAB2(SCH_1):PAGE102
    54 CLK_100M_CPU1_PE_REFCLK_R_DP @BASEBOARD_FAB2_LIB.BASEBOARD_FAB2(SCH_1):CLK_100M_CPU1_PE_REFCLK_R_DP     I1 @BASEBOARD_FAB2_LIB.BASEBOARD_FAB2(SCH_1):PAGE102
    55 CLK_100M_CPU1_PE_REFCLK_R_DN @BASEBOARD_FAB2_LIB.BASEBOARD_FAB2(SCH_1):CLK_100M_CPU1_PE_REFCLK_R_DN     I1 @BASEBOARD_FAB2_LIB.BASEBOARD_FAB2(SCH_1):PAGE102
    56 P3V3_DB1200 @BASEBOARD_FAB2_LIB.BASEBOARD_FAB2(SCH_1):P3V3_DB1200     I1 @BASEBOARD_FAB2_LIB.BASEBOARD_FAB2(SCH_1):PAGE102
    57 P3V3_DB1200 @BASEBOARD_FAB2_LIB.BASEBOARD_FAB2(SCH_1):P3V3_DB1200     I1 @BASEBOARD_FAB2_LIB.BASEBOARD_FAB2(SCH_1):PAGE102
    58    GND @BASEBOARD_FAB2_LIB.BASEBOARD_FAB2(SCH_1):GND     I1 @BASEBOARD_FAB2_LIB.BASEBOARD_FAB2(SCH_1):PAGE102
    59 CLK_100M_CPU1_RC_REFCLK0_R_DP @BASEBOARD_FAB2_LIB.BASEBOARD_FAB2(SCH_1):CLK_100M_CPU1_RC_REFCLK0_R_DP     I1 @BASEBOARD_FAB2_LIB.BASEBOARD_FAB2(SCH_1):PAGE102
    60 CLK_100M_CPU1_RC_REFCLK0_R_DN @BASEBOARD_FAB2_LIB.BASEBOARD_FAB2(SCH_1):CLK_100M_CPU1_RC_REFCLK0_R_DN     I1 @BASEBOARD_FAB2_LIB.BASEBOARD_FAB2(SCH_1):PAGE102
    61 FM_CPU1_MCP_CLK_EN_N @BASEBOARD_FAB2_LIB.BASEBOARD_FAB2(SCH_1):FM_CPU1_MCP_CLK_EN_N     I1 @BASEBOARD_FAB2_LIB.BASEBOARD_FAB2(SCH_1):PAGE102
    62 FM_CPU1_MCP_CLK_EN_N @BASEBOARD_FAB2_LIB.BASEBOARD_FAB2(SCH_1):FM_CPU1_MCP_CLK_EN_N     I1 @BASEBOARD_FAB2_LIB.BASEBOARD_FAB2(SCH_1):PAGE102
    63 CLK_100M_CPU1_RC_REFCLK1_R_DP @BASEBOARD_FAB2_LIB.BASEBOARD_FAB2(SCH_1):CLK_100M_CPU1_RC_REFCLK1_R_DP     I1 @BASEBOARD_FAB2_LIB.BASEBOARD_FAB2(SCH_1):PAGE102
    64 CLK_100M_CPU1_RC_REFCLK1_R_DN @BASEBOARD_FAB2_LIB.BASEBOARD_FAB2(SCH_1):CLK_100M_CPU1_RC_REFCLK1_R_DN     I1 @BASEBOARD_FAB2_LIB.BASEBOARD_FAB2(SCH_1):PAGE102
    65    GND @BASEBOARD_FAB2_LIB.BASEBOARD_FAB2(SCH_1):GND     I1 @BASEBOARD_FAB2_LIB.BASEBOARD_FAB2(SCH_1):PAGE102

EU4D3 IR354XX_SM-IR35411,IC,H73688-0A
    33 VR_PVCCIN_CPU0_PH3_BOOT_R @BASEBOARD_FAB2_LIB.BASEBOARD_FAB2(SCH_1):VR_PVCCIN_CPU0_PH3_BOOT_R    I70 @BASEBOARD_FAB2_LIB.BASEBOARD_FAB2(SCH_1):PAGE203
    35 P5V_STBY @BASEBOARD_FAB2_LIB.BASEBOARD_FAB2(SCH_1):P5V_STBY    I70 @BASEBOARD_FAB2_LIB.BASEBOARD_FAB2(SCH_1):PAGE203
    41 TP_PVCCIN_CPU0_PH3_GL_1 @BASEBOARD_FAB2_LIB.BASEBOARD_FAB2(SCH_1):TP_PVCCIN_CPU0_PH3_GL_1    I70 @BASEBOARD_FAB2_LIB.BASEBOARD_FAB2(SCH_1):PAGE203
     6 TP_PVCCIN_CPU0_PH3_GL_0 @BASEBOARD_FAB2_LIB.BASEBOARD_FAB2(SCH_1):TP_PVCCIN_CPU0_PH3_GL_0    I70 @BASEBOARD_FAB2_LIB.BASEBOARD_FAB2(SCH_1):PAGE203
    38 ISENSE_PVCCIN_CPU0_PH3_IMON @BASEBOARD_FAB2_LIB.BASEBOARD_FAB2(SCH_1):ISENSE_PVCCIN_CPU0_PH3_IMON    I70 @BASEBOARD_FAB2_LIB.BASEBOARD_FAB2(SCH_1):PAGE203
     2    GND @BASEBOARD_FAB2_LIB.BASEBOARD_FAB2(SCH_1):GND    I70 @BASEBOARD_FAB2_LIB.BASEBOARD_FAB2(SCH_1):PAGE203
    31     NC     NC    I70 @BASEBOARD_FAB2_LIB.BASEBOARD_FAB2(SCH_1):PAGE203
    37 VR_PVCCIN_CPU0_PH3_OCSET @BASEBOARD_FAB2_LIB.BASEBOARD_FAB2(SCH_1):VR_PVCCIN_CPU0_PH3_OCSET    I70 @BASEBOARD_FAB2_LIB.BASEBOARD_FAB2(SCH_1):PAGE203
    40    GND @BASEBOARD_FAB2_LIB.BASEBOARD_FAB2(SCH_1):GND    I70 @BASEBOARD_FAB2_LIB.BASEBOARD_FAB2(SCH_1):PAGE203
     7    GND @BASEBOARD_FAB2_LIB.BASEBOARD_FAB2(SCH_1):GND    I70 @BASEBOARD_FAB2_LIB.BASEBOARD_FAB2(SCH_1):PAGE203
     5    GND @BASEBOARD_FAB2_LIB.BASEBOARD_FAB2(SCH_1):GND    I70 @BASEBOARD_FAB2_LIB.BASEBOARD_FAB2(SCH_1):PAGE203
    32 VR_PVCCIN_CPU0_PH3_PHASE @BASEBOARD_FAB2_LIB.BASEBOARD_FAB2(SCH_1):VR_PVCCIN_CPU0_PH3_PHASE    I70 @BASEBOARD_FAB2_LIB.BASEBOARD_FAB2(SCH_1):PAGE203
    34 VR_PVCCIN_CPU0_PWM3 @BASEBOARD_FAB2_LIB.BASEBOARD_FAB2(SCH_1):VR_PVCCIN_CPU0_PWM3    I70 @BASEBOARD_FAB2_LIB.BASEBOARD_FAB2(SCH_1):PAGE203
    39 VR_PVCCIN_CPU0_AIREF3 @BASEBOARD_FAB2_LIB.BASEBOARD_FAB2(SCH_1):VR_PVCCIN_CPU0_AIREF3    I70 @BASEBOARD_FAB2_LIB.BASEBOARD_FAB2(SCH_1):PAGE203
    10 VR_PVCCIN_CPU0_PHASE3 @BASEBOARD_FAB2_LIB.BASEBOARD_FAB2(SCH_1):VR_PVCCIN_CPU0_PHASE3    I70 @BASEBOARD_FAB2_LIB.BASEBOARD_FAB2(SCH_1):PAGE203
    36 A_TSENSE_PVCCIN_CPU0 @BASEBOARD_FAB2_LIB.BASEBOARD_FAB2(SCH_1):A_TSENSE_PVCCIN_CPU0    I70 @BASEBOARD_FAB2_LIB.BASEBOARD_FAB2(SCH_1):PAGE203
     3 VR_PVCCIN_CPU0_PH3_VCIN @BASEBOARD_FAB2_LIB.BASEBOARD_FAB2(SCH_1):VR_PVCCIN_CPU0_PH3_VCIN    I70 @BASEBOARD_FAB2_LIB.BASEBOARD_FAB2(SCH_1):PAGE203
     4 P5V_STBY @BASEBOARD_FAB2_LIB.BASEBOARD_FAB2(SCH_1):P5V_STBY    I70 @BASEBOARD_FAB2_LIB.BASEBOARD_FAB2(SCH_1):PAGE203
    30 VR_FET_SW_P12V_STBY_PVCCIN_CPU0 @BASEBOARD_FAB2_LIB.BASEBOARD_FAB2(SCH_1):VR_FET_SW_P12V_STBY_PVCCIN_CPU0    I70 @BASEBOARD_FAB2_LIB.BASEBOARD_FAB2(SCH_1):PAGE203
    25 VR_FET_SW_P12V_STBY_PVCCIN_CPU0 @BASEBOARD_FAB2_LIB.BASEBOARD_FAB2(SCH_1):VR_FET_SW_P12V_STBY_PVCCIN_CPU0    I70 @BASEBOARD_FAB2_LIB.BASEBOARD_FAB2(SCH_1):PAGE203
     1 PVCCIN_CPU0 @BASEBOARD_FAB2_LIB.BASEBOARD_FAB2(SCH_1):PVCCIN_CPU0    I70 @BASEBOARD_FAB2_LIB.BASEBOARD_FAB2(SCH_1):PAGE203

EU4D4 PXE1610B_QFN-IC,H79206-001
     1 VR_PVSA_CPU0_PWM @BASEBOARD_FAB2_LIB.BASEBOARD_FAB2(SCH_1):VR_PVSA_CPU0_PWM   I155 @BASEBOARD_FAB2_LIB.BASEBOARD_FAB2(SCH_1):PAGE201
     2     NC     NC   I155 @BASEBOARD_FAB2_LIB.BASEBOARD_FAB2(SCH_1):PAGE201
     3 VR_PVCCIN_CPU0_PWM5 @BASEBOARD_FAB2_LIB.BASEBOARD_FAB2(SCH_1):VR_PVCCIN_CPU0_PWM5   I155 @BASEBOARD_FAB2_LIB.BASEBOARD_FAB2(SCH_1):PAGE201
     4 VR_PVCCIN_CPU0_PWM4 @BASEBOARD_FAB2_LIB.BASEBOARD_FAB2(SCH_1):VR_PVCCIN_CPU0_PWM4   I155 @BASEBOARD_FAB2_LIB.BASEBOARD_FAB2(SCH_1):PAGE201
     5 VR_PVCCIN_CPU0_PWM3 @BASEBOARD_FAB2_LIB.BASEBOARD_FAB2(SCH_1):VR_PVCCIN_CPU0_PWM3   I155 @BASEBOARD_FAB2_LIB.BASEBOARD_FAB2(SCH_1):PAGE201
     6 VR_PVCCIN_CPU0_PWM2 @BASEBOARD_FAB2_LIB.BASEBOARD_FAB2(SCH_1):VR_PVCCIN_CPU0_PWM2   I155 @BASEBOARD_FAB2_LIB.BASEBOARD_FAB2(SCH_1):PAGE201
     7 VR_PVCCIN_CPU0_PWM1 @BASEBOARD_FAB2_LIB.BASEBOARD_FAB2(SCH_1):VR_PVCCIN_CPU0_PWM1   I155 @BASEBOARD_FAB2_LIB.BASEBOARD_FAB2(SCH_1):PAGE201
     8 SMB_VR_STBY_LVC3_SDA @BASEBOARD_FAB2_LIB.BASEBOARD_FAB2(SCH_1):SMB_VR_STBY_LVC3_SDA   I155 @BASEBOARD_FAB2_LIB.BASEBOARD_FAB2(SCH_1):PAGE201
     9 SMB_VR_STBY_LVC3_SCL @BASEBOARD_FAB2_LIB.BASEBOARD_FAB2(SCH_1):SMB_VR_STBY_LVC3_SCL   I155 @BASEBOARD_FAB2_LIB.BASEBOARD_FAB2(SCH_1):PAGE201
    10     NC     NC   I155 @BASEBOARD_FAB2_LIB.BASEBOARD_FAB2(SCH_1):PAGE201
    11 VR_VRRDY_PVCCIN_CPU0 @BASEBOARD_FAB2_LIB.BASEBOARD_FAB2(SCH_1):VR_VRRDY_PVCCIN_CPU0   I155 @BASEBOARD_FAB2_LIB.BASEBOARD_FAB2(SCH_1):PAGE201
    12 VR_PVCCIN_CPU0_VREN @BASEBOARD_FAB2_LIB.BASEBOARD_FAB2(SCH_1):VR_PVCCIN_CPU0_VREN   I155 @BASEBOARD_FAB2_LIB.BASEBOARD_FAB2(SCH_1):PAGE201
    13 IRQ_PVCCIN_CPU0_VRHOT_LVC3_R_N @BASEBOARD_FAB2_LIB.BASEBOARD_FAB2(SCH_1):IRQ_PVCCIN_CPU0_VRHOT_LVC3_R_N   I155 @BASEBOARD_FAB2_LIB.BASEBOARD_FAB2(SCH_1):PAGE201
    14 FM_PVCCIN_CPU0_PWR_IN_ALERT_N @BASEBOARD_FAB2_LIB.BASEBOARD_FAB2(SCH_1):FM_PVCCIN_CPU0_PWR_IN_ALERT_N   I155 @BASEBOARD_FAB2_LIB.BASEBOARD_FAB2(SCH_1):PAGE201
    15 PWRGD_PVSA_CPU0_R @BASEBOARD_FAB2_LIB.BASEBOARD_FAB2(SCH_1):PWRGD_PVSA_CPU0_R   I155 @BASEBOARD_FAB2_LIB.BASEBOARD_FAB2(SCH_1):PAGE201
    16     NC     NC   I155 @BASEBOARD_FAB2_LIB.BASEBOARD_FAB2(SCH_1):PAGE201
    17 SVID_VCLK_PVCCIN_CPU0 @BASEBOARD_FAB2_LIB.BASEBOARD_FAB2(SCH_1):SVID_VCLK_PVCCIN_CPU0   I155 @BASEBOARD_FAB2_LIB.BASEBOARD_FAB2(SCH_1):PAGE201
    18 SVID_VDIO_PVCCIN_CPU0 @BASEBOARD_FAB2_LIB.BASEBOARD_FAB2(SCH_1):SVID_VDIO_PVCCIN_CPU0   I155 @BASEBOARD_FAB2_LIB.BASEBOARD_FAB2(SCH_1):PAGE201
    19 SVID_VALERT_VCCIN_CPU0 @BASEBOARD_FAB2_LIB.BASEBOARD_FAB2(SCH_1):SVID_VALERT_VCCIN_CPU0   I155 @BASEBOARD_FAB2_LIB.BASEBOARD_FAB2(SCH_1):PAGE201
    20 PU_VR_PVCCIN_CPU0_FLT1_SMBALT_N @BASEBOARD_FAB2_LIB.BASEBOARD_FAB2(SCH_1):PU_VR_PVCCIN_CPU0_FLT1_SMBALT_N_IMON   I155 @BASEBOARD_FAB2_LIB.BASEBOARD_FAB2(SCH_1):PAGE201
    21 VSENSE_PVCCIN_CPU0_AVSP @BASEBOARD_FAB2_LIB.BASEBOARD_FAB2(SCH_1):VSENSE_PVCCIN_CPU0_AVSP   I155 @BASEBOARD_FAB2_LIB.BASEBOARD_FAB2(SCH_1):PAGE201
    22 VSENSE_PVCCIN_CPU0_N @BASEBOARD_FAB2_LIB.BASEBOARD_FAB2(SCH_1):VSENSE_PVCCIN_CPU0_N   I155 @BASEBOARD_FAB2_LIB.BASEBOARD_FAB2(SCH_1):PAGE201
    23 VR_PVCCIN_CPU0_AIREF1 @BASEBOARD_FAB2_LIB.BASEBOARD_FAB2(SCH_1):VR_PVCCIN_CPU0_AIREF1   I155 @BASEBOARD_FAB2_LIB.BASEBOARD_FAB2(SCH_1):PAGE201
    24 ISENSE_PVCCIN_CPU0_PH1_IMON @BASEBOARD_FAB2_LIB.BASEBOARD_FAB2(SCH_1):ISENSE_PVCCIN_CPU0_PH1_IMON   I155 @BASEBOARD_FAB2_LIB.BASEBOARD_FAB2(SCH_1):PAGE201
    25 VR_PVCCIN_CPU0_AIREF2 @BASEBOARD_FAB2_LIB.BASEBOARD_FAB2(SCH_1):VR_PVCCIN_CPU0_AIREF2   I155 @BASEBOARD_FAB2_LIB.BASEBOARD_FAB2(SCH_1):PAGE201
    26 ISENSE_PVCCIN_CPU0_PH2_IMON @BASEBOARD_FAB2_LIB.BASEBOARD_FAB2(SCH_1):ISENSE_PVCCIN_CPU0_PH2_IMON   I155 @BASEBOARD_FAB2_LIB.BASEBOARD_FAB2(SCH_1):PAGE201
    27 VR_PVCCIN_CPU0_AIREF3 @BASEBOARD_FAB2_LIB.BASEBOARD_FAB2(SCH_1):VR_PVCCIN_CPU0_AIREF3   I155 @BASEBOARD_FAB2_LIB.BASEBOARD_FAB2(SCH_1):PAGE201
    28 ISENSE_PVCCIN_CPU0_PH3_IMON @BASEBOARD_FAB2_LIB.BASEBOARD_FAB2(SCH_1):ISENSE_PVCCIN_CPU0_PH3_IMON   I155 @BASEBOARD_FAB2_LIB.BASEBOARD_FAB2(SCH_1):PAGE201
    29 VR_PVCCIN_CPU0_AIREF4 @BASEBOARD_FAB2_LIB.BASEBOARD_FAB2(SCH_1):VR_PVCCIN_CPU0_AIREF4   I155 @BASEBOARD_FAB2_LIB.BASEBOARD_FAB2(SCH_1):PAGE201
    30 ISENSE_PVCCIN_CPU0_PH4_IMON @BASEBOARD_FAB2_LIB.BASEBOARD_FAB2(SCH_1):ISENSE_PVCCIN_CPU0_PH4_IMON   I155 @BASEBOARD_FAB2_LIB.BASEBOARD_FAB2(SCH_1):PAGE201
    31 VR_PVCCIN_CPU0_AIREF5 @BASEBOARD_FAB2_LIB.BASEBOARD_FAB2(SCH_1):VR_PVCCIN_CPU0_AIREF5   I155 @BASEBOARD_FAB2_LIB.BASEBOARD_FAB2(SCH_1):PAGE201
    32 ISENSE_PVCCIN_CPU0_PH5_IMON @BASEBOARD_FAB2_LIB.BASEBOARD_FAB2(SCH_1):ISENSE_PVCCIN_CPU0_PH5_IMON   I155 @BASEBOARD_FAB2_LIB.BASEBOARD_FAB2(SCH_1):PAGE201
    33     NC     NC   I155 @BASEBOARD_FAB2_LIB.BASEBOARD_FAB2(SCH_1):PAGE201
    34     NC     NC   I155 @BASEBOARD_FAB2_LIB.BASEBOARD_FAB2(SCH_1):PAGE201
    35 VSENSE_PVSA_CPU0_BVSP @BASEBOARD_FAB2_LIB.BASEBOARD_FAB2(SCH_1):VSENSE_PVSA_CPU0_BVSP   I155 @BASEBOARD_FAB2_LIB.BASEBOARD_FAB2(SCH_1):PAGE201
    36 VSENSE_PVSA_CPU0_N @BASEBOARD_FAB2_LIB.BASEBOARD_FAB2(SCH_1):VSENSE_PVSA_CPU0_N   I155 @BASEBOARD_FAB2_LIB.BASEBOARD_FAB2(SCH_1):PAGE201
    37 VR_PVSA_CPU0_BIREF1 @BASEBOARD_FAB2_LIB.BASEBOARD_FAB2(SCH_1):VR_PVSA_CPU0_BIREF1   I155 @BASEBOARD_FAB2_LIB.BASEBOARD_FAB2(SCH_1):PAGE201
    38 ISENSE_PVSA_CPU0_IMON @BASEBOARD_FAB2_LIB.BASEBOARD_FAB2(SCH_1):ISENSE_PVSA_CPU0_IMON   I155 @BASEBOARD_FAB2_LIB.BASEBOARD_FAB2(SCH_1):PAGE201
    39 PU_VR_PVCCIN_CPU0_IMON @BASEBOARD_FAB2_LIB.BASEBOARD_FAB2(SCH_1):PU_VR_PVCCIN_CPU0_IMON   I155 @BASEBOARD_FAB2_LIB.BASEBOARD_FAB2(SCH_1):PAGE201
    40     NC     NC   I155 @BASEBOARD_FAB2_LIB.BASEBOARD_FAB2(SCH_1):PAGE201
    41 VR_PVCCIN_CPU0_XADDR2 @BASEBOARD_FAB2_LIB.BASEBOARD_FAB2(SCH_1):VR_PVCCIN_CPU0_XADDR2   I155 @BASEBOARD_FAB2_LIB.BASEBOARD_FAB2(SCH_1):PAGE201
    42 A_TSENSE_PVSA_CPU0 @BASEBOARD_FAB2_LIB.BASEBOARD_FAB2(SCH_1):A_TSENSE_PVSA_CPU0   I155 @BASEBOARD_FAB2_LIB.BASEBOARD_FAB2(SCH_1):PAGE201
    43 A_TSENSE_PVCCIN_CPU0 @BASEBOARD_FAB2_LIB.BASEBOARD_FAB2(SCH_1):A_TSENSE_PVCCIN_CPU0   I155 @BASEBOARD_FAB2_LIB.BASEBOARD_FAB2(SCH_1):PAGE201
    44 VR_PVCCIN_CPU0_XADDR1 @BASEBOARD_FAB2_LIB.BASEBOARD_FAB2(SCH_1):VR_PVCCIN_CPU0_XADDR1   I155 @BASEBOARD_FAB2_LIB.BASEBOARD_FAB2(SCH_1):PAGE201
    45 VR_PVCCIN_CPU0_AVINSEN @BASEBOARD_FAB2_LIB.BASEBOARD_FAB2(SCH_1):VR_PVCCIN_CPU0_AVINSEN   I155 @BASEBOARD_FAB2_LIB.BASEBOARD_FAB2(SCH_1):PAGE201
    46     NC     NC   I155 @BASEBOARD_FAB2_LIB.BASEBOARD_FAB2(SCH_1):PAGE201
    47 VR_PVCCIN_CPU0_VDD @BASEBOARD_FAB2_LIB.BASEBOARD_FAB2(SCH_1):VR_PVCCIN_CPU0_VDD   I155 @BASEBOARD_FAB2_LIB.BASEBOARD_FAB2(SCH_1):PAGE201
    48 VR_PVCCIN_CPU0_VD12 @BASEBOARD_FAB2_LIB.BASEBOARD_FAB2(SCH_1):VR_PVCCIN_CPU0_VD12   I155 @BASEBOARD_FAB2_LIB.BASEBOARD_FAB2(SCH_1):PAGE201
    49    GND @BASEBOARD_FAB2_LIB.BASEBOARD_FAB2(SCH_1):GND   I155 @BASEBOARD_FAB2_LIB.BASEBOARD_FAB2(SCH_1):PAGE201

EU4D5 PXE1110B_QFN-IC,H89187-001
     1     NC     NC    I96 @BASEBOARD_FAB2_LIB.BASEBOARD_FAB2(SCH_1):PAGE213
     2     NC     NC    I96 @BASEBOARD_FAB2_LIB.BASEBOARD_FAB2(SCH_1):PAGE213
     3     NC     NC    I96 @BASEBOARD_FAB2_LIB.BASEBOARD_FAB2(SCH_1):PAGE213
     4     NC     NC    I96 @BASEBOARD_FAB2_LIB.BASEBOARD_FAB2(SCH_1):PAGE213
     5 VR_PVCCIO_CPU1_PWM1 @BASEBOARD_FAB2_LIB.BASEBOARD_FAB2(SCH_1):VR_PVCCIO_CPU1_PWM1    I96 @BASEBOARD_FAB2_LIB.BASEBOARD_FAB2(SCH_1):PAGE213
     6 SMB_VR_STBY_LVC3_SDA @BASEBOARD_FAB2_LIB.BASEBOARD_FAB2(SCH_1):SMB_VR_STBY_LVC3_SDA    I96 @BASEBOARD_FAB2_LIB.BASEBOARD_FAB2(SCH_1):PAGE213
     7 SMB_VR_STBY_LVC3_SCL @BASEBOARD_FAB2_LIB.BASEBOARD_FAB2(SCH_1):SMB_VR_STBY_LVC3_SCL    I96 @BASEBOARD_FAB2_LIB.BASEBOARD_FAB2(SCH_1):PAGE213
     8     NC     NC    I96 @BASEBOARD_FAB2_LIB.BASEBOARD_FAB2(SCH_1):PAGE213
     9 PWRGD_PVCCIO_CPU1_R @BASEBOARD_FAB2_LIB.BASEBOARD_FAB2(SCH_1):PWRGD_PVCCIO_CPU1_R    I96 @BASEBOARD_FAB2_LIB.BASEBOARD_FAB2(SCH_1):PAGE213
    10 VR_PVCCIO_CPU1_EN @BASEBOARD_FAB2_LIB.BASEBOARD_FAB2(SCH_1):VR_PVCCIO_CPU1_EN    I96 @BASEBOARD_FAB2_LIB.BASEBOARD_FAB2(SCH_1):PAGE213
    11 IRQ_PVCCIO_CPU1_VRHOT_N @BASEBOARD_FAB2_LIB.BASEBOARD_FAB2(SCH_1):IRQ_PVCCIO_CPU1_VRHOT_N    I96 @BASEBOARD_FAB2_LIB.BASEBOARD_FAB2(SCH_1):PAGE213
    12     NC     NC    I96 @BASEBOARD_FAB2_LIB.BASEBOARD_FAB2(SCH_1):PAGE213
    13     NC     NC    I96 @BASEBOARD_FAB2_LIB.BASEBOARD_FAB2(SCH_1):PAGE213
    14     NC     NC    I96 @BASEBOARD_FAB2_LIB.BASEBOARD_FAB2(SCH_1):PAGE213
    15 SVID_CLK_PVCCIO_CPU1 @BASEBOARD_FAB2_LIB.BASEBOARD_FAB2(SCH_1):SVID_CLK_PVCCIO_CPU1    I96 @BASEBOARD_FAB2_LIB.BASEBOARD_FAB2(SCH_1):PAGE213
    16 SVID_VDIO_PVCCIO_CPU1 @BASEBOARD_FAB2_LIB.BASEBOARD_FAB2(SCH_1):SVID_VDIO_PVCCIO_CPU1    I96 @BASEBOARD_FAB2_LIB.BASEBOARD_FAB2(SCH_1):PAGE213
    17 SVID_ALERT_PVCCIO_CPU1 @BASEBOARD_FAB2_LIB.BASEBOARD_FAB2(SCH_1):SVID_ALERT_PVCCIO_CPU1    I96 @BASEBOARD_FAB2_LIB.BASEBOARD_FAB2(SCH_1):PAGE213
    18     NC     NC    I96 @BASEBOARD_FAB2_LIB.BASEBOARD_FAB2(SCH_1):PAGE213
    19 VR_PVCCIO_CPU1_AVSP @BASEBOARD_FAB2_LIB.BASEBOARD_FAB2(SCH_1):VR_PVCCIO_CPU1_AVSP    I96 @BASEBOARD_FAB2_LIB.BASEBOARD_FAB2(SCH_1):PAGE213
    20 VSENSE_PVCCIO_CPU1_AVSN @BASEBOARD_FAB2_LIB.BASEBOARD_FAB2(SCH_1):VSENSE_PVCCIO_CPU1_AVSN    I96 @BASEBOARD_FAB2_LIB.BASEBOARD_FAB2(SCH_1):PAGE213
    21 VR_PVCCIO_CPU1_AIREF1 @BASEBOARD_FAB2_LIB.BASEBOARD_FAB2(SCH_1):VR_PVCCIO_CPU1_AIREF1    I96 @BASEBOARD_FAB2_LIB.BASEBOARD_FAB2(SCH_1):PAGE213
    22 ISENSE_PVCCIO_CPU1_PH1_IMON @BASEBOARD_FAB2_LIB.BASEBOARD_FAB2(SCH_1):ISENSE_PVCCIO_CPU1_PH1_IMON    I96 @BASEBOARD_FAB2_LIB.BASEBOARD_FAB2(SCH_1):PAGE213
    23    GND @BASEBOARD_FAB2_LIB.BASEBOARD_FAB2(SCH_1):GND    I96 @BASEBOARD_FAB2_LIB.BASEBOARD_FAB2(SCH_1):PAGE213
    24     NC     NC    I96 @BASEBOARD_FAB2_LIB.BASEBOARD_FAB2(SCH_1):PAGE213
    25     NC     NC    I96 @BASEBOARD_FAB2_LIB.BASEBOARD_FAB2(SCH_1):PAGE213
    26    GND @BASEBOARD_FAB2_LIB.BASEBOARD_FAB2(SCH_1):GND    I96 @BASEBOARD_FAB2_LIB.BASEBOARD_FAB2(SCH_1):PAGE213
    27    GND @BASEBOARD_FAB2_LIB.BASEBOARD_FAB2(SCH_1):GND    I96 @BASEBOARD_FAB2_LIB.BASEBOARD_FAB2(SCH_1):PAGE213
    28     NC     NC    I96 @BASEBOARD_FAB2_LIB.BASEBOARD_FAB2(SCH_1):PAGE213
    29     NC     NC    I96 @BASEBOARD_FAB2_LIB.BASEBOARD_FAB2(SCH_1):PAGE213
    30     NC     NC    I96 @BASEBOARD_FAB2_LIB.BASEBOARD_FAB2(SCH_1):PAGE213
    31     NC     NC    I96 @BASEBOARD_FAB2_LIB.BASEBOARD_FAB2(SCH_1):PAGE213
    32 PU_VR_PVCCIO_CPU1_FAULT1 @BASEBOARD_FAB2_LIB.BASEBOARD_FAB2(SCH_1):PU_VR_PVCCIO_CPU1_FAULT1    I96 @BASEBOARD_FAB2_LIB.BASEBOARD_FAB2(SCH_1):PAGE213
    33 VR_PVCCIO_CPU1_XADDR2 @BASEBOARD_FAB2_LIB.BASEBOARD_FAB2(SCH_1):VR_PVCCIO_CPU1_XADDR2    I96 @BASEBOARD_FAB2_LIB.BASEBOARD_FAB2(SCH_1):PAGE213
    34     NC     NC    I96 @BASEBOARD_FAB2_LIB.BASEBOARD_FAB2(SCH_1):PAGE213
    35 A_TSENSE_PVCCIO_CPU1 @BASEBOARD_FAB2_LIB.BASEBOARD_FAB2(SCH_1):A_TSENSE_PVCCIO_CPU1    I96 @BASEBOARD_FAB2_LIB.BASEBOARD_FAB2(SCH_1):PAGE213
    36 VR_PVCCIO_CPU1_XADDR1 @BASEBOARD_FAB2_LIB.BASEBOARD_FAB2(SCH_1):VR_PVCCIO_CPU1_XADDR1    I96 @BASEBOARD_FAB2_LIB.BASEBOARD_FAB2(SCH_1):PAGE213
    37 VR_PVCCIO_CPU1_VINSEN @BASEBOARD_FAB2_LIB.BASEBOARD_FAB2(SCH_1):VR_PVCCIO_CPU1_VINSEN    I96 @BASEBOARD_FAB2_LIB.BASEBOARD_FAB2(SCH_1):PAGE213
    38     NC     NC    I96 @BASEBOARD_FAB2_LIB.BASEBOARD_FAB2(SCH_1):PAGE213
    39 VR_PVCCIO_CPU1_VDD @BASEBOARD_FAB2_LIB.BASEBOARD_FAB2(SCH_1):VR_PVCCIO_CPU1_VDD    I96 @BASEBOARD_FAB2_LIB.BASEBOARD_FAB2(SCH_1):PAGE213
    40 VR_PVCCIO_CPU1_VD12 @BASEBOARD_FAB2_LIB.BASEBOARD_FAB2(SCH_1):VR_PVCCIO_CPU1_VD12    I96 @BASEBOARD_FAB2_LIB.BASEBOARD_FAB2(SCH_1):PAGE213
    41    GND @BASEBOARD_FAB2_LIB.BASEBOARD_FAB2(SCH_1):GND    I96 @BASEBOARD_FAB2_LIB.BASEBOARD_FAB2(SCH_1):PAGE213

EU4D6 IR354XX_SM-IR35411,IC,H73688-0A
    33 VR_PVCCIN_CPU0_PH2_BOOT_R @BASEBOARD_FAB2_LIB.BASEBOARD_FAB2(SCH_1):VR_PVCCIN_CPU0_PH2_BOOT_R    I64 @BASEBOARD_FAB2_LIB.BASEBOARD_FAB2(SCH_1):PAGE202
    35 P5V_STBY @BASEBOARD_FAB2_LIB.BASEBOARD_FAB2(SCH_1):P5V_STBY    I64 @BASEBOARD_FAB2_LIB.BASEBOARD_FAB2(SCH_1):PAGE202
    41 TP_PVCCIN_CPU0_PH2_GL_1 @BASEBOARD_FAB2_LIB.BASEBOARD_FAB2(SCH_1):TP_PVCCIN_CPU0_PH2_GL_1    I64 @BASEBOARD_FAB2_LIB.BASEBOARD_FAB2(SCH_1):PAGE202
     6 TP_PVCCIN_CPU0_PH2_GL_0 @BASEBOARD_FAB2_LIB.BASEBOARD_FAB2(SCH_1):TP_PVCCIN_CPU0_PH2_GL_0    I64 @BASEBOARD_FAB2_LIB.BASEBOARD_FAB2(SCH_1):PAGE202
    38 ISENSE_PVCCIN_CPU0_PH2_IMON @BASEBOARD_FAB2_LIB.BASEBOARD_FAB2(SCH_1):ISENSE_PVCCIN_CPU0_PH2_IMON    I64 @BASEBOARD_FAB2_LIB.BASEBOARD_FAB2(SCH_1):PAGE202
     2    GND @BASEBOARD_FAB2_LIB.BASEBOARD_FAB2(SCH_1):GND    I64 @BASEBOARD_FAB2_LIB.BASEBOARD_FAB2(SCH_1):PAGE202
    31     NC     NC    I64 @BASEBOARD_FAB2_LIB.BASEBOARD_FAB2(SCH_1):PAGE202
    37 VR_PVCCIN_CPU0_PH2_OCSET @BASEBOARD_FAB2_LIB.BASEBOARD_FAB2(SCH_1):VR_PVCCIN_CPU0_PH2_OCSET    I64 @BASEBOARD_FAB2_LIB.BASEBOARD_FAB2(SCH_1):PAGE202
    40    GND @BASEBOARD_FAB2_LIB.BASEBOARD_FAB2(SCH_1):GND    I64 @BASEBOARD_FAB2_LIB.BASEBOARD_FAB2(SCH_1):PAGE202
     7    GND @BASEBOARD_FAB2_LIB.BASEBOARD_FAB2(SCH_1):GND    I64 @BASEBOARD_FAB2_LIB.BASEBOARD_FAB2(SCH_1):PAGE202
     5    GND @BASEBOARD_FAB2_LIB.BASEBOARD_FAB2(SCH_1):GND    I64 @BASEBOARD_FAB2_LIB.BASEBOARD_FAB2(SCH_1):PAGE202
    32 VR_PVCCIN_CPU0_PH2_PHASE @BASEBOARD_FAB2_LIB.BASEBOARD_FAB2(SCH_1):VR_PVCCIN_CPU0_PH2_PHASE    I64 @BASEBOARD_FAB2_LIB.BASEBOARD_FAB2(SCH_1):PAGE202
    34 VR_PVCCIN_CPU0_PWM2 @BASEBOARD_FAB2_LIB.BASEBOARD_FAB2(SCH_1):VR_PVCCIN_CPU0_PWM2    I64 @BASEBOARD_FAB2_LIB.BASEBOARD_FAB2(SCH_1):PAGE202
    39 VR_PVCCIN_CPU0_AIREF2 @BASEBOARD_FAB2_LIB.BASEBOARD_FAB2(SCH_1):VR_PVCCIN_CPU0_AIREF2    I64 @BASEBOARD_FAB2_LIB.BASEBOARD_FAB2(SCH_1):PAGE202
    10 VR_PVCCIN_CPU0_PHASE2 @BASEBOARD_FAB2_LIB.BASEBOARD_FAB2(SCH_1):VR_PVCCIN_CPU0_PHASE2    I64 @BASEBOARD_FAB2_LIB.BASEBOARD_FAB2(SCH_1):PAGE202
    36 A_TSENSE_PVCCIN_CPU0 @BASEBOARD_FAB2_LIB.BASEBOARD_FAB2(SCH_1):A_TSENSE_PVCCIN_CPU0    I64 @BASEBOARD_FAB2_LIB.BASEBOARD_FAB2(SCH_1):PAGE202
     3 VR_PVCCIN_CPU0_PH2_VCIN @BASEBOARD_FAB2_LIB.BASEBOARD_FAB2(SCH_1):VR_PVCCIN_CPU0_PH2_VCIN    I64 @BASEBOARD_FAB2_LIB.BASEBOARD_FAB2(SCH_1):PAGE202
     4 P5V_STBY @BASEBOARD_FAB2_LIB.BASEBOARD_FAB2(SCH_1):P5V_STBY    I64 @BASEBOARD_FAB2_LIB.BASEBOARD_FAB2(SCH_1):PAGE202
    30 VR_FET_SW_P12V_STBY_PVCCIN_CPU0 @BASEBOARD_FAB2_LIB.BASEBOARD_FAB2(SCH_1):VR_FET_SW_P12V_STBY_PVCCIN_CPU0    I64 @BASEBOARD_FAB2_LIB.BASEBOARD_FAB2(SCH_1):PAGE202
    25 VR_FET_SW_P12V_STBY_PVCCIN_CPU0 @BASEBOARD_FAB2_LIB.BASEBOARD_FAB2(SCH_1):VR_FET_SW_P12V_STBY_PVCCIN_CPU0    I64 @BASEBOARD_FAB2_LIB.BASEBOARD_FAB2(SCH_1):PAGE202
     1 PVCCIN_CPU0 @BASEBOARD_FAB2_LIB.BASEBOARD_FAB2(SCH_1):PVCCIN_CPU0    I64 @BASEBOARD_FAB2_LIB.BASEBOARD_FAB2(SCH_1):PAGE202

EU4E1 IR354XX_SM-IR35411,IC,H73688-0A
    33 VR_PVCCIN_CPU0_PH1_BOOT_R @BASEBOARD_FAB2_LIB.BASEBOARD_FAB2(SCH_1):VR_PVCCIN_CPU0_PH1_BOOT_R    I63 @BASEBOARD_FAB2_LIB.BASEBOARD_FAB2(SCH_1):PAGE202
    35 P5V_STBY @BASEBOARD_FAB2_LIB.BASEBOARD_FAB2(SCH_1):P5V_STBY    I63 @BASEBOARD_FAB2_LIB.BASEBOARD_FAB2(SCH_1):PAGE202
    41 TP_PVCCIN_CPU0_PH1_GL_1 @BASEBOARD_FAB2_LIB.BASEBOARD_FAB2(SCH_1):TP_PVCCIN_CPU0_PH1_GL_1    I63 @BASEBOARD_FAB2_LIB.BASEBOARD_FAB2(SCH_1):PAGE202
     6 TP_PVCCIN_CPU0_PH1_GL_0 @BASEBOARD_FAB2_LIB.BASEBOARD_FAB2(SCH_1):TP_PVCCIN_CPU0_PH1_GL_0    I63 @BASEBOARD_FAB2_LIB.BASEBOARD_FAB2(SCH_1):PAGE202
    38 ISENSE_PVCCIN_CPU0_PH1_IMON @BASEBOARD_FAB2_LIB.BASEBOARD_FAB2(SCH_1):ISENSE_PVCCIN_CPU0_PH1_IMON    I63 @BASEBOARD_FAB2_LIB.BASEBOARD_FAB2(SCH_1):PAGE202
     2    GND @BASEBOARD_FAB2_LIB.BASEBOARD_FAB2(SCH_1):GND    I63 @BASEBOARD_FAB2_LIB.BASEBOARD_FAB2(SCH_1):PAGE202
    31     NC     NC    I63 @BASEBOARD_FAB2_LIB.BASEBOARD_FAB2(SCH_1):PAGE202
    37 VR_PVCCIN_CPU0_PH1_OCSET @BASEBOARD_FAB2_LIB.BASEBOARD_FAB2(SCH_1):VR_PVCCIN_CPU0_PH1_OCSET    I63 @BASEBOARD_FAB2_LIB.BASEBOARD_FAB2(SCH_1):PAGE202
    40    GND @BASEBOARD_FAB2_LIB.BASEBOARD_FAB2(SCH_1):GND    I63 @BASEBOARD_FAB2_LIB.BASEBOARD_FAB2(SCH_1):PAGE202
     7    GND @BASEBOARD_FAB2_LIB.BASEBOARD_FAB2(SCH_1):GND    I63 @BASEBOARD_FAB2_LIB.BASEBOARD_FAB2(SCH_1):PAGE202
     5    GND @BASEBOARD_FAB2_LIB.BASEBOARD_FAB2(SCH_1):GND    I63 @BASEBOARD_FAB2_LIB.BASEBOARD_FAB2(SCH_1):PAGE202
    32 VR_PVCCIN_CPU0_PH1_PHASE @BASEBOARD_FAB2_LIB.BASEBOARD_FAB2(SCH_1):VR_PVCCIN_CPU0_PH1_PHASE    I63 @BASEBOARD_FAB2_LIB.BASEBOARD_FAB2(SCH_1):PAGE202
    34 VR_PVCCIN_CPU0_PWM1 @BASEBOARD_FAB2_LIB.BASEBOARD_FAB2(SCH_1):VR_PVCCIN_CPU0_PWM1    I63 @BASEBOARD_FAB2_LIB.BASEBOARD_FAB2(SCH_1):PAGE202
    39 VR_PVCCIN_CPU0_AIREF1 @BASEBOARD_FAB2_LIB.BASEBOARD_FAB2(SCH_1):VR_PVCCIN_CPU0_AIREF1    I63 @BASEBOARD_FAB2_LIB.BASEBOARD_FAB2(SCH_1):PAGE202
    10 VR_PVCCIN_CPU0_PHASE1 @BASEBOARD_FAB2_LIB.BASEBOARD_FAB2(SCH_1):VR_PVCCIN_CPU0_PHASE1    I63 @BASEBOARD_FAB2_LIB.BASEBOARD_FAB2(SCH_1):PAGE202
    36 A_TSENSE_PVCCIN_CPU0 @BASEBOARD_FAB2_LIB.BASEBOARD_FAB2(SCH_1):A_TSENSE_PVCCIN_CPU0    I63 @BASEBOARD_FAB2_LIB.BASEBOARD_FAB2(SCH_1):PAGE202
     3 VR_PVCCIN_CPU0_PH1_VCIN @BASEBOARD_FAB2_LIB.BASEBOARD_FAB2(SCH_1):VR_PVCCIN_CPU0_PH1_VCIN    I63 @BASEBOARD_FAB2_LIB.BASEBOARD_FAB2(SCH_1):PAGE202
     4 P5V_STBY @BASEBOARD_FAB2_LIB.BASEBOARD_FAB2(SCH_1):P5V_STBY    I63 @BASEBOARD_FAB2_LIB.BASEBOARD_FAB2(SCH_1):PAGE202
    30 VR_FET_SW_P12V_STBY_PVCCIN_CPU0 @BASEBOARD_FAB2_LIB.BASEBOARD_FAB2(SCH_1):VR_FET_SW_P12V_STBY_PVCCIN_CPU0    I63 @BASEBOARD_FAB2_LIB.BASEBOARD_FAB2(SCH_1):PAGE202
    25 VR_FET_SW_P12V_STBY_PVCCIN_CPU0 @BASEBOARD_FAB2_LIB.BASEBOARD_FAB2(SCH_1):VR_FET_SW_P12V_STBY_PVCCIN_CPU0    I63 @BASEBOARD_FAB2_LIB.BASEBOARD_FAB2(SCH_1):PAGE202
     1 PVCCIN_CPU0 @BASEBOARD_FAB2_LIB.BASEBOARD_FAB2(SCH_1):PVCCIN_CPU0    I63 @BASEBOARD_FAB2_LIB.BASEBOARD_FAB2(SCH_1):PAGE202

EU4E2 IR354XX_SM-IR35412,IC,H73684-0A
    33 VR_PVCCIO_CPU1_PH1_BOOT_R @BASEBOARD_FAB2_LIB.BASEBOARD_FAB2(SCH_1):VR_PVCCIO_CPU1_PH1_BOOT_R   I126 @BASEBOARD_FAB2_LIB.BASEBOARD_FAB2(SCH_1):PAGE214
    35 P5V_STBY @BASEBOARD_FAB2_LIB.BASEBOARD_FAB2(SCH_1):P5V_STBY   I126 @BASEBOARD_FAB2_LIB.BASEBOARD_FAB2(SCH_1):PAGE214
    41 TP_PVCCIO_CPU1_GL_1 @BASEBOARD_FAB2_LIB.BASEBOARD_FAB2(SCH_1):TP_PVCCIO_CPU1_GL_1   I126 @BASEBOARD_FAB2_LIB.BASEBOARD_FAB2(SCH_1):PAGE214
     6 TP_PVCCIO_CPU1_GL_0 @BASEBOARD_FAB2_LIB.BASEBOARD_FAB2(SCH_1):TP_PVCCIO_CPU1_GL_0   I126 @BASEBOARD_FAB2_LIB.BASEBOARD_FAB2(SCH_1):PAGE214
    38 ISENSE_PVCCIO_CPU1_PH1_IMON @BASEBOARD_FAB2_LIB.BASEBOARD_FAB2(SCH_1):ISENSE_PVCCIO_CPU1_PH1_IMON   I126 @BASEBOARD_FAB2_LIB.BASEBOARD_FAB2(SCH_1):PAGE214
     2    GND @BASEBOARD_FAB2_LIB.BASEBOARD_FAB2(SCH_1):GND   I126 @BASEBOARD_FAB2_LIB.BASEBOARD_FAB2(SCH_1):PAGE214
    31     NC     NC   I126 @BASEBOARD_FAB2_LIB.BASEBOARD_FAB2(SCH_1):PAGE214
    37 VR_PVCCIO_CPU1_OCSET @BASEBOARD_FAB2_LIB.BASEBOARD_FAB2(SCH_1):VR_PVCCIO_CPU1_OCSET   I126 @BASEBOARD_FAB2_LIB.BASEBOARD_FAB2(SCH_1):PAGE214
    40    GND @BASEBOARD_FAB2_LIB.BASEBOARD_FAB2(SCH_1):GND   I126 @BASEBOARD_FAB2_LIB.BASEBOARD_FAB2(SCH_1):PAGE214
     7    GND @BASEBOARD_FAB2_LIB.BASEBOARD_FAB2(SCH_1):GND   I126 @BASEBOARD_FAB2_LIB.BASEBOARD_FAB2(SCH_1):PAGE214
     5    GND @BASEBOARD_FAB2_LIB.BASEBOARD_FAB2(SCH_1):GND   I126 @BASEBOARD_FAB2_LIB.BASEBOARD_FAB2(SCH_1):PAGE214
    32 VR_PVCCIO_CPU1_PH1_PHASE @BASEBOARD_FAB2_LIB.BASEBOARD_FAB2(SCH_1):VR_PVCCIO_CPU1_PH1_PHASE   I126 @BASEBOARD_FAB2_LIB.BASEBOARD_FAB2(SCH_1):PAGE214
    34 VR_PVCCIO_CPU1_PWM1 @BASEBOARD_FAB2_LIB.BASEBOARD_FAB2(SCH_1):VR_PVCCIO_CPU1_PWM1   I126 @BASEBOARD_FAB2_LIB.BASEBOARD_FAB2(SCH_1):PAGE214
    39 VR_PVCCIO_CPU1_AIREF1 @BASEBOARD_FAB2_LIB.BASEBOARD_FAB2(SCH_1):VR_PVCCIO_CPU1_AIREF1   I126 @BASEBOARD_FAB2_LIB.BASEBOARD_FAB2(SCH_1):PAGE214
    10 VR_PVCCIO_CPU1_PH1_SW @BASEBOARD_FAB2_LIB.BASEBOARD_FAB2(SCH_1):VR_PVCCIO_CPU1_PH1_SW   I126 @BASEBOARD_FAB2_LIB.BASEBOARD_FAB2(SCH_1):PAGE214
    36 A_TSENSE_PVCCIO_CPU1 @BASEBOARD_FAB2_LIB.BASEBOARD_FAB2(SCH_1):A_TSENSE_PVCCIO_CPU1   I126 @BASEBOARD_FAB2_LIB.BASEBOARD_FAB2(SCH_1):PAGE214
     3 VR_PVCCIO_CPU1_PH1_VCIN @BASEBOARD_FAB2_LIB.BASEBOARD_FAB2(SCH_1):VR_PVCCIO_CPU1_PH1_VCIN   I126 @BASEBOARD_FAB2_LIB.BASEBOARD_FAB2(SCH_1):PAGE214
     4 P5V_STBY @BASEBOARD_FAB2_LIB.BASEBOARD_FAB2(SCH_1):P5V_STBY   I126 @BASEBOARD_FAB2_LIB.BASEBOARD_FAB2(SCH_1):PAGE214
    30 VR_FET_SW_P12V_STBY_PVCCIN_CPU0 @BASEBOARD_FAB2_LIB.BASEBOARD_FAB2(SCH_1):VR_FET_SW_P12V_STBY_PVCCIN_CPU0   I126 @BASEBOARD_FAB2_LIB.BASEBOARD_FAB2(SCH_1):PAGE214
    25 VR_FET_SW_P12V_STBY_PVCCIN_CPU0 @BASEBOARD_FAB2_LIB.BASEBOARD_FAB2(SCH_1):VR_FET_SW_P12V_STBY_PVCCIN_CPU0   I126 @BASEBOARD_FAB2_LIB.BASEBOARD_FAB2(SCH_1):PAGE214
     1 PVCCIO_CPU1 @BASEBOARD_FAB2_LIB.BASEBOARD_FAB2(SCH_1):PVCCIO_CPU1   I126 @BASEBOARD_FAB2_LIB.BASEBOARD_FAB2(SCH_1):PAGE214

EU4G1 NCP3232L_SM-IC,H86355-001
     5 AGND_PVPP_GHJ @BASEBOARD_FAB2_LIB.BASEBOARD_FAB2(SCH_1):AGND_PVPP_GHJ   I225 @BASEBOARD_FAB2_LIB.BASEBOARD_FAB2(SCH_1):PAGE233
    36 VR_PVPP_GHJ_BOOT @BASEBOARD_FAB2_LIB.BASEBOARD_FAB2(SCH_1):VR_PVPP_GHJ_BOOT   I225 @BASEBOARD_FAB2_LIB.BASEBOARD_FAB2(SCH_1):PAGE233
     3 VR_COMP_PVPP_GHJ_3 @BASEBOARD_FAB2_LIB.BASEBOARD_FAB2(SCH_1):VR_COMP_PVPP_GHJ_3   I225 @BASEBOARD_FAB2_LIB.BASEBOARD_FAB2(SCH_1):PAGE233
    40 FM_PVPP_PVDDQ_CPU1_EN_GHJ @BASEBOARD_FAB2_LIB.BASEBOARD_FAB2(SCH_1):FM_PVPP_PVDDQ_CPU1_EN_GHJ   I225 @BASEBOARD_FAB2_LIB.BASEBOARD_FAB2(SCH_1):PAGE233
     2 VR_FB_PVPP_GHJ @BASEBOARD_FAB2_LIB.BASEBOARD_FAB2(SCH_1):VR_FB_PVPP_GHJ   I225 @BASEBOARD_FAB2_LIB.BASEBOARD_FAB2(SCH_1):PAGE233
    41    GND @BASEBOARD_FAB2_LIB.BASEBOARD_FAB2(SCH_1):GND   I225 @BASEBOARD_FAB2_LIB.BASEBOARD_FAB2(SCH_1):PAGE233
     4 VR_PVPP_GHJ_ISET @BASEBOARD_FAB2_LIB.BASEBOARD_FAB2(SCH_1):VR_PVPP_GHJ_ISET   I225 @BASEBOARD_FAB2_LIB.BASEBOARD_FAB2(SCH_1):PAGE233
     6 AGND_PVPP_GHJ @BASEBOARD_FAB2_LIB.BASEBOARD_FAB2(SCH_1):AGND_PVPP_GHJ   I225 @BASEBOARD_FAB2_LIB.BASEBOARD_FAB2(SCH_1):PAGE233
     7 PWRGD_PVPP_GHJ_R @BASEBOARD_FAB2_LIB.BASEBOARD_FAB2(SCH_1):PWRGD_PVPP_GHJ_R   I225 @BASEBOARD_FAB2_LIB.BASEBOARD_FAB2(SCH_1):PAGE233
    37    GND @BASEBOARD_FAB2_LIB.BASEBOARD_FAB2(SCH_1):GND   I225 @BASEBOARD_FAB2_LIB.BASEBOARD_FAB2(SCH_1):PAGE233
    28    GND @BASEBOARD_FAB2_LIB.BASEBOARD_FAB2(SCH_1):GND   I225 @BASEBOARD_FAB2_LIB.BASEBOARD_FAB2(SCH_1):PAGE233
    27    GND @BASEBOARD_FAB2_LIB.BASEBOARD_FAB2(SCH_1):GND   I225 @BASEBOARD_FAB2_LIB.BASEBOARD_FAB2(SCH_1):PAGE233
    26    GND @BASEBOARD_FAB2_LIB.BASEBOARD_FAB2(SCH_1):GND   I225 @BASEBOARD_FAB2_LIB.BASEBOARD_FAB2(SCH_1):PAGE233
    25    GND @BASEBOARD_FAB2_LIB.BASEBOARD_FAB2(SCH_1):GND   I225 @BASEBOARD_FAB2_LIB.BASEBOARD_FAB2(SCH_1):PAGE233
    24    GND @BASEBOARD_FAB2_LIB.BASEBOARD_FAB2(SCH_1):GND   I225 @BASEBOARD_FAB2_LIB.BASEBOARD_FAB2(SCH_1):PAGE233
    23    GND @BASEBOARD_FAB2_LIB.BASEBOARD_FAB2(SCH_1):GND   I225 @BASEBOARD_FAB2_LIB.BASEBOARD_FAB2(SCH_1):PAGE233
    22    GND @BASEBOARD_FAB2_LIB.BASEBOARD_FAB2(SCH_1):GND   I225 @BASEBOARD_FAB2_LIB.BASEBOARD_FAB2(SCH_1):PAGE233
    21    GND @BASEBOARD_FAB2_LIB.BASEBOARD_FAB2(SCH_1):GND   I225 @BASEBOARD_FAB2_LIB.BASEBOARD_FAB2(SCH_1):PAGE233
    20    GND @BASEBOARD_FAB2_LIB.BASEBOARD_FAB2(SCH_1):GND   I225 @BASEBOARD_FAB2_LIB.BASEBOARD_FAB2(SCH_1):PAGE233
    19    GND @BASEBOARD_FAB2_LIB.BASEBOARD_FAB2(SCH_1):GND   I225 @BASEBOARD_FAB2_LIB.BASEBOARD_FAB2(SCH_1):PAGE233
    18    GND @BASEBOARD_FAB2_LIB.BASEBOARD_FAB2(SCH_1):GND   I225 @BASEBOARD_FAB2_LIB.BASEBOARD_FAB2(SCH_1):PAGE233
    17    GND @BASEBOARD_FAB2_LIB.BASEBOARD_FAB2(SCH_1):GND   I225 @BASEBOARD_FAB2_LIB.BASEBOARD_FAB2(SCH_1):PAGE233
    16    GND @BASEBOARD_FAB2_LIB.BASEBOARD_FAB2(SCH_1):GND   I225 @BASEBOARD_FAB2_LIB.BASEBOARD_FAB2(SCH_1):PAGE233
     1 VR_PVPP_GHJ_SS @BASEBOARD_FAB2_LIB.BASEBOARD_FAB2(SCH_1):VR_PVPP_GHJ_SS   I225 @BASEBOARD_FAB2_LIB.BASEBOARD_FAB2(SCH_1):PAGE233
    38 VR_VB_PVPP_GHJ @BASEBOARD_FAB2_LIB.BASEBOARD_FAB2(SCH_1):VR_VB_PVPP_GHJ   I225 @BASEBOARD_FAB2_LIB.BASEBOARD_FAB2(SCH_1):PAGE233
    39 VR_FET_SW_P12V_STBY_PVPP_GHJ @BASEBOARD_FAB2_LIB.BASEBOARD_FAB2(SCH_1):VR_FET_SW_P12V_STBY_PVPP_GHJ   I225 @BASEBOARD_FAB2_LIB.BASEBOARD_FAB2(SCH_1):PAGE233
    42 VR_FET_SW_P12V_STBY_PVPP_GHJ @BASEBOARD_FAB2_LIB.BASEBOARD_FAB2(SCH_1):VR_FET_SW_P12V_STBY_PVPP_GHJ   I225 @BASEBOARD_FAB2_LIB.BASEBOARD_FAB2(SCH_1):PAGE233
    14 VR_FET_SW_P12V_STBY_PVPP_GHJ @BASEBOARD_FAB2_LIB.BASEBOARD_FAB2(SCH_1):VR_FET_SW_P12V_STBY_PVPP_GHJ   I225 @BASEBOARD_FAB2_LIB.BASEBOARD_FAB2(SCH_1):PAGE233
    13 VR_FET_SW_P12V_STBY_PVPP_GHJ @BASEBOARD_FAB2_LIB.BASEBOARD_FAB2(SCH_1):VR_FET_SW_P12V_STBY_PVPP_GHJ   I225 @BASEBOARD_FAB2_LIB.BASEBOARD_FAB2(SCH_1):PAGE233
    12 VR_FET_SW_P12V_STBY_PVPP_GHJ @BASEBOARD_FAB2_LIB.BASEBOARD_FAB2(SCH_1):VR_FET_SW_P12V_STBY_PVPP_GHJ   I225 @BASEBOARD_FAB2_LIB.BASEBOARD_FAB2(SCH_1):PAGE233
    11 VR_FET_SW_P12V_STBY_PVPP_GHJ @BASEBOARD_FAB2_LIB.BASEBOARD_FAB2(SCH_1):VR_FET_SW_P12V_STBY_PVPP_GHJ   I225 @BASEBOARD_FAB2_LIB.BASEBOARD_FAB2(SCH_1):PAGE233
    10 VR_FET_SW_P12V_STBY_PVPP_GHJ @BASEBOARD_FAB2_LIB.BASEBOARD_FAB2(SCH_1):VR_FET_SW_P12V_STBY_PVPP_GHJ   I225 @BASEBOARD_FAB2_LIB.BASEBOARD_FAB2(SCH_1):PAGE233
     9 VR_FET_SW_P12V_STBY_PVPP_GHJ @BASEBOARD_FAB2_LIB.BASEBOARD_FAB2(SCH_1):VR_FET_SW_P12V_STBY_PVPP_GHJ   I225 @BASEBOARD_FAB2_LIB.BASEBOARD_FAB2(SCH_1):PAGE233
     8 VR_FET_SW_P12V_STBY_PVPP_GHJ @BASEBOARD_FAB2_LIB.BASEBOARD_FAB2(SCH_1):VR_FET_SW_P12V_STBY_PVPP_GHJ   I225 @BASEBOARD_FAB2_LIB.BASEBOARD_FAB2(SCH_1):PAGE233
    35 VR_PVPP_GHJ_PHASE @BASEBOARD_FAB2_LIB.BASEBOARD_FAB2(SCH_1):VR_PVPP_GHJ_PHASE   I225 @BASEBOARD_FAB2_LIB.BASEBOARD_FAB2(SCH_1):PAGE233
    43 VR_PVPP_GHJ_PHASE @BASEBOARD_FAB2_LIB.BASEBOARD_FAB2(SCH_1):VR_PVPP_GHJ_PHASE   I225 @BASEBOARD_FAB2_LIB.BASEBOARD_FAB2(SCH_1):PAGE233
    34 VR_PVPP_GHJ_PHASE @BASEBOARD_FAB2_LIB.BASEBOARD_FAB2(SCH_1):VR_PVPP_GHJ_PHASE   I225 @BASEBOARD_FAB2_LIB.BASEBOARD_FAB2(SCH_1):PAGE233
    33 VR_PVPP_GHJ_PHASE @BASEBOARD_FAB2_LIB.BASEBOARD_FAB2(SCH_1):VR_PVPP_GHJ_PHASE   I225 @BASEBOARD_FAB2_LIB.BASEBOARD_FAB2(SCH_1):PAGE233
    32 VR_PVPP_GHJ_PHASE @BASEBOARD_FAB2_LIB.BASEBOARD_FAB2(SCH_1):VR_PVPP_GHJ_PHASE   I225 @BASEBOARD_FAB2_LIB.BASEBOARD_FAB2(SCH_1):PAGE233
    31 VR_PVPP_GHJ_PHASE @BASEBOARD_FAB2_LIB.BASEBOARD_FAB2(SCH_1):VR_PVPP_GHJ_PHASE   I225 @BASEBOARD_FAB2_LIB.BASEBOARD_FAB2(SCH_1):PAGE233
    30 VR_PVPP_GHJ_PHASE @BASEBOARD_FAB2_LIB.BASEBOARD_FAB2(SCH_1):VR_PVPP_GHJ_PHASE   I225 @BASEBOARD_FAB2_LIB.BASEBOARD_FAB2(SCH_1):PAGE233
    29 VR_PVPP_GHJ_PHASE @BASEBOARD_FAB2_LIB.BASEBOARD_FAB2(SCH_1):VR_PVPP_GHJ_PHASE   I225 @BASEBOARD_FAB2_LIB.BASEBOARD_FAB2(SCH_1):PAGE233
    15 VR_PVPP_GHJ_PHASE @BASEBOARD_FAB2_LIB.BASEBOARD_FAB2(SCH_1):VR_PVPP_GHJ_PHASE   I225 @BASEBOARD_FAB2_LIB.BASEBOARD_FAB2(SCH_1):PAGE233

EU4G2 MIC5166_DFN-IC,H55101-001
     7 FM_PVTT_GHJ_EN_R @BASEBOARD_FAB2_LIB.BASEBOARD_FAB2(SCH_1):FM_PVTT_GHJ_EN_R    I37 @BASEBOARD_FAB2_LIB.BASEBOARD_FAB2(SCH_1):PAGE229
    10 PVDDQ_GHJ @BASEBOARD_FAB2_LIB.BASEBOARD_FAB2(SCH_1):PVDDQ_GHJ    I37 @BASEBOARD_FAB2_LIB.BASEBOARD_FAB2(SCH_1):PAGE229
     1 VR_PVTT_GHJ_VREF @BASEBOARD_FAB2_LIB.BASEBOARD_FAB2(SCH_1):VR_PVTT_GHJ_VREF    I37 @BASEBOARD_FAB2_LIB.BASEBOARD_FAB2(SCH_1):PAGE229
     2 VR_PVTT_GHJ_BIAS @BASEBOARD_FAB2_LIB.BASEBOARD_FAB2(SCH_1):VR_PVTT_GHJ_BIAS    I37 @BASEBOARD_FAB2_LIB.BASEBOARD_FAB2(SCH_1):PAGE229
     3    GND @BASEBOARD_FAB2_LIB.BASEBOARD_FAB2(SCH_1):GND    I37 @BASEBOARD_FAB2_LIB.BASEBOARD_FAB2(SCH_1):PAGE229
     5 PWRGD_PVTT_GHJ_CPU1_R @BASEBOARD_FAB2_LIB.BASEBOARD_FAB2(SCH_1):PWRGD_PVTT_GHJ_CPU1_R    I37 @BASEBOARD_FAB2_LIB.BASEBOARD_FAB2(SCH_1):PAGE229
     4 VSENSE_PVDDQ_GHJ_VTT @BASEBOARD_FAB2_LIB.BASEBOARD_FAB2(SCH_1):VSENSE_PVDDQ_GHJ_VTT    I37 @BASEBOARD_FAB2_LIB.BASEBOARD_FAB2(SCH_1):PAGE229
     6 VR_PVTT_GHJ_SNS @BASEBOARD_FAB2_LIB.BASEBOARD_FAB2(SCH_1):VR_PVTT_GHJ_SNS    I37 @BASEBOARD_FAB2_LIB.BASEBOARD_FAB2(SCH_1):PAGE229
     8    GND @BASEBOARD_FAB2_LIB.BASEBOARD_FAB2(SCH_1):GND    I37 @BASEBOARD_FAB2_LIB.BASEBOARD_FAB2(SCH_1):PAGE229
     9 PVTT_GHJ @BASEBOARD_FAB2_LIB.BASEBOARD_FAB2(SCH_1):PVTT_GHJ    I37 @BASEBOARD_FAB2_LIB.BASEBOARD_FAB2(SCH_1):PAGE229
    11    GND @BASEBOARD_FAB2_LIB.BASEBOARD_FAB2(SCH_1):GND    I37 @BASEBOARD_FAB2_LIB.BASEBOARD_FAB2(SCH_1):PAGE229

EU4G3 MIC5166_DFN-IC,H55101-001
     7 FM_PVTT_ABC_EN_R @BASEBOARD_FAB2_LIB.BASEBOARD_FAB2(SCH_1):FM_PVTT_ABC_EN_R    I15 @BASEBOARD_FAB2_LIB.BASEBOARD_FAB2(SCH_1):PAGE221
    10 PVDDQ_ABC @BASEBOARD_FAB2_LIB.BASEBOARD_FAB2(SCH_1):PVDDQ_ABC    I15 @BASEBOARD_FAB2_LIB.BASEBOARD_FAB2(SCH_1):PAGE221
     1 VR_PVTT_ABC_VREF @BASEBOARD_FAB2_LIB.BASEBOARD_FAB2(SCH_1):VR_PVTT_ABC_VREF    I15 @BASEBOARD_FAB2_LIB.BASEBOARD_FAB2(SCH_1):PAGE221
     2 VR_PVTT_ABC_BIAS @BASEBOARD_FAB2_LIB.BASEBOARD_FAB2(SCH_1):VR_PVTT_ABC_BIAS    I15 @BASEBOARD_FAB2_LIB.BASEBOARD_FAB2(SCH_1):PAGE221
     3    GND @BASEBOARD_FAB2_LIB.BASEBOARD_FAB2(SCH_1):GND    I15 @BASEBOARD_FAB2_LIB.BASEBOARD_FAB2(SCH_1):PAGE221
     5 PWRGD_PVTT_ABC_CPU0_R @BASEBOARD_FAB2_LIB.BASEBOARD_FAB2(SCH_1):PWRGD_PVTT_ABC_CPU0_R    I15 @BASEBOARD_FAB2_LIB.BASEBOARD_FAB2(SCH_1):PAGE221
     4 VSENSE_PVDDQ_ABC_VTT @BASEBOARD_FAB2_LIB.BASEBOARD_FAB2(SCH_1):VSENSE_PVDDQ_ABC_VTT    I15 @BASEBOARD_FAB2_LIB.BASEBOARD_FAB2(SCH_1):PAGE221
     6 VR_PVTT_ABC_SNS @BASEBOARD_FAB2_LIB.BASEBOARD_FAB2(SCH_1):VR_PVTT_ABC_SNS    I15 @BASEBOARD_FAB2_LIB.BASEBOARD_FAB2(SCH_1):PAGE221
     8    GND @BASEBOARD_FAB2_LIB.BASEBOARD_FAB2(SCH_1):GND    I15 @BASEBOARD_FAB2_LIB.BASEBOARD_FAB2(SCH_1):PAGE221
     9 PVTT_ABC @BASEBOARD_FAB2_LIB.BASEBOARD_FAB2(SCH_1):PVTT_ABC    I15 @BASEBOARD_FAB2_LIB.BASEBOARD_FAB2(SCH_1):PAGE221
    11    GND @BASEBOARD_FAB2_LIB.BASEBOARD_FAB2(SCH_1):GND    I15 @BASEBOARD_FAB2_LIB.BASEBOARD_FAB2(SCH_1):PAGE221

EU7A1 IR354XX_SM-IR35411,IC,H73688-0A
    33 VR_PVDDQ_DEF_PH1_BOOT_R @BASEBOARD_FAB2_LIB.BASEBOARD_FAB2(SCH_1):VR_PVDDQ_DEF_PH1_BOOT_R   I106 @BASEBOARD_FAB2_LIB.BASEBOARD_FAB2(SCH_1):PAGE219
    35 P5V_STBY @BASEBOARD_FAB2_LIB.BASEBOARD_FAB2(SCH_1):P5V_STBY   I106 @BASEBOARD_FAB2_LIB.BASEBOARD_FAB2(SCH_1):PAGE219
    41 TP_PVDDQ_DEF_PH1_GL_1 @BASEBOARD_FAB2_LIB.BASEBOARD_FAB2(SCH_1):TP_PVDDQ_DEF_PH1_GL_1   I106 @BASEBOARD_FAB2_LIB.BASEBOARD_FAB2(SCH_1):PAGE219
     6 TP_PVDDQ_DEF_PH1_GL_0 @BASEBOARD_FAB2_LIB.BASEBOARD_FAB2(SCH_1):TP_PVDDQ_DEF_PH1_GL_0   I106 @BASEBOARD_FAB2_LIB.BASEBOARD_FAB2(SCH_1):PAGE219
    38 ISENSE_PVDDQ_DEF_PH1_IMON @BASEBOARD_FAB2_LIB.BASEBOARD_FAB2(SCH_1):ISENSE_PVDDQ_DEF_PH1_IMON   I106 @BASEBOARD_FAB2_LIB.BASEBOARD_FAB2(SCH_1):PAGE219
     2    GND @BASEBOARD_FAB2_LIB.BASEBOARD_FAB2(SCH_1):GND   I106 @BASEBOARD_FAB2_LIB.BASEBOARD_FAB2(SCH_1):PAGE219
    31     NC     NC   I106 @BASEBOARD_FAB2_LIB.BASEBOARD_FAB2(SCH_1):PAGE219
    37 VR_PVDDQ_DEF_PH1_OCSET @BASEBOARD_FAB2_LIB.BASEBOARD_FAB2(SCH_1):VR_PVDDQ_DEF_PH1_OCSET   I106 @BASEBOARD_FAB2_LIB.BASEBOARD_FAB2(SCH_1):PAGE219
    40    GND @BASEBOARD_FAB2_LIB.BASEBOARD_FAB2(SCH_1):GND   I106 @BASEBOARD_FAB2_LIB.BASEBOARD_FAB2(SCH_1):PAGE219
     7    GND @BASEBOARD_FAB2_LIB.BASEBOARD_FAB2(SCH_1):GND   I106 @BASEBOARD_FAB2_LIB.BASEBOARD_FAB2(SCH_1):PAGE219
     5    GND @BASEBOARD_FAB2_LIB.BASEBOARD_FAB2(SCH_1):GND   I106 @BASEBOARD_FAB2_LIB.BASEBOARD_FAB2(SCH_1):PAGE219
    32 VR_PVDDQ_DEF_PH1_PHASE @BASEBOARD_FAB2_LIB.BASEBOARD_FAB2(SCH_1):VR_PVDDQ_DEF_PH1_PHASE   I106 @BASEBOARD_FAB2_LIB.BASEBOARD_FAB2(SCH_1):PAGE219
    34 VR_PVDDQ_DEF_PWM1 @BASEBOARD_FAB2_LIB.BASEBOARD_FAB2(SCH_1):VR_PVDDQ_DEF_PWM1   I106 @BASEBOARD_FAB2_LIB.BASEBOARD_FAB2(SCH_1):PAGE219
    39 VR_PVDDQ_DEF_AIREF1 @BASEBOARD_FAB2_LIB.BASEBOARD_FAB2(SCH_1):VR_PVDDQ_DEF_AIREF1   I106 @BASEBOARD_FAB2_LIB.BASEBOARD_FAB2(SCH_1):PAGE219
    10 VR_PVDDQ_DEF_PH1_SW @BASEBOARD_FAB2_LIB.BASEBOARD_FAB2(SCH_1):VR_PVDDQ_DEF_PH1_SW   I106 @BASEBOARD_FAB2_LIB.BASEBOARD_FAB2(SCH_1):PAGE219
    36 A_TSENSE_PVDDQ_DEF @BASEBOARD_FAB2_LIB.BASEBOARD_FAB2(SCH_1):A_TSENSE_PVDDQ_DEF   I106 @BASEBOARD_FAB2_LIB.BASEBOARD_FAB2(SCH_1):PAGE219
     3 VR_PVDDQ_DEF_PH1_VCIN @BASEBOARD_FAB2_LIB.BASEBOARD_FAB2(SCH_1):VR_PVDDQ_DEF_PH1_VCIN   I106 @BASEBOARD_FAB2_LIB.BASEBOARD_FAB2(SCH_1):PAGE219
     4 P5V_STBY @BASEBOARD_FAB2_LIB.BASEBOARD_FAB2(SCH_1):P5V_STBY   I106 @BASEBOARD_FAB2_LIB.BASEBOARD_FAB2(SCH_1):PAGE219
    30 VR_FET_SW_P12V_STBY_PVDDQ_DEF @BASEBOARD_FAB2_LIB.BASEBOARD_FAB2(SCH_1):VR_FET_SW_P12V_STBY_PVDDQ_DEF   I106 @BASEBOARD_FAB2_LIB.BASEBOARD_FAB2(SCH_1):PAGE219
    25 VR_FET_SW_P12V_STBY_PVDDQ_DEF @BASEBOARD_FAB2_LIB.BASEBOARD_FAB2(SCH_1):VR_FET_SW_P12V_STBY_PVDDQ_DEF   I106 @BASEBOARD_FAB2_LIB.BASEBOARD_FAB2(SCH_1):PAGE219
     1 PVDDQ_DEF @BASEBOARD_FAB2_LIB.BASEBOARD_FAB2(SCH_1):PVDDQ_DEF   I106 @BASEBOARD_FAB2_LIB.BASEBOARD_FAB2(SCH_1):PAGE219

EU7A2 IR354XX_SM-IR35412,IC,H73684-0A
    33 VR_P1V05_PCH_STBY_PH1_BOOT_R @BASEBOARD_FAB2_LIB.BASEBOARD_FAB2(SCH_1):VR_P1V05_PCH_STBY_PH1_BOOT_R   I117 @BASEBOARD_FAB2_LIB.BASEBOARD_FAB2(SCH_1):PAGE236
    35 P5V_STBY @BASEBOARD_FAB2_LIB.BASEBOARD_FAB2(SCH_1):P5V_STBY   I117 @BASEBOARD_FAB2_LIB.BASEBOARD_FAB2(SCH_1):PAGE236
    41 TP_P1V05_PCH_GL_1 @BASEBOARD_FAB2_LIB.BASEBOARD_FAB2(SCH_1):TP_P1V05_PCH_GL_1   I117 @BASEBOARD_FAB2_LIB.BASEBOARD_FAB2(SCH_1):PAGE236
     6 TP_P1V05_PCH_GL_0 @BASEBOARD_FAB2_LIB.BASEBOARD_FAB2(SCH_1):TP_P1V05_PCH_GL_0   I117 @BASEBOARD_FAB2_LIB.BASEBOARD_FAB2(SCH_1):PAGE236
    38 ISENSE_P1V05_PCH_STBY_PH1_IMON @BASEBOARD_FAB2_LIB.BASEBOARD_FAB2(SCH_1):ISENSE_P1V05_PCH_STBY_PH1_IMON   I117 @BASEBOARD_FAB2_LIB.BASEBOARD_FAB2(SCH_1):PAGE236
     2    GND @BASEBOARD_FAB2_LIB.BASEBOARD_FAB2(SCH_1):GND   I117 @BASEBOARD_FAB2_LIB.BASEBOARD_FAB2(SCH_1):PAGE236
    31     NC     NC   I117 @BASEBOARD_FAB2_LIB.BASEBOARD_FAB2(SCH_1):PAGE236
    37 VR_P1V05_PCH_STBY_OCSET @BASEBOARD_FAB2_LIB.BASEBOARD_FAB2(SCH_1):VR_P1V05_PCH_STBY_OCSET   I117 @BASEBOARD_FAB2_LIB.BASEBOARD_FAB2(SCH_1):PAGE236
    40    GND @BASEBOARD_FAB2_LIB.BASEBOARD_FAB2(SCH_1):GND   I117 @BASEBOARD_FAB2_LIB.BASEBOARD_FAB2(SCH_1):PAGE236
     7    GND @BASEBOARD_FAB2_LIB.BASEBOARD_FAB2(SCH_1):GND   I117 @BASEBOARD_FAB2_LIB.BASEBOARD_FAB2(SCH_1):PAGE236
     5    GND @BASEBOARD_FAB2_LIB.BASEBOARD_FAB2(SCH_1):GND   I117 @BASEBOARD_FAB2_LIB.BASEBOARD_FAB2(SCH_1):PAGE236
    32 VR_P1V05_PCH_STBY_PH1_PHASE @BASEBOARD_FAB2_LIB.BASEBOARD_FAB2(SCH_1):VR_P1V05_PCH_STBY_PH1_PHASE   I117 @BASEBOARD_FAB2_LIB.BASEBOARD_FAB2(SCH_1):PAGE236
    34 VR_P1V05_PCH_STBY_PWM1 @BASEBOARD_FAB2_LIB.BASEBOARD_FAB2(SCH_1):VR_P1V05_PCH_STBY_PWM1   I117 @BASEBOARD_FAB2_LIB.BASEBOARD_FAB2(SCH_1):PAGE236
    39 VR_P1V05_PCH_BIREF1 @BASEBOARD_FAB2_LIB.BASEBOARD_FAB2(SCH_1):VR_P1V05_PCH_BIREF1   I117 @BASEBOARD_FAB2_LIB.BASEBOARD_FAB2(SCH_1):PAGE236
    10 VR_P1V05_PCH_STBY_PH1_PHASE_SW @BASEBOARD_FAB2_LIB.BASEBOARD_FAB2(SCH_1):VR_P1V05_PCH_STBY_PH1_PHASE_SW   I117 @BASEBOARD_FAB2_LIB.BASEBOARD_FAB2(SCH_1):PAGE236
    36 A_TSENSE_P1V05_PCH_STBY_TMON @BASEBOARD_FAB2_LIB.BASEBOARD_FAB2(SCH_1):A_TSENSE_P1V05_PCH_STBY_TMON   I117 @BASEBOARD_FAB2_LIB.BASEBOARD_FAB2(SCH_1):PAGE236
     3 VR_P1V05_PCH_STBY_PH1_VCIN @BASEBOARD_FAB2_LIB.BASEBOARD_FAB2(SCH_1):VR_P1V05_PCH_STBY_PH1_VCIN   I117 @BASEBOARD_FAB2_LIB.BASEBOARD_FAB2(SCH_1):PAGE236
     4 P5V_STBY @BASEBOARD_FAB2_LIB.BASEBOARD_FAB2(SCH_1):P5V_STBY   I117 @BASEBOARD_FAB2_LIB.BASEBOARD_FAB2(SCH_1):PAGE236
    30 VR_FET_SW_P12V_STBY_PVDDQ_DEF @BASEBOARD_FAB2_LIB.BASEBOARD_FAB2(SCH_1):VR_FET_SW_P12V_STBY_PVDDQ_DEF   I117 @BASEBOARD_FAB2_LIB.BASEBOARD_FAB2(SCH_1):PAGE236
    25 VR_FET_SW_P12V_STBY_PVDDQ_DEF @BASEBOARD_FAB2_LIB.BASEBOARD_FAB2(SCH_1):VR_FET_SW_P12V_STBY_PVDDQ_DEF   I117 @BASEBOARD_FAB2_LIB.BASEBOARD_FAB2(SCH_1):PAGE236
     1 P1V05_PCH_STBY @BASEBOARD_FAB2_LIB.BASEBOARD_FAB2(SCH_1):P1V05_PCH_STBY   I117 @BASEBOARD_FAB2_LIB.BASEBOARD_FAB2(SCH_1):PAGE236

EU7A3 IR354XX_SM-IR35412,IC,H73684-0A
    33 VR_PVNN_PCH_PH1_BOOT_R @BASEBOARD_FAB2_LIB.BASEBOARD_FAB2(SCH_1):VR_PVNN_PCH_PH1_BOOT_R   I116 @BASEBOARD_FAB2_LIB.BASEBOARD_FAB2(SCH_1):PAGE236
    35 P5V_STBY @BASEBOARD_FAB2_LIB.BASEBOARD_FAB2(SCH_1):P5V_STBY   I116 @BASEBOARD_FAB2_LIB.BASEBOARD_FAB2(SCH_1):PAGE236
    41 TP_PVNN_PCH_GL_1 @BASEBOARD_FAB2_LIB.BASEBOARD_FAB2(SCH_1):TP_PVNN_PCH_GL_1   I116 @BASEBOARD_FAB2_LIB.BASEBOARD_FAB2(SCH_1):PAGE236
     6 TP_PVNN_PCH_GL_0 @BASEBOARD_FAB2_LIB.BASEBOARD_FAB2(SCH_1):TP_PVNN_PCH_GL_0   I116 @BASEBOARD_FAB2_LIB.BASEBOARD_FAB2(SCH_1):PAGE236
    38 ISENSE_PVNN_PCH_PH1_IMON @BASEBOARD_FAB2_LIB.BASEBOARD_FAB2(SCH_1):ISENSE_PVNN_PCH_PH1_IMON   I116 @BASEBOARD_FAB2_LIB.BASEBOARD_FAB2(SCH_1):PAGE236
     2    GND @BASEBOARD_FAB2_LIB.BASEBOARD_FAB2(SCH_1):GND   I116 @BASEBOARD_FAB2_LIB.BASEBOARD_FAB2(SCH_1):PAGE236
    31     NC     NC   I116 @BASEBOARD_FAB2_LIB.BASEBOARD_FAB2(SCH_1):PAGE236
    37 VR_PVNN_PCH_STBY_OCSET @BASEBOARD_FAB2_LIB.BASEBOARD_FAB2(SCH_1):VR_PVNN_PCH_STBY_OCSET   I116 @BASEBOARD_FAB2_LIB.BASEBOARD_FAB2(SCH_1):PAGE236
    40    GND @BASEBOARD_FAB2_LIB.BASEBOARD_FAB2(SCH_1):GND   I116 @BASEBOARD_FAB2_LIB.BASEBOARD_FAB2(SCH_1):PAGE236
     7    GND @BASEBOARD_FAB2_LIB.BASEBOARD_FAB2(SCH_1):GND   I116 @BASEBOARD_FAB2_LIB.BASEBOARD_FAB2(SCH_1):PAGE236
     5    GND @BASEBOARD_FAB2_LIB.BASEBOARD_FAB2(SCH_1):GND   I116 @BASEBOARD_FAB2_LIB.BASEBOARD_FAB2(SCH_1):PAGE236
    32 VR_PVNN_PCH_PH1_PHASE @BASEBOARD_FAB2_LIB.BASEBOARD_FAB2(SCH_1):VR_PVNN_PCH_PH1_PHASE   I116 @BASEBOARD_FAB2_LIB.BASEBOARD_FAB2(SCH_1):PAGE236
    34 VR_PVNN_PCH_PWM1 @BASEBOARD_FAB2_LIB.BASEBOARD_FAB2(SCH_1):VR_PVNN_PCH_PWM1   I116 @BASEBOARD_FAB2_LIB.BASEBOARD_FAB2(SCH_1):PAGE236
    39 VR_PVNN_PCH_AIREF1 @BASEBOARD_FAB2_LIB.BASEBOARD_FAB2(SCH_1):VR_PVNN_PCH_AIREF1   I116 @BASEBOARD_FAB2_LIB.BASEBOARD_FAB2(SCH_1):PAGE236
    10 VR_PVNN_PCH_PH1_PHASE_SW @BASEBOARD_FAB2_LIB.BASEBOARD_FAB2(SCH_1):VR_PVNN_PCH_PH1_PHASE_SW   I116 @BASEBOARD_FAB2_LIB.BASEBOARD_FAB2(SCH_1):PAGE236
    36 A_TSENSE_PVNN_PCH_TMON @BASEBOARD_FAB2_LIB.BASEBOARD_FAB2(SCH_1):A_TSENSE_PVNN_PCH_TMON   I116 @BASEBOARD_FAB2_LIB.BASEBOARD_FAB2(SCH_1):PAGE236
     3 VR_PVNN_PCH_PH1_VCIN @BASEBOARD_FAB2_LIB.BASEBOARD_FAB2(SCH_1):VR_PVNN_PCH_PH1_VCIN   I116 @BASEBOARD_FAB2_LIB.BASEBOARD_FAB2(SCH_1):PAGE236
     4 P5V_STBY @BASEBOARD_FAB2_LIB.BASEBOARD_FAB2(SCH_1):P5V_STBY   I116 @BASEBOARD_FAB2_LIB.BASEBOARD_FAB2(SCH_1):PAGE236
    30 VR_FET_SW_P12V_STBY_PVDDQ_DEF @BASEBOARD_FAB2_LIB.BASEBOARD_FAB2(SCH_1):VR_FET_SW_P12V_STBY_PVDDQ_DEF   I116 @BASEBOARD_FAB2_LIB.BASEBOARD_FAB2(SCH_1):PAGE236
    25 VR_FET_SW_P12V_STBY_PVDDQ_DEF @BASEBOARD_FAB2_LIB.BASEBOARD_FAB2(SCH_1):VR_FET_SW_P12V_STBY_PVDDQ_DEF   I116 @BASEBOARD_FAB2_LIB.BASEBOARD_FAB2(SCH_1):PAGE236
     1 PVNN_PCH_STBY @BASEBOARD_FAB2_LIB.BASEBOARD_FAB2(SCH_1):PVNN_PCH_STBY   I116 @BASEBOARD_FAB2_LIB.BASEBOARD_FAB2(SCH_1):PAGE236

EU7A4 IR354XX_SM-IR35411,IC,H73688-0A
    33 VR_PVDDQ_DEF_PH2_BOOT_R @BASEBOARD_FAB2_LIB.BASEBOARD_FAB2(SCH_1):VR_PVDDQ_DEF_PH2_BOOT_R   I107 @BASEBOARD_FAB2_LIB.BASEBOARD_FAB2(SCH_1):PAGE219
    35 P5V_STBY @BASEBOARD_FAB2_LIB.BASEBOARD_FAB2(SCH_1):P5V_STBY   I107 @BASEBOARD_FAB2_LIB.BASEBOARD_FAB2(SCH_1):PAGE219
    41 TP_PVDDQ_DEF_PH2_GL_1 @BASEBOARD_FAB2_LIB.BASEBOARD_FAB2(SCH_1):TP_PVDDQ_DEF_PH2_GL_1   I107 @BASEBOARD_FAB2_LIB.BASEBOARD_FAB2(SCH_1):PAGE219
     6 TP_PVDDQ_DEF_PH2_GL_0 @BASEBOARD_FAB2_LIB.BASEBOARD_FAB2(SCH_1):TP_PVDDQ_DEF_PH2_GL_0   I107 @BASEBOARD_FAB2_LIB.BASEBOARD_FAB2(SCH_1):PAGE219
    38 ISENSE_PVDDQ_DEF_PH2_IMON @BASEBOARD_FAB2_LIB.BASEBOARD_FAB2(SCH_1):ISENSE_PVDDQ_DEF_PH2_IMON   I107 @BASEBOARD_FAB2_LIB.BASEBOARD_FAB2(SCH_1):PAGE219
     2    GND @BASEBOARD_FAB2_LIB.BASEBOARD_FAB2(SCH_1):GND   I107 @BASEBOARD_FAB2_LIB.BASEBOARD_FAB2(SCH_1):PAGE219
    31     NC     NC   I107 @BASEBOARD_FAB2_LIB.BASEBOARD_FAB2(SCH_1):PAGE219
    37 VR_PVDDQ_DEF_PH2_OCSET @BASEBOARD_FAB2_LIB.BASEBOARD_FAB2(SCH_1):VR_PVDDQ_DEF_PH2_OCSET   I107 @BASEBOARD_FAB2_LIB.BASEBOARD_FAB2(SCH_1):PAGE219
    40    GND @BASEBOARD_FAB2_LIB.BASEBOARD_FAB2(SCH_1):GND   I107 @BASEBOARD_FAB2_LIB.BASEBOARD_FAB2(SCH_1):PAGE219
     7    GND @BASEBOARD_FAB2_LIB.BASEBOARD_FAB2(SCH_1):GND   I107 @BASEBOARD_FAB2_LIB.BASEBOARD_FAB2(SCH_1):PAGE219
     5    GND @BASEBOARD_FAB2_LIB.BASEBOARD_FAB2(SCH_1):GND   I107 @BASEBOARD_FAB2_LIB.BASEBOARD_FAB2(SCH_1):PAGE219
    32 VR_PVDDQ_DEF_PH2_PHASE @BASEBOARD_FAB2_LIB.BASEBOARD_FAB2(SCH_1):VR_PVDDQ_DEF_PH2_PHASE   I107 @BASEBOARD_FAB2_LIB.BASEBOARD_FAB2(SCH_1):PAGE219
    34 VR_PVDDQ_DEF_PWM2 @BASEBOARD_FAB2_LIB.BASEBOARD_FAB2(SCH_1):VR_PVDDQ_DEF_PWM2   I107 @BASEBOARD_FAB2_LIB.BASEBOARD_FAB2(SCH_1):PAGE219
    39 VR_PVDDQ_DEF_AIREF2 @BASEBOARD_FAB2_LIB.BASEBOARD_FAB2(SCH_1):VR_PVDDQ_DEF_AIREF2   I107 @BASEBOARD_FAB2_LIB.BASEBOARD_FAB2(SCH_1):PAGE219
    10 VR_PVDDQ_DEF_PH2_SW @BASEBOARD_FAB2_LIB.BASEBOARD_FAB2(SCH_1):VR_PVDDQ_DEF_PH2_SW   I107 @BASEBOARD_FAB2_LIB.BASEBOARD_FAB2(SCH_1):PAGE219
    36 A_TSENSE_PVDDQ_DEF @BASEBOARD_FAB2_LIB.BASEBOARD_FAB2(SCH_1):A_TSENSE_PVDDQ_DEF   I107 @BASEBOARD_FAB2_LIB.BASEBOARD_FAB2(SCH_1):PAGE219
     3 VR_PVDDQ_DEF_PH2_VCIN @BASEBOARD_FAB2_LIB.BASEBOARD_FAB2(SCH_1):VR_PVDDQ_DEF_PH2_VCIN   I107 @BASEBOARD_FAB2_LIB.BASEBOARD_FAB2(SCH_1):PAGE219
     4 P5V_STBY @BASEBOARD_FAB2_LIB.BASEBOARD_FAB2(SCH_1):P5V_STBY   I107 @BASEBOARD_FAB2_LIB.BASEBOARD_FAB2(SCH_1):PAGE219
    30 VR_FET_SW_P12V_STBY_PVDDQ_DEF @BASEBOARD_FAB2_LIB.BASEBOARD_FAB2(SCH_1):VR_FET_SW_P12V_STBY_PVDDQ_DEF   I107 @BASEBOARD_FAB2_LIB.BASEBOARD_FAB2(SCH_1):PAGE219
    25 VR_FET_SW_P12V_STBY_PVDDQ_DEF @BASEBOARD_FAB2_LIB.BASEBOARD_FAB2(SCH_1):VR_FET_SW_P12V_STBY_PVDDQ_DEF   I107 @BASEBOARD_FAB2_LIB.BASEBOARD_FAB2(SCH_1):PAGE219
     1 PVDDQ_DEF @BASEBOARD_FAB2_LIB.BASEBOARD_FAB2(SCH_1):PVDDQ_DEF   I107 @BASEBOARD_FAB2_LIB.BASEBOARD_FAB2(SCH_1):PAGE219

EU7A5 PXM1310B_QFN-IC,H89186-001
     1     NC     NC    I69 @BASEBOARD_FAB2_LIB.BASEBOARD_FAB2(SCH_1):PAGE218
     2     NC     NC    I69 @BASEBOARD_FAB2_LIB.BASEBOARD_FAB2(SCH_1):PAGE218
     3     NC     NC    I69 @BASEBOARD_FAB2_LIB.BASEBOARD_FAB2(SCH_1):PAGE218
     4 VR_PVDDQ_DEF_PWM2 @BASEBOARD_FAB2_LIB.BASEBOARD_FAB2(SCH_1):VR_PVDDQ_DEF_PWM2    I69 @BASEBOARD_FAB2_LIB.BASEBOARD_FAB2(SCH_1):PAGE218
     5 VR_PVDDQ_DEF_PWM1 @BASEBOARD_FAB2_LIB.BASEBOARD_FAB2(SCH_1):VR_PVDDQ_DEF_PWM1    I69 @BASEBOARD_FAB2_LIB.BASEBOARD_FAB2(SCH_1):PAGE218
     6 SMB_VR_STBY_LVC3_SDA @BASEBOARD_FAB2_LIB.BASEBOARD_FAB2(SCH_1):SMB_VR_STBY_LVC3_SDA    I69 @BASEBOARD_FAB2_LIB.BASEBOARD_FAB2(SCH_1):PAGE218
     7 SMB_VR_STBY_LVC3_SCL @BASEBOARD_FAB2_LIB.BASEBOARD_FAB2(SCH_1):SMB_VR_STBY_LVC3_SCL    I69 @BASEBOARD_FAB2_LIB.BASEBOARD_FAB2(SCH_1):PAGE218
     8     NC     NC    I69 @BASEBOARD_FAB2_LIB.BASEBOARD_FAB2(SCH_1):PAGE218
     9 PWRGD_PVDDQ_DEF_R @BASEBOARD_FAB2_LIB.BASEBOARD_FAB2(SCH_1):PWRGD_PVDDQ_DEF_R    I69 @BASEBOARD_FAB2_LIB.BASEBOARD_FAB2(SCH_1):PAGE218
    10 VR_PVDDQ_DEF_VREN @BASEBOARD_FAB2_LIB.BASEBOARD_FAB2(SCH_1):VR_PVDDQ_DEF_VREN    I69 @BASEBOARD_FAB2_LIB.BASEBOARD_FAB2(SCH_1):PAGE218
    11 IRQ_PVDDQ_DEF_VRHOT_LVT3_R_N @BASEBOARD_FAB2_LIB.BASEBOARD_FAB2(SCH_1):IRQ_PVDDQ_DEF_VRHOT_LVT3_R_N    I69 @BASEBOARD_FAB2_LIB.BASEBOARD_FAB2(SCH_1):PAGE218
    12     NC     NC    I69 @BASEBOARD_FAB2_LIB.BASEBOARD_FAB2(SCH_1):PAGE218
    13 PU_VR_PVDDQ_DEF_FAULT1 @BASEBOARD_FAB2_LIB.BASEBOARD_FAB2(SCH_1):PU_VR_PVDDQ_DEF_FAULT1    I69 @BASEBOARD_FAB2_LIB.BASEBOARD_FAB2(SCH_1):PAGE218
    14 TP_PVDDQ_DEF_MP1 @BASEBOARD_FAB2_LIB.BASEBOARD_FAB2(SCH_1):TP_PVDDQ_DEF_MP1    I69 @BASEBOARD_FAB2_LIB.BASEBOARD_FAB2(SCH_1):PAGE218
    15 SVID_CLK_PVDDQ_DEF @BASEBOARD_FAB2_LIB.BASEBOARD_FAB2(SCH_1):SVID_CLK_PVDDQ_DEF    I69 @BASEBOARD_FAB2_LIB.BASEBOARD_FAB2(SCH_1):PAGE218
    16 SVID_VDIO_PVDDQ_DEF @BASEBOARD_FAB2_LIB.BASEBOARD_FAB2(SCH_1):SVID_VDIO_PVDDQ_DEF    I69 @BASEBOARD_FAB2_LIB.BASEBOARD_FAB2(SCH_1):PAGE218
    17 SVID_ALERT_PVDDQ_DEF @BASEBOARD_FAB2_LIB.BASEBOARD_FAB2(SCH_1):SVID_ALERT_PVDDQ_DEF    I69 @BASEBOARD_FAB2_LIB.BASEBOARD_FAB2(SCH_1):PAGE218
    18 TP_PVDDQ_DEF_MP2 @BASEBOARD_FAB2_LIB.BASEBOARD_FAB2(SCH_1):TP_PVDDQ_DEF_MP2    I69 @BASEBOARD_FAB2_LIB.BASEBOARD_FAB2(SCH_1):PAGE218
    19 VR_PVDDQ_DEF_AVSP @BASEBOARD_FAB2_LIB.BASEBOARD_FAB2(SCH_1):VR_PVDDQ_DEF_AVSP    I69 @BASEBOARD_FAB2_LIB.BASEBOARD_FAB2(SCH_1):PAGE218
    20 VSENSE_PVDDQ_DEF_N @BASEBOARD_FAB2_LIB.BASEBOARD_FAB2(SCH_1):VSENSE_PVDDQ_DEF_N    I69 @BASEBOARD_FAB2_LIB.BASEBOARD_FAB2(SCH_1):PAGE218
    21 VR_PVDDQ_DEF_AIREF1 @BASEBOARD_FAB2_LIB.BASEBOARD_FAB2(SCH_1):VR_PVDDQ_DEF_AIREF1    I69 @BASEBOARD_FAB2_LIB.BASEBOARD_FAB2(SCH_1):PAGE218
    22 ISENSE_PVDDQ_DEF_PH1_IMON @BASEBOARD_FAB2_LIB.BASEBOARD_FAB2(SCH_1):ISENSE_PVDDQ_DEF_PH1_IMON    I69 @BASEBOARD_FAB2_LIB.BASEBOARD_FAB2(SCH_1):PAGE218
    23 VR_PVDDQ_DEF_AIREF2 @BASEBOARD_FAB2_LIB.BASEBOARD_FAB2(SCH_1):VR_PVDDQ_DEF_AIREF2    I69 @BASEBOARD_FAB2_LIB.BASEBOARD_FAB2(SCH_1):PAGE218
    24 ISENSE_PVDDQ_DEF_PH2_IMON @BASEBOARD_FAB2_LIB.BASEBOARD_FAB2(SCH_1):ISENSE_PVDDQ_DEF_PH2_IMON    I69 @BASEBOARD_FAB2_LIB.BASEBOARD_FAB2(SCH_1):PAGE218
    25     NC     NC    I69 @BASEBOARD_FAB2_LIB.BASEBOARD_FAB2(SCH_1):PAGE218
    26     NC     NC    I69 @BASEBOARD_FAB2_LIB.BASEBOARD_FAB2(SCH_1):PAGE218
    27    GND @BASEBOARD_FAB2_LIB.BASEBOARD_FAB2(SCH_1):GND    I69 @BASEBOARD_FAB2_LIB.BASEBOARD_FAB2(SCH_1):PAGE218
    28     NC     NC    I69 @BASEBOARD_FAB2_LIB.BASEBOARD_FAB2(SCH_1):PAGE218
    29     NC     NC    I69 @BASEBOARD_FAB2_LIB.BASEBOARD_FAB2(SCH_1):PAGE218
    30     NC     NC    I69 @BASEBOARD_FAB2_LIB.BASEBOARD_FAB2(SCH_1):PAGE218
    31     NC     NC    I69 @BASEBOARD_FAB2_LIB.BASEBOARD_FAB2(SCH_1):PAGE218
    32    GND @BASEBOARD_FAB2_LIB.BASEBOARD_FAB2(SCH_1):GND    I69 @BASEBOARD_FAB2_LIB.BASEBOARD_FAB2(SCH_1):PAGE218
    33 VR_PVDDQ_DEF_XADDR2 @BASEBOARD_FAB2_LIB.BASEBOARD_FAB2(SCH_1):VR_PVDDQ_DEF_XADDR2    I69 @BASEBOARD_FAB2_LIB.BASEBOARD_FAB2(SCH_1):PAGE218
    34     NC     NC    I69 @BASEBOARD_FAB2_LIB.BASEBOARD_FAB2(SCH_1):PAGE218
    35 A_TSENSE_PVDDQ_DEF @BASEBOARD_FAB2_LIB.BASEBOARD_FAB2(SCH_1):A_TSENSE_PVDDQ_DEF    I69 @BASEBOARD_FAB2_LIB.BASEBOARD_FAB2(SCH_1):PAGE218
    36 VR_PVDDQ_DEF_XADDR1 @BASEBOARD_FAB2_LIB.BASEBOARD_FAB2(SCH_1):VR_PVDDQ_DEF_XADDR1    I69 @BASEBOARD_FAB2_LIB.BASEBOARD_FAB2(SCH_1):PAGE218
    37 VR_PVDDQ_DEF_VINSEN @BASEBOARD_FAB2_LIB.BASEBOARD_FAB2(SCH_1):VR_PVDDQ_DEF_VINSEN    I69 @BASEBOARD_FAB2_LIB.BASEBOARD_FAB2(SCH_1):PAGE218
    38 VR_PVDDQ_DEF_AIINSEN @BASEBOARD_FAB2_LIB.BASEBOARD_FAB2(SCH_1):VR_PVDDQ_DEF_AIINSEN    I69 @BASEBOARD_FAB2_LIB.BASEBOARD_FAB2(SCH_1):PAGE218
    39 VR_PVDDQ_DEF_VDD @BASEBOARD_FAB2_LIB.BASEBOARD_FAB2(SCH_1):VR_PVDDQ_DEF_VDD    I69 @BASEBOARD_FAB2_LIB.BASEBOARD_FAB2(SCH_1):PAGE218
    40 VR_PVDDQ_DEF_VD12 @BASEBOARD_FAB2_LIB.BASEBOARD_FAB2(SCH_1):VR_PVDDQ_DEF_VD12    I69 @BASEBOARD_FAB2_LIB.BASEBOARD_FAB2(SCH_1):PAGE218
    41    GND @BASEBOARD_FAB2_LIB.BASEBOARD_FAB2(SCH_1):GND    I69 @BASEBOARD_FAB2_LIB.BASEBOARD_FAB2(SCH_1):PAGE218

EU7B1 NCP3232L_SM-IC,H86355-001
     5 AGND_PVPP_DEF @BASEBOARD_FAB2_LIB.BASEBOARD_FAB2(SCH_1):AGND_PVPP_DEF   I214 @BASEBOARD_FAB2_LIB.BASEBOARD_FAB2(SCH_1):PAGE232
    36 VR_PVPP_DEF_BOOT @BASEBOARD_FAB2_LIB.BASEBOARD_FAB2(SCH_1):VR_PVPP_DEF_BOOT   I214 @BASEBOARD_FAB2_LIB.BASEBOARD_FAB2(SCH_1):PAGE232
     3 VR_COMP_PVPP_DEF_3 @BASEBOARD_FAB2_LIB.BASEBOARD_FAB2(SCH_1):VR_COMP_PVPP_DEF_3   I214 @BASEBOARD_FAB2_LIB.BASEBOARD_FAB2(SCH_1):PAGE232
    40 FM_PVPP_PVDDQ_CPU0_EN_DEF @BASEBOARD_FAB2_LIB.BASEBOARD_FAB2(SCH_1):FM_PVPP_PVDDQ_CPU0_EN_DEF   I214 @BASEBOARD_FAB2_LIB.BASEBOARD_FAB2(SCH_1):PAGE232
     2 VR_FB_PVPP_DEF @BASEBOARD_FAB2_LIB.BASEBOARD_FAB2(SCH_1):VR_FB_PVPP_DEF   I214 @BASEBOARD_FAB2_LIB.BASEBOARD_FAB2(SCH_1):PAGE232
    41    GND @BASEBOARD_FAB2_LIB.BASEBOARD_FAB2(SCH_1):GND   I214 @BASEBOARD_FAB2_LIB.BASEBOARD_FAB2(SCH_1):PAGE232
     4 VR_PVPP_DEF_ISET @BASEBOARD_FAB2_LIB.BASEBOARD_FAB2(SCH_1):VR_PVPP_DEF_ISET   I214 @BASEBOARD_FAB2_LIB.BASEBOARD_FAB2(SCH_1):PAGE232
     6 AGND_PVPP_DEF @BASEBOARD_FAB2_LIB.BASEBOARD_FAB2(SCH_1):AGND_PVPP_DEF   I214 @BASEBOARD_FAB2_LIB.BASEBOARD_FAB2(SCH_1):PAGE232
     7 PWRGD_PVPP_DEF_R @BASEBOARD_FAB2_LIB.BASEBOARD_FAB2(SCH_1):PWRGD_PVPP_DEF_R   I214 @BASEBOARD_FAB2_LIB.BASEBOARD_FAB2(SCH_1):PAGE232
    37    GND @BASEBOARD_FAB2_LIB.BASEBOARD_FAB2(SCH_1):GND   I214 @BASEBOARD_FAB2_LIB.BASEBOARD_FAB2(SCH_1):PAGE232
    28    GND @BASEBOARD_FAB2_LIB.BASEBOARD_FAB2(SCH_1):GND   I214 @BASEBOARD_FAB2_LIB.BASEBOARD_FAB2(SCH_1):PAGE232
    27    GND @BASEBOARD_FAB2_LIB.BASEBOARD_FAB2(SCH_1):GND   I214 @BASEBOARD_FAB2_LIB.BASEBOARD_FAB2(SCH_1):PAGE232
    26    GND @BASEBOARD_FAB2_LIB.BASEBOARD_FAB2(SCH_1):GND   I214 @BASEBOARD_FAB2_LIB.BASEBOARD_FAB2(SCH_1):PAGE232
    25    GND @BASEBOARD_FAB2_LIB.BASEBOARD_FAB2(SCH_1):GND   I214 @BASEBOARD_FAB2_LIB.BASEBOARD_FAB2(SCH_1):PAGE232
    24    GND @BASEBOARD_FAB2_LIB.BASEBOARD_FAB2(SCH_1):GND   I214 @BASEBOARD_FAB2_LIB.BASEBOARD_FAB2(SCH_1):PAGE232
    23    GND @BASEBOARD_FAB2_LIB.BASEBOARD_FAB2(SCH_1):GND   I214 @BASEBOARD_FAB2_LIB.BASEBOARD_FAB2(SCH_1):PAGE232
    22    GND @BASEBOARD_FAB2_LIB.BASEBOARD_FAB2(SCH_1):GND   I214 @BASEBOARD_FAB2_LIB.BASEBOARD_FAB2(SCH_1):PAGE232
    21    GND @BASEBOARD_FAB2_LIB.BASEBOARD_FAB2(SCH_1):GND   I214 @BASEBOARD_FAB2_LIB.BASEBOARD_FAB2(SCH_1):PAGE232
    20    GND @BASEBOARD_FAB2_LIB.BASEBOARD_FAB2(SCH_1):GND   I214 @BASEBOARD_FAB2_LIB.BASEBOARD_FAB2(SCH_1):PAGE232
    19    GND @BASEBOARD_FAB2_LIB.BASEBOARD_FAB2(SCH_1):GND   I214 @BASEBOARD_FAB2_LIB.BASEBOARD_FAB2(SCH_1):PAGE232
    18    GND @BASEBOARD_FAB2_LIB.BASEBOARD_FAB2(SCH_1):GND   I214 @BASEBOARD_FAB2_LIB.BASEBOARD_FAB2(SCH_1):PAGE232
    17    GND @BASEBOARD_FAB2_LIB.BASEBOARD_FAB2(SCH_1):GND   I214 @BASEBOARD_FAB2_LIB.BASEBOARD_FAB2(SCH_1):PAGE232
    16    GND @BASEBOARD_FAB2_LIB.BASEBOARD_FAB2(SCH_1):GND   I214 @BASEBOARD_FAB2_LIB.BASEBOARD_FAB2(SCH_1):PAGE232
     1 VR_PVPP_DEF_SS @BASEBOARD_FAB2_LIB.BASEBOARD_FAB2(SCH_1):VR_PVPP_DEF_SS   I214 @BASEBOARD_FAB2_LIB.BASEBOARD_FAB2(SCH_1):PAGE232
    38 VR_VB_PVPP_DEF @BASEBOARD_FAB2_LIB.BASEBOARD_FAB2(SCH_1):VR_VB_PVPP_DEF   I214 @BASEBOARD_FAB2_LIB.BASEBOARD_FAB2(SCH_1):PAGE232
    39 VR_FET_SW_P12V_STBY_PVPP_DEF @BASEBOARD_FAB2_LIB.BASEBOARD_FAB2(SCH_1):VR_FET_SW_P12V_STBY_PVPP_DEF   I214 @BASEBOARD_FAB2_LIB.BASEBOARD_FAB2(SCH_1):PAGE232
    42 VR_FET_SW_P12V_STBY_PVPP_DEF @BASEBOARD_FAB2_LIB.BASEBOARD_FAB2(SCH_1):VR_FET_SW_P12V_STBY_PVPP_DEF   I214 @BASEBOARD_FAB2_LIB.BASEBOARD_FAB2(SCH_1):PAGE232
    14 VR_FET_SW_P12V_STBY_PVPP_DEF @BASEBOARD_FAB2_LIB.BASEBOARD_FAB2(SCH_1):VR_FET_SW_P12V_STBY_PVPP_DEF   I214 @BASEBOARD_FAB2_LIB.BASEBOARD_FAB2(SCH_1):PAGE232
    13 VR_FET_SW_P12V_STBY_PVPP_DEF @BASEBOARD_FAB2_LIB.BASEBOARD_FAB2(SCH_1):VR_FET_SW_P12V_STBY_PVPP_DEF   I214 @BASEBOARD_FAB2_LIB.BASEBOARD_FAB2(SCH_1):PAGE232
    12 VR_FET_SW_P12V_STBY_PVPP_DEF @BASEBOARD_FAB2_LIB.BASEBOARD_FAB2(SCH_1):VR_FET_SW_P12V_STBY_PVPP_DEF   I214 @BASEBOARD_FAB2_LIB.BASEBOARD_FAB2(SCH_1):PAGE232
    11 VR_FET_SW_P12V_STBY_PVPP_DEF @BASEBOARD_FAB2_LIB.BASEBOARD_FAB2(SCH_1):VR_FET_SW_P12V_STBY_PVPP_DEF   I214 @BASEBOARD_FAB2_LIB.BASEBOARD_FAB2(SCH_1):PAGE232
    10 VR_FET_SW_P12V_STBY_PVPP_DEF @BASEBOARD_FAB2_LIB.BASEBOARD_FAB2(SCH_1):VR_FET_SW_P12V_STBY_PVPP_DEF   I214 @BASEBOARD_FAB2_LIB.BASEBOARD_FAB2(SCH_1):PAGE232
     9 VR_FET_SW_P12V_STBY_PVPP_DEF @BASEBOARD_FAB2_LIB.BASEBOARD_FAB2(SCH_1):VR_FET_SW_P12V_STBY_PVPP_DEF   I214 @BASEBOARD_FAB2_LIB.BASEBOARD_FAB2(SCH_1):PAGE232
     8 VR_FET_SW_P12V_STBY_PVPP_DEF @BASEBOARD_FAB2_LIB.BASEBOARD_FAB2(SCH_1):VR_FET_SW_P12V_STBY_PVPP_DEF   I214 @BASEBOARD_FAB2_LIB.BASEBOARD_FAB2(SCH_1):PAGE232
    35 VR_PVPP_DEF_PHASE @BASEBOARD_FAB2_LIB.BASEBOARD_FAB2(SCH_1):VR_PVPP_DEF_PHASE   I214 @BASEBOARD_FAB2_LIB.BASEBOARD_FAB2(SCH_1):PAGE232
    43 VR_PVPP_DEF_PHASE @BASEBOARD_FAB2_LIB.BASEBOARD_FAB2(SCH_1):VR_PVPP_DEF_PHASE   I214 @BASEBOARD_FAB2_LIB.BASEBOARD_FAB2(SCH_1):PAGE232
    34 VR_PVPP_DEF_PHASE @BASEBOARD_FAB2_LIB.BASEBOARD_FAB2(SCH_1):VR_PVPP_DEF_PHASE   I214 @BASEBOARD_FAB2_LIB.BASEBOARD_FAB2(SCH_1):PAGE232
    33 VR_PVPP_DEF_PHASE @BASEBOARD_FAB2_LIB.BASEBOARD_FAB2(SCH_1):VR_PVPP_DEF_PHASE   I214 @BASEBOARD_FAB2_LIB.BASEBOARD_FAB2(SCH_1):PAGE232
    32 VR_PVPP_DEF_PHASE @BASEBOARD_FAB2_LIB.BASEBOARD_FAB2(SCH_1):VR_PVPP_DEF_PHASE   I214 @BASEBOARD_FAB2_LIB.BASEBOARD_FAB2(SCH_1):PAGE232
    31 VR_PVPP_DEF_PHASE @BASEBOARD_FAB2_LIB.BASEBOARD_FAB2(SCH_1):VR_PVPP_DEF_PHASE   I214 @BASEBOARD_FAB2_LIB.BASEBOARD_FAB2(SCH_1):PAGE232
    30 VR_PVPP_DEF_PHASE @BASEBOARD_FAB2_LIB.BASEBOARD_FAB2(SCH_1):VR_PVPP_DEF_PHASE   I214 @BASEBOARD_FAB2_LIB.BASEBOARD_FAB2(SCH_1):PAGE232
    29 VR_PVPP_DEF_PHASE @BASEBOARD_FAB2_LIB.BASEBOARD_FAB2(SCH_1):VR_PVPP_DEF_PHASE   I214 @BASEBOARD_FAB2_LIB.BASEBOARD_FAB2(SCH_1):PAGE232
    15 VR_PVPP_DEF_PHASE @BASEBOARD_FAB2_LIB.BASEBOARD_FAB2(SCH_1):VR_PVPP_DEF_PHASE   I214 @BASEBOARD_FAB2_LIB.BASEBOARD_FAB2(SCH_1):PAGE232

EU7C1 IR354XX_SM-IR35412,IC,H73684-0A
    33 VR_PVCCIO_CPU0_PH1_BOOT_R @BASEBOARD_FAB2_LIB.BASEBOARD_FAB2(SCH_1):VR_PVCCIO_CPU0_PH1_BOOT_R   I101 @BASEBOARD_FAB2_LIB.BASEBOARD_FAB2(SCH_1):PAGE212
    35 P5V_STBY @BASEBOARD_FAB2_LIB.BASEBOARD_FAB2(SCH_1):P5V_STBY   I101 @BASEBOARD_FAB2_LIB.BASEBOARD_FAB2(SCH_1):PAGE212
    41 TP_PVCCIO_CPU0_GL_1 @BASEBOARD_FAB2_LIB.BASEBOARD_FAB2(SCH_1):TP_PVCCIO_CPU0_GL_1   I101 @BASEBOARD_FAB2_LIB.BASEBOARD_FAB2(SCH_1):PAGE212
     6 TP_PVCCIO_CPU0_GL_0 @BASEBOARD_FAB2_LIB.BASEBOARD_FAB2(SCH_1):TP_PVCCIO_CPU0_GL_0   I101 @BASEBOARD_FAB2_LIB.BASEBOARD_FAB2(SCH_1):PAGE212
    38 ISENSE_PVCCIO_CPU0_PH1_IMON @BASEBOARD_FAB2_LIB.BASEBOARD_FAB2(SCH_1):ISENSE_PVCCIO_CPU0_PH1_IMON   I101 @BASEBOARD_FAB2_LIB.BASEBOARD_FAB2(SCH_1):PAGE212
     2    GND @BASEBOARD_FAB2_LIB.BASEBOARD_FAB2(SCH_1):GND   I101 @BASEBOARD_FAB2_LIB.BASEBOARD_FAB2(SCH_1):PAGE212
    31     NC     NC   I101 @BASEBOARD_FAB2_LIB.BASEBOARD_FAB2(SCH_1):PAGE212
    37 VR_PVCCIO_CPU0_OCSET @BASEBOARD_FAB2_LIB.BASEBOARD_FAB2(SCH_1):VR_PVCCIO_CPU0_OCSET   I101 @BASEBOARD_FAB2_LIB.BASEBOARD_FAB2(SCH_1):PAGE212
    40    GND @BASEBOARD_FAB2_LIB.BASEBOARD_FAB2(SCH_1):GND   I101 @BASEBOARD_FAB2_LIB.BASEBOARD_FAB2(SCH_1):PAGE212
     7    GND @BASEBOARD_FAB2_LIB.BASEBOARD_FAB2(SCH_1):GND   I101 @BASEBOARD_FAB2_LIB.BASEBOARD_FAB2(SCH_1):PAGE212
     5    GND @BASEBOARD_FAB2_LIB.BASEBOARD_FAB2(SCH_1):GND   I101 @BASEBOARD_FAB2_LIB.BASEBOARD_FAB2(SCH_1):PAGE212
    32 VR_PVCCIO_CPU0_PH1_PHASE @BASEBOARD_FAB2_LIB.BASEBOARD_FAB2(SCH_1):VR_PVCCIO_CPU0_PH1_PHASE   I101 @BASEBOARD_FAB2_LIB.BASEBOARD_FAB2(SCH_1):PAGE212
    34 VR_PVCCIO_CPU0_PWM1 @BASEBOARD_FAB2_LIB.BASEBOARD_FAB2(SCH_1):VR_PVCCIO_CPU0_PWM1   I101 @BASEBOARD_FAB2_LIB.BASEBOARD_FAB2(SCH_1):PAGE212
    39 VR_PVCCIO_CPU0_AIREF1 @BASEBOARD_FAB2_LIB.BASEBOARD_FAB2(SCH_1):VR_PVCCIO_CPU0_AIREF1   I101 @BASEBOARD_FAB2_LIB.BASEBOARD_FAB2(SCH_1):PAGE212
    10 VR_PVCCIO_CPU0_PH1_SW @BASEBOARD_FAB2_LIB.BASEBOARD_FAB2(SCH_1):VR_PVCCIO_CPU0_PH1_SW   I101 @BASEBOARD_FAB2_LIB.BASEBOARD_FAB2(SCH_1):PAGE212
    36 A_TSENSE_PVCCIO_CPU0 @BASEBOARD_FAB2_LIB.BASEBOARD_FAB2(SCH_1):A_TSENSE_PVCCIO_CPU0   I101 @BASEBOARD_FAB2_LIB.BASEBOARD_FAB2(SCH_1):PAGE212
     3 VR_PVCCIO_CPU0_PH1_VCIN @BASEBOARD_FAB2_LIB.BASEBOARD_FAB2(SCH_1):VR_PVCCIO_CPU0_PH1_VCIN   I101 @BASEBOARD_FAB2_LIB.BASEBOARD_FAB2(SCH_1):PAGE212
     4 P5V_STBY @BASEBOARD_FAB2_LIB.BASEBOARD_FAB2(SCH_1):P5V_STBY   I101 @BASEBOARD_FAB2_LIB.BASEBOARD_FAB2(SCH_1):PAGE212
    30 VR_FET_SW_P12V_STBY_PVCCIO_CPU0 @BASEBOARD_FAB2_LIB.BASEBOARD_FAB2(SCH_1):VR_FET_SW_P12V_STBY_PVCCIO_CPU0   I101 @BASEBOARD_FAB2_LIB.BASEBOARD_FAB2(SCH_1):PAGE212
    25 VR_FET_SW_P12V_STBY_PVCCIO_CPU0 @BASEBOARD_FAB2_LIB.BASEBOARD_FAB2(SCH_1):VR_FET_SW_P12V_STBY_PVCCIO_CPU0   I101 @BASEBOARD_FAB2_LIB.BASEBOARD_FAB2(SCH_1):PAGE212
     1 PVCCIO_CPU0 @BASEBOARD_FAB2_LIB.BASEBOARD_FAB2(SCH_1):PVCCIO_CPU0   I101 @BASEBOARD_FAB2_LIB.BASEBOARD_FAB2(SCH_1):PAGE212

EU7E1 SLG55021_SM-IC,G56246-001
     4    GND @BASEBOARD_FAB2_LIB.BASEBOARD_FAB2(SCH_1):GND    I19 @BASEBOARD_FAB2_LIB.BASEBOARD_FAB2(SCH_1):PAGE198
     9    GND @BASEBOARD_FAB2_LIB.BASEBOARD_FAB2(SCH_1):GND    I19 @BASEBOARD_FAB2_LIB.BASEBOARD_FAB2(SCH_1):PAGE198
     1 P5V_STBY @BASEBOARD_FAB2_LIB.BASEBOARD_FAB2(SCH_1):P5V_STBY    I19 @BASEBOARD_FAB2_LIB.BASEBOARD_FAB2(SCH_1):PAGE198
     2 FM_P12V_MAIN_SW_EN @BASEBOARD_FAB2_LIB.BASEBOARD_FAB2(SCH_1):FM_P12V_MAIN_SW_EN    I19 @BASEBOARD_FAB2_LIB.BASEBOARD_FAB2(SCH_1):PAGE198
     3 P5V_STBY @BASEBOARD_FAB2_LIB.BASEBOARD_FAB2(SCH_1):P5V_STBY    I19 @BASEBOARD_FAB2_LIB.BASEBOARD_FAB2(SCH_1):PAGE198
     5 P12V_STBY @BASEBOARD_FAB2_LIB.BASEBOARD_FAB2(SCH_1):P12V_STBY    I19 @BASEBOARD_FAB2_LIB.BASEBOARD_FAB2(SCH_1):PAGE198
     6   P12V @BASEBOARD_FAB2_LIB.BASEBOARD_FAB2(SCH_1):P12V    I19 @BASEBOARD_FAB2_LIB.BASEBOARD_FAB2(SCH_1):PAGE198
     7 P12V_SWITCH_G @BASEBOARD_FAB2_LIB.BASEBOARD_FAB2(SCH_1):P12V_SWITCH_G    I19 @BASEBOARD_FAB2_LIB.BASEBOARD_FAB2(SCH_1):PAGE198
     8 TP_SLG55021_P12V_MAIN_8 @BASEBOARD_FAB2_LIB.BASEBOARD_FAB2(SCH_1):TP_SLG55021_P12V_MAIN_8    I19 @BASEBOARD_FAB2_LIB.BASEBOARD_FAB2(SCH_1):PAGE198

EU7E2 TPS54821_LCC-IC,H63269-001
    13 VR_P5V_STBY_BOOT @BASEBOARD_FAB2_LIB.BASEBOARD_FAB2(SCH_1):VR_P5V_STBY_BOOT    I83 @BASEBOARD_FAB2_LIB.BASEBOARD_FAB2(SCH_1):PAGE241
     8 VR_P5V_STBY_COMP @BASEBOARD_FAB2_LIB.BASEBOARD_FAB2(SCH_1):VR_P5V_STBY_COMP    I83 @BASEBOARD_FAB2_LIB.BASEBOARD_FAB2(SCH_1):PAGE241
    10 VR_P5V_STBY_EN @BASEBOARD_FAB2_LIB.BASEBOARD_FAB2(SCH_1):VR_P5V_STBY_EN    I83 @BASEBOARD_FAB2_LIB.BASEBOARD_FAB2(SCH_1):PAGE241
     3    GND @BASEBOARD_FAB2_LIB.BASEBOARD_FAB2(SCH_1):GND    I83 @BASEBOARD_FAB2_LIB.BASEBOARD_FAB2(SCH_1):PAGE241
     2    GND @BASEBOARD_FAB2_LIB.BASEBOARD_FAB2(SCH_1):GND    I83 @BASEBOARD_FAB2_LIB.BASEBOARD_FAB2(SCH_1):PAGE241
    12 VR_P5V_STBY_PHASE @BASEBOARD_FAB2_LIB.BASEBOARD_FAB2(SCH_1):VR_P5V_STBY_PHASE    I83 @BASEBOARD_FAB2_LIB.BASEBOARD_FAB2(SCH_1):PAGE241
    11 VR_P5V_STBY_PHASE @BASEBOARD_FAB2_LIB.BASEBOARD_FAB2(SCH_1):VR_P5V_STBY_PHASE    I83 @BASEBOARD_FAB2_LIB.BASEBOARD_FAB2(SCH_1):PAGE241
     5 VR_FET_SW_P5V_STBY_PVIN @BASEBOARD_FAB2_LIB.BASEBOARD_FAB2(SCH_1):VR_FET_SW_P5V_STBY_PVIN    I83 @BASEBOARD_FAB2_LIB.BASEBOARD_FAB2(SCH_1):PAGE241
     4 VR_FET_SW_P5V_STBY_PVIN @BASEBOARD_FAB2_LIB.BASEBOARD_FAB2(SCH_1):VR_FET_SW_P5V_STBY_PVIN    I83 @BASEBOARD_FAB2_LIB.BASEBOARD_FAB2(SCH_1):PAGE241
    14 PWRGD_P5V_STBY_R @BASEBOARD_FAB2_LIB.BASEBOARD_FAB2(SCH_1):PWRGD_P5V_STBY_R    I83 @BASEBOARD_FAB2_LIB.BASEBOARD_FAB2(SCH_1):PAGE241
     1 VR_P5V_STBY_RT @BASEBOARD_FAB2_LIB.BASEBOARD_FAB2(SCH_1):VR_P5V_STBY_RT    I83 @BASEBOARD_FAB2_LIB.BASEBOARD_FAB2(SCH_1):PAGE241
     9 VR_P5V_STBY_SS @BASEBOARD_FAB2_LIB.BASEBOARD_FAB2(SCH_1):VR_P5V_STBY_SS    I83 @BASEBOARD_FAB2_LIB.BASEBOARD_FAB2(SCH_1):PAGE241
    15    GND @BASEBOARD_FAB2_LIB.BASEBOARD_FAB2(SCH_1):GND    I83 @BASEBOARD_FAB2_LIB.BASEBOARD_FAB2(SCH_1):PAGE241
     6 VR_P5V_STBY_VIN @BASEBOARD_FAB2_LIB.BASEBOARD_FAB2(SCH_1):VR_P5V_STBY_VIN    I83 @BASEBOARD_FAB2_LIB.BASEBOARD_FAB2(SCH_1):PAGE241
     7 VR_P5V_STBY_VSENSE @BASEBOARD_FAB2_LIB.BASEBOARD_FAB2(SCH_1):VR_P5V_STBY_VSENSE    I83 @BASEBOARD_FAB2_LIB.BASEBOARD_FAB2(SCH_1):PAGE241

EU7F1 NCP3232L_SM-IC,H86355-001
     5 AGND_PVPP_ABC @BASEBOARD_FAB2_LIB.BASEBOARD_FAB2(SCH_1):AGND_PVPP_ABC   I193 @BASEBOARD_FAB2_LIB.BASEBOARD_FAB2(SCH_1):PAGE231
    36 VR_PVPP_ABC_BOOT @BASEBOARD_FAB2_LIB.BASEBOARD_FAB2(SCH_1):VR_PVPP_ABC_BOOT   I193 @BASEBOARD_FAB2_LIB.BASEBOARD_FAB2(SCH_1):PAGE231
     3 VR_COMP_PVPP_ABC_3 @BASEBOARD_FAB2_LIB.BASEBOARD_FAB2(SCH_1):VR_COMP_PVPP_ABC_3   I193 @BASEBOARD_FAB2_LIB.BASEBOARD_FAB2(SCH_1):PAGE231
    40 FM_PVPP_PVDDQ_CPU0_EN_ABC @BASEBOARD_FAB2_LIB.BASEBOARD_FAB2(SCH_1):FM_PVPP_PVDDQ_CPU0_EN_ABC   I193 @BASEBOARD_FAB2_LIB.BASEBOARD_FAB2(SCH_1):PAGE231
     2 VR_FB_PVPP_ABC @BASEBOARD_FAB2_LIB.BASEBOARD_FAB2(SCH_1):VR_FB_PVPP_ABC   I193 @BASEBOARD_FAB2_LIB.BASEBOARD_FAB2(SCH_1):PAGE231
    41    GND @BASEBOARD_FAB2_LIB.BASEBOARD_FAB2(SCH_1):GND   I193 @BASEBOARD_FAB2_LIB.BASEBOARD_FAB2(SCH_1):PAGE231
     4 VR_PVPP_ABC_ISET @BASEBOARD_FAB2_LIB.BASEBOARD_FAB2(SCH_1):VR_PVPP_ABC_ISET   I193 @BASEBOARD_FAB2_LIB.BASEBOARD_FAB2(SCH_1):PAGE231
     6 AGND_PVPP_ABC @BASEBOARD_FAB2_LIB.BASEBOARD_FAB2(SCH_1):AGND_PVPP_ABC   I193 @BASEBOARD_FAB2_LIB.BASEBOARD_FAB2(SCH_1):PAGE231
     7 PWRGD_PVPP_ABC_R @BASEBOARD_FAB2_LIB.BASEBOARD_FAB2(SCH_1):PWRGD_PVPP_ABC_R   I193 @BASEBOARD_FAB2_LIB.BASEBOARD_FAB2(SCH_1):PAGE231
    37    GND @BASEBOARD_FAB2_LIB.BASEBOARD_FAB2(SCH_1):GND   I193 @BASEBOARD_FAB2_LIB.BASEBOARD_FAB2(SCH_1):PAGE231
    28    GND @BASEBOARD_FAB2_LIB.BASEBOARD_FAB2(SCH_1):GND   I193 @BASEBOARD_FAB2_LIB.BASEBOARD_FAB2(SCH_1):PAGE231
    27    GND @BASEBOARD_FAB2_LIB.BASEBOARD_FAB2(SCH_1):GND   I193 @BASEBOARD_FAB2_LIB.BASEBOARD_FAB2(SCH_1):PAGE231
    26    GND @BASEBOARD_FAB2_LIB.BASEBOARD_FAB2(SCH_1):GND   I193 @BASEBOARD_FAB2_LIB.BASEBOARD_FAB2(SCH_1):PAGE231
    25    GND @BASEBOARD_FAB2_LIB.BASEBOARD_FAB2(SCH_1):GND   I193 @BASEBOARD_FAB2_LIB.BASEBOARD_FAB2(SCH_1):PAGE231
    24    GND @BASEBOARD_FAB2_LIB.BASEBOARD_FAB2(SCH_1):GND   I193 @BASEBOARD_FAB2_LIB.BASEBOARD_FAB2(SCH_1):PAGE231
    23    GND @BASEBOARD_FAB2_LIB.BASEBOARD_FAB2(SCH_1):GND   I193 @BASEBOARD_FAB2_LIB.BASEBOARD_FAB2(SCH_1):PAGE231
    22    GND @BASEBOARD_FAB2_LIB.BASEBOARD_FAB2(SCH_1):GND   I193 @BASEBOARD_FAB2_LIB.BASEBOARD_FAB2(SCH_1):PAGE231
    21    GND @BASEBOARD_FAB2_LIB.BASEBOARD_FAB2(SCH_1):GND   I193 @BASEBOARD_FAB2_LIB.BASEBOARD_FAB2(SCH_1):PAGE231
    20    GND @BASEBOARD_FAB2_LIB.BASEBOARD_FAB2(SCH_1):GND   I193 @BASEBOARD_FAB2_LIB.BASEBOARD_FAB2(SCH_1):PAGE231
    19    GND @BASEBOARD_FAB2_LIB.BASEBOARD_FAB2(SCH_1):GND   I193 @BASEBOARD_FAB2_LIB.BASEBOARD_FAB2(SCH_1):PAGE231
    18    GND @BASEBOARD_FAB2_LIB.BASEBOARD_FAB2(SCH_1):GND   I193 @BASEBOARD_FAB2_LIB.BASEBOARD_FAB2(SCH_1):PAGE231
    17    GND @BASEBOARD_FAB2_LIB.BASEBOARD_FAB2(SCH_1):GND   I193 @BASEBOARD_FAB2_LIB.BASEBOARD_FAB2(SCH_1):PAGE231
    16    GND @BASEBOARD_FAB2_LIB.BASEBOARD_FAB2(SCH_1):GND   I193 @BASEBOARD_FAB2_LIB.BASEBOARD_FAB2(SCH_1):PAGE231
     1 VR_PVPP_ABC_SS @BASEBOARD_FAB2_LIB.BASEBOARD_FAB2(SCH_1):VR_PVPP_ABC_SS   I193 @BASEBOARD_FAB2_LIB.BASEBOARD_FAB2(SCH_1):PAGE231
    38 VR_VB_PVPP_ABC @BASEBOARD_FAB2_LIB.BASEBOARD_FAB2(SCH_1):VR_VB_PVPP_ABC   I193 @BASEBOARD_FAB2_LIB.BASEBOARD_FAB2(SCH_1):PAGE231
    39 VR_FET_SW_P12V_STBY_PVPP_ABC @BASEBOARD_FAB2_LIB.BASEBOARD_FAB2(SCH_1):VR_FET_SW_P12V_STBY_PVPP_ABC   I193 @BASEBOARD_FAB2_LIB.BASEBOARD_FAB2(SCH_1):PAGE231
    42 VR_FET_SW_P12V_STBY_PVPP_ABC @BASEBOARD_FAB2_LIB.BASEBOARD_FAB2(SCH_1):VR_FET_SW_P12V_STBY_PVPP_ABC   I193 @BASEBOARD_FAB2_LIB.BASEBOARD_FAB2(SCH_1):PAGE231
    14 VR_FET_SW_P12V_STBY_PVPP_ABC @BASEBOARD_FAB2_LIB.BASEBOARD_FAB2(SCH_1):VR_FET_SW_P12V_STBY_PVPP_ABC   I193 @BASEBOARD_FAB2_LIB.BASEBOARD_FAB2(SCH_1):PAGE231
    13 VR_FET_SW_P12V_STBY_PVPP_ABC @BASEBOARD_FAB2_LIB.BASEBOARD_FAB2(SCH_1):VR_FET_SW_P12V_STBY_PVPP_ABC   I193 @BASEBOARD_FAB2_LIB.BASEBOARD_FAB2(SCH_1):PAGE231
    12 VR_FET_SW_P12V_STBY_PVPP_ABC @BASEBOARD_FAB2_LIB.BASEBOARD_FAB2(SCH_1):VR_FET_SW_P12V_STBY_PVPP_ABC   I193 @BASEBOARD_FAB2_LIB.BASEBOARD_FAB2(SCH_1):PAGE231
    11 VR_FET_SW_P12V_STBY_PVPP_ABC @BASEBOARD_FAB2_LIB.BASEBOARD_FAB2(SCH_1):VR_FET_SW_P12V_STBY_PVPP_ABC   I193 @BASEBOARD_FAB2_LIB.BASEBOARD_FAB2(SCH_1):PAGE231
    10 VR_FET_SW_P12V_STBY_PVPP_ABC @BASEBOARD_FAB2_LIB.BASEBOARD_FAB2(SCH_1):VR_FET_SW_P12V_STBY_PVPP_ABC   I193 @BASEBOARD_FAB2_LIB.BASEBOARD_FAB2(SCH_1):PAGE231
     9 VR_FET_SW_P12V_STBY_PVPP_ABC @BASEBOARD_FAB2_LIB.BASEBOARD_FAB2(SCH_1):VR_FET_SW_P12V_STBY_PVPP_ABC   I193 @BASEBOARD_FAB2_LIB.BASEBOARD_FAB2(SCH_1):PAGE231
     8 VR_FET_SW_P12V_STBY_PVPP_ABC @BASEBOARD_FAB2_LIB.BASEBOARD_FAB2(SCH_1):VR_FET_SW_P12V_STBY_PVPP_ABC   I193 @BASEBOARD_FAB2_LIB.BASEBOARD_FAB2(SCH_1):PAGE231
    35 VR_PVPP_ABC_PHASE @BASEBOARD_FAB2_LIB.BASEBOARD_FAB2(SCH_1):VR_PVPP_ABC_PHASE   I193 @BASEBOARD_FAB2_LIB.BASEBOARD_FAB2(SCH_1):PAGE231
    43 VR_PVPP_ABC_PHASE @BASEBOARD_FAB2_LIB.BASEBOARD_FAB2(SCH_1):VR_PVPP_ABC_PHASE   I193 @BASEBOARD_FAB2_LIB.BASEBOARD_FAB2(SCH_1):PAGE231
    34 VR_PVPP_ABC_PHASE @BASEBOARD_FAB2_LIB.BASEBOARD_FAB2(SCH_1):VR_PVPP_ABC_PHASE   I193 @BASEBOARD_FAB2_LIB.BASEBOARD_FAB2(SCH_1):PAGE231
    33 VR_PVPP_ABC_PHASE @BASEBOARD_FAB2_LIB.BASEBOARD_FAB2(SCH_1):VR_PVPP_ABC_PHASE   I193 @BASEBOARD_FAB2_LIB.BASEBOARD_FAB2(SCH_1):PAGE231
    32 VR_PVPP_ABC_PHASE @BASEBOARD_FAB2_LIB.BASEBOARD_FAB2(SCH_1):VR_PVPP_ABC_PHASE   I193 @BASEBOARD_FAB2_LIB.BASEBOARD_FAB2(SCH_1):PAGE231
    31 VR_PVPP_ABC_PHASE @BASEBOARD_FAB2_LIB.BASEBOARD_FAB2(SCH_1):VR_PVPP_ABC_PHASE   I193 @BASEBOARD_FAB2_LIB.BASEBOARD_FAB2(SCH_1):PAGE231
    30 VR_PVPP_ABC_PHASE @BASEBOARD_FAB2_LIB.BASEBOARD_FAB2(SCH_1):VR_PVPP_ABC_PHASE   I193 @BASEBOARD_FAB2_LIB.BASEBOARD_FAB2(SCH_1):PAGE231
    29 VR_PVPP_ABC_PHASE @BASEBOARD_FAB2_LIB.BASEBOARD_FAB2(SCH_1):VR_PVPP_ABC_PHASE   I193 @BASEBOARD_FAB2_LIB.BASEBOARD_FAB2(SCH_1):PAGE231
    15 VR_PVPP_ABC_PHASE @BASEBOARD_FAB2_LIB.BASEBOARD_FAB2(SCH_1):VR_PVPP_ABC_PHASE   I193 @BASEBOARD_FAB2_LIB.BASEBOARD_FAB2(SCH_1):PAGE231

EU7G1 PXM1310B_QFN-IC,H89186-001
     1     NC     NC    I69 @BASEBOARD_FAB2_LIB.BASEBOARD_FAB2(SCH_1):PAGE215
     2     NC     NC    I69 @BASEBOARD_FAB2_LIB.BASEBOARD_FAB2(SCH_1):PAGE215
     3     NC     NC    I69 @BASEBOARD_FAB2_LIB.BASEBOARD_FAB2(SCH_1):PAGE215
     4 VR_PVDDQ_ABC_PWM2 @BASEBOARD_FAB2_LIB.BASEBOARD_FAB2(SCH_1):VR_PVDDQ_ABC_PWM2    I69 @BASEBOARD_FAB2_LIB.BASEBOARD_FAB2(SCH_1):PAGE215
     5 VR_PVDDQ_ABC_PWM1 @BASEBOARD_FAB2_LIB.BASEBOARD_FAB2(SCH_1):VR_PVDDQ_ABC_PWM1    I69 @BASEBOARD_FAB2_LIB.BASEBOARD_FAB2(SCH_1):PAGE215
     6 SMB_VR_STBY_LVC3_SDA @BASEBOARD_FAB2_LIB.BASEBOARD_FAB2(SCH_1):SMB_VR_STBY_LVC3_SDA    I69 @BASEBOARD_FAB2_LIB.BASEBOARD_FAB2(SCH_1):PAGE215
     7 SMB_VR_STBY_LVC3_SCL @BASEBOARD_FAB2_LIB.BASEBOARD_FAB2(SCH_1):SMB_VR_STBY_LVC3_SCL    I69 @BASEBOARD_FAB2_LIB.BASEBOARD_FAB2(SCH_1):PAGE215
     8     NC     NC    I69 @BASEBOARD_FAB2_LIB.BASEBOARD_FAB2(SCH_1):PAGE215
     9 PWRGD_PVDDQ_ABC_R @BASEBOARD_FAB2_LIB.BASEBOARD_FAB2(SCH_1):PWRGD_PVDDQ_ABC_R    I69 @BASEBOARD_FAB2_LIB.BASEBOARD_FAB2(SCH_1):PAGE215
    10 VR_PVDDQ_ABC_VREN @BASEBOARD_FAB2_LIB.BASEBOARD_FAB2(SCH_1):VR_PVDDQ_ABC_VREN    I69 @BASEBOARD_FAB2_LIB.BASEBOARD_FAB2(SCH_1):PAGE215
    11 IRQ_PVDDQ_ABC_VRHOT_LVT3_R_N @BASEBOARD_FAB2_LIB.BASEBOARD_FAB2(SCH_1):IRQ_PVDDQ_ABC_VRHOT_LVT3_R_N    I69 @BASEBOARD_FAB2_LIB.BASEBOARD_FAB2(SCH_1):PAGE215
    12     NC     NC    I69 @BASEBOARD_FAB2_LIB.BASEBOARD_FAB2(SCH_1):PAGE215
    13 PU_VR_PVDDQ_ABC_FAULT1 @BASEBOARD_FAB2_LIB.BASEBOARD_FAB2(SCH_1):PU_VR_PVDDQ_ABC_FAULT1    I69 @BASEBOARD_FAB2_LIB.BASEBOARD_FAB2(SCH_1):PAGE215
    14 TP_PVDDQ_ABC_MP1 @BASEBOARD_FAB2_LIB.BASEBOARD_FAB2(SCH_1):TP_PVDDQ_ABC_MP1    I69 @BASEBOARD_FAB2_LIB.BASEBOARD_FAB2(SCH_1):PAGE215
    15 SVID_CLK_PVDDQ_ABC @BASEBOARD_FAB2_LIB.BASEBOARD_FAB2(SCH_1):SVID_CLK_PVDDQ_ABC    I69 @BASEBOARD_FAB2_LIB.BASEBOARD_FAB2(SCH_1):PAGE215
    16 SVID_VDIO_PVDDQ_ABC @BASEBOARD_FAB2_LIB.BASEBOARD_FAB2(SCH_1):SVID_VDIO_PVDDQ_ABC    I69 @BASEBOARD_FAB2_LIB.BASEBOARD_FAB2(SCH_1):PAGE215
    17 SVID_ALERT_PVDDQ_ABC @BASEBOARD_FAB2_LIB.BASEBOARD_FAB2(SCH_1):SVID_ALERT_PVDDQ_ABC    I69 @BASEBOARD_FAB2_LIB.BASEBOARD_FAB2(SCH_1):PAGE215
    18 TP_PVDDQ_ABC_MP2 @BASEBOARD_FAB2_LIB.BASEBOARD_FAB2(SCH_1):TP_PVDDQ_ABC_MP2    I69 @BASEBOARD_FAB2_LIB.BASEBOARD_FAB2(SCH_1):PAGE215
    19 VR_PVDDQ_ABC_AVSP @BASEBOARD_FAB2_LIB.BASEBOARD_FAB2(SCH_1):VR_PVDDQ_ABC_AVSP    I69 @BASEBOARD_FAB2_LIB.BASEBOARD_FAB2(SCH_1):PAGE215
    20 VSENSE_PVDDQ_ABC_N @BASEBOARD_FAB2_LIB.BASEBOARD_FAB2(SCH_1):VSENSE_PVDDQ_ABC_N    I69 @BASEBOARD_FAB2_LIB.BASEBOARD_FAB2(SCH_1):PAGE215
    21 VR_PVDDQ_ABC_AIREF1 @BASEBOARD_FAB2_LIB.BASEBOARD_FAB2(SCH_1):VR_PVDDQ_ABC_AIREF1    I69 @BASEBOARD_FAB2_LIB.BASEBOARD_FAB2(SCH_1):PAGE215
    22 ISENSE_PVDDQ_ABC_PH1_IMON @BASEBOARD_FAB2_LIB.BASEBOARD_FAB2(SCH_1):ISENSE_PVDDQ_ABC_PH1_IMON    I69 @BASEBOARD_FAB2_LIB.BASEBOARD_FAB2(SCH_1):PAGE215
    23 VR_PVDDQ_ABC_AIREF2 @BASEBOARD_FAB2_LIB.BASEBOARD_FAB2(SCH_1):VR_PVDDQ_ABC_AIREF2    I69 @BASEBOARD_FAB2_LIB.BASEBOARD_FAB2(SCH_1):PAGE215
    24 ISENSE_PVDDQ_ABC_PH2_IMON @BASEBOARD_FAB2_LIB.BASEBOARD_FAB2(SCH_1):ISENSE_PVDDQ_ABC_PH2_IMON    I69 @BASEBOARD_FAB2_LIB.BASEBOARD_FAB2(SCH_1):PAGE215
    25     NC     NC    I69 @BASEBOARD_FAB2_LIB.BASEBOARD_FAB2(SCH_1):PAGE215
    26     NC     NC    I69 @BASEBOARD_FAB2_LIB.BASEBOARD_FAB2(SCH_1):PAGE215
    27    GND @BASEBOARD_FAB2_LIB.BASEBOARD_FAB2(SCH_1):GND    I69 @BASEBOARD_FAB2_LIB.BASEBOARD_FAB2(SCH_1):PAGE215
    28     NC     NC    I69 @BASEBOARD_FAB2_LIB.BASEBOARD_FAB2(SCH_1):PAGE215
    29     NC     NC    I69 @BASEBOARD_FAB2_LIB.BASEBOARD_FAB2(SCH_1):PAGE215
    30     NC     NC    I69 @BASEBOARD_FAB2_LIB.BASEBOARD_FAB2(SCH_1):PAGE215
    31     NC     NC    I69 @BASEBOARD_FAB2_LIB.BASEBOARD_FAB2(SCH_1):PAGE215
    32    GND @BASEBOARD_FAB2_LIB.BASEBOARD_FAB2(SCH_1):GND    I69 @BASEBOARD_FAB2_LIB.BASEBOARD_FAB2(SCH_1):PAGE215
    33 VR_PVDDQ_ABC_XADDR2 @BASEBOARD_FAB2_LIB.BASEBOARD_FAB2(SCH_1):VR_PVDDQ_ABC_XADDR2    I69 @BASEBOARD_FAB2_LIB.BASEBOARD_FAB2(SCH_1):PAGE215
    34     NC     NC    I69 @BASEBOARD_FAB2_LIB.BASEBOARD_FAB2(SCH_1):PAGE215
    35 A_TSENSE_PVDDQ_ABC @BASEBOARD_FAB2_LIB.BASEBOARD_FAB2(SCH_1):A_TSENSE_PVDDQ_ABC    I69 @BASEBOARD_FAB2_LIB.BASEBOARD_FAB2(SCH_1):PAGE215
    36 VR_PVDDQ_ABC_XADDR1 @BASEBOARD_FAB2_LIB.BASEBOARD_FAB2(SCH_1):VR_PVDDQ_ABC_XADDR1    I69 @BASEBOARD_FAB2_LIB.BASEBOARD_FAB2(SCH_1):PAGE215
    37 VR_PVDDQ_ABC_VINSEN @BASEBOARD_FAB2_LIB.BASEBOARD_FAB2(SCH_1):VR_PVDDQ_ABC_VINSEN    I69 @BASEBOARD_FAB2_LIB.BASEBOARD_FAB2(SCH_1):PAGE215
    38 VR_PVDDQ_ABC_AIINSEN @BASEBOARD_FAB2_LIB.BASEBOARD_FAB2(SCH_1):VR_PVDDQ_ABC_AIINSEN    I69 @BASEBOARD_FAB2_LIB.BASEBOARD_FAB2(SCH_1):PAGE215
    39 VR_PVDDQ_ABC_VDD @BASEBOARD_FAB2_LIB.BASEBOARD_FAB2(SCH_1):VR_PVDDQ_ABC_VDD    I69 @BASEBOARD_FAB2_LIB.BASEBOARD_FAB2(SCH_1):PAGE215
    40 VR_PVDDQ_ABC_VD12 @BASEBOARD_FAB2_LIB.BASEBOARD_FAB2(SCH_1):VR_PVDDQ_ABC_VD12    I69 @BASEBOARD_FAB2_LIB.BASEBOARD_FAB2(SCH_1):PAGE215
    41    GND @BASEBOARD_FAB2_LIB.BASEBOARD_FAB2(SCH_1):GND    I69 @BASEBOARD_FAB2_LIB.BASEBOARD_FAB2(SCH_1):PAGE215

EU7G2 IR354XX_SM-IR35411,IC,H73688-0A
    33 VR_PVDDQ_ABC_PH1_BOOT_R @BASEBOARD_FAB2_LIB.BASEBOARD_FAB2(SCH_1):VR_PVDDQ_ABC_PH1_BOOT_R   I102 @BASEBOARD_FAB2_LIB.BASEBOARD_FAB2(SCH_1):PAGE216
    35 P5V_STBY @BASEBOARD_FAB2_LIB.BASEBOARD_FAB2(SCH_1):P5V_STBY   I102 @BASEBOARD_FAB2_LIB.BASEBOARD_FAB2(SCH_1):PAGE216
    41 TP_PVDDQ_ABC_PH1_GL_1 @BASEBOARD_FAB2_LIB.BASEBOARD_FAB2(SCH_1):TP_PVDDQ_ABC_PH1_GL_1   I102 @BASEBOARD_FAB2_LIB.BASEBOARD_FAB2(SCH_1):PAGE216
     6 TP_PVDDQ_ABC_PH1_GL_0 @BASEBOARD_FAB2_LIB.BASEBOARD_FAB2(SCH_1):TP_PVDDQ_ABC_PH1_GL_0   I102 @BASEBOARD_FAB2_LIB.BASEBOARD_FAB2(SCH_1):PAGE216
    38 ISENSE_PVDDQ_ABC_PH1_IMON @BASEBOARD_FAB2_LIB.BASEBOARD_FAB2(SCH_1):ISENSE_PVDDQ_ABC_PH1_IMON   I102 @BASEBOARD_FAB2_LIB.BASEBOARD_FAB2(SCH_1):PAGE216
     2    GND @BASEBOARD_FAB2_LIB.BASEBOARD_FAB2(SCH_1):GND   I102 @BASEBOARD_FAB2_LIB.BASEBOARD_FAB2(SCH_1):PAGE216
    31     NC     NC   I102 @BASEBOARD_FAB2_LIB.BASEBOARD_FAB2(SCH_1):PAGE216
    37 VR_PVDDQ_ABC_PH1_OCSET @BASEBOARD_FAB2_LIB.BASEBOARD_FAB2(SCH_1):VR_PVDDQ_ABC_PH1_OCSET   I102 @BASEBOARD_FAB2_LIB.BASEBOARD_FAB2(SCH_1):PAGE216
    40    GND @BASEBOARD_FAB2_LIB.BASEBOARD_FAB2(SCH_1):GND   I102 @BASEBOARD_FAB2_LIB.BASEBOARD_FAB2(SCH_1):PAGE216
     7    GND @BASEBOARD_FAB2_LIB.BASEBOARD_FAB2(SCH_1):GND   I102 @BASEBOARD_FAB2_LIB.BASEBOARD_FAB2(SCH_1):PAGE216
     5    GND @BASEBOARD_FAB2_LIB.BASEBOARD_FAB2(SCH_1):GND   I102 @BASEBOARD_FAB2_LIB.BASEBOARD_FAB2(SCH_1):PAGE216
    32 VR_PVDDQ_ABC_PH1_PHASE @BASEBOARD_FAB2_LIB.BASEBOARD_FAB2(SCH_1):VR_PVDDQ_ABC_PH1_PHASE   I102 @BASEBOARD_FAB2_LIB.BASEBOARD_FAB2(SCH_1):PAGE216
    34 VR_PVDDQ_ABC_PWM1 @BASEBOARD_FAB2_LIB.BASEBOARD_FAB2(SCH_1):VR_PVDDQ_ABC_PWM1   I102 @BASEBOARD_FAB2_LIB.BASEBOARD_FAB2(SCH_1):PAGE216
    39 VR_PVDDQ_ABC_AIREF1 @BASEBOARD_FAB2_LIB.BASEBOARD_FAB2(SCH_1):VR_PVDDQ_ABC_AIREF1   I102 @BASEBOARD_FAB2_LIB.BASEBOARD_FAB2(SCH_1):PAGE216
    10 VR_PVDDQ_ABC_PH1_SW @BASEBOARD_FAB2_LIB.BASEBOARD_FAB2(SCH_1):VR_PVDDQ_ABC_PH1_SW   I102 @BASEBOARD_FAB2_LIB.BASEBOARD_FAB2(SCH_1):PAGE216
    36 A_TSENSE_PVDDQ_ABC @BASEBOARD_FAB2_LIB.BASEBOARD_FAB2(SCH_1):A_TSENSE_PVDDQ_ABC   I102 @BASEBOARD_FAB2_LIB.BASEBOARD_FAB2(SCH_1):PAGE216
     3 VR_PVDDQ_ABC_PH1_VCIN @BASEBOARD_FAB2_LIB.BASEBOARD_FAB2(SCH_1):VR_PVDDQ_ABC_PH1_VCIN   I102 @BASEBOARD_FAB2_LIB.BASEBOARD_FAB2(SCH_1):PAGE216
     4 P5V_STBY @BASEBOARD_FAB2_LIB.BASEBOARD_FAB2(SCH_1):P5V_STBY   I102 @BASEBOARD_FAB2_LIB.BASEBOARD_FAB2(SCH_1):PAGE216
    30 VR_FET_SW_P12V_STBY_PVDDQ_ABC @BASEBOARD_FAB2_LIB.BASEBOARD_FAB2(SCH_1):VR_FET_SW_P12V_STBY_PVDDQ_ABC   I102 @BASEBOARD_FAB2_LIB.BASEBOARD_FAB2(SCH_1):PAGE216
    25 VR_FET_SW_P12V_STBY_PVDDQ_ABC @BASEBOARD_FAB2_LIB.BASEBOARD_FAB2(SCH_1):VR_FET_SW_P12V_STBY_PVDDQ_ABC   I102 @BASEBOARD_FAB2_LIB.BASEBOARD_FAB2(SCH_1):PAGE216
     1 PVDDQ_ABC @BASEBOARD_FAB2_LIB.BASEBOARD_FAB2(SCH_1):PVDDQ_ABC   I102 @BASEBOARD_FAB2_LIB.BASEBOARD_FAB2(SCH_1):PAGE216

EU7G3 IR354XX_SM-IR35411,IC,H73688-0A
    33 VR_PVDDQ_ABC_PH2_BOOT_R @BASEBOARD_FAB2_LIB.BASEBOARD_FAB2(SCH_1):VR_PVDDQ_ABC_PH2_BOOT_R   I103 @BASEBOARD_FAB2_LIB.BASEBOARD_FAB2(SCH_1):PAGE216
    35 P5V_STBY @BASEBOARD_FAB2_LIB.BASEBOARD_FAB2(SCH_1):P5V_STBY   I103 @BASEBOARD_FAB2_LIB.BASEBOARD_FAB2(SCH_1):PAGE216
    41 TP_PVDDQ_ABC_PH2_GL_1 @BASEBOARD_FAB2_LIB.BASEBOARD_FAB2(SCH_1):TP_PVDDQ_ABC_PH2_GL_1   I103 @BASEBOARD_FAB2_LIB.BASEBOARD_FAB2(SCH_1):PAGE216
     6 TP_PVDDQ_ABC_PH2_GL_0 @BASEBOARD_FAB2_LIB.BASEBOARD_FAB2(SCH_1):TP_PVDDQ_ABC_PH2_GL_0   I103 @BASEBOARD_FAB2_LIB.BASEBOARD_FAB2(SCH_1):PAGE216
    38 ISENSE_PVDDQ_ABC_PH2_IMON @BASEBOARD_FAB2_LIB.BASEBOARD_FAB2(SCH_1):ISENSE_PVDDQ_ABC_PH2_IMON   I103 @BASEBOARD_FAB2_LIB.BASEBOARD_FAB2(SCH_1):PAGE216
     2    GND @BASEBOARD_FAB2_LIB.BASEBOARD_FAB2(SCH_1):GND   I103 @BASEBOARD_FAB2_LIB.BASEBOARD_FAB2(SCH_1):PAGE216
    31     NC     NC   I103 @BASEBOARD_FAB2_LIB.BASEBOARD_FAB2(SCH_1):PAGE216
    37 VR_PVDDQ_ABC_PH2_OCSET @BASEBOARD_FAB2_LIB.BASEBOARD_FAB2(SCH_1):VR_PVDDQ_ABC_PH2_OCSET   I103 @BASEBOARD_FAB2_LIB.BASEBOARD_FAB2(SCH_1):PAGE216
    40    GND @BASEBOARD_FAB2_LIB.BASEBOARD_FAB2(SCH_1):GND   I103 @BASEBOARD_FAB2_LIB.BASEBOARD_FAB2(SCH_1):PAGE216
     7    GND @BASEBOARD_FAB2_LIB.BASEBOARD_FAB2(SCH_1):GND   I103 @BASEBOARD_FAB2_LIB.BASEBOARD_FAB2(SCH_1):PAGE216
     5    GND @BASEBOARD_FAB2_LIB.BASEBOARD_FAB2(SCH_1):GND   I103 @BASEBOARD_FAB2_LIB.BASEBOARD_FAB2(SCH_1):PAGE216
    32 VR_PVDDQ_ABC_PH2_PHASE @BASEBOARD_FAB2_LIB.BASEBOARD_FAB2(SCH_1):VR_PVDDQ_ABC_PH2_PHASE   I103 @BASEBOARD_FAB2_LIB.BASEBOARD_FAB2(SCH_1):PAGE216
    34 VR_PVDDQ_ABC_PWM2 @BASEBOARD_FAB2_LIB.BASEBOARD_FAB2(SCH_1):VR_PVDDQ_ABC_PWM2   I103 @BASEBOARD_FAB2_LIB.BASEBOARD_FAB2(SCH_1):PAGE216
    39 VR_PVDDQ_ABC_AIREF2 @BASEBOARD_FAB2_LIB.BASEBOARD_FAB2(SCH_1):VR_PVDDQ_ABC_AIREF2   I103 @BASEBOARD_FAB2_LIB.BASEBOARD_FAB2(SCH_1):PAGE216
    10 VR_PVDDQ_ABC_PH2_SW @BASEBOARD_FAB2_LIB.BASEBOARD_FAB2(SCH_1):VR_PVDDQ_ABC_PH2_SW   I103 @BASEBOARD_FAB2_LIB.BASEBOARD_FAB2(SCH_1):PAGE216
    36 A_TSENSE_PVDDQ_ABC @BASEBOARD_FAB2_LIB.BASEBOARD_FAB2(SCH_1):A_TSENSE_PVDDQ_ABC   I103 @BASEBOARD_FAB2_LIB.BASEBOARD_FAB2(SCH_1):PAGE216
     3 VR_PVDDQ_ABC_PH2_VCIN @BASEBOARD_FAB2_LIB.BASEBOARD_FAB2(SCH_1):VR_PVDDQ_ABC_PH2_VCIN   I103 @BASEBOARD_FAB2_LIB.BASEBOARD_FAB2(SCH_1):PAGE216
     4 P5V_STBY @BASEBOARD_FAB2_LIB.BASEBOARD_FAB2(SCH_1):P5V_STBY   I103 @BASEBOARD_FAB2_LIB.BASEBOARD_FAB2(SCH_1):PAGE216
    30 VR_FET_SW_P12V_STBY_PVDDQ_ABC @BASEBOARD_FAB2_LIB.BASEBOARD_FAB2(SCH_1):VR_FET_SW_P12V_STBY_PVDDQ_ABC   I103 @BASEBOARD_FAB2_LIB.BASEBOARD_FAB2(SCH_1):PAGE216
    25 VR_FET_SW_P12V_STBY_PVDDQ_ABC @BASEBOARD_FAB2_LIB.BASEBOARD_FAB2(SCH_1):VR_FET_SW_P12V_STBY_PVDDQ_ABC   I103 @BASEBOARD_FAB2_LIB.BASEBOARD_FAB2(SCH_1):PAGE216
     1 PVDDQ_ABC @BASEBOARD_FAB2_LIB.BASEBOARD_FAB2(SCH_1):PVDDQ_ABC   I103 @BASEBOARD_FAB2_LIB.BASEBOARD_FAB2(SCH_1):PAGE216

EU8A1 PXE1110B_QFN-IC,H89187-001
     1     NC     NC   I229 @BASEBOARD_FAB2_LIB.BASEBOARD_FAB2(SCH_1):PAGE235
     2     NC     NC   I229 @BASEBOARD_FAB2_LIB.BASEBOARD_FAB2(SCH_1):PAGE235
     3 VR_P1V05_PCH_STBY_PWM1 @BASEBOARD_FAB2_LIB.BASEBOARD_FAB2(SCH_1):VR_P1V05_PCH_STBY_PWM1   I229 @BASEBOARD_FAB2_LIB.BASEBOARD_FAB2(SCH_1):PAGE235
     4     NC     NC   I229 @BASEBOARD_FAB2_LIB.BASEBOARD_FAB2(SCH_1):PAGE235
     5 VR_PVNN_PCH_PWM1 @BASEBOARD_FAB2_LIB.BASEBOARD_FAB2(SCH_1):VR_PVNN_PCH_PWM1   I229 @BASEBOARD_FAB2_LIB.BASEBOARD_FAB2(SCH_1):PAGE235
     6 SMB_VR_STBY_LVC3_SDA @BASEBOARD_FAB2_LIB.BASEBOARD_FAB2(SCH_1):SMB_VR_STBY_LVC3_SDA   I229 @BASEBOARD_FAB2_LIB.BASEBOARD_FAB2(SCH_1):PAGE235
     7 SMB_VR_STBY_LVC3_SCL @BASEBOARD_FAB2_LIB.BASEBOARD_FAB2(SCH_1):SMB_VR_STBY_LVC3_SCL   I229 @BASEBOARD_FAB2_LIB.BASEBOARD_FAB2(SCH_1):PAGE235
     8     NC     NC   I229 @BASEBOARD_FAB2_LIB.BASEBOARD_FAB2(SCH_1):PAGE235
     9 PWRGD_PVNN_PCH_R @BASEBOARD_FAB2_LIB.BASEBOARD_FAB2(SCH_1):PWRGD_PVNN_PCH_R   I229 @BASEBOARD_FAB2_LIB.BASEBOARD_FAB2(SCH_1):PAGE235
    10 VR_PVNN_PCH_VREN @BASEBOARD_FAB2_LIB.BASEBOARD_FAB2(SCH_1):VR_PVNN_PCH_VREN   I229 @BASEBOARD_FAB2_LIB.BASEBOARD_FAB2(SCH_1):PAGE235
    11 IRQ_PVNN_PCH_VRHOT_N @BASEBOARD_FAB2_LIB.BASEBOARD_FAB2(SCH_1):IRQ_PVNN_PCH_VRHOT_N   I229 @BASEBOARD_FAB2_LIB.BASEBOARD_FAB2(SCH_1):PAGE235
    12 PU_PVNN_PCH_PINALRT_N @BASEBOARD_FAB2_LIB.BASEBOARD_FAB2(SCH_1):PU_PVNN_PCH_PINALRT_N   I229 @BASEBOARD_FAB2_LIB.BASEBOARD_FAB2(SCH_1):PAGE235
    13 VID_PCH_CORE_PVNN_AUX_VID_0 @BASEBOARD_FAB2_LIB.BASEBOARD_FAB2(SCH_1):VID_PCH_CORE_PVNN_AUX_VID_0   I229 @BASEBOARD_FAB2_LIB.BASEBOARD_FAB2(SCH_1):PAGE235
    14 VID_PCH_CORE_PVNN_AUX_VID_1 @BASEBOARD_FAB2_LIB.BASEBOARD_FAB2(SCH_1):VID_PCH_CORE_PVNN_AUX_VID_1   I229 @BASEBOARD_FAB2_LIB.BASEBOARD_FAB2(SCH_1):PAGE235
    15 PU_PVNN_PCH_VCLK @BASEBOARD_FAB2_LIB.BASEBOARD_FAB2(SCH_1):PU_PVNN_PCH_VCLK   I229 @BASEBOARD_FAB2_LIB.BASEBOARD_FAB2(SCH_1):PAGE235
    16 PU_PVNN_PCH_VDIO @BASEBOARD_FAB2_LIB.BASEBOARD_FAB2(SCH_1):PU_PVNN_PCH_VDIO   I229 @BASEBOARD_FAB2_LIB.BASEBOARD_FAB2(SCH_1):PAGE235
    17     NC     NC   I229 @BASEBOARD_FAB2_LIB.BASEBOARD_FAB2(SCH_1):PAGE235
    18     NC     NC   I229 @BASEBOARD_FAB2_LIB.BASEBOARD_FAB2(SCH_1):PAGE235
    19 VR_PVNN_PCH_AVSP @BASEBOARD_FAB2_LIB.BASEBOARD_FAB2(SCH_1):VR_PVNN_PCH_AVSP   I229 @BASEBOARD_FAB2_LIB.BASEBOARD_FAB2(SCH_1):PAGE235
    20 VSENSE_PVNN_PCH_STBY_AVSN @BASEBOARD_FAB2_LIB.BASEBOARD_FAB2(SCH_1):VSENSE_PVNN_PCH_STBY_AVSN   I229 @BASEBOARD_FAB2_LIB.BASEBOARD_FAB2(SCH_1):PAGE235
    21 VR_PVNN_PCH_AIREF1 @BASEBOARD_FAB2_LIB.BASEBOARD_FAB2(SCH_1):VR_PVNN_PCH_AIREF1   I229 @BASEBOARD_FAB2_LIB.BASEBOARD_FAB2(SCH_1):PAGE235
    22 ISENSE_PVNN_PCH_PH1_IMON @BASEBOARD_FAB2_LIB.BASEBOARD_FAB2(SCH_1):ISENSE_PVNN_PCH_PH1_IMON   I229 @BASEBOARD_FAB2_LIB.BASEBOARD_FAB2(SCH_1):PAGE235
    23    GND @BASEBOARD_FAB2_LIB.BASEBOARD_FAB2(SCH_1):GND   I229 @BASEBOARD_FAB2_LIB.BASEBOARD_FAB2(SCH_1):PAGE235
    24     NC     NC   I229 @BASEBOARD_FAB2_LIB.BASEBOARD_FAB2(SCH_1):PAGE235
    25 VR_P1V05_PCH_BIREF1 @BASEBOARD_FAB2_LIB.BASEBOARD_FAB2(SCH_1):VR_P1V05_PCH_BIREF1   I229 @BASEBOARD_FAB2_LIB.BASEBOARD_FAB2(SCH_1):PAGE235
    26 ISENSE_P1V05_PCH_STBY_PH1_IMON @BASEBOARD_FAB2_LIB.BASEBOARD_FAB2(SCH_1):ISENSE_P1V05_PCH_STBY_PH1_IMON   I229 @BASEBOARD_FAB2_LIB.BASEBOARD_FAB2(SCH_1):PAGE235
    27    GND @BASEBOARD_FAB2_LIB.BASEBOARD_FAB2(SCH_1):GND   I229 @BASEBOARD_FAB2_LIB.BASEBOARD_FAB2(SCH_1):PAGE235
    28     NC     NC   I229 @BASEBOARD_FAB2_LIB.BASEBOARD_FAB2(SCH_1):PAGE235
    29 VR_P1V05_PCH_STBY_AVSP @BASEBOARD_FAB2_LIB.BASEBOARD_FAB2(SCH_1):VR_P1V05_PCH_STBY_AVSP   I229 @BASEBOARD_FAB2_LIB.BASEBOARD_FAB2(SCH_1):PAGE235
    30 VSENSE_P1V05_PCH_STBY_AVSN @BASEBOARD_FAB2_LIB.BASEBOARD_FAB2(SCH_1):VSENSE_P1V05_PCH_STBY_AVSN   I229 @BASEBOARD_FAB2_LIB.BASEBOARD_FAB2(SCH_1):PAGE235
    31     NC     NC   I229 @BASEBOARD_FAB2_LIB.BASEBOARD_FAB2(SCH_1):PAGE235
    32 PU_VR_PVNN_PCH_FAULT1 @BASEBOARD_FAB2_LIB.BASEBOARD_FAB2(SCH_1):PU_VR_PVNN_PCH_FAULT1   I229 @BASEBOARD_FAB2_LIB.BASEBOARD_FAB2(SCH_1):PAGE235
    33 VR_PVNN_PCH_XADDR2 @BASEBOARD_FAB2_LIB.BASEBOARD_FAB2(SCH_1):VR_PVNN_PCH_XADDR2   I229 @BASEBOARD_FAB2_LIB.BASEBOARD_FAB2(SCH_1):PAGE235
    34 A_TSENSE_P1V05_PCH_STBY_TMON @BASEBOARD_FAB2_LIB.BASEBOARD_FAB2(SCH_1):A_TSENSE_P1V05_PCH_STBY_TMON   I229 @BASEBOARD_FAB2_LIB.BASEBOARD_FAB2(SCH_1):PAGE235
    35 A_TSENSE_PVNN_PCH_TMON @BASEBOARD_FAB2_LIB.BASEBOARD_FAB2(SCH_1):A_TSENSE_PVNN_PCH_TMON   I229 @BASEBOARD_FAB2_LIB.BASEBOARD_FAB2(SCH_1):PAGE235
    36 VR_PVNN_PCH_XADDR1 @BASEBOARD_FAB2_LIB.BASEBOARD_FAB2(SCH_1):VR_PVNN_PCH_XADDR1   I229 @BASEBOARD_FAB2_LIB.BASEBOARD_FAB2(SCH_1):PAGE235
    37 VR_PVNN_PCH_VINSEN @BASEBOARD_FAB2_LIB.BASEBOARD_FAB2(SCH_1):VR_PVNN_PCH_VINSEN   I229 @BASEBOARD_FAB2_LIB.BASEBOARD_FAB2(SCH_1):PAGE235
    38     NC     NC   I229 @BASEBOARD_FAB2_LIB.BASEBOARD_FAB2(SCH_1):PAGE235
    39 VR_PVNN_PCH_VDD @BASEBOARD_FAB2_LIB.BASEBOARD_FAB2(SCH_1):VR_PVNN_PCH_VDD   I229 @BASEBOARD_FAB2_LIB.BASEBOARD_FAB2(SCH_1):PAGE235
    40 VR_PVNN_P1V05_PCH_VD12 @BASEBOARD_FAB2_LIB.BASEBOARD_FAB2(SCH_1):VR_PVNN_P1V05_PCH_VD12   I229 @BASEBOARD_FAB2_LIB.BASEBOARD_FAB2(SCH_1):PAGE235
    41    GND @BASEBOARD_FAB2_LIB.BASEBOARD_FAB2(SCH_1):GND   I229 @BASEBOARD_FAB2_LIB.BASEBOARD_FAB2(SCH_1):PAGE235

EU8A2 RT9059_DFN-IC,H65765-001
     4 VR_P1V8_PCH_STBY_FB @BASEBOARD_FAB2_LIB.BASEBOARD_FAB2(SCH_1):VR_P1V8_PCH_STBY_FB    I86 @BASEBOARD_FAB2_LIB.BASEBOARD_FAB2(SCH_1):PAGE237
     6 PWRGD_P3V3_STBY @BASEBOARD_FAB2_LIB.BASEBOARD_FAB2(SCH_1):PWRGD_P3V3_STBY    I86 @BASEBOARD_FAB2_LIB.BASEBOARD_FAB2(SCH_1):PAGE237
    11    GND @BASEBOARD_FAB2_LIB.BASEBOARD_FAB2(SCH_1):GND    I86 @BASEBOARD_FAB2_LIB.BASEBOARD_FAB2(SCH_1):PAGE237
     5 PWRGD_P1V8_PCH_STBY_R @BASEBOARD_FAB2_LIB.BASEBOARD_FAB2(SCH_1):PWRGD_P1V8_PCH_STBY_R    I86 @BASEBOARD_FAB2_LIB.BASEBOARD_FAB2(SCH_1):PAGE237
    10 P3V3_STBY @BASEBOARD_FAB2_LIB.BASEBOARD_FAB2(SCH_1):P3V3_STBY    I86 @BASEBOARD_FAB2_LIB.BASEBOARD_FAB2(SCH_1):PAGE237
     9 P3V3_STBY @BASEBOARD_FAB2_LIB.BASEBOARD_FAB2(SCH_1):P3V3_STBY    I86 @BASEBOARD_FAB2_LIB.BASEBOARD_FAB2(SCH_1):PAGE237
     8 P3V3_STBY @BASEBOARD_FAB2_LIB.BASEBOARD_FAB2(SCH_1):P3V3_STBY    I86 @BASEBOARD_FAB2_LIB.BASEBOARD_FAB2(SCH_1):PAGE237
     7 P3V3_STBY @BASEBOARD_FAB2_LIB.BASEBOARD_FAB2(SCH_1):P3V3_STBY    I86 @BASEBOARD_FAB2_LIB.BASEBOARD_FAB2(SCH_1):PAGE237
     3 P1V8_PCH_STBY @BASEBOARD_FAB2_LIB.BASEBOARD_FAB2(SCH_1):P1V8_PCH_STBY    I86 @BASEBOARD_FAB2_LIB.BASEBOARD_FAB2(SCH_1):PAGE237
     2 P1V8_PCH_STBY @BASEBOARD_FAB2_LIB.BASEBOARD_FAB2(SCH_1):P1V8_PCH_STBY    I86 @BASEBOARD_FAB2_LIB.BASEBOARD_FAB2(SCH_1):PAGE237
     1 P1V8_PCH_STBY @BASEBOARD_FAB2_LIB.BASEBOARD_FAB2(SCH_1):P1V8_PCH_STBY    I86 @BASEBOARD_FAB2_LIB.BASEBOARD_FAB2(SCH_1):PAGE237

EU8B1 SLG55021_SM-IC,G56246-001
     4    GND @BASEBOARD_FAB2_LIB.BASEBOARD_FAB2(SCH_1):GND    I13 @BASEBOARD_FAB2_LIB.BASEBOARD_FAB2(SCH_1):PAGE198
     9    GND @BASEBOARD_FAB2_LIB.BASEBOARD_FAB2(SCH_1):GND    I13 @BASEBOARD_FAB2_LIB.BASEBOARD_FAB2(SCH_1):PAGE198
     1 P5V_STBY @BASEBOARD_FAB2_LIB.BASEBOARD_FAB2(SCH_1):P5V_STBY    I13 @BASEBOARD_FAB2_LIB.BASEBOARD_FAB2(SCH_1):PAGE198
     2 FM_CTNR_PS_ON @BASEBOARD_FAB2_LIB.BASEBOARD_FAB2(SCH_1):FM_CTNR_PS_ON    I13 @BASEBOARD_FAB2_LIB.BASEBOARD_FAB2(SCH_1):PAGE198
     3 P5V_STBY @BASEBOARD_FAB2_LIB.BASEBOARD_FAB2(SCH_1):P5V_STBY    I13 @BASEBOARD_FAB2_LIB.BASEBOARD_FAB2(SCH_1):PAGE198
     5 P5V_STBY @BASEBOARD_FAB2_LIB.BASEBOARD_FAB2(SCH_1):P5V_STBY    I13 @BASEBOARD_FAB2_LIB.BASEBOARD_FAB2(SCH_1):PAGE198
     6    P5V @BASEBOARD_FAB2_LIB.BASEBOARD_FAB2(SCH_1):P5V    I13 @BASEBOARD_FAB2_LIB.BASEBOARD_FAB2(SCH_1):PAGE198
     7 P5V_SWITCH_G @BASEBOARD_FAB2_LIB.BASEBOARD_FAB2(SCH_1):P5V_SWITCH_G    I13 @BASEBOARD_FAB2_LIB.BASEBOARD_FAB2(SCH_1):PAGE198
     8 TP_SLG55021_P5V_8 @BASEBOARD_FAB2_LIB.BASEBOARD_FAB2(SCH_1):TP_SLG55021_P5V_8    I13 @BASEBOARD_FAB2_LIB.BASEBOARD_FAB2(SCH_1):PAGE198

EU8E1 CSD87384M_SM-IC,H66258-001
     4 VR_P3V3_STBY_LGATE @BASEBOARD_FAB2_LIB.BASEBOARD_FAB2(SCH_1):VR_P3V3_STBY_LGATE   I170 @BASEBOARD_FAB2_LIB.BASEBOARD_FAB2(SCH_1):PAGE240
     3    GND @BASEBOARD_FAB2_LIB.BASEBOARD_FAB2(SCH_1):GND   I170 @BASEBOARD_FAB2_LIB.BASEBOARD_FAB2(SCH_1):PAGE240
     1 VR_P3V3_STBY_UGATE @BASEBOARD_FAB2_LIB.BASEBOARD_FAB2(SCH_1):VR_P3V3_STBY_UGATE   I170 @BASEBOARD_FAB2_LIB.BASEBOARD_FAB2(SCH_1):PAGE240
     2 VR_FET_SW_P12V_STBY_P3V3_STBY @BASEBOARD_FAB2_LIB.BASEBOARD_FAB2(SCH_1):VR_FET_SW_P12V_STBY_P3V3_STBY   I170 @BASEBOARD_FAB2_LIB.BASEBOARD_FAB2(SCH_1):PAGE240
     5 VR_P3V3_STBY_PHASE @BASEBOARD_FAB2_LIB.BASEBOARD_FAB2(SCH_1):VR_P3V3_STBY_PHASE   I170 @BASEBOARD_FAB2_LIB.BASEBOARD_FAB2(SCH_1):PAGE240

EU8F1 RT8240_QFN-IC,H66262-001
     4 VR_P3V3_STBY_BOOT @BASEBOARD_FAB2_LIB.BASEBOARD_FAB2(SCH_1):VR_P3V3_STBY_BOOT   I125 @BASEBOARD_FAB2_LIB.BASEBOARD_FAB2(SCH_1):PAGE240
    10 VR_P3V3_STBY_OCSELECT @BASEBOARD_FAB2_LIB.BASEBOARD_FAB2(SCH_1):VR_P3V3_STBY_OCSELECT   I125 @BASEBOARD_FAB2_LIB.BASEBOARD_FAB2(SCH_1):PAGE240
     8 VR_P3V3_STBY_EN @BASEBOARD_FAB2_LIB.BASEBOARD_FAB2(SCH_1):VR_P3V3_STBY_EN   I125 @BASEBOARD_FAB2_LIB.BASEBOARD_FAB2(SCH_1):PAGE240
    11 AGND_P3V3_STBY @BASEBOARD_FAB2_LIB.BASEBOARD_FAB2(SCH_1):AGND_P3V3_STBY   I125 @BASEBOARD_FAB2_LIB.BASEBOARD_FAB2(SCH_1):PAGE240
    13 AGND_P3V3_STBY @BASEBOARD_FAB2_LIB.BASEBOARD_FAB2(SCH_1):AGND_P3V3_STBY   I125 @BASEBOARD_FAB2_LIB.BASEBOARD_FAB2(SCH_1):PAGE240
    12 AGND_P3V3_STBY @BASEBOARD_FAB2_LIB.BASEBOARD_FAB2(SCH_1):AGND_P3V3_STBY   I125 @BASEBOARD_FAB2_LIB.BASEBOARD_FAB2(SCH_1):PAGE240
     1 VR_P3V3_STBY_LGATE @BASEBOARD_FAB2_LIB.BASEBOARD_FAB2(SCH_1):VR_P3V3_STBY_LGATE   I125 @BASEBOARD_FAB2_LIB.BASEBOARD_FAB2(SCH_1):PAGE240
     9 PWRGD_P3V3_STBY_R @BASEBOARD_FAB2_LIB.BASEBOARD_FAB2(SCH_1):PWRGD_P3V3_STBY_R   I125 @BASEBOARD_FAB2_LIB.BASEBOARD_FAB2(SCH_1):PAGE240
     2 VR_P3V3_STBY_PHASE @BASEBOARD_FAB2_LIB.BASEBOARD_FAB2(SCH_1):VR_P3V3_STBY_PHASE   I125 @BASEBOARD_FAB2_LIB.BASEBOARD_FAB2(SCH_1):PAGE240
     7 VSENSE_RGND_P3V3_STBY @BASEBOARD_FAB2_LIB.BASEBOARD_FAB2(SCH_1):VSENSE_RGND_P3V3_STBY   I125 @BASEBOARD_FAB2_LIB.BASEBOARD_FAB2(SCH_1):PAGE240
     3 VR_P3V3_STBY_UGATE @BASEBOARD_FAB2_LIB.BASEBOARD_FAB2(SCH_1):VR_P3V3_STBY_UGATE   I125 @BASEBOARD_FAB2_LIB.BASEBOARD_FAB2(SCH_1):PAGE240
     5 P5V_STBY @BASEBOARD_FAB2_LIB.BASEBOARD_FAB2(SCH_1):P5V_STBY   I125 @BASEBOARD_FAB2_LIB.BASEBOARD_FAB2(SCH_1):PAGE240
     6 VSENSE_VOUT_P3V3_STBY @BASEBOARD_FAB2_LIB.BASEBOARD_FAB2(SCH_1):VSENSE_VOUT_P3V3_STBY   I125 @BASEBOARD_FAB2_LIB.BASEBOARD_FAB2(SCH_1):PAGE240

EU8F2 ICS9FGP204_MLFP-IC,E95226-001
    12 P3V3_STBY_MNG @BASEBOARD_FAB2_LIB.BASEBOARD_FAB2(SCH_1):P3V3_STBY_MNG    I34 @BASEBOARD_FAB2_LIB.BASEBOARD_FAB2(SCH_1):PAGE101
    13 CLK_32K_SUSCLK_PLD_R @BASEBOARD_FAB2_LIB.BASEBOARD_FAB2(SCH_1):CLK_32K_SUSCLK_PLD_R    I34 @BASEBOARD_FAB2_LIB.BASEBOARD_FAB2(SCH_1):PAGE101
    14    GND @BASEBOARD_FAB2_LIB.BASEBOARD_FAB2(SCH_1):GND    I34 @BASEBOARD_FAB2_LIB.BASEBOARD_FAB2(SCH_1):PAGE101
    16 CLK_25M_BMC_R @BASEBOARD_FAB2_LIB.BASEBOARD_FAB2(SCH_1):CLK_25M_BMC_R    I34 @BASEBOARD_FAB2_LIB.BASEBOARD_FAB2(SCH_1):PAGE101
    17 CLK_25M_CPLD_R @BASEBOARD_FAB2_LIB.BASEBOARD_FAB2(SCH_1):CLK_25M_CPLD_R    I34 @BASEBOARD_FAB2_LIB.BASEBOARD_FAB2(SCH_1):PAGE101
    32 CLK_50M_CKMNG_BMC_1_R @BASEBOARD_FAB2_LIB.BASEBOARD_FAB2(SCH_1):CLK_50M_CKMNG_BMC_1_R    I34 @BASEBOARD_FAB2_LIB.BASEBOARD_FAB2(SCH_1):PAGE101
    29 CLK_50M_CKMNG_BMC_2_R @BASEBOARD_FAB2_LIB.BASEBOARD_FAB2(SCH_1):CLK_50M_CKMNG_BMC_2_R    I34 @BASEBOARD_FAB2_LIB.BASEBOARD_FAB2(SCH_1):PAGE101
    24 TP_CLK5_50M_CKMNG @BASEBOARD_FAB2_LIB.BASEBOARD_FAB2(SCH_1):TP_CLK5_50M_CKMNG    I34 @BASEBOARD_FAB2_LIB.BASEBOARD_FAB2(SCH_1):PAGE101
    25 CLK_50M_CKMNG_PCH_10GBE_R @BASEBOARD_FAB2_LIB.BASEBOARD_FAB2(SCH_1):CLK_50M_CKMNG_PCH_10GBE_R    I34 @BASEBOARD_FAB2_LIB.BASEBOARD_FAB2(SCH_1):PAGE101
    28 CLK_50M_CKMNG_SPRVLLE_R @BASEBOARD_FAB2_LIB.BASEBOARD_FAB2(SCH_1):CLK_50M_CKMNG_SPRVLLE_R    I34 @BASEBOARD_FAB2_LIB.BASEBOARD_FAB2(SCH_1):PAGE101
    33 CLK_50M_CKMNG_OCP_R @BASEBOARD_FAB2_LIB.BASEBOARD_FAB2(SCH_1):CLK_50M_CKMNG_OCP_R    I34 @BASEBOARD_FAB2_LIB.BASEBOARD_FAB2(SCH_1):PAGE101
    41    GND @BASEBOARD_FAB2_LIB.BASEBOARD_FAB2(SCH_1):GND    I34 @BASEBOARD_FAB2_LIB.BASEBOARD_FAB2(SCH_1):PAGE101
    21    GND @BASEBOARD_FAB2_LIB.BASEBOARD_FAB2(SCH_1):GND    I34 @BASEBOARD_FAB2_LIB.BASEBOARD_FAB2(SCH_1):PAGE101
     1    GND @BASEBOARD_FAB2_LIB.BASEBOARD_FAB2(SCH_1):GND    I34 @BASEBOARD_FAB2_LIB.BASEBOARD_FAB2(SCH_1):PAGE101
     4 TP_CLK_96M_CKMNG_N @BASEBOARD_FAB2_LIB.BASEBOARD_FAB2(SCH_1):TP_CLK_96M_CKMNG_N    I34 @BASEBOARD_FAB2_LIB.BASEBOARD_FAB2(SCH_1):PAGE101
     3 TP_CLK_96M_CKMNG_P @BASEBOARD_FAB2_LIB.BASEBOARD_FAB2(SCH_1):TP_CLK_96M_CKMNG_P    I34 @BASEBOARD_FAB2_LIB.BASEBOARD_FAB2(SCH_1):PAGE101
     8 TP_CLK_100M_R_DN @BASEBOARD_FAB2_LIB.BASEBOARD_FAB2(SCH_1):TP_CLK_100M_R_DN    I34 @BASEBOARD_FAB2_LIB.BASEBOARD_FAB2(SCH_1):PAGE101
    18    GND @BASEBOARD_FAB2_LIB.BASEBOARD_FAB2(SCH_1):GND    I34 @BASEBOARD_FAB2_LIB.BASEBOARD_FAB2(SCH_1):PAGE101
     7 TP_CLK_100M_R_DP @BASEBOARD_FAB2_LIB.BASEBOARD_FAB2(SCH_1):TP_CLK_100M_R_DP    I34 @BASEBOARD_FAB2_LIB.BASEBOARD_FAB2(SCH_1):PAGE101
    15 P3V3_STBY_MNG @BASEBOARD_FAB2_LIB.BASEBOARD_FAB2(SCH_1):P3V3_STBY_MNG    I34 @BASEBOARD_FAB2_LIB.BASEBOARD_FAB2(SCH_1):PAGE101
    11 A_COMP_CKMNG @BASEBOARD_FAB2_LIB.BASEBOARD_FAB2(SCH_1):A_COMP_CKMNG    I34 @BASEBOARD_FAB2_LIB.BASEBOARD_FAB2(SCH_1):PAGE101
    19 XTAL_CK_MNG_IN @BASEBOARD_FAB2_LIB.BASEBOARD_FAB2(SCH_1):XTAL_CK_MNG_IN    I34 @BASEBOARD_FAB2_LIB.BASEBOARD_FAB2(SCH_1):PAGE101
    27    GND @BASEBOARD_FAB2_LIB.BASEBOARD_FAB2(SCH_1):GND    I34 @BASEBOARD_FAB2_LIB.BASEBOARD_FAB2(SCH_1):PAGE101
    26 P3V3_STBY_MNG_RMII @BASEBOARD_FAB2_LIB.BASEBOARD_FAB2(SCH_1):P3V3_STBY_MNG_RMII    I34 @BASEBOARD_FAB2_LIB.BASEBOARD_FAB2(SCH_1):PAGE101
    31 P3V3_STBY_MNG_RMII @BASEBOARD_FAB2_LIB.BASEBOARD_FAB2(SCH_1):P3V3_STBY_MNG_RMII    I34 @BASEBOARD_FAB2_LIB.BASEBOARD_FAB2(SCH_1):PAGE101
    30    GND @BASEBOARD_FAB2_LIB.BASEBOARD_FAB2(SCH_1):GND    I34 @BASEBOARD_FAB2_LIB.BASEBOARD_FAB2(SCH_1):PAGE101
    22 PU_33P_33M_SMBADR @BASEBOARD_FAB2_LIB.BASEBOARD_FAB2(SCH_1):PU_33P_33M_SMBADR    I34 @BASEBOARD_FAB2_LIB.BASEBOARD_FAB2(SCH_1):PAGE101
    23 P3V3_STBY_MNG @BASEBOARD_FAB2_LIB.BASEBOARD_FAB2(SCH_1):P3V3_STBY_MNG    I34 @BASEBOARD_FAB2_LIB.BASEBOARD_FAB2(SCH_1):PAGE101
     5 PD_CKMNG_OE @BASEBOARD_FAB2_LIB.BASEBOARD_FAB2(SCH_1):PD_CKMNG_OE    I34 @BASEBOARD_FAB2_LIB.BASEBOARD_FAB2(SCH_1):PAGE101
     2 P3V3_STBY_MNG @BASEBOARD_FAB2_LIB.BASEBOARD_FAB2(SCH_1):P3V3_STBY_MNG    I34 @BASEBOARD_FAB2_LIB.BASEBOARD_FAB2(SCH_1):PAGE101
     6 PD_CKMNG_OE @BASEBOARD_FAB2_LIB.BASEBOARD_FAB2(SCH_1):PD_CKMNG_OE    I34 @BASEBOARD_FAB2_LIB.BASEBOARD_FAB2(SCH_1):PAGE101
    10    GND @BASEBOARD_FAB2_LIB.BASEBOARD_FAB2(SCH_1):GND    I34 @BASEBOARD_FAB2_LIB.BASEBOARD_FAB2(SCH_1):PAGE101
     9 P3V3_STBY_MNG_CPU @BASEBOARD_FAB2_LIB.BASEBOARD_FAB2(SCH_1):P3V3_STBY_MNG_CPU    I34 @BASEBOARD_FAB2_LIB.BASEBOARD_FAB2(SCH_1):PAGE101
    40 PWRGD_P3V3_STBY @BASEBOARD_FAB2_LIB.BASEBOARD_FAB2(SCH_1):PWRGD_P3V3_STBY    I34 @BASEBOARD_FAB2_LIB.BASEBOARD_FAB2(SCH_1):PAGE101
    38 SMB_HOST_STBY_LVC3_SCL_R4 @BASEBOARD_FAB2_LIB.BASEBOARD_FAB2(SCH_1):SMB_HOST_STBY_LVC3_SCL_R4    I34 @BASEBOARD_FAB2_LIB.BASEBOARD_FAB2(SCH_1):PAGE101
    20 XTAL_CK_MNG_OUT_R @BASEBOARD_FAB2_LIB.BASEBOARD_FAB2(SCH_1):XTAL_CK_MNG_OUT_R    I34 @BASEBOARD_FAB2_LIB.BASEBOARD_FAB2(SCH_1):PAGE101
    39 SMB_HOST_STBY_LVC3_SDA_R4 @BASEBOARD_FAB2_LIB.BASEBOARD_FAB2(SCH_1):SMB_HOST_STBY_LVC3_SDA_R4    I34 @BASEBOARD_FAB2_LIB.BASEBOARD_FAB2(SCH_1):PAGE101
    34 P3V3_STBY_MNG_RGMII @BASEBOARD_FAB2_LIB.BASEBOARD_FAB2(SCH_1):P3V3_STBY_MNG_RGMII    I34 @BASEBOARD_FAB2_LIB.BASEBOARD_FAB2(SCH_1):PAGE101
    35    GND @BASEBOARD_FAB2_LIB.BASEBOARD_FAB2(SCH_1):GND    I34 @BASEBOARD_FAB2_LIB.BASEBOARD_FAB2(SCH_1):PAGE101
    37 TP_CLK_125M_BMCA @BASEBOARD_FAB2_LIB.BASEBOARD_FAB2(SCH_1):TP_CLK_125M_BMCA    I34 @BASEBOARD_FAB2_LIB.BASEBOARD_FAB2(SCH_1):PAGE101
    36 TP_CLK_125M @BASEBOARD_FAB2_LIB.BASEBOARD_FAB2(SCH_1):TP_CLK_125M    I34 @BASEBOARD_FAB2_LIB.BASEBOARD_FAB2(SCH_1):PAGE101

EU9E1 SPRINGVILLE_SM1-IC,G47144-004
    37 A_CBOT @BASEBOARD_FAB2_LIB.BASEBOARD_FAB2(SCH_1):A_CBOT    I72 @BASEBOARD_FAB2_LIB.BASEBOARD_FAB2(SCH_1):PAGE139
    40 A_CTOP @BASEBOARD_FAB2_LIB.BASEBOARD_FAB2(SCH_1):A_CTOP    I72 @BASEBOARD_FAB2_LIB.BASEBOARD_FAB2(SCH_1):PAGE139
    28 PU_DEV_OFF_N @BASEBOARD_FAB2_LIB.BASEBOARD_FAB2(SCH_1):PU_DEV_OFF_N    I72 @BASEBOARD_FAB2_LIB.BASEBOARD_FAB2(SCH_1):PAGE139
    65    GND @BASEBOARD_FAB2_LIB.BASEBOARD_FAB2(SCH_1):GND    I72 @BASEBOARD_FAB2_LIB.BASEBOARD_FAB2(SCH_1):PAGE139
    19 PU_JTAG_SPRV_TCK @BASEBOARD_FAB2_LIB.BASEBOARD_FAB2(SCH_1):PU_JTAG_SPRV_TCK    I72 @BASEBOARD_FAB2_LIB.BASEBOARD_FAB2(SCH_1):PAGE139
    29 PU_JTAG_SPRV_TDI @BASEBOARD_FAB2_LIB.BASEBOARD_FAB2(SCH_1):PU_JTAG_SPRV_TDI    I72 @BASEBOARD_FAB2_LIB.BASEBOARD_FAB2(SCH_1):PAGE139
     4 PU_JTAG_SPRV_TDO @BASEBOARD_FAB2_LIB.BASEBOARD_FAB2(SCH_1):PU_JTAG_SPRV_TDO    I72 @BASEBOARD_FAB2_LIB.BASEBOARD_FAB2(SCH_1):PAGE139
    18 PU_JTAG_SPRV_TMS @BASEBOARD_FAB2_LIB.BASEBOARD_FAB2(SCH_1):PU_JTAG_SPRV_TMS    I72 @BASEBOARD_FAB2_LIB.BASEBOARD_FAB2(SCH_1):PAGE139
     1 PU_SPRV_LAN_PWR_GOOD @BASEBOARD_FAB2_LIB.BASEBOARD_FAB2(SCH_1):PU_SPRV_LAN_PWR_GOOD    I72 @BASEBOARD_FAB2_LIB.BASEBOARD_FAB2(SCH_1):PAGE139
    31 LED_LAN_0_N @BASEBOARD_FAB2_LIB.BASEBOARD_FAB2(SCH_1):LED_LAN_0_N    I72 @BASEBOARD_FAB2_LIB.BASEBOARD_FAB2(SCH_1):PAGE139
    30 LED_LAN_1_N @BASEBOARD_FAB2_LIB.BASEBOARD_FAB2(SCH_1):LED_LAN_1_N    I72 @BASEBOARD_FAB2_LIB.BASEBOARD_FAB2(SCH_1):PAGE139
    33 LED_LAN_2_N @BASEBOARD_FAB2_LIB.BASEBOARD_FAB2(SCH_1):LED_LAN_2_N    I72 @BASEBOARD_FAB2_LIB.BASEBOARD_FAB2(SCH_1):PAGE139
    57 NIC_MDI_SPRV_RJ45_0_DN @BASEBOARD_FAB2_LIB.BASEBOARD_FAB2(SCH_1):NIC_MDI_SPRV_RJ45_0_DN    I72 @BASEBOARD_FAB2_LIB.BASEBOARD_FAB2(SCH_1):PAGE139
    54 NIC_MDI_SPRV_RJ45_1_DN @BASEBOARD_FAB2_LIB.BASEBOARD_FAB2(SCH_1):NIC_MDI_SPRV_RJ45_1_DN    I72 @BASEBOARD_FAB2_LIB.BASEBOARD_FAB2(SCH_1):PAGE139
    52 NIC_SET_N_MDI_2_DN @BASEBOARD_FAB2_LIB.BASEBOARD_FAB2(SCH_1):NIC_SET_N_MDI_2_DN    I72 @BASEBOARD_FAB2_LIB.BASEBOARD_FAB2(SCH_1):PAGE139
    49 NIC_SER_N_MDI_3_DN @BASEBOARD_FAB2_LIB.BASEBOARD_FAB2(SCH_1):NIC_SER_N_MDI_3_DN    I72 @BASEBOARD_FAB2_LIB.BASEBOARD_FAB2(SCH_1):PAGE139
    58 NIC_MDI_SPRV_RJ45_0_DP @BASEBOARD_FAB2_LIB.BASEBOARD_FAB2(SCH_1):NIC_MDI_SPRV_RJ45_0_DP    I72 @BASEBOARD_FAB2_LIB.BASEBOARD_FAB2(SCH_1):PAGE139
    55 NIC_MDI_SPRV_RJ45_1_DP @BASEBOARD_FAB2_LIB.BASEBOARD_FAB2(SCH_1):NIC_MDI_SPRV_RJ45_1_DP    I72 @BASEBOARD_FAB2_LIB.BASEBOARD_FAB2(SCH_1):PAGE139
    53 NIC_SET_P_MDI_2_DP @BASEBOARD_FAB2_LIB.BASEBOARD_FAB2(SCH_1):NIC_SET_P_MDI_2_DP    I72 @BASEBOARD_FAB2_LIB.BASEBOARD_FAB2(SCH_1):PAGE139
    50 NIC_SER_P_MDI_3_DP @BASEBOARD_FAB2_LIB.BASEBOARD_FAB2(SCH_1):NIC_SER_P_MDI_3_DP    I72 @BASEBOARD_FAB2_LIB.BASEBOARD_FAB2(SCH_1):PAGE139
    22     NC     NC    I72 @BASEBOARD_FAB2_LIB.BASEBOARD_FAB2(SCH_1):PAGE139
    43 RMII_PCH_SPRNGVLLE_ARB_OUT @BASEBOARD_FAB2_LIB.BASEBOARD_FAB2(SCH_1):RMII_PCH_SPRNGVLLE_ARB_OUT    I72 @BASEBOARD_FAB2_LIB.BASEBOARD_FAB2(SCH_1):PAGE139
    44 RMII_PCH_SPRNGVLLE_ARB_IN_R @BASEBOARD_FAB2_LIB.BASEBOARD_FAB2(SCH_1):RMII_PCH_SPRNGVLLE_ARB_IN_R    I72 @BASEBOARD_FAB2_LIB.BASEBOARD_FAB2(SCH_1):PAGE139
     2 CLK_50M_CKMNG_SPRVLLE @BASEBOARD_FAB2_LIB.BASEBOARD_FAB2(SCH_1):CLK_50M_CKMNG_SPRVLLE    I72 @BASEBOARD_FAB2_LIB.BASEBOARD_FAB2(SCH_1):PAGE139
     3 RMII_BMC_PCH_SPRNGVLLE_CRSDV_R @BASEBOARD_FAB2_LIB.BASEBOARD_FAB2(SCH_1):RMII_BMC_PCH_SPRNGVLLE_CRSDV_R    I72 @BASEBOARD_FAB2_LIB.BASEBOARD_FAB2(SCH_1):PAGE139
     6 RMII_SPRNGVLLE_BMC_PCH_RXD0_R @BASEBOARD_FAB2_LIB.BASEBOARD_FAB2(SCH_1):RMII_SPRNGVLLE_BMC_PCH_RXD0_R    I72 @BASEBOARD_FAB2_LIB.BASEBOARD_FAB2(SCH_1):PAGE139
     5 RMII_SPRNGVLLE_BMC_PCH_RXD1_R @BASEBOARD_FAB2_LIB.BASEBOARD_FAB2(SCH_1):RMII_SPRNGVLLE_BMC_PCH_RXD1_R    I72 @BASEBOARD_FAB2_LIB.BASEBOARD_FAB2(SCH_1):PAGE139
     9 RMII_BMC_PCH_SPRNGVLLE_TXD0 @BASEBOARD_FAB2_LIB.BASEBOARD_FAB2(SCH_1):RMII_BMC_PCH_SPRNGVLLE_TXD0    I72 @BASEBOARD_FAB2_LIB.BASEBOARD_FAB2(SCH_1):PAGE139
     8 RMII_BMC_PCH_SPRNGVLLE_TXD1 @BASEBOARD_FAB2_LIB.BASEBOARD_FAB2(SCH_1):RMII_BMC_PCH_SPRNGVLLE_TXD1    I72 @BASEBOARD_FAB2_LIB.BASEBOARD_FAB2(SCH_1):PAGE139
     7 RMII_BMC_PCH_SPRNGVLLE_TXEN @BASEBOARD_FAB2_LIB.BASEBOARD_FAB2(SCH_1):RMII_BMC_PCH_SPRNGVLLE_TXEN    I72 @BASEBOARD_FAB2_LIB.BASEBOARD_FAB2(SCH_1):PAGE139
    15 SPI_NIC_CS_R_N @BASEBOARD_FAB2_LIB.BASEBOARD_FAB2(SCH_1):SPI_NIC_CS_R_N    I72 @BASEBOARD_FAB2_LIB.BASEBOARD_FAB2(SCH_1):PAGE139
    12 SPI_NIC_MOSI_R @BASEBOARD_FAB2_LIB.BASEBOARD_FAB2(SCH_1):SPI_NIC_MOSI_R    I72 @BASEBOARD_FAB2_LIB.BASEBOARD_FAB2(SCH_1):PAGE139
    13 SPI_NIC_SCLK_R @BASEBOARD_FAB2_LIB.BASEBOARD_FAB2(SCH_1):SPI_NIC_SCLK_R    I72 @BASEBOARD_FAB2_LIB.BASEBOARD_FAB2(SCH_1):PAGE139
    14 SPI_NIC_MISO @BASEBOARD_FAB2_LIB.BASEBOARD_FAB2(SCH_1):SPI_NIC_MISO    I72 @BASEBOARD_FAB2_LIB.BASEBOARD_FAB2(SCH_1):PAGE139
    25 CLK_100M_SPRV_DN @BASEBOARD_FAB2_LIB.BASEBOARD_FAB2(SCH_1):CLK_100M_SPRV_DN    I72 @BASEBOARD_FAB2_LIB.BASEBOARD_FAB2(SCH_1):PAGE139
    26 CLK_100M_SPRV_DP @BASEBOARD_FAB2_LIB.BASEBOARD_FAB2(SCH_1):CLK_100M_SPRV_DP    I72 @BASEBOARD_FAB2_LIB.BASEBOARD_FAB2(SCH_1):PAGE139
    23 PE_PCH_SPRV_TX_C_DN @BASEBOARD_FAB2_LIB.BASEBOARD_FAB2(SCH_1):PE_PCH_SPRV_TX_C_DN    I72 @BASEBOARD_FAB2_LIB.BASEBOARD_FAB2(SCH_1):PAGE139
    24 PE_PCH_SPRV_TX_C_DP @BASEBOARD_FAB2_LIB.BASEBOARD_FAB2(SCH_1):PE_PCH_SPRV_TX_C_DP    I72 @BASEBOARD_FAB2_LIB.BASEBOARD_FAB2(SCH_1):PAGE139
    17 RST_PLTRST_SPRV_R_N @BASEBOARD_FAB2_LIB.BASEBOARD_FAB2(SCH_1):RST_PLTRST_SPRV_R_N    I72 @BASEBOARD_FAB2_LIB.BASEBOARD_FAB2(SCH_1):PAGE139
    20 PE_PCH_SPRV_RX_DN @BASEBOARD_FAB2_LIB.BASEBOARD_FAB2(SCH_1):PE_PCH_SPRV_RX_DN    I72 @BASEBOARD_FAB2_LIB.BASEBOARD_FAB2(SCH_1):PAGE139
    21 PE_PCH_SPRV_RX_DP @BASEBOARD_FAB2_LIB.BASEBOARD_FAB2(SCH_1):PE_PCH_SPRV_RX_DP    I72 @BASEBOARD_FAB2_LIB.BASEBOARD_FAB2(SCH_1):PAGE139
    16 FM_PE_SPRV_WAKE_N @BASEBOARD_FAB2_LIB.BASEBOARD_FAB2(SCH_1):FM_PE_SPRV_WAKE_N    I72 @BASEBOARD_FAB2_LIB.BASEBOARD_FAB2(SCH_1):PAGE139
    48 PD_SPRV_RSET @BASEBOARD_FAB2_LIB.BASEBOARD_FAB2(SCH_1):PD_SPRV_RSET    I72 @BASEBOARD_FAB2_LIB.BASEBOARD_FAB2(SCH_1):PAGE139
    63 TP_SPRV_SDP0 @BASEBOARD_FAB2_LIB.BASEBOARD_FAB2(SCH_1):TP_SPRV_SDP0    I72 @BASEBOARD_FAB2_LIB.BASEBOARD_FAB2(SCH_1):PAGE139
    61 FM_1GB_LOM_DISABLE_N @BASEBOARD_FAB2_LIB.BASEBOARD_FAB2(SCH_1):FM_1GB_LOM_DISABLE_N    I72 @BASEBOARD_FAB2_LIB.BASEBOARD_FAB2(SCH_1):PAGE139
    62 TP_SPRV_SDP2 @BASEBOARD_FAB2_LIB.BASEBOARD_FAB2(SCH_1):TP_SPRV_SDP2    I72 @BASEBOARD_FAB2_LIB.BASEBOARD_FAB2(SCH_1):PAGE139
    60 TP_SPRV_SDP3 @BASEBOARD_FAB2_LIB.BASEBOARD_FAB2(SCH_1):TP_SPRV_SDP3    I72 @BASEBOARD_FAB2_LIB.BASEBOARD_FAB2(SCH_1):PAGE139
    35 IRQ_LOM_ALERT_N @BASEBOARD_FAB2_LIB.BASEBOARD_FAB2(SCH_1):IRQ_LOM_ALERT_N    I72 @BASEBOARD_FAB2_LIB.BASEBOARD_FAB2(SCH_1):PAGE139
    34 SMB_SPRINGVILLE_STBY_LVC3_SCL @BASEBOARD_FAB2_LIB.BASEBOARD_FAB2(SCH_1):SMB_SPRINGVILLE_STBY_LVC3_SCL    I72 @BASEBOARD_FAB2_LIB.BASEBOARD_FAB2(SCH_1):PAGE139
    36 SMB_SPRINGVILLE_STBY_LVC3_SDA @BASEBOARD_FAB2_LIB.BASEBOARD_FAB2(SCH_1):SMB_SPRINGVILLE_STBY_LVC3_SDA    I72 @BASEBOARD_FAB2_LIB.BASEBOARD_FAB2(SCH_1):PAGE139
    42 P0V9_LAN @BASEBOARD_FAB2_LIB.BASEBOARD_FAB2(SCH_1):P0V9_LAN    I72 @BASEBOARD_FAB2_LIB.BASEBOARD_FAB2(SCH_1):PAGE139
    11 P0V9_LAN @BASEBOARD_FAB2_LIB.BASEBOARD_FAB2(SCH_1):P0V9_LAN    I72 @BASEBOARD_FAB2_LIB.BASEBOARD_FAB2(SCH_1):PAGE139
    32 P0V9_LAN @BASEBOARD_FAB2_LIB.BASEBOARD_FAB2(SCH_1):P0V9_LAN    I72 @BASEBOARD_FAB2_LIB.BASEBOARD_FAB2(SCH_1):PAGE139
    59 P0V9_LAN @BASEBOARD_FAB2_LIB.BASEBOARD_FAB2(SCH_1):P0V9_LAN    I72 @BASEBOARD_FAB2_LIB.BASEBOARD_FAB2(SCH_1):PAGE139
    38 P0V9_LAN_I210 @BASEBOARD_FAB2_LIB.BASEBOARD_FAB2(SCH_1):P0V9_LAN_I210    I72 @BASEBOARD_FAB2_LIB.BASEBOARD_FAB2(SCH_1):PAGE139
    47 P1V5_LAN @BASEBOARD_FAB2_LIB.BASEBOARD_FAB2(SCH_1):P1V5_LAN    I72 @BASEBOARD_FAB2_LIB.BASEBOARD_FAB2(SCH_1):PAGE139
    56 P1V5_LAN_I210 @BASEBOARD_FAB2_LIB.BASEBOARD_FAB2(SCH_1):P1V5_LAN_I210    I72 @BASEBOARD_FAB2_LIB.BASEBOARD_FAB2(SCH_1):PAGE139
    39 P1V5_LAN @BASEBOARD_FAB2_LIB.BASEBOARD_FAB2(SCH_1):P1V5_LAN    I72 @BASEBOARD_FAB2_LIB.BASEBOARD_FAB2(SCH_1):PAGE139
    10 P3V3_STBY @BASEBOARD_FAB2_LIB.BASEBOARD_FAB2(SCH_1):P3V3_STBY    I72 @BASEBOARD_FAB2_LIB.BASEBOARD_FAB2(SCH_1):PAGE139
    27 P3V3_STBY @BASEBOARD_FAB2_LIB.BASEBOARD_FAB2(SCH_1):P3V3_STBY    I72 @BASEBOARD_FAB2_LIB.BASEBOARD_FAB2(SCH_1):PAGE139
    41 P3V3_STBY @BASEBOARD_FAB2_LIB.BASEBOARD_FAB2(SCH_1):P3V3_STBY    I72 @BASEBOARD_FAB2_LIB.BASEBOARD_FAB2(SCH_1):PAGE139
    51 P3V3_STBY_P1V5_LAN_I210 @BASEBOARD_FAB2_LIB.BASEBOARD_FAB2(SCH_1):P3V3_STBY_P1V5_LAN_I210    I72 @BASEBOARD_FAB2_LIB.BASEBOARD_FAB2(SCH_1):PAGE139
    64 P3V3_STBY @BASEBOARD_FAB2_LIB.BASEBOARD_FAB2(SCH_1):P3V3_STBY    I72 @BASEBOARD_FAB2_LIB.BASEBOARD_FAB2(SCH_1):PAGE139
    46 XTAL_25MHZ_IN_R @BASEBOARD_FAB2_LIB.BASEBOARD_FAB2(SCH_1):XTAL_25MHZ_IN_R    I72 @BASEBOARD_FAB2_LIB.BASEBOARD_FAB2(SCH_1):PAGE139
    45 XTAL_25MHZ_OUT @BASEBOARD_FAB2_LIB.BASEBOARD_FAB2(SCH_1):XTAL_25MHZ_OUT    I72 @BASEBOARD_FAB2_LIB.BASEBOARD_FAB2(SCH_1):PAGE139

EU9F1 RT9059_DFN-IC,H65765-001
     4 VR_P1V15_BMC_STBY_FB @BASEBOARD_FAB2_LIB.BASEBOARD_FAB2(SCH_1):VR_P1V15_BMC_STBY_FB    I40 @BASEBOARD_FAB2_LIB.BASEBOARD_FAB2(SCH_1):PAGE238
     6 PWRGD_P1V2_BMC_STBY @BASEBOARD_FAB2_LIB.BASEBOARD_FAB2(SCH_1):PWRGD_P1V2_BMC_STBY    I40 @BASEBOARD_FAB2_LIB.BASEBOARD_FAB2(SCH_1):PAGE238
    11    GND @BASEBOARD_FAB2_LIB.BASEBOARD_FAB2(SCH_1):GND    I40 @BASEBOARD_FAB2_LIB.BASEBOARD_FAB2(SCH_1):PAGE238
     5 PWRGD_P1V15_BMC_STBY_R @BASEBOARD_FAB2_LIB.BASEBOARD_FAB2(SCH_1):PWRGD_P1V15_BMC_STBY_R    I40 @BASEBOARD_FAB2_LIB.BASEBOARD_FAB2(SCH_1):PAGE238
    10 P3V3_STBY @BASEBOARD_FAB2_LIB.BASEBOARD_FAB2(SCH_1):P3V3_STBY    I40 @BASEBOARD_FAB2_LIB.BASEBOARD_FAB2(SCH_1):PAGE238
     9 P3V3_STBY @BASEBOARD_FAB2_LIB.BASEBOARD_FAB2(SCH_1):P3V3_STBY    I40 @BASEBOARD_FAB2_LIB.BASEBOARD_FAB2(SCH_1):PAGE238
     8 P3V3_STBY @BASEBOARD_FAB2_LIB.BASEBOARD_FAB2(SCH_1):P3V3_STBY    I40 @BASEBOARD_FAB2_LIB.BASEBOARD_FAB2(SCH_1):PAGE238
     7 P3V3_STBY @BASEBOARD_FAB2_LIB.BASEBOARD_FAB2(SCH_1):P3V3_STBY    I40 @BASEBOARD_FAB2_LIB.BASEBOARD_FAB2(SCH_1):PAGE238
     3 P1V15_AUX_BMC @BASEBOARD_FAB2_LIB.BASEBOARD_FAB2(SCH_1):P1V15_AUX_BMC    I40 @BASEBOARD_FAB2_LIB.BASEBOARD_FAB2(SCH_1):PAGE238
     2 P1V15_AUX_BMC @BASEBOARD_FAB2_LIB.BASEBOARD_FAB2(SCH_1):P1V15_AUX_BMC    I40 @BASEBOARD_FAB2_LIB.BASEBOARD_FAB2(SCH_1):PAGE238
     1 P1V15_AUX_BMC @BASEBOARD_FAB2_LIB.BASEBOARD_FAB2(SCH_1):P1V15_AUX_BMC    I40 @BASEBOARD_FAB2_LIB.BASEBOARD_FAB2(SCH_1):PAGE238

EU9F2 RT9059_DFN-IC,H65765-001
     4 VR_P1V2_BMC_STBY_FB @BASEBOARD_FAB2_LIB.BASEBOARD_FAB2(SCH_1):VR_P1V2_BMC_STBY_FB    I70 @BASEBOARD_FAB2_LIB.BASEBOARD_FAB2(SCH_1):PAGE239
     6 PWRGD_P2V5_BMC_STBY @BASEBOARD_FAB2_LIB.BASEBOARD_FAB2(SCH_1):PWRGD_P2V5_BMC_STBY    I70 @BASEBOARD_FAB2_LIB.BASEBOARD_FAB2(SCH_1):PAGE239
    11    GND @BASEBOARD_FAB2_LIB.BASEBOARD_FAB2(SCH_1):GND    I70 @BASEBOARD_FAB2_LIB.BASEBOARD_FAB2(SCH_1):PAGE239
     5 PWRGD_P1V2_BMC_STBY_R @BASEBOARD_FAB2_LIB.BASEBOARD_FAB2(SCH_1):PWRGD_P1V2_BMC_STBY_R    I70 @BASEBOARD_FAB2_LIB.BASEBOARD_FAB2(SCH_1):PAGE239
    10 P3V3_STBY @BASEBOARD_FAB2_LIB.BASEBOARD_FAB2(SCH_1):P3V3_STBY    I70 @BASEBOARD_FAB2_LIB.BASEBOARD_FAB2(SCH_1):PAGE239
     9 P3V3_STBY @BASEBOARD_FAB2_LIB.BASEBOARD_FAB2(SCH_1):P3V3_STBY    I70 @BASEBOARD_FAB2_LIB.BASEBOARD_FAB2(SCH_1):PAGE239
     8 P3V3_STBY @BASEBOARD_FAB2_LIB.BASEBOARD_FAB2(SCH_1):P3V3_STBY    I70 @BASEBOARD_FAB2_LIB.BASEBOARD_FAB2(SCH_1):PAGE239
     7 P3V3_STBY @BASEBOARD_FAB2_LIB.BASEBOARD_FAB2(SCH_1):P3V3_STBY    I70 @BASEBOARD_FAB2_LIB.BASEBOARD_FAB2(SCH_1):PAGE239
     3 P1V2_AUX_BMC @BASEBOARD_FAB2_LIB.BASEBOARD_FAB2(SCH_1):P1V2_AUX_BMC    I70 @BASEBOARD_FAB2_LIB.BASEBOARD_FAB2(SCH_1):PAGE239
     2 P1V2_AUX_BMC @BASEBOARD_FAB2_LIB.BASEBOARD_FAB2(SCH_1):P1V2_AUX_BMC    I70 @BASEBOARD_FAB2_LIB.BASEBOARD_FAB2(SCH_1):PAGE239
     1 P1V2_AUX_BMC @BASEBOARD_FAB2_LIB.BASEBOARD_FAB2(SCH_1):P1V2_AUX_BMC    I70 @BASEBOARD_FAB2_LIB.BASEBOARD_FAB2(SCH_1):PAGE239

EU9M1 SLG55021_SM-IC,G56246-001
     4    GND @BASEBOARD_FAB2_LIB.BASEBOARD_FAB2(SCH_1):GND    I69 @BASEBOARD_FAB2_LIB.BASEBOARD_FAB2(SCH_1):PAGE198
     9    GND @BASEBOARD_FAB2_LIB.BASEBOARD_FAB2(SCH_1):GND    I69 @BASEBOARD_FAB2_LIB.BASEBOARD_FAB2(SCH_1):PAGE198
     1 P5V_STBY @BASEBOARD_FAB2_LIB.BASEBOARD_FAB2(SCH_1):P5V_STBY    I69 @BASEBOARD_FAB2_LIB.BASEBOARD_FAB2(SCH_1):PAGE198
     2 FM_ENABLE_FAN_POWER @BASEBOARD_FAB2_LIB.BASEBOARD_FAB2(SCH_1):FM_ENABLE_FAN_POWER    I69 @BASEBOARD_FAB2_LIB.BASEBOARD_FAB2(SCH_1):PAGE198
     3 P5V_STBY @BASEBOARD_FAB2_LIB.BASEBOARD_FAB2(SCH_1):P5V_STBY    I69 @BASEBOARD_FAB2_LIB.BASEBOARD_FAB2(SCH_1):PAGE198
     5 P12V_STBY @BASEBOARD_FAB2_LIB.BASEBOARD_FAB2(SCH_1):P12V_STBY    I69 @BASEBOARD_FAB2_LIB.BASEBOARD_FAB2(SCH_1):PAGE198
     6 P12V_FAN @BASEBOARD_FAB2_LIB.BASEBOARD_FAB2(SCH_1):P12V_FAN    I69 @BASEBOARD_FAB2_LIB.BASEBOARD_FAB2(SCH_1):PAGE198
     7 P12V_FAN_SWITCH_G @BASEBOARD_FAB2_LIB.BASEBOARD_FAB2(SCH_1):P12V_FAN_SWITCH_G    I69 @BASEBOARD_FAB2_LIB.BASEBOARD_FAB2(SCH_1):PAGE198
     8 TP_SLG55021_P12V_FAN_8 @BASEBOARD_FAB2_LIB.BASEBOARD_FAB2(SCH_1):TP_SLG55021_P12V_FAN_8    I69 @BASEBOARD_FAB2_LIB.BASEBOARD_FAB2(SCH_1):PAGE198

EU9R1 MOSFETN_1D3S_SOT5-IC,G68777-001
     1 P12V_STBY @BASEBOARD_FAB2_LIB.BASEBOARD_FAB2(SCH_1):P12V_STBY    I57 @BASEBOARD_FAB2_LIB.BASEBOARD_FAB2(SCH_1):PAGE200
     2 P12V_STBY @BASEBOARD_FAB2_LIB.BASEBOARD_FAB2(SCH_1):P12V_STBY    I57 @BASEBOARD_FAB2_LIB.BASEBOARD_FAB2(SCH_1):PAGE200
     3 P12V_STBY @BASEBOARD_FAB2_LIB.BASEBOARD_FAB2(SCH_1):P12V_STBY    I57 @BASEBOARD_FAB2_LIB.BASEBOARD_FAB2(SCH_1):PAGE200
     5 P12V_MB0_SW @BASEBOARD_FAB2_LIB.BASEBOARD_FAB2(SCH_1):P12V_MB0_SW    I57 @BASEBOARD_FAB2_LIB.BASEBOARD_FAB2(SCH_1):PAGE200
     4 A_HSC_GATE2_R @BASEBOARD_FAB2_LIB.BASEBOARD_FAB2(SCH_1):A_HSC_GATE2_R    I57 @BASEBOARD_FAB2_LIB.BASEBOARD_FAB2(SCH_1):PAGE200

EU25F2 RT9059_DFN-IC,H65765-001
     4 VR_P2V5_BMC_STBY_FB @BASEBOARD_FAB2_LIB.BASEBOARD_FAB2(SCH_1):VR_P2V5_BMC_STBY_FB    I73 @BASEBOARD_FAB2_LIB.BASEBOARD_FAB2(SCH_1):PAGE239
     6 PWRGD_P3V3_STBY @BASEBOARD_FAB2_LIB.BASEBOARD_FAB2(SCH_1):PWRGD_P3V3_STBY    I73 @BASEBOARD_FAB2_LIB.BASEBOARD_FAB2(SCH_1):PAGE239
    11    GND @BASEBOARD_FAB2_LIB.BASEBOARD_FAB2(SCH_1):GND    I73 @BASEBOARD_FAB2_LIB.BASEBOARD_FAB2(SCH_1):PAGE239
     5 PWRGD_P2V5_BMC_STBY_R @BASEBOARD_FAB2_LIB.BASEBOARD_FAB2(SCH_1):PWRGD_P2V5_BMC_STBY_R    I73 @BASEBOARD_FAB2_LIB.BASEBOARD_FAB2(SCH_1):PAGE239
    10 P3V3_STBY @BASEBOARD_FAB2_LIB.BASEBOARD_FAB2(SCH_1):P3V3_STBY    I73 @BASEBOARD_FAB2_LIB.BASEBOARD_FAB2(SCH_1):PAGE239
     9 P3V3_STBY @BASEBOARD_FAB2_LIB.BASEBOARD_FAB2(SCH_1):P3V3_STBY    I73 @BASEBOARD_FAB2_LIB.BASEBOARD_FAB2(SCH_1):PAGE239
     8 P3V3_STBY @BASEBOARD_FAB2_LIB.BASEBOARD_FAB2(SCH_1):P3V3_STBY    I73 @BASEBOARD_FAB2_LIB.BASEBOARD_FAB2(SCH_1):PAGE239
     7 P3V3_STBY @BASEBOARD_FAB2_LIB.BASEBOARD_FAB2(SCH_1):P3V3_STBY    I73 @BASEBOARD_FAB2_LIB.BASEBOARD_FAB2(SCH_1):PAGE239
     3 P2V5_AUX_BMC @BASEBOARD_FAB2_LIB.BASEBOARD_FAB2(SCH_1):P2V5_AUX_BMC    I73 @BASEBOARD_FAB2_LIB.BASEBOARD_FAB2(SCH_1):PAGE239
     2 P2V5_AUX_BMC @BASEBOARD_FAB2_LIB.BASEBOARD_FAB2(SCH_1):P2V5_AUX_BMC    I73 @BASEBOARD_FAB2_LIB.BASEBOARD_FAB2(SCH_1):PAGE239
     1 P2V5_AUX_BMC @BASEBOARD_FAB2_LIB.BASEBOARD_FAB2(SCH_1):P2V5_AUX_BMC    I73 @BASEBOARD_FAB2_LIB.BASEBOARD_FAB2(SCH_1):PAGE239

F1L1 FUSE_SMT-IC,H45581-001
     1 P5V_STBY_DBG @BASEBOARD_FAB2_LIB.BASEBOARD_FAB2(SCH_1):P5V_STBY_DBG   I129 @BASEBOARD_FAB2_LIB.BASEBOARD_FAB2(SCH_1):PAGE155
     2 P5V_STBY_DGB_FS @BASEBOARD_FAB2_LIB.BASEBOARD_FAB2(SCH_1):P5V_STBY_DGB_FS   I129 @BASEBOARD_FAB2_LIB.BASEBOARD_FAB2(SCH_1):PAGE155

F8B1 FUSE-3A75V-GP_DISCRET-G5-FUSE-A
     1 P5V_HDD_SATA @BASEBOARD_FAB2_LIB.BASEBOARD_FAB2(SCH_1):P5V_HDD_SATA    I71 @BASEBOARD_FAB2_LIB.BASEBOARD_FAB2(SCH_1):PAGE172
     2    P5V @BASEBOARD_FAB2_LIB.BASEBOARD_FAB2(SCH_1):P5V    I71 @BASEBOARD_FAB2_LIB.BASEBOARD_FAB2(SCH_1):PAGE172

F9B1 FUSE_SM-IC,C94311-016
     1   P12V @BASEBOARD_FAB2_LIB.BASEBOARD_FAB2(SCH_1):P12V    I66 @BASEBOARD_FAB2_LIB.BASEBOARD_FAB2(SCH_1):PAGE172
     2 P12V_HDD_SATA @BASEBOARD_FAB2_LIB.BASEBOARD_FAB2(SCH_1):P12V_HDD_SATA    I66 @BASEBOARD_FAB2_LIB.BASEBOARD_FAB2(SCH_1):PAGE172

F25W1 POLYSW-D5A6V-2-GP-U_DISCRET-GAA
     1 P5V_VGA @BASEBOARD_FAB2_LIB.BASEBOARD_FAB2(SCH_1):P5V_VGA    I89 @BASEBOARD_FAB2_LIB.BASEBOARD_FAB2(SCH_1):PAGE255
     2 P5V_VGA_D @BASEBOARD_FAB2_LIB.BASEBOARD_FAB2(SCH_1):P5V_VGA_D    I89 @BASEBOARD_FAB2_LIB.BASEBOARD_FAB2(SCH_1):PAGE255

F30W1 POLYSW-1D1A6V-2-GP-U_DISCRET-GA
     1 P5V_STBY @BASEBOARD_FAB2_LIB.BASEBOARD_FAB2(SCH_1):P5V_STBY    I44 @BASEBOARD_FAB2_LIB.BASEBOARD_FAB2(SCH_1):PAGE253
     2 P5V_STBY_USBC @BASEBOARD_FAB2_LIB.BASEBOARD_FAB2(SCH_1):P5V_STBY_USBC    I44 @BASEBOARD_FAB2_LIB.BASEBOARD_FAB2(SCH_1):PAGE253

FB1U3 FERRITE_SMLF-30,FB,693286-021
     1 A_P1V05_STBY_PCH_SENSOR @BASEBOARD_FAB2_LIB.BASEBOARD_FAB2(SCH_1):A_P1V05_STBY_PCH_SENSOR    I57 @BASEBOARD_FAB2_LIB.BASEBOARD_FAB2(SCH_1):PAGE169
     2 P1V05_PCH_STBY @BASEBOARD_FAB2_LIB.BASEBOARD_FAB2(SCH_1):P1V05_PCH_STBY    I57 @BASEBOARD_FAB2_LIB.BASEBOARD_FAB2(SCH_1):PAGE169

FB1U4 FERRITE_SMLF-30,FB,693286-021
     1 A_PVNN_STBY_PCH_SENSOR @BASEBOARD_FAB2_LIB.BASEBOARD_FAB2(SCH_1):A_PVNN_STBY_PCH_SENSOR   I155 @BASEBOARD_FAB2_LIB.BASEBOARD_FAB2(SCH_1):PAGE169
     2 PVNN_PCH_STBY @BASEBOARD_FAB2_LIB.BASEBOARD_FAB2(SCH_1):PVNN_PCH_STBY   I155 @BASEBOARD_FAB2_LIB.BASEBOARD_FAB2(SCH_1):PAGE169

FB2M1 FERRITE_SM-120,FB,693286-027
     1 P1V05_PCH_STBY @BASEBOARD_FAB2_LIB.BASEBOARD_FAB2(SCH_1):P1V05_PCH_STBY    I46 @BASEBOARD_FAB2_LIB.BASEBOARD_FAB2(SCH_1):PAGE127
     2 P1V05_PCH_STBY_WM20_PLL @BASEBOARD_FAB2_LIB.BASEBOARD_FAB2(SCH_1):P1V05_PCH_STBY_WM20_PLL    I46 @BASEBOARD_FAB2_LIB.BASEBOARD_FAB2(SCH_1):PAGE127

FB2M2 FERRITE_SM-120,FB,693286-027
     1 P1V05_PCH_STBY @BASEBOARD_FAB2_LIB.BASEBOARD_FAB2(SCH_1):P1V05_PCH_STBY    I69 @BASEBOARD_FAB2_LIB.BASEBOARD_FAB2(SCH_1):PAGE127
     2 P1V05_PCH_STBY_WM26_PLL @BASEBOARD_FAB2_LIB.BASEBOARD_FAB2(SCH_1):P1V05_PCH_STBY_WM26_PLL    I69 @BASEBOARD_FAB2_LIB.BASEBOARD_FAB2(SCH_1):PAGE127

FB2T1 HCB1608KF-800T30-GP_DISCRET-G9A
     1 P3V3_STBY @BASEBOARD_FAB2_LIB.BASEBOARD_FAB2(SCH_1):P3V3_STBY    I22 @BASEBOARD_FAB2_LIB.BASEBOARD_FAB2(SCH_1):PAGE149
     2 VCC_VA_3V3 @BASEBOARD_FAB2_LIB.BASEBOARD_FAB2(SCH_1):VCC_VA_3V3    I22 @BASEBOARD_FAB2_LIB.BASEBOARD_FAB2(SCH_1):PAGE149

FB2T2 FERRITE_SMLF-600,FB,656554-043
     1 P3V3_STBY @BASEBOARD_FAB2_LIB.BASEBOARD_FAB2(SCH_1):P3V3_STBY   I114 @BASEBOARD_FAB2_LIB.BASEBOARD_FAB2(SCH_1):PAGE101
     2 P3V3_STBY_MNG @BASEBOARD_FAB2_LIB.BASEBOARD_FAB2(SCH_1):P3V3_STBY_MNG   I114 @BASEBOARD_FAB2_LIB.BASEBOARD_FAB2(SCH_1):PAGE101

FB2T3 HCB1608KF-800T30-GP_DISCRET-G9A
     1 P3V3_STBY @BASEBOARD_FAB2_LIB.BASEBOARD_FAB2(SCH_1):P3V3_STBY    I85 @BASEBOARD_FAB2_LIB.BASEBOARD_FAB2(SCH_1):PAGE149
     2 VCC_ADCAV3V3 @BASEBOARD_FAB2_LIB.BASEBOARD_FAB2(SCH_1):VCC_ADCAV3V3    I85 @BASEBOARD_FAB2_LIB.BASEBOARD_FAB2(SCH_1):PAGE149

FB2T4 HCB1608KF-800T30-GP_DISCRET-G9A
     1 P3V3_STBY @BASEBOARD_FAB2_LIB.BASEBOARD_FAB2(SCH_1):P3V3_STBY    I86 @BASEBOARD_FAB2_LIB.BASEBOARD_FAB2(SCH_1):PAGE149
     2 VCC_D_3V3 @BASEBOARD_FAB2_LIB.BASEBOARD_FAB2(SCH_1):VCC_D_3V3    I86 @BASEBOARD_FAB2_LIB.BASEBOARD_FAB2(SCH_1):PAGE149

FB2T5 HCB1608KF-800T30-GP_DISCRET-G9A
     1 P3V3_STBY @BASEBOARD_FAB2_LIB.BASEBOARD_FAB2(SCH_1):P3V3_STBY    I88 @BASEBOARD_FAB2_LIB.BASEBOARD_FAB2(SCH_1):PAGE149
     2 VCC_PA_3V3 @BASEBOARD_FAB2_LIB.BASEBOARD_FAB2(SCH_1):VCC_PA_3V3    I88 @BASEBOARD_FAB2_LIB.BASEBOARD_FAB2(SCH_1):PAGE149

FB2T7 HCB1608KF-800T30-GP_DISCRET-G9A
     1 P1V15_AUX_BMC @BASEBOARD_FAB2_LIB.BASEBOARD_FAB2(SCH_1):P1V15_AUX_BMC    I42 @BASEBOARD_FAB2_LIB.BASEBOARD_FAB2(SCH_1):PAGE149
     2 VCC_A_1V1 @BASEBOARD_FAB2_LIB.BASEBOARD_FAB2(SCH_1):VCC_A_1V1    I42 @BASEBOARD_FAB2_LIB.BASEBOARD_FAB2(SCH_1):PAGE149

FB3M1 FERRITE_SM-120,FB,693286-027
     1 P1V05_PCH_STBY @BASEBOARD_FAB2_LIB.BASEBOARD_FAB2(SCH_1):P1V05_PCH_STBY     I8 @BASEBOARD_FAB2_LIB.BASEBOARD_FAB2(SCH_1):PAGE127
     2 P1V05_PCH_STBY_VCCA_PLL1 @BASEBOARD_FAB2_LIB.BASEBOARD_FAB2(SCH_1):P1V05_PCH_STBY_VCCA_PLL1     I8 @BASEBOARD_FAB2_LIB.BASEBOARD_FAB2(SCH_1):PAGE127

FB3M2 FERRITE_SM-120,FB,693286-027
     1 P1V05_PCH_STBY @BASEBOARD_FAB2_LIB.BASEBOARD_FAB2(SCH_1):P1V05_PCH_STBY    I17 @BASEBOARD_FAB2_LIB.BASEBOARD_FAB2(SCH_1):PAGE127
     2 P1V05_PCH_STBY_VCCA_PLL0 @BASEBOARD_FAB2_LIB.BASEBOARD_FAB2(SCH_1):P1V05_PCH_STBY_VCCA_PLL0    I17 @BASEBOARD_FAB2_LIB.BASEBOARD_FAB2(SCH_1):PAGE127

FB3M3 FERRITE_SM-120,FB,693286-027
     1 P1V05_PCH_STBY @BASEBOARD_FAB2_LIB.BASEBOARD_FAB2(SCH_1):P1V05_PCH_STBY    I26 @BASEBOARD_FAB2_LIB.BASEBOARD_FAB2(SCH_1):PAGE127
     2 P1V05_PCH_STBY_VCCA_XTAL @BASEBOARD_FAB2_LIB.BASEBOARD_FAB2(SCH_1):P1V05_PCH_STBY_VCCA_XTAL    I26 @BASEBOARD_FAB2_LIB.BASEBOARD_FAB2(SCH_1):PAGE127

FB3M4 FERRITE_SM-120,FB,693286-027
     1 P1V05_PCH_STBY @BASEBOARD_FAB2_LIB.BASEBOARD_FAB2(SCH_1):P1V05_PCH_STBY    I56 @BASEBOARD_FAB2_LIB.BASEBOARD_FAB2(SCH_1):PAGE127
     2 P1V05_PCH_STBY_ISCLK_PLL @BASEBOARD_FAB2_LIB.BASEBOARD_FAB2(SCH_1):P1V05_PCH_STBY_ISCLK_PLL    I56 @BASEBOARD_FAB2_LIB.BASEBOARD_FAB2(SCH_1):PAGE127

FB4A1 FERRITE_SM-22,FB,656554-051
     1 P12V_STBY @BASEBOARD_FAB2_LIB.BASEBOARD_FAB2(SCH_1):P12V_STBY   I154 @BASEBOARD_FAB2_LIB.BASEBOARD_FAB2(SCH_1):PAGE234
     2 VR_FET_SW_P12V_STBY_PVPP_KLM @BASEBOARD_FAB2_LIB.BASEBOARD_FAB2(SCH_1):VR_FET_SW_P12V_STBY_PVPP_KLM   I154 @BASEBOARD_FAB2_LIB.BASEBOARD_FAB2(SCH_1):PAGE234

FB4G1 FERRITE_SM-22,FB,656554-051
     1 P12V_STBY @BASEBOARD_FAB2_LIB.BASEBOARD_FAB2(SCH_1):P12V_STBY   I198 @BASEBOARD_FAB2_LIB.BASEBOARD_FAB2(SCH_1):PAGE233
     2 VR_FET_SW_P12V_STBY_PVPP_GHJ @BASEBOARD_FAB2_LIB.BASEBOARD_FAB2(SCH_1):VR_FET_SW_P12V_STBY_PVPP_GHJ   I198 @BASEBOARD_FAB2_LIB.BASEBOARD_FAB2(SCH_1):PAGE233

FB6P1 FERRITE_SMLF-600,FB,656554-043
     1   P3V3 @BASEBOARD_FAB2_LIB.BASEBOARD_FAB2(SCH_1):P3V3     I8 @BASEBOARD_FAB2_LIB.BASEBOARD_FAB2(SCH_1):PAGE102
     2 P3V3_DB1200 @BASEBOARD_FAB2_LIB.BASEBOARD_FAB2(SCH_1):P3V3_DB1200     I8 @BASEBOARD_FAB2_LIB.BASEBOARD_FAB2(SCH_1):PAGE102

FB7B1 FERRITE_SM-22,FB,656554-051
     1 P12V_STBY @BASEBOARD_FAB2_LIB.BASEBOARD_FAB2(SCH_1):P12V_STBY   I200 @BASEBOARD_FAB2_LIB.BASEBOARD_FAB2(SCH_1):PAGE232
     2 VR_FET_SW_P12V_STBY_PVPP_DEF @BASEBOARD_FAB2_LIB.BASEBOARD_FAB2(SCH_1):VR_FET_SW_P12V_STBY_PVPP_DEF   I200 @BASEBOARD_FAB2_LIB.BASEBOARD_FAB2(SCH_1):PAGE232

FB7E1 FERRITE_SM-22,FB,656554-051
     1 P12V_STBY @BASEBOARD_FAB2_LIB.BASEBOARD_FAB2(SCH_1):P12V_STBY    I82 @BASEBOARD_FAB2_LIB.BASEBOARD_FAB2(SCH_1):PAGE241
     2 VR_FET_SW_P5V_STBY_PVIN @BASEBOARD_FAB2_LIB.BASEBOARD_FAB2(SCH_1):VR_FET_SW_P5V_STBY_PVIN    I82 @BASEBOARD_FAB2_LIB.BASEBOARD_FAB2(SCH_1):PAGE241

FB7F1 FERRITE_SM-22,FB,656554-051
     1 P12V_STBY @BASEBOARD_FAB2_LIB.BASEBOARD_FAB2(SCH_1):P12V_STBY   I162 @BASEBOARD_FAB2_LIB.BASEBOARD_FAB2(SCH_1):PAGE231
     2 VR_FET_SW_P12V_STBY_PVPP_ABC @BASEBOARD_FAB2_LIB.BASEBOARD_FAB2(SCH_1):VR_FET_SW_P12V_STBY_PVPP_ABC   I162 @BASEBOARD_FAB2_LIB.BASEBOARD_FAB2(SCH_1):PAGE231

FB9E1 BLM31SN500SN1L-GP_DISCRET-GB1-A
     1 P12V_STBY @BASEBOARD_FAB2_LIB.BASEBOARD_FAB2(SCH_1):P12V_STBY   I193 @BASEBOARD_FAB2_LIB.BASEBOARD_FAB2(SCH_1):PAGE240
     2 VR_FET_SW_P12V_STBY_P3V3_STBY @BASEBOARD_FAB2_LIB.BASEBOARD_FAB2(SCH_1):VR_FET_SW_P12V_STBY_P3V3_STBY   I193 @BASEBOARD_FAB2_LIB.BASEBOARD_FAB2(SCH_1):PAGE240

FB25W1 BLM15AG121SN-1GP_DISCRET-G-BLMA
     1 XDP_CPU_TCK0_R @BASEBOARD_FAB2_LIB.BASEBOARD_FAB2(SCH_1):XDP_CPU_TCK0_R    I71 @BASEBOARD_FAB2_LIB.BASEBOARD_FAB2(SCH_1):PAGE269
     2 XDP_CPU_TCK0 @BASEBOARD_FAB2_LIB.BASEBOARD_FAB2(SCH_1):XDP_CPU_TCK0    I71 @BASEBOARD_FAB2_LIB.BASEBOARD_FAB2(SCH_1):PAGE269

FB25W2 BLM15AG121SN-1GP_DISCRET-G-BLMA
     1 XDP_PCH_TCK1_R @BASEBOARD_FAB2_LIB.BASEBOARD_FAB2(SCH_1):XDP_PCH_TCK1_R    I72 @BASEBOARD_FAB2_LIB.BASEBOARD_FAB2(SCH_1):PAGE269
     2 XDP_PCH_TCK1 @BASEBOARD_FAB2_LIB.BASEBOARD_FAB2(SCH_1):XDP_PCH_TCK1    I72 @BASEBOARD_FAB2_LIB.BASEBOARD_FAB2(SCH_1):PAGE269

FB25W3 BLM15AG121SN-1GP_DISCRET-G-BLMA
     1 XDP_TRST_R_N @BASEBOARD_FAB2_LIB.BASEBOARD_FAB2(SCH_1):XDP_TRST_R_N    I73 @BASEBOARD_FAB2_LIB.BASEBOARD_FAB2(SCH_1):PAGE269
     2 XDP_TRST_N @BASEBOARD_FAB2_LIB.BASEBOARD_FAB2(SCH_1):XDP_TRST_N    I73 @BASEBOARD_FAB2_LIB.BASEBOARD_FAB2(SCH_1):PAGE269

FB25W4 BLM15AG121SN-1GP_DISCRET-G-BLMA
     1 XDP_TDI_R @BASEBOARD_FAB2_LIB.BASEBOARD_FAB2(SCH_1):XDP_TDI_R    I75 @BASEBOARD_FAB2_LIB.BASEBOARD_FAB2(SCH_1):PAGE269
     2 XDP_TDI @BASEBOARD_FAB2_LIB.BASEBOARD_FAB2(SCH_1):XDP_TDI    I75 @BASEBOARD_FAB2_LIB.BASEBOARD_FAB2(SCH_1):PAGE269

FB25W5 BLM15AG121SN-1GP_DISCRET-G-BLMA
     1 XDP_TMS_R @BASEBOARD_FAB2_LIB.BASEBOARD_FAB2(SCH_1):XDP_TMS_R    I74 @BASEBOARD_FAB2_LIB.BASEBOARD_FAB2(SCH_1):PAGE269
     2 XDP_TMS @BASEBOARD_FAB2_LIB.BASEBOARD_FAB2(SCH_1):XDP_TMS    I74 @BASEBOARD_FAB2_LIB.BASEBOARD_FAB2(SCH_1):PAGE269

J1A1 SCONN288_H44441004_PIP-SCONN,HA
    79 M_M_MA<0> @BASEBOARD_FAB2_LIB.BASEBOARD_FAB2(SCH_1):M_M_MA(0)   I186 @BASEBOARD_FAB2_LIB.BASEBOARD_FAB2(SCH_1):PAGE87
    72 M_M_MA<1> @BASEBOARD_FAB2_LIB.BASEBOARD_FAB2(SCH_1):M_M_MA(1)   I186 @BASEBOARD_FAB2_LIB.BASEBOARD_FAB2(SCH_1):PAGE87
   225 M_M_MA<10> @BASEBOARD_FAB2_LIB.BASEBOARD_FAB2(SCH_1):M_M_MA(10)   I186 @BASEBOARD_FAB2_LIB.BASEBOARD_FAB2(SCH_1):PAGE87
   210 M_M_MA<11> @BASEBOARD_FAB2_LIB.BASEBOARD_FAB2(SCH_1):M_M_MA(11)   I186 @BASEBOARD_FAB2_LIB.BASEBOARD_FAB2(SCH_1):PAGE87
    65 M_M_MA<12> @BASEBOARD_FAB2_LIB.BASEBOARD_FAB2(SCH_1):M_M_MA(12)   I186 @BASEBOARD_FAB2_LIB.BASEBOARD_FAB2(SCH_1):PAGE87
   232 M_M_MA<13> @BASEBOARD_FAB2_LIB.BASEBOARD_FAB2(SCH_1):M_M_MA(13)   I186 @BASEBOARD_FAB2_LIB.BASEBOARD_FAB2(SCH_1):PAGE87
   228 M_M_MA<14> @BASEBOARD_FAB2_LIB.BASEBOARD_FAB2(SCH_1):M_M_MA(14)   I186 @BASEBOARD_FAB2_LIB.BASEBOARD_FAB2(SCH_1):PAGE87
    86 M_M_MA<15> @BASEBOARD_FAB2_LIB.BASEBOARD_FAB2(SCH_1):M_M_MA(15)   I186 @BASEBOARD_FAB2_LIB.BASEBOARD_FAB2(SCH_1):PAGE87
    82 M_M_MA<16> @BASEBOARD_FAB2_LIB.BASEBOARD_FAB2(SCH_1):M_M_MA(16)   I186 @BASEBOARD_FAB2_LIB.BASEBOARD_FAB2(SCH_1):PAGE87
   234 M_M_MA<17> @BASEBOARD_FAB2_LIB.BASEBOARD_FAB2(SCH_1):M_M_MA(17)   I186 @BASEBOARD_FAB2_LIB.BASEBOARD_FAB2(SCH_1):PAGE87
   216 M_M_MA<2> @BASEBOARD_FAB2_LIB.BASEBOARD_FAB2(SCH_1):M_M_MA(2)   I186 @BASEBOARD_FAB2_LIB.BASEBOARD_FAB2(SCH_1):PAGE87
    71 M_M_MA<3> @BASEBOARD_FAB2_LIB.BASEBOARD_FAB2(SCH_1):M_M_MA(3)   I186 @BASEBOARD_FAB2_LIB.BASEBOARD_FAB2(SCH_1):PAGE87
   214 M_M_MA<4> @BASEBOARD_FAB2_LIB.BASEBOARD_FAB2(SCH_1):M_M_MA(4)   I186 @BASEBOARD_FAB2_LIB.BASEBOARD_FAB2(SCH_1):PAGE87
   213 M_M_MA<5> @BASEBOARD_FAB2_LIB.BASEBOARD_FAB2(SCH_1):M_M_MA(5)   I186 @BASEBOARD_FAB2_LIB.BASEBOARD_FAB2(SCH_1):PAGE87
    69 M_M_MA<6> @BASEBOARD_FAB2_LIB.BASEBOARD_FAB2(SCH_1):M_M_MA(6)   I186 @BASEBOARD_FAB2_LIB.BASEBOARD_FAB2(SCH_1):PAGE87
   211 M_M_MA<7> @BASEBOARD_FAB2_LIB.BASEBOARD_FAB2(SCH_1):M_M_MA(7)   I186 @BASEBOARD_FAB2_LIB.BASEBOARD_FAB2(SCH_1):PAGE87
    68 M_M_MA<8> @BASEBOARD_FAB2_LIB.BASEBOARD_FAB2(SCH_1):M_M_MA(8)   I186 @BASEBOARD_FAB2_LIB.BASEBOARD_FAB2(SCH_1):PAGE87
    66 M_M_MA<9> @BASEBOARD_FAB2_LIB.BASEBOARD_FAB2(SCH_1):M_M_MA(9)   I186 @BASEBOARD_FAB2_LIB.BASEBOARD_FAB2(SCH_1):PAGE87
    62 M_M_ACT_N @BASEBOARD_FAB2_LIB.BASEBOARD_FAB2(SCH_1):M_M_ACT_N   I186 @BASEBOARD_FAB2_LIB.BASEBOARD_FAB2(SCH_1):PAGE87
   208 M_M_ALERT_N @BASEBOARD_FAB2_LIB.BASEBOARD_FAB2(SCH_1):M_M_ALERT_N   I186 @BASEBOARD_FAB2_LIB.BASEBOARD_FAB2(SCH_1):PAGE87
   224 M_M_BA<1> @BASEBOARD_FAB2_LIB.BASEBOARD_FAB2(SCH_1):M_M_BA(1)   I186 @BASEBOARD_FAB2_LIB.BASEBOARD_FAB2(SCH_1):PAGE87
    81 M_M_BA<0> @BASEBOARD_FAB2_LIB.BASEBOARD_FAB2(SCH_1):M_M_BA(0)   I186 @BASEBOARD_FAB2_LIB.BASEBOARD_FAB2(SCH_1):PAGE87
   207 M_M_BG<1> @BASEBOARD_FAB2_LIB.BASEBOARD_FAB2(SCH_1):M_M_BG(1)   I186 @BASEBOARD_FAB2_LIB.BASEBOARD_FAB2(SCH_1):PAGE87
    63 M_M_BG<0> @BASEBOARD_FAB2_LIB.BASEBOARD_FAB2(SCH_1):M_M_BG(0)   I186 @BASEBOARD_FAB2_LIB.BASEBOARD_FAB2(SCH_1):PAGE87
   235 M_M_C<2> @BASEBOARD_FAB2_LIB.BASEBOARD_FAB2(SCH_1):M_M_C(2)   I186 @BASEBOARD_FAB2_LIB.BASEBOARD_FAB2(SCH_1):PAGE87
   199 M_M_ECC<6> @BASEBOARD_FAB2_LIB.BASEBOARD_FAB2(SCH_1):M_M_ECC(6)   I186 @BASEBOARD_FAB2_LIB.BASEBOARD_FAB2(SCH_1):PAGE87
    54 M_M_ECC<7> @BASEBOARD_FAB2_LIB.BASEBOARD_FAB2(SCH_1):M_M_ECC(7)   I186 @BASEBOARD_FAB2_LIB.BASEBOARD_FAB2(SCH_1):PAGE87
   192 M_M_ECC<4> @BASEBOARD_FAB2_LIB.BASEBOARD_FAB2(SCH_1):M_M_ECC(4)   I186 @BASEBOARD_FAB2_LIB.BASEBOARD_FAB2(SCH_1):PAGE87
    47 M_M_ECC<5> @BASEBOARD_FAB2_LIB.BASEBOARD_FAB2(SCH_1):M_M_ECC(5)   I186 @BASEBOARD_FAB2_LIB.BASEBOARD_FAB2(SCH_1):PAGE87
   201 M_M_ECC<2> @BASEBOARD_FAB2_LIB.BASEBOARD_FAB2(SCH_1):M_M_ECC(2)   I186 @BASEBOARD_FAB2_LIB.BASEBOARD_FAB2(SCH_1):PAGE87
    56 M_M_ECC<3> @BASEBOARD_FAB2_LIB.BASEBOARD_FAB2(SCH_1):M_M_ECC(3)   I186 @BASEBOARD_FAB2_LIB.BASEBOARD_FAB2(SCH_1):PAGE87
   194 M_M_ECC<0> @BASEBOARD_FAB2_LIB.BASEBOARD_FAB2(SCH_1):M_M_ECC(0)   I186 @BASEBOARD_FAB2_LIB.BASEBOARD_FAB2(SCH_1):PAGE87
    49 M_M_ECC<1> @BASEBOARD_FAB2_LIB.BASEBOARD_FAB2(SCH_1):M_M_ECC(1)   I186 @BASEBOARD_FAB2_LIB.BASEBOARD_FAB2(SCH_1):PAGE87
    75 M_M_CLK_DN<0> @BASEBOARD_FAB2_LIB.BASEBOARD_FAB2(SCH_1):M_M_CLK_DN(0)   I186 @BASEBOARD_FAB2_LIB.BASEBOARD_FAB2(SCH_1):PAGE87
    74 M_M_CLK_DP<0> @BASEBOARD_FAB2_LIB.BASEBOARD_FAB2(SCH_1):M_M_CLK_DP(0)   I186 @BASEBOARD_FAB2_LIB.BASEBOARD_FAB2(SCH_1):PAGE87
   219 M_M_CLK_DN<1> @BASEBOARD_FAB2_LIB.BASEBOARD_FAB2(SCH_1):M_M_CLK_DN(1)   I186 @BASEBOARD_FAB2_LIB.BASEBOARD_FAB2(SCH_1):PAGE87
   218 M_M_CLK_DP<1> @BASEBOARD_FAB2_LIB.BASEBOARD_FAB2(SCH_1):M_M_CLK_DP(1)   I186 @BASEBOARD_FAB2_LIB.BASEBOARD_FAB2(SCH_1):PAGE87
   203 M_M_CKE<1> @BASEBOARD_FAB2_LIB.BASEBOARD_FAB2(SCH_1):M_M_CKE(1)   I186 @BASEBOARD_FAB2_LIB.BASEBOARD_FAB2(SCH_1):PAGE87
    60 M_M_CKE<0> @BASEBOARD_FAB2_LIB.BASEBOARD_FAB2(SCH_1):M_M_CKE(0)   I186 @BASEBOARD_FAB2_LIB.BASEBOARD_FAB2(SCH_1):PAGE87
   280 M_M_DQ<62> @BASEBOARD_FAB2_LIB.BASEBOARD_FAB2(SCH_1):M_M_DQ(62)   I186 @BASEBOARD_FAB2_LIB.BASEBOARD_FAB2(SCH_1):PAGE87
   135 M_M_DQ<63> @BASEBOARD_FAB2_LIB.BASEBOARD_FAB2(SCH_1):M_M_DQ(63)   I186 @BASEBOARD_FAB2_LIB.BASEBOARD_FAB2(SCH_1):PAGE87
   273 M_M_DQ<60> @BASEBOARD_FAB2_LIB.BASEBOARD_FAB2(SCH_1):M_M_DQ(60)   I186 @BASEBOARD_FAB2_LIB.BASEBOARD_FAB2(SCH_1):PAGE87
   128 M_M_DQ<61> @BASEBOARD_FAB2_LIB.BASEBOARD_FAB2(SCH_1):M_M_DQ(61)   I186 @BASEBOARD_FAB2_LIB.BASEBOARD_FAB2(SCH_1):PAGE87
   282 M_M_DQ<58> @BASEBOARD_FAB2_LIB.BASEBOARD_FAB2(SCH_1):M_M_DQ(58)   I186 @BASEBOARD_FAB2_LIB.BASEBOARD_FAB2(SCH_1):PAGE87
   137 M_M_DQ<59> @BASEBOARD_FAB2_LIB.BASEBOARD_FAB2(SCH_1):M_M_DQ(59)   I186 @BASEBOARD_FAB2_LIB.BASEBOARD_FAB2(SCH_1):PAGE87
   275 M_M_DQ<56> @BASEBOARD_FAB2_LIB.BASEBOARD_FAB2(SCH_1):M_M_DQ(56)   I186 @BASEBOARD_FAB2_LIB.BASEBOARD_FAB2(SCH_1):PAGE87
   130 M_M_DQ<57> @BASEBOARD_FAB2_LIB.BASEBOARD_FAB2(SCH_1):M_M_DQ(57)   I186 @BASEBOARD_FAB2_LIB.BASEBOARD_FAB2(SCH_1):PAGE87
   269 M_M_DQ<54> @BASEBOARD_FAB2_LIB.BASEBOARD_FAB2(SCH_1):M_M_DQ(54)   I186 @BASEBOARD_FAB2_LIB.BASEBOARD_FAB2(SCH_1):PAGE87
   124 M_M_DQ<55> @BASEBOARD_FAB2_LIB.BASEBOARD_FAB2(SCH_1):M_M_DQ(55)   I186 @BASEBOARD_FAB2_LIB.BASEBOARD_FAB2(SCH_1):PAGE87
   262 M_M_DQ<52> @BASEBOARD_FAB2_LIB.BASEBOARD_FAB2(SCH_1):M_M_DQ(52)   I186 @BASEBOARD_FAB2_LIB.BASEBOARD_FAB2(SCH_1):PAGE87
   117 M_M_DQ<53> @BASEBOARD_FAB2_LIB.BASEBOARD_FAB2(SCH_1):M_M_DQ(53)   I186 @BASEBOARD_FAB2_LIB.BASEBOARD_FAB2(SCH_1):PAGE87
   271 M_M_DQ<50> @BASEBOARD_FAB2_LIB.BASEBOARD_FAB2(SCH_1):M_M_DQ(50)   I186 @BASEBOARD_FAB2_LIB.BASEBOARD_FAB2(SCH_1):PAGE87
   126 M_M_DQ<51> @BASEBOARD_FAB2_LIB.BASEBOARD_FAB2(SCH_1):M_M_DQ(51)   I186 @BASEBOARD_FAB2_LIB.BASEBOARD_FAB2(SCH_1):PAGE87
   264 M_M_DQ<48> @BASEBOARD_FAB2_LIB.BASEBOARD_FAB2(SCH_1):M_M_DQ(48)   I186 @BASEBOARD_FAB2_LIB.BASEBOARD_FAB2(SCH_1):PAGE87
   119 M_M_DQ<49> @BASEBOARD_FAB2_LIB.BASEBOARD_FAB2(SCH_1):M_M_DQ(49)   I186 @BASEBOARD_FAB2_LIB.BASEBOARD_FAB2(SCH_1):PAGE87
   258 M_M_DQ<46> @BASEBOARD_FAB2_LIB.BASEBOARD_FAB2(SCH_1):M_M_DQ(46)   I186 @BASEBOARD_FAB2_LIB.BASEBOARD_FAB2(SCH_1):PAGE87
   113 M_M_DQ<47> @BASEBOARD_FAB2_LIB.BASEBOARD_FAB2(SCH_1):M_M_DQ(47)   I186 @BASEBOARD_FAB2_LIB.BASEBOARD_FAB2(SCH_1):PAGE87
   251 M_M_DQ<44> @BASEBOARD_FAB2_LIB.BASEBOARD_FAB2(SCH_1):M_M_DQ(44)   I186 @BASEBOARD_FAB2_LIB.BASEBOARD_FAB2(SCH_1):PAGE87
   106 M_M_DQ<45> @BASEBOARD_FAB2_LIB.BASEBOARD_FAB2(SCH_1):M_M_DQ(45)   I186 @BASEBOARD_FAB2_LIB.BASEBOARD_FAB2(SCH_1):PAGE87
   260 M_M_DQ<42> @BASEBOARD_FAB2_LIB.BASEBOARD_FAB2(SCH_1):M_M_DQ(42)   I186 @BASEBOARD_FAB2_LIB.BASEBOARD_FAB2(SCH_1):PAGE87
   115 M_M_DQ<43> @BASEBOARD_FAB2_LIB.BASEBOARD_FAB2(SCH_1):M_M_DQ(43)   I186 @BASEBOARD_FAB2_LIB.BASEBOARD_FAB2(SCH_1):PAGE87
   253 M_M_DQ<40> @BASEBOARD_FAB2_LIB.BASEBOARD_FAB2(SCH_1):M_M_DQ(40)   I186 @BASEBOARD_FAB2_LIB.BASEBOARD_FAB2(SCH_1):PAGE87
   108 M_M_DQ<41> @BASEBOARD_FAB2_LIB.BASEBOARD_FAB2(SCH_1):M_M_DQ(41)   I186 @BASEBOARD_FAB2_LIB.BASEBOARD_FAB2(SCH_1):PAGE87
   247 M_M_DQ<38> @BASEBOARD_FAB2_LIB.BASEBOARD_FAB2(SCH_1):M_M_DQ(38)   I186 @BASEBOARD_FAB2_LIB.BASEBOARD_FAB2(SCH_1):PAGE87
   102 M_M_DQ<39> @BASEBOARD_FAB2_LIB.BASEBOARD_FAB2(SCH_1):M_M_DQ(39)   I186 @BASEBOARD_FAB2_LIB.BASEBOARD_FAB2(SCH_1):PAGE87
   240 M_M_DQ<36> @BASEBOARD_FAB2_LIB.BASEBOARD_FAB2(SCH_1):M_M_DQ(36)   I186 @BASEBOARD_FAB2_LIB.BASEBOARD_FAB2(SCH_1):PAGE87
    95 M_M_DQ<37> @BASEBOARD_FAB2_LIB.BASEBOARD_FAB2(SCH_1):M_M_DQ(37)   I186 @BASEBOARD_FAB2_LIB.BASEBOARD_FAB2(SCH_1):PAGE87
   249 M_M_DQ<34> @BASEBOARD_FAB2_LIB.BASEBOARD_FAB2(SCH_1):M_M_DQ(34)   I186 @BASEBOARD_FAB2_LIB.BASEBOARD_FAB2(SCH_1):PAGE87
   104 M_M_DQ<35> @BASEBOARD_FAB2_LIB.BASEBOARD_FAB2(SCH_1):M_M_DQ(35)   I186 @BASEBOARD_FAB2_LIB.BASEBOARD_FAB2(SCH_1):PAGE87
   242 M_M_DQ<32> @BASEBOARD_FAB2_LIB.BASEBOARD_FAB2(SCH_1):M_M_DQ(32)   I186 @BASEBOARD_FAB2_LIB.BASEBOARD_FAB2(SCH_1):PAGE87
    97 M_M_DQ<33> @BASEBOARD_FAB2_LIB.BASEBOARD_FAB2(SCH_1):M_M_DQ(33)   I186 @BASEBOARD_FAB2_LIB.BASEBOARD_FAB2(SCH_1):PAGE87
   188 M_M_DQ<30> @BASEBOARD_FAB2_LIB.BASEBOARD_FAB2(SCH_1):M_M_DQ(30)   I186 @BASEBOARD_FAB2_LIB.BASEBOARD_FAB2(SCH_1):PAGE87
    43 M_M_DQ<31> @BASEBOARD_FAB2_LIB.BASEBOARD_FAB2(SCH_1):M_M_DQ(31)   I186 @BASEBOARD_FAB2_LIB.BASEBOARD_FAB2(SCH_1):PAGE87
   181 M_M_DQ<28> @BASEBOARD_FAB2_LIB.BASEBOARD_FAB2(SCH_1):M_M_DQ(28)   I186 @BASEBOARD_FAB2_LIB.BASEBOARD_FAB2(SCH_1):PAGE87
    36 M_M_DQ<29> @BASEBOARD_FAB2_LIB.BASEBOARD_FAB2(SCH_1):M_M_DQ(29)   I186 @BASEBOARD_FAB2_LIB.BASEBOARD_FAB2(SCH_1):PAGE87
   190 M_M_DQ<26> @BASEBOARD_FAB2_LIB.BASEBOARD_FAB2(SCH_1):M_M_DQ(26)   I186 @BASEBOARD_FAB2_LIB.BASEBOARD_FAB2(SCH_1):PAGE87
    45 M_M_DQ<27> @BASEBOARD_FAB2_LIB.BASEBOARD_FAB2(SCH_1):M_M_DQ(27)   I186 @BASEBOARD_FAB2_LIB.BASEBOARD_FAB2(SCH_1):PAGE87
   183 M_M_DQ<24> @BASEBOARD_FAB2_LIB.BASEBOARD_FAB2(SCH_1):M_M_DQ(24)   I186 @BASEBOARD_FAB2_LIB.BASEBOARD_FAB2(SCH_1):PAGE87
    38 M_M_DQ<25> @BASEBOARD_FAB2_LIB.BASEBOARD_FAB2(SCH_1):M_M_DQ(25)   I186 @BASEBOARD_FAB2_LIB.BASEBOARD_FAB2(SCH_1):PAGE87
   177 M_M_DQ<22> @BASEBOARD_FAB2_LIB.BASEBOARD_FAB2(SCH_1):M_M_DQ(22)   I186 @BASEBOARD_FAB2_LIB.BASEBOARD_FAB2(SCH_1):PAGE87
    32 M_M_DQ<23> @BASEBOARD_FAB2_LIB.BASEBOARD_FAB2(SCH_1):M_M_DQ(23)   I186 @BASEBOARD_FAB2_LIB.BASEBOARD_FAB2(SCH_1):PAGE87
   170 M_M_DQ<20> @BASEBOARD_FAB2_LIB.BASEBOARD_FAB2(SCH_1):M_M_DQ(20)   I186 @BASEBOARD_FAB2_LIB.BASEBOARD_FAB2(SCH_1):PAGE87
    25 M_M_DQ<21> @BASEBOARD_FAB2_LIB.BASEBOARD_FAB2(SCH_1):M_M_DQ(21)   I186 @BASEBOARD_FAB2_LIB.BASEBOARD_FAB2(SCH_1):PAGE87
   179 M_M_DQ<18> @BASEBOARD_FAB2_LIB.BASEBOARD_FAB2(SCH_1):M_M_DQ(18)   I186 @BASEBOARD_FAB2_LIB.BASEBOARD_FAB2(SCH_1):PAGE87
    34 M_M_DQ<19> @BASEBOARD_FAB2_LIB.BASEBOARD_FAB2(SCH_1):M_M_DQ(19)   I186 @BASEBOARD_FAB2_LIB.BASEBOARD_FAB2(SCH_1):PAGE87
   172 M_M_DQ<16> @BASEBOARD_FAB2_LIB.BASEBOARD_FAB2(SCH_1):M_M_DQ(16)   I186 @BASEBOARD_FAB2_LIB.BASEBOARD_FAB2(SCH_1):PAGE87
    27 M_M_DQ<17> @BASEBOARD_FAB2_LIB.BASEBOARD_FAB2(SCH_1):M_M_DQ(17)   I186 @BASEBOARD_FAB2_LIB.BASEBOARD_FAB2(SCH_1):PAGE87
   166 M_M_DQ<14> @BASEBOARD_FAB2_LIB.BASEBOARD_FAB2(SCH_1):M_M_DQ(14)   I186 @BASEBOARD_FAB2_LIB.BASEBOARD_FAB2(SCH_1):PAGE87
    21 M_M_DQ<15> @BASEBOARD_FAB2_LIB.BASEBOARD_FAB2(SCH_1):M_M_DQ(15)   I186 @BASEBOARD_FAB2_LIB.BASEBOARD_FAB2(SCH_1):PAGE87
   159 M_M_DQ<12> @BASEBOARD_FAB2_LIB.BASEBOARD_FAB2(SCH_1):M_M_DQ(12)   I186 @BASEBOARD_FAB2_LIB.BASEBOARD_FAB2(SCH_1):PAGE87
    14 M_M_DQ<13> @BASEBOARD_FAB2_LIB.BASEBOARD_FAB2(SCH_1):M_M_DQ(13)   I186 @BASEBOARD_FAB2_LIB.BASEBOARD_FAB2(SCH_1):PAGE87
   168 M_M_DQ<10> @BASEBOARD_FAB2_LIB.BASEBOARD_FAB2(SCH_1):M_M_DQ(10)   I186 @BASEBOARD_FAB2_LIB.BASEBOARD_FAB2(SCH_1):PAGE87
    23 M_M_DQ<11> @BASEBOARD_FAB2_LIB.BASEBOARD_FAB2(SCH_1):M_M_DQ(11)   I186 @BASEBOARD_FAB2_LIB.BASEBOARD_FAB2(SCH_1):PAGE87
   161 M_M_DQ<8> @BASEBOARD_FAB2_LIB.BASEBOARD_FAB2(SCH_1):M_M_DQ(8)   I186 @BASEBOARD_FAB2_LIB.BASEBOARD_FAB2(SCH_1):PAGE87
    16 M_M_DQ<9> @BASEBOARD_FAB2_LIB.BASEBOARD_FAB2(SCH_1):M_M_DQ(9)   I186 @BASEBOARD_FAB2_LIB.BASEBOARD_FAB2(SCH_1):PAGE87
   155 M_M_DQ<6> @BASEBOARD_FAB2_LIB.BASEBOARD_FAB2(SCH_1):M_M_DQ(6)   I186 @BASEBOARD_FAB2_LIB.BASEBOARD_FAB2(SCH_1):PAGE87
    10 M_M_DQ<7> @BASEBOARD_FAB2_LIB.BASEBOARD_FAB2(SCH_1):M_M_DQ(7)   I186 @BASEBOARD_FAB2_LIB.BASEBOARD_FAB2(SCH_1):PAGE87
   148 M_M_DQ<4> @BASEBOARD_FAB2_LIB.BASEBOARD_FAB2(SCH_1):M_M_DQ(4)   I186 @BASEBOARD_FAB2_LIB.BASEBOARD_FAB2(SCH_1):PAGE87
     3 M_M_DQ<5> @BASEBOARD_FAB2_LIB.BASEBOARD_FAB2(SCH_1):M_M_DQ(5)   I186 @BASEBOARD_FAB2_LIB.BASEBOARD_FAB2(SCH_1):PAGE87
   157 M_M_DQ<2> @BASEBOARD_FAB2_LIB.BASEBOARD_FAB2(SCH_1):M_M_DQ(2)   I186 @BASEBOARD_FAB2_LIB.BASEBOARD_FAB2(SCH_1):PAGE87
    12 M_M_DQ<3> @BASEBOARD_FAB2_LIB.BASEBOARD_FAB2(SCH_1):M_M_DQ(3)   I186 @BASEBOARD_FAB2_LIB.BASEBOARD_FAB2(SCH_1):PAGE87
   150 M_M_DQ<0> @BASEBOARD_FAB2_LIB.BASEBOARD_FAB2(SCH_1):M_M_DQ(0)   I186 @BASEBOARD_FAB2_LIB.BASEBOARD_FAB2(SCH_1):PAGE87
     5 M_M_DQ<1> @BASEBOARD_FAB2_LIB.BASEBOARD_FAB2(SCH_1):M_M_DQ(1)   I186 @BASEBOARD_FAB2_LIB.BASEBOARD_FAB2(SCH_1):PAGE87
    78 FM_DIMM_EVENT_COD_N @BASEBOARD_FAB2_LIB.BASEBOARD_FAB2(SCH_1):FM_DIMM_EVENT_COD_N   I186 @BASEBOARD_FAB2_LIB.BASEBOARD_FAB2(SCH_1):PAGE87
    91 M_M_ODT<1> @BASEBOARD_FAB2_LIB.BASEBOARD_FAB2(SCH_1):M_M_ODT(1)   I186 @BASEBOARD_FAB2_LIB.BASEBOARD_FAB2(SCH_1):PAGE87
    87 M_M_ODT<0> @BASEBOARD_FAB2_LIB.BASEBOARD_FAB2(SCH_1):M_M_ODT(0)   I186 @BASEBOARD_FAB2_LIB.BASEBOARD_FAB2(SCH_1):PAGE87
   222 M_M_PAR @BASEBOARD_FAB2_LIB.BASEBOARD_FAB2(SCH_1):M_M_PAR   I186 @BASEBOARD_FAB2_LIB.BASEBOARD_FAB2(SCH_1):PAGE87
    58 M_KLM_RST_N @BASEBOARD_FAB2_LIB.BASEBOARD_FAB2(SCH_1):M_KLM_RST_N   I186 @BASEBOARD_FAB2_LIB.BASEBOARD_FAB2(SCH_1):PAGE87
   144 TP_CH_M_DIMM_M0_RFU_2 @BASEBOARD_FAB2_LIB.BASEBOARD_FAB2(SCH_1):TP_CH_M_DIMM_M0_RFU_2   I186 @BASEBOARD_FAB2_LIB.BASEBOARD_FAB2(SCH_1):PAGE87
   227 TP_CH_M_DIMM_M0_RFU_1 @BASEBOARD_FAB2_LIB.BASEBOARD_FAB2(SCH_1):TP_CH_M_DIMM_M0_RFU_1   I186 @BASEBOARD_FAB2_LIB.BASEBOARD_FAB2(SCH_1):PAGE87
   205 TP_CH_M_DIMM_M0_RFU_0 @BASEBOARD_FAB2_LIB.BASEBOARD_FAB2(SCH_1):TP_CH_M_DIMM_M0_RFU_0   I186 @BASEBOARD_FAB2_LIB.BASEBOARD_FAB2(SCH_1):PAGE87
    84 M_M_CS_N<0> @BASEBOARD_FAB2_LIB.BASEBOARD_FAB2(SCH_1):M_M_CS_N(0)   I186 @BASEBOARD_FAB2_LIB.BASEBOARD_FAB2(SCH_1):PAGE87
    89 M_M_CS_N<1> @BASEBOARD_FAB2_LIB.BASEBOARD_FAB2(SCH_1):M_M_CS_N(1)   I186 @BASEBOARD_FAB2_LIB.BASEBOARD_FAB2(SCH_1):PAGE87
    93 M_M_CS_N<2> @BASEBOARD_FAB2_LIB.BASEBOARD_FAB2(SCH_1):M_M_CS_N(2)   I186 @BASEBOARD_FAB2_LIB.BASEBOARD_FAB2(SCH_1):PAGE87
   237 M_M_CS_N<3> @BASEBOARD_FAB2_LIB.BASEBOARD_FAB2(SCH_1):M_M_CS_N(3)   I186 @BASEBOARD_FAB2_LIB.BASEBOARD_FAB2(SCH_1):PAGE87
   238 PVPP_KLM @BASEBOARD_FAB2_LIB.BASEBOARD_FAB2(SCH_1):PVPP_KLM   I186 @BASEBOARD_FAB2_LIB.BASEBOARD_FAB2(SCH_1):PAGE87
   140    GND @BASEBOARD_FAB2_LIB.BASEBOARD_FAB2(SCH_1):GND   I186 @BASEBOARD_FAB2_LIB.BASEBOARD_FAB2(SCH_1):PAGE87
   139    GND @BASEBOARD_FAB2_LIB.BASEBOARD_FAB2(SCH_1):GND   I186 @BASEBOARD_FAB2_LIB.BASEBOARD_FAB2(SCH_1):PAGE87
   230 FM_ADR_COMPLETE_KLM_N @BASEBOARD_FAB2_LIB.BASEBOARD_FAB2(SCH_1):FM_ADR_COMPLETE_KLM_N   I186 @BASEBOARD_FAB2_LIB.BASEBOARD_FAB2(SCH_1):PAGE87
   141 SMB_DDR_KLM_VPP_SCL @BASEBOARD_FAB2_LIB.BASEBOARD_FAB2(SCH_1):SMB_DDR_KLM_VPP_SCL   I186 @BASEBOARD_FAB2_LIB.BASEBOARD_FAB2(SCH_1):PAGE87
   285 SMB_DDR_KLM_VPP_SDA @BASEBOARD_FAB2_LIB.BASEBOARD_FAB2(SCH_1):SMB_DDR_KLM_VPP_SDA   I186 @BASEBOARD_FAB2_LIB.BASEBOARD_FAB2(SCH_1):PAGE87
   284 PVPP_KLM @BASEBOARD_FAB2_LIB.BASEBOARD_FAB2(SCH_1):PVPP_KLM   I186 @BASEBOARD_FAB2_LIB.BASEBOARD_FAB2(SCH_1):PAGE87
   146 M_M_VREF @BASEBOARD_FAB2_LIB.BASEBOARD_FAB2(SCH_1):M_M_VREF   I186 @BASEBOARD_FAB2_LIB.BASEBOARD_FAB2(SCH_1):PAGE87
   152 M_M_DQS_DN<0> @BASEBOARD_FAB2_LIB.BASEBOARD_FAB2(SCH_1):M_M_DQS_DN(0)   I187 @BASEBOARD_FAB2_LIB.BASEBOARD_FAB2(SCH_1):PAGE87
   153 M_M_DQS_DP<0> @BASEBOARD_FAB2_LIB.BASEBOARD_FAB2(SCH_1):M_M_DQS_DP(0)   I187 @BASEBOARD_FAB2_LIB.BASEBOARD_FAB2(SCH_1):PAGE87
    19 M_M_DQS_DN<10> @BASEBOARD_FAB2_LIB.BASEBOARD_FAB2(SCH_1):M_M_DQS_DN(10)   I187 @BASEBOARD_FAB2_LIB.BASEBOARD_FAB2(SCH_1):PAGE87
    18 M_M_DQS_DP<10> @BASEBOARD_FAB2_LIB.BASEBOARD_FAB2(SCH_1):M_M_DQS_DP(10)   I187 @BASEBOARD_FAB2_LIB.BASEBOARD_FAB2(SCH_1):PAGE87
    30 M_M_DQS_DN<11> @BASEBOARD_FAB2_LIB.BASEBOARD_FAB2(SCH_1):M_M_DQS_DN(11)   I187 @BASEBOARD_FAB2_LIB.BASEBOARD_FAB2(SCH_1):PAGE87
    29 M_M_DQS_DP<11> @BASEBOARD_FAB2_LIB.BASEBOARD_FAB2(SCH_1):M_M_DQS_DP(11)   I187 @BASEBOARD_FAB2_LIB.BASEBOARD_FAB2(SCH_1):PAGE87
    41 M_M_DQS_DN<12> @BASEBOARD_FAB2_LIB.BASEBOARD_FAB2(SCH_1):M_M_DQS_DN(12)   I187 @BASEBOARD_FAB2_LIB.BASEBOARD_FAB2(SCH_1):PAGE87
    40 M_M_DQS_DP<12> @BASEBOARD_FAB2_LIB.BASEBOARD_FAB2(SCH_1):M_M_DQS_DP(12)   I187 @BASEBOARD_FAB2_LIB.BASEBOARD_FAB2(SCH_1):PAGE87
   100 M_M_DQS_DN<13> @BASEBOARD_FAB2_LIB.BASEBOARD_FAB2(SCH_1):M_M_DQS_DN(13)   I187 @BASEBOARD_FAB2_LIB.BASEBOARD_FAB2(SCH_1):PAGE87
    99 M_M_DQS_DP<13> @BASEBOARD_FAB2_LIB.BASEBOARD_FAB2(SCH_1):M_M_DQS_DP(13)   I187 @BASEBOARD_FAB2_LIB.BASEBOARD_FAB2(SCH_1):PAGE87
   111 M_M_DQS_DN<14> @BASEBOARD_FAB2_LIB.BASEBOARD_FAB2(SCH_1):M_M_DQS_DN(14)   I187 @BASEBOARD_FAB2_LIB.BASEBOARD_FAB2(SCH_1):PAGE87
   110 M_M_DQS_DP<14> @BASEBOARD_FAB2_LIB.BASEBOARD_FAB2(SCH_1):M_M_DQS_DP(14)   I187 @BASEBOARD_FAB2_LIB.BASEBOARD_FAB2(SCH_1):PAGE87
   122 M_M_DQS_DN<15> @BASEBOARD_FAB2_LIB.BASEBOARD_FAB2(SCH_1):M_M_DQS_DN(15)   I187 @BASEBOARD_FAB2_LIB.BASEBOARD_FAB2(SCH_1):PAGE87
   121 M_M_DQS_DP<15> @BASEBOARD_FAB2_LIB.BASEBOARD_FAB2(SCH_1):M_M_DQS_DP(15)   I187 @BASEBOARD_FAB2_LIB.BASEBOARD_FAB2(SCH_1):PAGE87
   133 M_M_DQS_DN<16> @BASEBOARD_FAB2_LIB.BASEBOARD_FAB2(SCH_1):M_M_DQS_DN(16)   I187 @BASEBOARD_FAB2_LIB.BASEBOARD_FAB2(SCH_1):PAGE87
   132 M_M_DQS_DP<16> @BASEBOARD_FAB2_LIB.BASEBOARD_FAB2(SCH_1):M_M_DQS_DP(16)   I187 @BASEBOARD_FAB2_LIB.BASEBOARD_FAB2(SCH_1):PAGE87
    52 M_M_DQS_DN<17> @BASEBOARD_FAB2_LIB.BASEBOARD_FAB2(SCH_1):M_M_DQS_DN(17)   I187 @BASEBOARD_FAB2_LIB.BASEBOARD_FAB2(SCH_1):PAGE87
    51 M_M_DQS_DP<17> @BASEBOARD_FAB2_LIB.BASEBOARD_FAB2(SCH_1):M_M_DQS_DP(17)   I187 @BASEBOARD_FAB2_LIB.BASEBOARD_FAB2(SCH_1):PAGE87
   163 M_M_DQS_DN<1> @BASEBOARD_FAB2_LIB.BASEBOARD_FAB2(SCH_1):M_M_DQS_DN(1)   I187 @BASEBOARD_FAB2_LIB.BASEBOARD_FAB2(SCH_1):PAGE87
   164 M_M_DQS_DP<1> @BASEBOARD_FAB2_LIB.BASEBOARD_FAB2(SCH_1):M_M_DQS_DP(1)   I187 @BASEBOARD_FAB2_LIB.BASEBOARD_FAB2(SCH_1):PAGE87
   174 M_M_DQS_DN<2> @BASEBOARD_FAB2_LIB.BASEBOARD_FAB2(SCH_1):M_M_DQS_DN(2)   I187 @BASEBOARD_FAB2_LIB.BASEBOARD_FAB2(SCH_1):PAGE87
   175 M_M_DQS_DP<2> @BASEBOARD_FAB2_LIB.BASEBOARD_FAB2(SCH_1):M_M_DQS_DP(2)   I187 @BASEBOARD_FAB2_LIB.BASEBOARD_FAB2(SCH_1):PAGE87
   185 M_M_DQS_DN<3> @BASEBOARD_FAB2_LIB.BASEBOARD_FAB2(SCH_1):M_M_DQS_DN(3)   I187 @BASEBOARD_FAB2_LIB.BASEBOARD_FAB2(SCH_1):PAGE87
   186 M_M_DQS_DP<3> @BASEBOARD_FAB2_LIB.BASEBOARD_FAB2(SCH_1):M_M_DQS_DP(3)   I187 @BASEBOARD_FAB2_LIB.BASEBOARD_FAB2(SCH_1):PAGE87
   244 M_M_DQS_DN<4> @BASEBOARD_FAB2_LIB.BASEBOARD_FAB2(SCH_1):M_M_DQS_DN(4)   I187 @BASEBOARD_FAB2_LIB.BASEBOARD_FAB2(SCH_1):PAGE87
   245 M_M_DQS_DP<4> @BASEBOARD_FAB2_LIB.BASEBOARD_FAB2(SCH_1):M_M_DQS_DP(4)   I187 @BASEBOARD_FAB2_LIB.BASEBOARD_FAB2(SCH_1):PAGE87
   255 M_M_DQS_DN<5> @BASEBOARD_FAB2_LIB.BASEBOARD_FAB2(SCH_1):M_M_DQS_DN(5)   I187 @BASEBOARD_FAB2_LIB.BASEBOARD_FAB2(SCH_1):PAGE87
   256 M_M_DQS_DP<5> @BASEBOARD_FAB2_LIB.BASEBOARD_FAB2(SCH_1):M_M_DQS_DP(5)   I187 @BASEBOARD_FAB2_LIB.BASEBOARD_FAB2(SCH_1):PAGE87
   266 M_M_DQS_DN<6> @BASEBOARD_FAB2_LIB.BASEBOARD_FAB2(SCH_1):M_M_DQS_DN(6)   I187 @BASEBOARD_FAB2_LIB.BASEBOARD_FAB2(SCH_1):PAGE87
   267 M_M_DQS_DP<6> @BASEBOARD_FAB2_LIB.BASEBOARD_FAB2(SCH_1):M_M_DQS_DP(6)   I187 @BASEBOARD_FAB2_LIB.BASEBOARD_FAB2(SCH_1):PAGE87
   277 M_M_DQS_DN<7> @BASEBOARD_FAB2_LIB.BASEBOARD_FAB2(SCH_1):M_M_DQS_DN(7)   I187 @BASEBOARD_FAB2_LIB.BASEBOARD_FAB2(SCH_1):PAGE87
   278 M_M_DQS_DP<7> @BASEBOARD_FAB2_LIB.BASEBOARD_FAB2(SCH_1):M_M_DQS_DP(7)   I187 @BASEBOARD_FAB2_LIB.BASEBOARD_FAB2(SCH_1):PAGE87
   196 M_M_DQS_DN<8> @BASEBOARD_FAB2_LIB.BASEBOARD_FAB2(SCH_1):M_M_DQS_DN(8)   I187 @BASEBOARD_FAB2_LIB.BASEBOARD_FAB2(SCH_1):PAGE87
   197 M_M_DQS_DP<8> @BASEBOARD_FAB2_LIB.BASEBOARD_FAB2(SCH_1):M_M_DQS_DP(8)   I187 @BASEBOARD_FAB2_LIB.BASEBOARD_FAB2(SCH_1):PAGE87
     8 M_M_DQS_DN<9> @BASEBOARD_FAB2_LIB.BASEBOARD_FAB2(SCH_1):M_M_DQS_DN(9)   I187 @BASEBOARD_FAB2_LIB.BASEBOARD_FAB2(SCH_1):PAGE87
     7 M_M_DQS_DP<9> @BASEBOARD_FAB2_LIB.BASEBOARD_FAB2(SCH_1):M_M_DQS_DP(9)   I187 @BASEBOARD_FAB2_LIB.BASEBOARD_FAB2(SCH_1):PAGE87
     2    GND @BASEBOARD_FAB2_LIB.BASEBOARD_FAB2(SCH_1):GND   I185 @BASEBOARD_FAB2_LIB.BASEBOARD_FAB2(SCH_1):PAGE87
     4    GND @BASEBOARD_FAB2_LIB.BASEBOARD_FAB2(SCH_1):GND   I185 @BASEBOARD_FAB2_LIB.BASEBOARD_FAB2(SCH_1):PAGE87
     6    GND @BASEBOARD_FAB2_LIB.BASEBOARD_FAB2(SCH_1):GND   I185 @BASEBOARD_FAB2_LIB.BASEBOARD_FAB2(SCH_1):PAGE87
     9    GND @BASEBOARD_FAB2_LIB.BASEBOARD_FAB2(SCH_1):GND   I185 @BASEBOARD_FAB2_LIB.BASEBOARD_FAB2(SCH_1):PAGE87
    11    GND @BASEBOARD_FAB2_LIB.BASEBOARD_FAB2(SCH_1):GND   I185 @BASEBOARD_FAB2_LIB.BASEBOARD_FAB2(SCH_1):PAGE87
    13    GND @BASEBOARD_FAB2_LIB.BASEBOARD_FAB2(SCH_1):GND   I185 @BASEBOARD_FAB2_LIB.BASEBOARD_FAB2(SCH_1):PAGE87
    15    GND @BASEBOARD_FAB2_LIB.BASEBOARD_FAB2(SCH_1):GND   I185 @BASEBOARD_FAB2_LIB.BASEBOARD_FAB2(SCH_1):PAGE87
    17    GND @BASEBOARD_FAB2_LIB.BASEBOARD_FAB2(SCH_1):GND   I185 @BASEBOARD_FAB2_LIB.BASEBOARD_FAB2(SCH_1):PAGE87
    20    GND @BASEBOARD_FAB2_LIB.BASEBOARD_FAB2(SCH_1):GND   I185 @BASEBOARD_FAB2_LIB.BASEBOARD_FAB2(SCH_1):PAGE87
    22    GND @BASEBOARD_FAB2_LIB.BASEBOARD_FAB2(SCH_1):GND   I185 @BASEBOARD_FAB2_LIB.BASEBOARD_FAB2(SCH_1):PAGE87
    24    GND @BASEBOARD_FAB2_LIB.BASEBOARD_FAB2(SCH_1):GND   I185 @BASEBOARD_FAB2_LIB.BASEBOARD_FAB2(SCH_1):PAGE87
    26    GND @BASEBOARD_FAB2_LIB.BASEBOARD_FAB2(SCH_1):GND   I185 @BASEBOARD_FAB2_LIB.BASEBOARD_FAB2(SCH_1):PAGE87
    28    GND @BASEBOARD_FAB2_LIB.BASEBOARD_FAB2(SCH_1):GND   I185 @BASEBOARD_FAB2_LIB.BASEBOARD_FAB2(SCH_1):PAGE87
    31    GND @BASEBOARD_FAB2_LIB.BASEBOARD_FAB2(SCH_1):GND   I185 @BASEBOARD_FAB2_LIB.BASEBOARD_FAB2(SCH_1):PAGE87
    33    GND @BASEBOARD_FAB2_LIB.BASEBOARD_FAB2(SCH_1):GND   I185 @BASEBOARD_FAB2_LIB.BASEBOARD_FAB2(SCH_1):PAGE87
    35    GND @BASEBOARD_FAB2_LIB.BASEBOARD_FAB2(SCH_1):GND   I185 @BASEBOARD_FAB2_LIB.BASEBOARD_FAB2(SCH_1):PAGE87
    37    GND @BASEBOARD_FAB2_LIB.BASEBOARD_FAB2(SCH_1):GND   I185 @BASEBOARD_FAB2_LIB.BASEBOARD_FAB2(SCH_1):PAGE87
    39    GND @BASEBOARD_FAB2_LIB.BASEBOARD_FAB2(SCH_1):GND   I185 @BASEBOARD_FAB2_LIB.BASEBOARD_FAB2(SCH_1):PAGE87
    42    GND @BASEBOARD_FAB2_LIB.BASEBOARD_FAB2(SCH_1):GND   I185 @BASEBOARD_FAB2_LIB.BASEBOARD_FAB2(SCH_1):PAGE87
    44    GND @BASEBOARD_FAB2_LIB.BASEBOARD_FAB2(SCH_1):GND   I185 @BASEBOARD_FAB2_LIB.BASEBOARD_FAB2(SCH_1):PAGE87
    46    GND @BASEBOARD_FAB2_LIB.BASEBOARD_FAB2(SCH_1):GND   I185 @BASEBOARD_FAB2_LIB.BASEBOARD_FAB2(SCH_1):PAGE87
    48    GND @BASEBOARD_FAB2_LIB.BASEBOARD_FAB2(SCH_1):GND   I185 @BASEBOARD_FAB2_LIB.BASEBOARD_FAB2(SCH_1):PAGE87
    50    GND @BASEBOARD_FAB2_LIB.BASEBOARD_FAB2(SCH_1):GND   I185 @BASEBOARD_FAB2_LIB.BASEBOARD_FAB2(SCH_1):PAGE87
    53    GND @BASEBOARD_FAB2_LIB.BASEBOARD_FAB2(SCH_1):GND   I185 @BASEBOARD_FAB2_LIB.BASEBOARD_FAB2(SCH_1):PAGE87
    55    GND @BASEBOARD_FAB2_LIB.BASEBOARD_FAB2(SCH_1):GND   I185 @BASEBOARD_FAB2_LIB.BASEBOARD_FAB2(SCH_1):PAGE87
    57    GND @BASEBOARD_FAB2_LIB.BASEBOARD_FAB2(SCH_1):GND   I185 @BASEBOARD_FAB2_LIB.BASEBOARD_FAB2(SCH_1):PAGE87
    94    GND @BASEBOARD_FAB2_LIB.BASEBOARD_FAB2(SCH_1):GND   I185 @BASEBOARD_FAB2_LIB.BASEBOARD_FAB2(SCH_1):PAGE87
    96    GND @BASEBOARD_FAB2_LIB.BASEBOARD_FAB2(SCH_1):GND   I185 @BASEBOARD_FAB2_LIB.BASEBOARD_FAB2(SCH_1):PAGE87
    98    GND @BASEBOARD_FAB2_LIB.BASEBOARD_FAB2(SCH_1):GND   I185 @BASEBOARD_FAB2_LIB.BASEBOARD_FAB2(SCH_1):PAGE87
   101    GND @BASEBOARD_FAB2_LIB.BASEBOARD_FAB2(SCH_1):GND   I185 @BASEBOARD_FAB2_LIB.BASEBOARD_FAB2(SCH_1):PAGE87
   103    GND @BASEBOARD_FAB2_LIB.BASEBOARD_FAB2(SCH_1):GND   I185 @BASEBOARD_FAB2_LIB.BASEBOARD_FAB2(SCH_1):PAGE87
   105    GND @BASEBOARD_FAB2_LIB.BASEBOARD_FAB2(SCH_1):GND   I185 @BASEBOARD_FAB2_LIB.BASEBOARD_FAB2(SCH_1):PAGE87
   107    GND @BASEBOARD_FAB2_LIB.BASEBOARD_FAB2(SCH_1):GND   I185 @BASEBOARD_FAB2_LIB.BASEBOARD_FAB2(SCH_1):PAGE87
   109    GND @BASEBOARD_FAB2_LIB.BASEBOARD_FAB2(SCH_1):GND   I185 @BASEBOARD_FAB2_LIB.BASEBOARD_FAB2(SCH_1):PAGE87
   112    GND @BASEBOARD_FAB2_LIB.BASEBOARD_FAB2(SCH_1):GND   I185 @BASEBOARD_FAB2_LIB.BASEBOARD_FAB2(SCH_1):PAGE87
   114    GND @BASEBOARD_FAB2_LIB.BASEBOARD_FAB2(SCH_1):GND   I185 @BASEBOARD_FAB2_LIB.BASEBOARD_FAB2(SCH_1):PAGE87
   116    GND @BASEBOARD_FAB2_LIB.BASEBOARD_FAB2(SCH_1):GND   I185 @BASEBOARD_FAB2_LIB.BASEBOARD_FAB2(SCH_1):PAGE87
   118    GND @BASEBOARD_FAB2_LIB.BASEBOARD_FAB2(SCH_1):GND   I185 @BASEBOARD_FAB2_LIB.BASEBOARD_FAB2(SCH_1):PAGE87
   120    GND @BASEBOARD_FAB2_LIB.BASEBOARD_FAB2(SCH_1):GND   I185 @BASEBOARD_FAB2_LIB.BASEBOARD_FAB2(SCH_1):PAGE87
   123    GND @BASEBOARD_FAB2_LIB.BASEBOARD_FAB2(SCH_1):GND   I185 @BASEBOARD_FAB2_LIB.BASEBOARD_FAB2(SCH_1):PAGE87
   125    GND @BASEBOARD_FAB2_LIB.BASEBOARD_FAB2(SCH_1):GND   I185 @BASEBOARD_FAB2_LIB.BASEBOARD_FAB2(SCH_1):PAGE87
   127    GND @BASEBOARD_FAB2_LIB.BASEBOARD_FAB2(SCH_1):GND   I185 @BASEBOARD_FAB2_LIB.BASEBOARD_FAB2(SCH_1):PAGE87
   129    GND @BASEBOARD_FAB2_LIB.BASEBOARD_FAB2(SCH_1):GND   I185 @BASEBOARD_FAB2_LIB.BASEBOARD_FAB2(SCH_1):PAGE87
   131    GND @BASEBOARD_FAB2_LIB.BASEBOARD_FAB2(SCH_1):GND   I185 @BASEBOARD_FAB2_LIB.BASEBOARD_FAB2(SCH_1):PAGE87
   134    GND @BASEBOARD_FAB2_LIB.BASEBOARD_FAB2(SCH_1):GND   I185 @BASEBOARD_FAB2_LIB.BASEBOARD_FAB2(SCH_1):PAGE87
   136    GND @BASEBOARD_FAB2_LIB.BASEBOARD_FAB2(SCH_1):GND   I185 @BASEBOARD_FAB2_LIB.BASEBOARD_FAB2(SCH_1):PAGE87
   138    GND @BASEBOARD_FAB2_LIB.BASEBOARD_FAB2(SCH_1):GND   I185 @BASEBOARD_FAB2_LIB.BASEBOARD_FAB2(SCH_1):PAGE87
   147    GND @BASEBOARD_FAB2_LIB.BASEBOARD_FAB2(SCH_1):GND   I185 @BASEBOARD_FAB2_LIB.BASEBOARD_FAB2(SCH_1):PAGE87
   149    GND @BASEBOARD_FAB2_LIB.BASEBOARD_FAB2(SCH_1):GND   I185 @BASEBOARD_FAB2_LIB.BASEBOARD_FAB2(SCH_1):PAGE87
   151    GND @BASEBOARD_FAB2_LIB.BASEBOARD_FAB2(SCH_1):GND   I185 @BASEBOARD_FAB2_LIB.BASEBOARD_FAB2(SCH_1):PAGE87
   154    GND @BASEBOARD_FAB2_LIB.BASEBOARD_FAB2(SCH_1):GND   I185 @BASEBOARD_FAB2_LIB.BASEBOARD_FAB2(SCH_1):PAGE87
   156    GND @BASEBOARD_FAB2_LIB.BASEBOARD_FAB2(SCH_1):GND   I185 @BASEBOARD_FAB2_LIB.BASEBOARD_FAB2(SCH_1):PAGE87
   158    GND @BASEBOARD_FAB2_LIB.BASEBOARD_FAB2(SCH_1):GND   I185 @BASEBOARD_FAB2_LIB.BASEBOARD_FAB2(SCH_1):PAGE87
   160    GND @BASEBOARD_FAB2_LIB.BASEBOARD_FAB2(SCH_1):GND   I185 @BASEBOARD_FAB2_LIB.BASEBOARD_FAB2(SCH_1):PAGE87
   162    GND @BASEBOARD_FAB2_LIB.BASEBOARD_FAB2(SCH_1):GND   I185 @BASEBOARD_FAB2_LIB.BASEBOARD_FAB2(SCH_1):PAGE87
   165    GND @BASEBOARD_FAB2_LIB.BASEBOARD_FAB2(SCH_1):GND   I185 @BASEBOARD_FAB2_LIB.BASEBOARD_FAB2(SCH_1):PAGE87
   167    GND @BASEBOARD_FAB2_LIB.BASEBOARD_FAB2(SCH_1):GND   I185 @BASEBOARD_FAB2_LIB.BASEBOARD_FAB2(SCH_1):PAGE87
   169    GND @BASEBOARD_FAB2_LIB.BASEBOARD_FAB2(SCH_1):GND   I185 @BASEBOARD_FAB2_LIB.BASEBOARD_FAB2(SCH_1):PAGE87
   171    GND @BASEBOARD_FAB2_LIB.BASEBOARD_FAB2(SCH_1):GND   I185 @BASEBOARD_FAB2_LIB.BASEBOARD_FAB2(SCH_1):PAGE87
   173    GND @BASEBOARD_FAB2_LIB.BASEBOARD_FAB2(SCH_1):GND   I185 @BASEBOARD_FAB2_LIB.BASEBOARD_FAB2(SCH_1):PAGE87
   176    GND @BASEBOARD_FAB2_LIB.BASEBOARD_FAB2(SCH_1):GND   I185 @BASEBOARD_FAB2_LIB.BASEBOARD_FAB2(SCH_1):PAGE87
   178    GND @BASEBOARD_FAB2_LIB.BASEBOARD_FAB2(SCH_1):GND   I185 @BASEBOARD_FAB2_LIB.BASEBOARD_FAB2(SCH_1):PAGE87
   180    GND @BASEBOARD_FAB2_LIB.BASEBOARD_FAB2(SCH_1):GND   I185 @BASEBOARD_FAB2_LIB.BASEBOARD_FAB2(SCH_1):PAGE87
   182    GND @BASEBOARD_FAB2_LIB.BASEBOARD_FAB2(SCH_1):GND   I185 @BASEBOARD_FAB2_LIB.BASEBOARD_FAB2(SCH_1):PAGE87
   184    GND @BASEBOARD_FAB2_LIB.BASEBOARD_FAB2(SCH_1):GND   I185 @BASEBOARD_FAB2_LIB.BASEBOARD_FAB2(SCH_1):PAGE87
   187    GND @BASEBOARD_FAB2_LIB.BASEBOARD_FAB2(SCH_1):GND   I185 @BASEBOARD_FAB2_LIB.BASEBOARD_FAB2(SCH_1):PAGE87
   189    GND @BASEBOARD_FAB2_LIB.BASEBOARD_FAB2(SCH_1):GND   I185 @BASEBOARD_FAB2_LIB.BASEBOARD_FAB2(SCH_1):PAGE87
   191    GND @BASEBOARD_FAB2_LIB.BASEBOARD_FAB2(SCH_1):GND   I185 @BASEBOARD_FAB2_LIB.BASEBOARD_FAB2(SCH_1):PAGE87
   193    GND @BASEBOARD_FAB2_LIB.BASEBOARD_FAB2(SCH_1):GND   I185 @BASEBOARD_FAB2_LIB.BASEBOARD_FAB2(SCH_1):PAGE87
   195    GND @BASEBOARD_FAB2_LIB.BASEBOARD_FAB2(SCH_1):GND   I185 @BASEBOARD_FAB2_LIB.BASEBOARD_FAB2(SCH_1):PAGE87
   198    GND @BASEBOARD_FAB2_LIB.BASEBOARD_FAB2(SCH_1):GND   I185 @BASEBOARD_FAB2_LIB.BASEBOARD_FAB2(SCH_1):PAGE87
   200    GND @BASEBOARD_FAB2_LIB.BASEBOARD_FAB2(SCH_1):GND   I185 @BASEBOARD_FAB2_LIB.BASEBOARD_FAB2(SCH_1):PAGE87
   202    GND @BASEBOARD_FAB2_LIB.BASEBOARD_FAB2(SCH_1):GND   I185 @BASEBOARD_FAB2_LIB.BASEBOARD_FAB2(SCH_1):PAGE87
   239    GND @BASEBOARD_FAB2_LIB.BASEBOARD_FAB2(SCH_1):GND   I185 @BASEBOARD_FAB2_LIB.BASEBOARD_FAB2(SCH_1):PAGE87
   241    GND @BASEBOARD_FAB2_LIB.BASEBOARD_FAB2(SCH_1):GND   I185 @BASEBOARD_FAB2_LIB.BASEBOARD_FAB2(SCH_1):PAGE87
   243    GND @BASEBOARD_FAB2_LIB.BASEBOARD_FAB2(SCH_1):GND   I185 @BASEBOARD_FAB2_LIB.BASEBOARD_FAB2(SCH_1):PAGE87
   246    GND @BASEBOARD_FAB2_LIB.BASEBOARD_FAB2(SCH_1):GND   I185 @BASEBOARD_FAB2_LIB.BASEBOARD_FAB2(SCH_1):PAGE87
   248    GND @BASEBOARD_FAB2_LIB.BASEBOARD_FAB2(SCH_1):GND   I185 @BASEBOARD_FAB2_LIB.BASEBOARD_FAB2(SCH_1):PAGE87
   250    GND @BASEBOARD_FAB2_LIB.BASEBOARD_FAB2(SCH_1):GND   I185 @BASEBOARD_FAB2_LIB.BASEBOARD_FAB2(SCH_1):PAGE87
   252    GND @BASEBOARD_FAB2_LIB.BASEBOARD_FAB2(SCH_1):GND   I185 @BASEBOARD_FAB2_LIB.BASEBOARD_FAB2(SCH_1):PAGE87
   254    GND @BASEBOARD_FAB2_LIB.BASEBOARD_FAB2(SCH_1):GND   I185 @BASEBOARD_FAB2_LIB.BASEBOARD_FAB2(SCH_1):PAGE87
   257    GND @BASEBOARD_FAB2_LIB.BASEBOARD_FAB2(SCH_1):GND   I185 @BASEBOARD_FAB2_LIB.BASEBOARD_FAB2(SCH_1):PAGE87
   259    GND @BASEBOARD_FAB2_LIB.BASEBOARD_FAB2(SCH_1):GND   I185 @BASEBOARD_FAB2_LIB.BASEBOARD_FAB2(SCH_1):PAGE87
   261    GND @BASEBOARD_FAB2_LIB.BASEBOARD_FAB2(SCH_1):GND   I185 @BASEBOARD_FAB2_LIB.BASEBOARD_FAB2(SCH_1):PAGE87
   263    GND @BASEBOARD_FAB2_LIB.BASEBOARD_FAB2(SCH_1):GND   I185 @BASEBOARD_FAB2_LIB.BASEBOARD_FAB2(SCH_1):PAGE87
   265    GND @BASEBOARD_FAB2_LIB.BASEBOARD_FAB2(SCH_1):GND   I185 @BASEBOARD_FAB2_LIB.BASEBOARD_FAB2(SCH_1):PAGE87
   268    GND @BASEBOARD_FAB2_LIB.BASEBOARD_FAB2(SCH_1):GND   I185 @BASEBOARD_FAB2_LIB.BASEBOARD_FAB2(SCH_1):PAGE87
   270    GND @BASEBOARD_FAB2_LIB.BASEBOARD_FAB2(SCH_1):GND   I185 @BASEBOARD_FAB2_LIB.BASEBOARD_FAB2(SCH_1):PAGE87
   272    GND @BASEBOARD_FAB2_LIB.BASEBOARD_FAB2(SCH_1):GND   I185 @BASEBOARD_FAB2_LIB.BASEBOARD_FAB2(SCH_1):PAGE87
   274    GND @BASEBOARD_FAB2_LIB.BASEBOARD_FAB2(SCH_1):GND   I185 @BASEBOARD_FAB2_LIB.BASEBOARD_FAB2(SCH_1):PAGE87
   276    GND @BASEBOARD_FAB2_LIB.BASEBOARD_FAB2(SCH_1):GND   I185 @BASEBOARD_FAB2_LIB.BASEBOARD_FAB2(SCH_1):PAGE87
   279    GND @BASEBOARD_FAB2_LIB.BASEBOARD_FAB2(SCH_1):GND   I185 @BASEBOARD_FAB2_LIB.BASEBOARD_FAB2(SCH_1):PAGE87
   281    GND @BASEBOARD_FAB2_LIB.BASEBOARD_FAB2(SCH_1):GND   I185 @BASEBOARD_FAB2_LIB.BASEBOARD_FAB2(SCH_1):PAGE87
   283    GND @BASEBOARD_FAB2_LIB.BASEBOARD_FAB2(SCH_1):GND   I185 @BASEBOARD_FAB2_LIB.BASEBOARD_FAB2(SCH_1):PAGE87
     1 P12V_NVDIMM_KLM @BASEBOARD_FAB2_LIB.BASEBOARD_FAB2(SCH_1):P12V_NVDIMM_KLM   I169 @BASEBOARD_FAB2_LIB.BASEBOARD_FAB2(SCH_1):PAGE87
   145 P12V_NVDIMM_KLM @BASEBOARD_FAB2_LIB.BASEBOARD_FAB2(SCH_1):P12V_NVDIMM_KLM   I169 @BASEBOARD_FAB2_LIB.BASEBOARD_FAB2(SCH_1):PAGE87
    59 PVDDQ_KLM @BASEBOARD_FAB2_LIB.BASEBOARD_FAB2(SCH_1):PVDDQ_KLM   I169 @BASEBOARD_FAB2_LIB.BASEBOARD_FAB2(SCH_1):PAGE87
    61 PVDDQ_KLM @BASEBOARD_FAB2_LIB.BASEBOARD_FAB2(SCH_1):PVDDQ_KLM   I169 @BASEBOARD_FAB2_LIB.BASEBOARD_FAB2(SCH_1):PAGE87
    64 PVDDQ_KLM @BASEBOARD_FAB2_LIB.BASEBOARD_FAB2(SCH_1):PVDDQ_KLM   I169 @BASEBOARD_FAB2_LIB.BASEBOARD_FAB2(SCH_1):PAGE87
    67 PVDDQ_KLM @BASEBOARD_FAB2_LIB.BASEBOARD_FAB2(SCH_1):PVDDQ_KLM   I169 @BASEBOARD_FAB2_LIB.BASEBOARD_FAB2(SCH_1):PAGE87
    70 PVDDQ_KLM @BASEBOARD_FAB2_LIB.BASEBOARD_FAB2(SCH_1):PVDDQ_KLM   I169 @BASEBOARD_FAB2_LIB.BASEBOARD_FAB2(SCH_1):PAGE87
    73 PVDDQ_KLM @BASEBOARD_FAB2_LIB.BASEBOARD_FAB2(SCH_1):PVDDQ_KLM   I169 @BASEBOARD_FAB2_LIB.BASEBOARD_FAB2(SCH_1):PAGE87
    76 PVDDQ_KLM @BASEBOARD_FAB2_LIB.BASEBOARD_FAB2(SCH_1):PVDDQ_KLM   I169 @BASEBOARD_FAB2_LIB.BASEBOARD_FAB2(SCH_1):PAGE87
    80 PVDDQ_KLM @BASEBOARD_FAB2_LIB.BASEBOARD_FAB2(SCH_1):PVDDQ_KLM   I169 @BASEBOARD_FAB2_LIB.BASEBOARD_FAB2(SCH_1):PAGE87
    83 PVDDQ_KLM @BASEBOARD_FAB2_LIB.BASEBOARD_FAB2(SCH_1):PVDDQ_KLM   I169 @BASEBOARD_FAB2_LIB.BASEBOARD_FAB2(SCH_1):PAGE87
    85 PVDDQ_KLM @BASEBOARD_FAB2_LIB.BASEBOARD_FAB2(SCH_1):PVDDQ_KLM   I169 @BASEBOARD_FAB2_LIB.BASEBOARD_FAB2(SCH_1):PAGE87
    88 PVDDQ_KLM @BASEBOARD_FAB2_LIB.BASEBOARD_FAB2(SCH_1):PVDDQ_KLM   I169 @BASEBOARD_FAB2_LIB.BASEBOARD_FAB2(SCH_1):PAGE87
    90 PVDDQ_KLM @BASEBOARD_FAB2_LIB.BASEBOARD_FAB2(SCH_1):PVDDQ_KLM   I169 @BASEBOARD_FAB2_LIB.BASEBOARD_FAB2(SCH_1):PAGE87
    92 PVDDQ_KLM @BASEBOARD_FAB2_LIB.BASEBOARD_FAB2(SCH_1):PVDDQ_KLM   I169 @BASEBOARD_FAB2_LIB.BASEBOARD_FAB2(SCH_1):PAGE87
   204 PVDDQ_KLM @BASEBOARD_FAB2_LIB.BASEBOARD_FAB2(SCH_1):PVDDQ_KLM   I169 @BASEBOARD_FAB2_LIB.BASEBOARD_FAB2(SCH_1):PAGE87
   206 PVDDQ_KLM @BASEBOARD_FAB2_LIB.BASEBOARD_FAB2(SCH_1):PVDDQ_KLM   I169 @BASEBOARD_FAB2_LIB.BASEBOARD_FAB2(SCH_1):PAGE87
   209 PVDDQ_KLM @BASEBOARD_FAB2_LIB.BASEBOARD_FAB2(SCH_1):PVDDQ_KLM   I169 @BASEBOARD_FAB2_LIB.BASEBOARD_FAB2(SCH_1):PAGE87
   212 PVDDQ_KLM @BASEBOARD_FAB2_LIB.BASEBOARD_FAB2(SCH_1):PVDDQ_KLM   I169 @BASEBOARD_FAB2_LIB.BASEBOARD_FAB2(SCH_1):PAGE87
   215 PVDDQ_KLM @BASEBOARD_FAB2_LIB.BASEBOARD_FAB2(SCH_1):PVDDQ_KLM   I169 @BASEBOARD_FAB2_LIB.BASEBOARD_FAB2(SCH_1):PAGE87
   217 PVDDQ_KLM @BASEBOARD_FAB2_LIB.BASEBOARD_FAB2(SCH_1):PVDDQ_KLM   I169 @BASEBOARD_FAB2_LIB.BASEBOARD_FAB2(SCH_1):PAGE87
   220 PVDDQ_KLM @BASEBOARD_FAB2_LIB.BASEBOARD_FAB2(SCH_1):PVDDQ_KLM   I169 @BASEBOARD_FAB2_LIB.BASEBOARD_FAB2(SCH_1):PAGE87
   223 PVDDQ_KLM @BASEBOARD_FAB2_LIB.BASEBOARD_FAB2(SCH_1):PVDDQ_KLM   I169 @BASEBOARD_FAB2_LIB.BASEBOARD_FAB2(SCH_1):PAGE87
   226 PVDDQ_KLM @BASEBOARD_FAB2_LIB.BASEBOARD_FAB2(SCH_1):PVDDQ_KLM   I169 @BASEBOARD_FAB2_LIB.BASEBOARD_FAB2(SCH_1):PAGE87
   229 PVDDQ_KLM @BASEBOARD_FAB2_LIB.BASEBOARD_FAB2(SCH_1):PVDDQ_KLM   I169 @BASEBOARD_FAB2_LIB.BASEBOARD_FAB2(SCH_1):PAGE87
   231 PVDDQ_KLM @BASEBOARD_FAB2_LIB.BASEBOARD_FAB2(SCH_1):PVDDQ_KLM   I169 @BASEBOARD_FAB2_LIB.BASEBOARD_FAB2(SCH_1):PAGE87
   233 PVDDQ_KLM @BASEBOARD_FAB2_LIB.BASEBOARD_FAB2(SCH_1):PVDDQ_KLM   I169 @BASEBOARD_FAB2_LIB.BASEBOARD_FAB2(SCH_1):PAGE87
   236 PVDDQ_KLM @BASEBOARD_FAB2_LIB.BASEBOARD_FAB2(SCH_1):PVDDQ_KLM   I169 @BASEBOARD_FAB2_LIB.BASEBOARD_FAB2(SCH_1):PAGE87
   142 PVPP_KLM @BASEBOARD_FAB2_LIB.BASEBOARD_FAB2(SCH_1):PVPP_KLM   I169 @BASEBOARD_FAB2_LIB.BASEBOARD_FAB2(SCH_1):PAGE87
   143 PVPP_KLM @BASEBOARD_FAB2_LIB.BASEBOARD_FAB2(SCH_1):PVPP_KLM   I169 @BASEBOARD_FAB2_LIB.BASEBOARD_FAB2(SCH_1):PAGE87
   288 PVPP_KLM @BASEBOARD_FAB2_LIB.BASEBOARD_FAB2(SCH_1):PVPP_KLM   I169 @BASEBOARD_FAB2_LIB.BASEBOARD_FAB2(SCH_1):PAGE87
   286 PVPP_KLM @BASEBOARD_FAB2_LIB.BASEBOARD_FAB2(SCH_1):PVPP_KLM   I169 @BASEBOARD_FAB2_LIB.BASEBOARD_FAB2(SCH_1):PAGE87
   287 PVPP_KLM @BASEBOARD_FAB2_LIB.BASEBOARD_FAB2(SCH_1):PVPP_KLM   I169 @BASEBOARD_FAB2_LIB.BASEBOARD_FAB2(SCH_1):PAGE87
    77 PVTT_KLM @BASEBOARD_FAB2_LIB.BASEBOARD_FAB2(SCH_1):PVTT_KLM   I169 @BASEBOARD_FAB2_LIB.BASEBOARD_FAB2(SCH_1):PAGE87
   221 PVTT_KLM @BASEBOARD_FAB2_LIB.BASEBOARD_FAB2(SCH_1):PVTT_KLM   I169 @BASEBOARD_FAB2_LIB.BASEBOARD_FAB2(SCH_1):PAGE87

J1A2 SCONN288_H44441004_PIP-SCONN,HA
    79 M_L_MA<0> @BASEBOARD_FAB2_LIB.BASEBOARD_FAB2(SCH_1):M_L_MA(0)   I111 @BASEBOARD_FAB2_LIB.BASEBOARD_FAB2(SCH_1):PAGE85
    72 M_L_MA<1> @BASEBOARD_FAB2_LIB.BASEBOARD_FAB2(SCH_1):M_L_MA(1)   I111 @BASEBOARD_FAB2_LIB.BASEBOARD_FAB2(SCH_1):PAGE85
   225 M_L_MA<10> @BASEBOARD_FAB2_LIB.BASEBOARD_FAB2(SCH_1):M_L_MA(10)   I111 @BASEBOARD_FAB2_LIB.BASEBOARD_FAB2(SCH_1):PAGE85
   210 M_L_MA<11> @BASEBOARD_FAB2_LIB.BASEBOARD_FAB2(SCH_1):M_L_MA(11)   I111 @BASEBOARD_FAB2_LIB.BASEBOARD_FAB2(SCH_1):PAGE85
    65 M_L_MA<12> @BASEBOARD_FAB2_LIB.BASEBOARD_FAB2(SCH_1):M_L_MA(12)   I111 @BASEBOARD_FAB2_LIB.BASEBOARD_FAB2(SCH_1):PAGE85
   232 M_L_MA<13> @BASEBOARD_FAB2_LIB.BASEBOARD_FAB2(SCH_1):M_L_MA(13)   I111 @BASEBOARD_FAB2_LIB.BASEBOARD_FAB2(SCH_1):PAGE85
   228 M_L_MA<14> @BASEBOARD_FAB2_LIB.BASEBOARD_FAB2(SCH_1):M_L_MA(14)   I111 @BASEBOARD_FAB2_LIB.BASEBOARD_FAB2(SCH_1):PAGE85
    86 M_L_MA<15> @BASEBOARD_FAB2_LIB.BASEBOARD_FAB2(SCH_1):M_L_MA(15)   I111 @BASEBOARD_FAB2_LIB.BASEBOARD_FAB2(SCH_1):PAGE85
    82 M_L_MA<16> @BASEBOARD_FAB2_LIB.BASEBOARD_FAB2(SCH_1):M_L_MA(16)   I111 @BASEBOARD_FAB2_LIB.BASEBOARD_FAB2(SCH_1):PAGE85
   234 M_L_MA<17> @BASEBOARD_FAB2_LIB.BASEBOARD_FAB2(SCH_1):M_L_MA(17)   I111 @BASEBOARD_FAB2_LIB.BASEBOARD_FAB2(SCH_1):PAGE85
   216 M_L_MA<2> @BASEBOARD_FAB2_LIB.BASEBOARD_FAB2(SCH_1):M_L_MA(2)   I111 @BASEBOARD_FAB2_LIB.BASEBOARD_FAB2(SCH_1):PAGE85
    71 M_L_MA<3> @BASEBOARD_FAB2_LIB.BASEBOARD_FAB2(SCH_1):M_L_MA(3)   I111 @BASEBOARD_FAB2_LIB.BASEBOARD_FAB2(SCH_1):PAGE85
   214 M_L_MA<4> @BASEBOARD_FAB2_LIB.BASEBOARD_FAB2(SCH_1):M_L_MA(4)   I111 @BASEBOARD_FAB2_LIB.BASEBOARD_FAB2(SCH_1):PAGE85
   213 M_L_MA<5> @BASEBOARD_FAB2_LIB.BASEBOARD_FAB2(SCH_1):M_L_MA(5)   I111 @BASEBOARD_FAB2_LIB.BASEBOARD_FAB2(SCH_1):PAGE85
    69 M_L_MA<6> @BASEBOARD_FAB2_LIB.BASEBOARD_FAB2(SCH_1):M_L_MA(6)   I111 @BASEBOARD_FAB2_LIB.BASEBOARD_FAB2(SCH_1):PAGE85
   211 M_L_MA<7> @BASEBOARD_FAB2_LIB.BASEBOARD_FAB2(SCH_1):M_L_MA(7)   I111 @BASEBOARD_FAB2_LIB.BASEBOARD_FAB2(SCH_1):PAGE85
    68 M_L_MA<8> @BASEBOARD_FAB2_LIB.BASEBOARD_FAB2(SCH_1):M_L_MA(8)   I111 @BASEBOARD_FAB2_LIB.BASEBOARD_FAB2(SCH_1):PAGE85
    66 M_L_MA<9> @BASEBOARD_FAB2_LIB.BASEBOARD_FAB2(SCH_1):M_L_MA(9)   I111 @BASEBOARD_FAB2_LIB.BASEBOARD_FAB2(SCH_1):PAGE85
    62 M_L_ACT_N @BASEBOARD_FAB2_LIB.BASEBOARD_FAB2(SCH_1):M_L_ACT_N   I111 @BASEBOARD_FAB2_LIB.BASEBOARD_FAB2(SCH_1):PAGE85
   208 M_L_ALERT_N @BASEBOARD_FAB2_LIB.BASEBOARD_FAB2(SCH_1):M_L_ALERT_N   I111 @BASEBOARD_FAB2_LIB.BASEBOARD_FAB2(SCH_1):PAGE85
   224 M_L_BA<1> @BASEBOARD_FAB2_LIB.BASEBOARD_FAB2(SCH_1):M_L_BA(1)   I111 @BASEBOARD_FAB2_LIB.BASEBOARD_FAB2(SCH_1):PAGE85
    81 M_L_BA<0> @BASEBOARD_FAB2_LIB.BASEBOARD_FAB2(SCH_1):M_L_BA(0)   I111 @BASEBOARD_FAB2_LIB.BASEBOARD_FAB2(SCH_1):PAGE85
   207 M_L_BG<1> @BASEBOARD_FAB2_LIB.BASEBOARD_FAB2(SCH_1):M_L_BG(1)   I111 @BASEBOARD_FAB2_LIB.BASEBOARD_FAB2(SCH_1):PAGE85
    63 M_L_BG<0> @BASEBOARD_FAB2_LIB.BASEBOARD_FAB2(SCH_1):M_L_BG(0)   I111 @BASEBOARD_FAB2_LIB.BASEBOARD_FAB2(SCH_1):PAGE85
   235 M_L_C<2> @BASEBOARD_FAB2_LIB.BASEBOARD_FAB2(SCH_1):M_L_C(2)   I111 @BASEBOARD_FAB2_LIB.BASEBOARD_FAB2(SCH_1):PAGE85
   199 M_L_ECC<6> @BASEBOARD_FAB2_LIB.BASEBOARD_FAB2(SCH_1):M_L_ECC(6)   I111 @BASEBOARD_FAB2_LIB.BASEBOARD_FAB2(SCH_1):PAGE85
    54 M_L_ECC<7> @BASEBOARD_FAB2_LIB.BASEBOARD_FAB2(SCH_1):M_L_ECC(7)   I111 @BASEBOARD_FAB2_LIB.BASEBOARD_FAB2(SCH_1):PAGE85
   192 M_L_ECC<4> @BASEBOARD_FAB2_LIB.BASEBOARD_FAB2(SCH_1):M_L_ECC(4)   I111 @BASEBOARD_FAB2_LIB.BASEBOARD_FAB2(SCH_1):PAGE85
    47 M_L_ECC<5> @BASEBOARD_FAB2_LIB.BASEBOARD_FAB2(SCH_1):M_L_ECC(5)   I111 @BASEBOARD_FAB2_LIB.BASEBOARD_FAB2(SCH_1):PAGE85
   201 M_L_ECC<2> @BASEBOARD_FAB2_LIB.BASEBOARD_FAB2(SCH_1):M_L_ECC(2)   I111 @BASEBOARD_FAB2_LIB.BASEBOARD_FAB2(SCH_1):PAGE85
    56 M_L_ECC<3> @BASEBOARD_FAB2_LIB.BASEBOARD_FAB2(SCH_1):M_L_ECC(3)   I111 @BASEBOARD_FAB2_LIB.BASEBOARD_FAB2(SCH_1):PAGE85
   194 M_L_ECC<0> @BASEBOARD_FAB2_LIB.BASEBOARD_FAB2(SCH_1):M_L_ECC(0)   I111 @BASEBOARD_FAB2_LIB.BASEBOARD_FAB2(SCH_1):PAGE85
    49 M_L_ECC<1> @BASEBOARD_FAB2_LIB.BASEBOARD_FAB2(SCH_1):M_L_ECC(1)   I111 @BASEBOARD_FAB2_LIB.BASEBOARD_FAB2(SCH_1):PAGE85
    75 M_L_CLK_DN<0> @BASEBOARD_FAB2_LIB.BASEBOARD_FAB2(SCH_1):M_L_CLK_DN(0)   I111 @BASEBOARD_FAB2_LIB.BASEBOARD_FAB2(SCH_1):PAGE85
    74 M_L_CLK_DP<0> @BASEBOARD_FAB2_LIB.BASEBOARD_FAB2(SCH_1):M_L_CLK_DP(0)   I111 @BASEBOARD_FAB2_LIB.BASEBOARD_FAB2(SCH_1):PAGE85
   219 M_L_CLK_DN<1> @BASEBOARD_FAB2_LIB.BASEBOARD_FAB2(SCH_1):M_L_CLK_DN(1)   I111 @BASEBOARD_FAB2_LIB.BASEBOARD_FAB2(SCH_1):PAGE85
   218 M_L_CLK_DP<1> @BASEBOARD_FAB2_LIB.BASEBOARD_FAB2(SCH_1):M_L_CLK_DP(1)   I111 @BASEBOARD_FAB2_LIB.BASEBOARD_FAB2(SCH_1):PAGE85
   203 M_L_CKE<1> @BASEBOARD_FAB2_LIB.BASEBOARD_FAB2(SCH_1):M_L_CKE(1)   I111 @BASEBOARD_FAB2_LIB.BASEBOARD_FAB2(SCH_1):PAGE85
    60 M_L_CKE<0> @BASEBOARD_FAB2_LIB.BASEBOARD_FAB2(SCH_1):M_L_CKE(0)   I111 @BASEBOARD_FAB2_LIB.BASEBOARD_FAB2(SCH_1):PAGE85
   280 M_L_DQ<62> @BASEBOARD_FAB2_LIB.BASEBOARD_FAB2(SCH_1):M_L_DQ(62)   I111 @BASEBOARD_FAB2_LIB.BASEBOARD_FAB2(SCH_1):PAGE85
   135 M_L_DQ<63> @BASEBOARD_FAB2_LIB.BASEBOARD_FAB2(SCH_1):M_L_DQ(63)   I111 @BASEBOARD_FAB2_LIB.BASEBOARD_FAB2(SCH_1):PAGE85
   273 M_L_DQ<60> @BASEBOARD_FAB2_LIB.BASEBOARD_FAB2(SCH_1):M_L_DQ(60)   I111 @BASEBOARD_FAB2_LIB.BASEBOARD_FAB2(SCH_1):PAGE85
   128 M_L_DQ<61> @BASEBOARD_FAB2_LIB.BASEBOARD_FAB2(SCH_1):M_L_DQ(61)   I111 @BASEBOARD_FAB2_LIB.BASEBOARD_FAB2(SCH_1):PAGE85
   282 M_L_DQ<58> @BASEBOARD_FAB2_LIB.BASEBOARD_FAB2(SCH_1):M_L_DQ(58)   I111 @BASEBOARD_FAB2_LIB.BASEBOARD_FAB2(SCH_1):PAGE85
   137 M_L_DQ<59> @BASEBOARD_FAB2_LIB.BASEBOARD_FAB2(SCH_1):M_L_DQ(59)   I111 @BASEBOARD_FAB2_LIB.BASEBOARD_FAB2(SCH_1):PAGE85
   275 M_L_DQ<56> @BASEBOARD_FAB2_LIB.BASEBOARD_FAB2(SCH_1):M_L_DQ(56)   I111 @BASEBOARD_FAB2_LIB.BASEBOARD_FAB2(SCH_1):PAGE85
   130 M_L_DQ<57> @BASEBOARD_FAB2_LIB.BASEBOARD_FAB2(SCH_1):M_L_DQ(57)   I111 @BASEBOARD_FAB2_LIB.BASEBOARD_FAB2(SCH_1):PAGE85
   269 M_L_DQ<54> @BASEBOARD_FAB2_LIB.BASEBOARD_FAB2(SCH_1):M_L_DQ(54)   I111 @BASEBOARD_FAB2_LIB.BASEBOARD_FAB2(SCH_1):PAGE85
   124 M_L_DQ<55> @BASEBOARD_FAB2_LIB.BASEBOARD_FAB2(SCH_1):M_L_DQ(55)   I111 @BASEBOARD_FAB2_LIB.BASEBOARD_FAB2(SCH_1):PAGE85
   262 M_L_DQ<52> @BASEBOARD_FAB2_LIB.BASEBOARD_FAB2(SCH_1):M_L_DQ(52)   I111 @BASEBOARD_FAB2_LIB.BASEBOARD_FAB2(SCH_1):PAGE85
   117 M_L_DQ<53> @BASEBOARD_FAB2_LIB.BASEBOARD_FAB2(SCH_1):M_L_DQ(53)   I111 @BASEBOARD_FAB2_LIB.BASEBOARD_FAB2(SCH_1):PAGE85
   271 M_L_DQ<50> @BASEBOARD_FAB2_LIB.BASEBOARD_FAB2(SCH_1):M_L_DQ(50)   I111 @BASEBOARD_FAB2_LIB.BASEBOARD_FAB2(SCH_1):PAGE85
   126 M_L_DQ<51> @BASEBOARD_FAB2_LIB.BASEBOARD_FAB2(SCH_1):M_L_DQ(51)   I111 @BASEBOARD_FAB2_LIB.BASEBOARD_FAB2(SCH_1):PAGE85
   264 M_L_DQ<48> @BASEBOARD_FAB2_LIB.BASEBOARD_FAB2(SCH_1):M_L_DQ(48)   I111 @BASEBOARD_FAB2_LIB.BASEBOARD_FAB2(SCH_1):PAGE85
   119 M_L_DQ<49> @BASEBOARD_FAB2_LIB.BASEBOARD_FAB2(SCH_1):M_L_DQ(49)   I111 @BASEBOARD_FAB2_LIB.BASEBOARD_FAB2(SCH_1):PAGE85
   258 M_L_DQ<46> @BASEBOARD_FAB2_LIB.BASEBOARD_FAB2(SCH_1):M_L_DQ(46)   I111 @BASEBOARD_FAB2_LIB.BASEBOARD_FAB2(SCH_1):PAGE85
   113 M_L_DQ<47> @BASEBOARD_FAB2_LIB.BASEBOARD_FAB2(SCH_1):M_L_DQ(47)   I111 @BASEBOARD_FAB2_LIB.BASEBOARD_FAB2(SCH_1):PAGE85
   251 M_L_DQ<44> @BASEBOARD_FAB2_LIB.BASEBOARD_FAB2(SCH_1):M_L_DQ(44)   I111 @BASEBOARD_FAB2_LIB.BASEBOARD_FAB2(SCH_1):PAGE85
   106 M_L_DQ<45> @BASEBOARD_FAB2_LIB.BASEBOARD_FAB2(SCH_1):M_L_DQ(45)   I111 @BASEBOARD_FAB2_LIB.BASEBOARD_FAB2(SCH_1):PAGE85
   260 M_L_DQ<42> @BASEBOARD_FAB2_LIB.BASEBOARD_FAB2(SCH_1):M_L_DQ(42)   I111 @BASEBOARD_FAB2_LIB.BASEBOARD_FAB2(SCH_1):PAGE85
   115 M_L_DQ<43> @BASEBOARD_FAB2_LIB.BASEBOARD_FAB2(SCH_1):M_L_DQ(43)   I111 @BASEBOARD_FAB2_LIB.BASEBOARD_FAB2(SCH_1):PAGE85
   253 M_L_DQ<40> @BASEBOARD_FAB2_LIB.BASEBOARD_FAB2(SCH_1):M_L_DQ(40)   I111 @BASEBOARD_FAB2_LIB.BASEBOARD_FAB2(SCH_1):PAGE85
   108 M_L_DQ<41> @BASEBOARD_FAB2_LIB.BASEBOARD_FAB2(SCH_1):M_L_DQ(41)   I111 @BASEBOARD_FAB2_LIB.BASEBOARD_FAB2(SCH_1):PAGE85
   247 M_L_DQ<38> @BASEBOARD_FAB2_LIB.BASEBOARD_FAB2(SCH_1):M_L_DQ(38)   I111 @BASEBOARD_FAB2_LIB.BASEBOARD_FAB2(SCH_1):PAGE85
   102 M_L_DQ<39> @BASEBOARD_FAB2_LIB.BASEBOARD_FAB2(SCH_1):M_L_DQ(39)   I111 @BASEBOARD_FAB2_LIB.BASEBOARD_FAB2(SCH_1):PAGE85
   240 M_L_DQ<36> @BASEBOARD_FAB2_LIB.BASEBOARD_FAB2(SCH_1):M_L_DQ(36)   I111 @BASEBOARD_FAB2_LIB.BASEBOARD_FAB2(SCH_1):PAGE85
    95 M_L_DQ<37> @BASEBOARD_FAB2_LIB.BASEBOARD_FAB2(SCH_1):M_L_DQ(37)   I111 @BASEBOARD_FAB2_LIB.BASEBOARD_FAB2(SCH_1):PAGE85
   249 M_L_DQ<34> @BASEBOARD_FAB2_LIB.BASEBOARD_FAB2(SCH_1):M_L_DQ(34)   I111 @BASEBOARD_FAB2_LIB.BASEBOARD_FAB2(SCH_1):PAGE85
   104 M_L_DQ<35> @BASEBOARD_FAB2_LIB.BASEBOARD_FAB2(SCH_1):M_L_DQ(35)   I111 @BASEBOARD_FAB2_LIB.BASEBOARD_FAB2(SCH_1):PAGE85
   242 M_L_DQ<32> @BASEBOARD_FAB2_LIB.BASEBOARD_FAB2(SCH_1):M_L_DQ(32)   I111 @BASEBOARD_FAB2_LIB.BASEBOARD_FAB2(SCH_1):PAGE85
    97 M_L_DQ<33> @BASEBOARD_FAB2_LIB.BASEBOARD_FAB2(SCH_1):M_L_DQ(33)   I111 @BASEBOARD_FAB2_LIB.BASEBOARD_FAB2(SCH_1):PAGE85
   188 M_L_DQ<30> @BASEBOARD_FAB2_LIB.BASEBOARD_FAB2(SCH_1):M_L_DQ(30)   I111 @BASEBOARD_FAB2_LIB.BASEBOARD_FAB2(SCH_1):PAGE85
    43 M_L_DQ<31> @BASEBOARD_FAB2_LIB.BASEBOARD_FAB2(SCH_1):M_L_DQ(31)   I111 @BASEBOARD_FAB2_LIB.BASEBOARD_FAB2(SCH_1):PAGE85
   181 M_L_DQ<28> @BASEBOARD_FAB2_LIB.BASEBOARD_FAB2(SCH_1):M_L_DQ(28)   I111 @BASEBOARD_FAB2_LIB.BASEBOARD_FAB2(SCH_1):PAGE85
    36 M_L_DQ<29> @BASEBOARD_FAB2_LIB.BASEBOARD_FAB2(SCH_1):M_L_DQ(29)   I111 @BASEBOARD_FAB2_LIB.BASEBOARD_FAB2(SCH_1):PAGE85
   190 M_L_DQ<26> @BASEBOARD_FAB2_LIB.BASEBOARD_FAB2(SCH_1):M_L_DQ(26)   I111 @BASEBOARD_FAB2_LIB.BASEBOARD_FAB2(SCH_1):PAGE85
    45 M_L_DQ<27> @BASEBOARD_FAB2_LIB.BASEBOARD_FAB2(SCH_1):M_L_DQ(27)   I111 @BASEBOARD_FAB2_LIB.BASEBOARD_FAB2(SCH_1):PAGE85
   183 M_L_DQ<24> @BASEBOARD_FAB2_LIB.BASEBOARD_FAB2(SCH_1):M_L_DQ(24)   I111 @BASEBOARD_FAB2_LIB.BASEBOARD_FAB2(SCH_1):PAGE85
    38 M_L_DQ<25> @BASEBOARD_FAB2_LIB.BASEBOARD_FAB2(SCH_1):M_L_DQ(25)   I111 @BASEBOARD_FAB2_LIB.BASEBOARD_FAB2(SCH_1):PAGE85
   177 M_L_DQ<22> @BASEBOARD_FAB2_LIB.BASEBOARD_FAB2(SCH_1):M_L_DQ(22)   I111 @BASEBOARD_FAB2_LIB.BASEBOARD_FAB2(SCH_1):PAGE85
    32 M_L_DQ<23> @BASEBOARD_FAB2_LIB.BASEBOARD_FAB2(SCH_1):M_L_DQ(23)   I111 @BASEBOARD_FAB2_LIB.BASEBOARD_FAB2(SCH_1):PAGE85
   170 M_L_DQ<20> @BASEBOARD_FAB2_LIB.BASEBOARD_FAB2(SCH_1):M_L_DQ(20)   I111 @BASEBOARD_FAB2_LIB.BASEBOARD_FAB2(SCH_1):PAGE85
    25 M_L_DQ<21> @BASEBOARD_FAB2_LIB.BASEBOARD_FAB2(SCH_1):M_L_DQ(21)   I111 @BASEBOARD_FAB2_LIB.BASEBOARD_FAB2(SCH_1):PAGE85
   179 M_L_DQ<18> @BASEBOARD_FAB2_LIB.BASEBOARD_FAB2(SCH_1):M_L_DQ(18)   I111 @BASEBOARD_FAB2_LIB.BASEBOARD_FAB2(SCH_1):PAGE85
    34 M_L_DQ<19> @BASEBOARD_FAB2_LIB.BASEBOARD_FAB2(SCH_1):M_L_DQ(19)   I111 @BASEBOARD_FAB2_LIB.BASEBOARD_FAB2(SCH_1):PAGE85
   172 M_L_DQ<16> @BASEBOARD_FAB2_LIB.BASEBOARD_FAB2(SCH_1):M_L_DQ(16)   I111 @BASEBOARD_FAB2_LIB.BASEBOARD_FAB2(SCH_1):PAGE85
    27 M_L_DQ<17> @BASEBOARD_FAB2_LIB.BASEBOARD_FAB2(SCH_1):M_L_DQ(17)   I111 @BASEBOARD_FAB2_LIB.BASEBOARD_FAB2(SCH_1):PAGE85
   166 M_L_DQ<14> @BASEBOARD_FAB2_LIB.BASEBOARD_FAB2(SCH_1):M_L_DQ(14)   I111 @BASEBOARD_FAB2_LIB.BASEBOARD_FAB2(SCH_1):PAGE85
    21 M_L_DQ<15> @BASEBOARD_FAB2_LIB.BASEBOARD_FAB2(SCH_1):M_L_DQ(15)   I111 @BASEBOARD_FAB2_LIB.BASEBOARD_FAB2(SCH_1):PAGE85
   159 M_L_DQ<12> @BASEBOARD_FAB2_LIB.BASEBOARD_FAB2(SCH_1):M_L_DQ(12)   I111 @BASEBOARD_FAB2_LIB.BASEBOARD_FAB2(SCH_1):PAGE85
    14 M_L_DQ<13> @BASEBOARD_FAB2_LIB.BASEBOARD_FAB2(SCH_1):M_L_DQ(13)   I111 @BASEBOARD_FAB2_LIB.BASEBOARD_FAB2(SCH_1):PAGE85
   168 M_L_DQ<10> @BASEBOARD_FAB2_LIB.BASEBOARD_FAB2(SCH_1):M_L_DQ(10)   I111 @BASEBOARD_FAB2_LIB.BASEBOARD_FAB2(SCH_1):PAGE85
    23 M_L_DQ<11> @BASEBOARD_FAB2_LIB.BASEBOARD_FAB2(SCH_1):M_L_DQ(11)   I111 @BASEBOARD_FAB2_LIB.BASEBOARD_FAB2(SCH_1):PAGE85
   161 M_L_DQ<8> @BASEBOARD_FAB2_LIB.BASEBOARD_FAB2(SCH_1):M_L_DQ(8)   I111 @BASEBOARD_FAB2_LIB.BASEBOARD_FAB2(SCH_1):PAGE85
    16 M_L_DQ<9> @BASEBOARD_FAB2_LIB.BASEBOARD_FAB2(SCH_1):M_L_DQ(9)   I111 @BASEBOARD_FAB2_LIB.BASEBOARD_FAB2(SCH_1):PAGE85
   155 M_L_DQ<6> @BASEBOARD_FAB2_LIB.BASEBOARD_FAB2(SCH_1):M_L_DQ(6)   I111 @BASEBOARD_FAB2_LIB.BASEBOARD_FAB2(SCH_1):PAGE85
    10 M_L_DQ<7> @BASEBOARD_FAB2_LIB.BASEBOARD_FAB2(SCH_1):M_L_DQ(7)   I111 @BASEBOARD_FAB2_LIB.BASEBOARD_FAB2(SCH_1):PAGE85
   148 M_L_DQ<4> @BASEBOARD_FAB2_LIB.BASEBOARD_FAB2(SCH_1):M_L_DQ(4)   I111 @BASEBOARD_FAB2_LIB.BASEBOARD_FAB2(SCH_1):PAGE85
     3 M_L_DQ<5> @BASEBOARD_FAB2_LIB.BASEBOARD_FAB2(SCH_1):M_L_DQ(5)   I111 @BASEBOARD_FAB2_LIB.BASEBOARD_FAB2(SCH_1):PAGE85
   157 M_L_DQ<2> @BASEBOARD_FAB2_LIB.BASEBOARD_FAB2(SCH_1):M_L_DQ(2)   I111 @BASEBOARD_FAB2_LIB.BASEBOARD_FAB2(SCH_1):PAGE85
    12 M_L_DQ<3> @BASEBOARD_FAB2_LIB.BASEBOARD_FAB2(SCH_1):M_L_DQ(3)   I111 @BASEBOARD_FAB2_LIB.BASEBOARD_FAB2(SCH_1):PAGE85
   150 M_L_DQ<0> @BASEBOARD_FAB2_LIB.BASEBOARD_FAB2(SCH_1):M_L_DQ(0)   I111 @BASEBOARD_FAB2_LIB.BASEBOARD_FAB2(SCH_1):PAGE85
     5 M_L_DQ<1> @BASEBOARD_FAB2_LIB.BASEBOARD_FAB2(SCH_1):M_L_DQ(1)   I111 @BASEBOARD_FAB2_LIB.BASEBOARD_FAB2(SCH_1):PAGE85
    78 FM_DIMM_EVENT_COD_N @BASEBOARD_FAB2_LIB.BASEBOARD_FAB2(SCH_1):FM_DIMM_EVENT_COD_N   I111 @BASEBOARD_FAB2_LIB.BASEBOARD_FAB2(SCH_1):PAGE85
    91 M_L_ODT<1> @BASEBOARD_FAB2_LIB.BASEBOARD_FAB2(SCH_1):M_L_ODT(1)   I111 @BASEBOARD_FAB2_LIB.BASEBOARD_FAB2(SCH_1):PAGE85
    87 M_L_ODT<0> @BASEBOARD_FAB2_LIB.BASEBOARD_FAB2(SCH_1):M_L_ODT(0)   I111 @BASEBOARD_FAB2_LIB.BASEBOARD_FAB2(SCH_1):PAGE85
   222 M_L_PAR @BASEBOARD_FAB2_LIB.BASEBOARD_FAB2(SCH_1):M_L_PAR   I111 @BASEBOARD_FAB2_LIB.BASEBOARD_FAB2(SCH_1):PAGE85
    58 M_KLM_RST_N @BASEBOARD_FAB2_LIB.BASEBOARD_FAB2(SCH_1):M_KLM_RST_N   I111 @BASEBOARD_FAB2_LIB.BASEBOARD_FAB2(SCH_1):PAGE85
   144 TP_CH_L_DIMM_L0_RFU_2 @BASEBOARD_FAB2_LIB.BASEBOARD_FAB2(SCH_1):TP_CH_L_DIMM_L0_RFU_2   I111 @BASEBOARD_FAB2_LIB.BASEBOARD_FAB2(SCH_1):PAGE85
   227 TP_CH_L_DIMM_L0_RFU_1 @BASEBOARD_FAB2_LIB.BASEBOARD_FAB2(SCH_1):TP_CH_L_DIMM_L0_RFU_1   I111 @BASEBOARD_FAB2_LIB.BASEBOARD_FAB2(SCH_1):PAGE85
   205 TP_CH_L_DIMM_L0_RFU_0 @BASEBOARD_FAB2_LIB.BASEBOARD_FAB2(SCH_1):TP_CH_L_DIMM_L0_RFU_0   I111 @BASEBOARD_FAB2_LIB.BASEBOARD_FAB2(SCH_1):PAGE85
    84 M_L_CS_N<0> @BASEBOARD_FAB2_LIB.BASEBOARD_FAB2(SCH_1):M_L_CS_N(0)   I111 @BASEBOARD_FAB2_LIB.BASEBOARD_FAB2(SCH_1):PAGE85
    89 M_L_CS_N<1> @BASEBOARD_FAB2_LIB.BASEBOARD_FAB2(SCH_1):M_L_CS_N(1)   I111 @BASEBOARD_FAB2_LIB.BASEBOARD_FAB2(SCH_1):PAGE85
    93 M_L_CS_N<2> @BASEBOARD_FAB2_LIB.BASEBOARD_FAB2(SCH_1):M_L_CS_N(2)   I111 @BASEBOARD_FAB2_LIB.BASEBOARD_FAB2(SCH_1):PAGE85
   237 M_L_CS_N<3> @BASEBOARD_FAB2_LIB.BASEBOARD_FAB2(SCH_1):M_L_CS_N(3)   I111 @BASEBOARD_FAB2_LIB.BASEBOARD_FAB2(SCH_1):PAGE85
   238    GND @BASEBOARD_FAB2_LIB.BASEBOARD_FAB2(SCH_1):GND   I111 @BASEBOARD_FAB2_LIB.BASEBOARD_FAB2(SCH_1):PAGE85
   140 PVPP_KLM @BASEBOARD_FAB2_LIB.BASEBOARD_FAB2(SCH_1):PVPP_KLM   I111 @BASEBOARD_FAB2_LIB.BASEBOARD_FAB2(SCH_1):PAGE85
   139    GND @BASEBOARD_FAB2_LIB.BASEBOARD_FAB2(SCH_1):GND   I111 @BASEBOARD_FAB2_LIB.BASEBOARD_FAB2(SCH_1):PAGE85
   230 FM_ADR_COMPLETE_KLM_N @BASEBOARD_FAB2_LIB.BASEBOARD_FAB2(SCH_1):FM_ADR_COMPLETE_KLM_N   I111 @BASEBOARD_FAB2_LIB.BASEBOARD_FAB2(SCH_1):PAGE85
   141 SMB_DDR_KLM_VPP_SCL @BASEBOARD_FAB2_LIB.BASEBOARD_FAB2(SCH_1):SMB_DDR_KLM_VPP_SCL   I111 @BASEBOARD_FAB2_LIB.BASEBOARD_FAB2(SCH_1):PAGE85
   285 SMB_DDR_KLM_VPP_SDA @BASEBOARD_FAB2_LIB.BASEBOARD_FAB2(SCH_1):SMB_DDR_KLM_VPP_SDA   I111 @BASEBOARD_FAB2_LIB.BASEBOARD_FAB2(SCH_1):PAGE85
   284 PVPP_KLM @BASEBOARD_FAB2_LIB.BASEBOARD_FAB2(SCH_1):PVPP_KLM   I111 @BASEBOARD_FAB2_LIB.BASEBOARD_FAB2(SCH_1):PAGE85
   146 M_L_VREF @BASEBOARD_FAB2_LIB.BASEBOARD_FAB2(SCH_1):M_L_VREF   I111 @BASEBOARD_FAB2_LIB.BASEBOARD_FAB2(SCH_1):PAGE85
   152 M_L_DQS_DN<0> @BASEBOARD_FAB2_LIB.BASEBOARD_FAB2(SCH_1):M_L_DQS_DN(0)    I66 @BASEBOARD_FAB2_LIB.BASEBOARD_FAB2(SCH_1):PAGE85
   153 M_L_DQS_DP<0> @BASEBOARD_FAB2_LIB.BASEBOARD_FAB2(SCH_1):M_L_DQS_DP(0)    I66 @BASEBOARD_FAB2_LIB.BASEBOARD_FAB2(SCH_1):PAGE85
    19 M_L_DQS_DN<10> @BASEBOARD_FAB2_LIB.BASEBOARD_FAB2(SCH_1):M_L_DQS_DN(10)    I66 @BASEBOARD_FAB2_LIB.BASEBOARD_FAB2(SCH_1):PAGE85
    18 M_L_DQS_DP<10> @BASEBOARD_FAB2_LIB.BASEBOARD_FAB2(SCH_1):M_L_DQS_DP(10)    I66 @BASEBOARD_FAB2_LIB.BASEBOARD_FAB2(SCH_1):PAGE85
    30 M_L_DQS_DN<11> @BASEBOARD_FAB2_LIB.BASEBOARD_FAB2(SCH_1):M_L_DQS_DN(11)    I66 @BASEBOARD_FAB2_LIB.BASEBOARD_FAB2(SCH_1):PAGE85
    29 M_L_DQS_DP<11> @BASEBOARD_FAB2_LIB.BASEBOARD_FAB2(SCH_1):M_L_DQS_DP(11)    I66 @BASEBOARD_FAB2_LIB.BASEBOARD_FAB2(SCH_1):PAGE85
    41 M_L_DQS_DN<12> @BASEBOARD_FAB2_LIB.BASEBOARD_FAB2(SCH_1):M_L_DQS_DN(12)    I66 @BASEBOARD_FAB2_LIB.BASEBOARD_FAB2(SCH_1):PAGE85
    40 M_L_DQS_DP<12> @BASEBOARD_FAB2_LIB.BASEBOARD_FAB2(SCH_1):M_L_DQS_DP(12)    I66 @BASEBOARD_FAB2_LIB.BASEBOARD_FAB2(SCH_1):PAGE85
   100 M_L_DQS_DN<13> @BASEBOARD_FAB2_LIB.BASEBOARD_FAB2(SCH_1):M_L_DQS_DN(13)    I66 @BASEBOARD_FAB2_LIB.BASEBOARD_FAB2(SCH_1):PAGE85
    99 M_L_DQS_DP<13> @BASEBOARD_FAB2_LIB.BASEBOARD_FAB2(SCH_1):M_L_DQS_DP(13)    I66 @BASEBOARD_FAB2_LIB.BASEBOARD_FAB2(SCH_1):PAGE85
   111 M_L_DQS_DN<14> @BASEBOARD_FAB2_LIB.BASEBOARD_FAB2(SCH_1):M_L_DQS_DN(14)    I66 @BASEBOARD_FAB2_LIB.BASEBOARD_FAB2(SCH_1):PAGE85
   110 M_L_DQS_DP<14> @BASEBOARD_FAB2_LIB.BASEBOARD_FAB2(SCH_1):M_L_DQS_DP(14)    I66 @BASEBOARD_FAB2_LIB.BASEBOARD_FAB2(SCH_1):PAGE85
   122 M_L_DQS_DN<15> @BASEBOARD_FAB2_LIB.BASEBOARD_FAB2(SCH_1):M_L_DQS_DN(15)    I66 @BASEBOARD_FAB2_LIB.BASEBOARD_FAB2(SCH_1):PAGE85
   121 M_L_DQS_DP<15> @BASEBOARD_FAB2_LIB.BASEBOARD_FAB2(SCH_1):M_L_DQS_DP(15)    I66 @BASEBOARD_FAB2_LIB.BASEBOARD_FAB2(SCH_1):PAGE85
   133 M_L_DQS_DN<16> @BASEBOARD_FAB2_LIB.BASEBOARD_FAB2(SCH_1):M_L_DQS_DN(16)    I66 @BASEBOARD_FAB2_LIB.BASEBOARD_FAB2(SCH_1):PAGE85
   132 M_L_DQS_DP<16> @BASEBOARD_FAB2_LIB.BASEBOARD_FAB2(SCH_1):M_L_DQS_DP(16)    I66 @BASEBOARD_FAB2_LIB.BASEBOARD_FAB2(SCH_1):PAGE85
    52 M_L_DQS_DN<17> @BASEBOARD_FAB2_LIB.BASEBOARD_FAB2(SCH_1):M_L_DQS_DN(17)    I66 @BASEBOARD_FAB2_LIB.BASEBOARD_FAB2(SCH_1):PAGE85
    51 M_L_DQS_DP<17> @BASEBOARD_FAB2_LIB.BASEBOARD_FAB2(SCH_1):M_L_DQS_DP(17)    I66 @BASEBOARD_FAB2_LIB.BASEBOARD_FAB2(SCH_1):PAGE85
   163 M_L_DQS_DN<1> @BASEBOARD_FAB2_LIB.BASEBOARD_FAB2(SCH_1):M_L_DQS_DN(1)    I66 @BASEBOARD_FAB2_LIB.BASEBOARD_FAB2(SCH_1):PAGE85
   164 M_L_DQS_DP<1> @BASEBOARD_FAB2_LIB.BASEBOARD_FAB2(SCH_1):M_L_DQS_DP(1)    I66 @BASEBOARD_FAB2_LIB.BASEBOARD_FAB2(SCH_1):PAGE85
   174 M_L_DQS_DN<2> @BASEBOARD_FAB2_LIB.BASEBOARD_FAB2(SCH_1):M_L_DQS_DN(2)    I66 @BASEBOARD_FAB2_LIB.BASEBOARD_FAB2(SCH_1):PAGE85
   175 M_L_DQS_DP<2> @BASEBOARD_FAB2_LIB.BASEBOARD_FAB2(SCH_1):M_L_DQS_DP(2)    I66 @BASEBOARD_FAB2_LIB.BASEBOARD_FAB2(SCH_1):PAGE85
   185 M_L_DQS_DN<3> @BASEBOARD_FAB2_LIB.BASEBOARD_FAB2(SCH_1):M_L_DQS_DN(3)    I66 @BASEBOARD_FAB2_LIB.BASEBOARD_FAB2(SCH_1):PAGE85
   186 M_L_DQS_DP<3> @BASEBOARD_FAB2_LIB.BASEBOARD_FAB2(SCH_1):M_L_DQS_DP(3)    I66 @BASEBOARD_FAB2_LIB.BASEBOARD_FAB2(SCH_1):PAGE85
   244 M_L_DQS_DN<4> @BASEBOARD_FAB2_LIB.BASEBOARD_FAB2(SCH_1):M_L_DQS_DN(4)    I66 @BASEBOARD_FAB2_LIB.BASEBOARD_FAB2(SCH_1):PAGE85
   245 M_L_DQS_DP<4> @BASEBOARD_FAB2_LIB.BASEBOARD_FAB2(SCH_1):M_L_DQS_DP(4)    I66 @BASEBOARD_FAB2_LIB.BASEBOARD_FAB2(SCH_1):PAGE85
   255 M_L_DQS_DN<5> @BASEBOARD_FAB2_LIB.BASEBOARD_FAB2(SCH_1):M_L_DQS_DN(5)    I66 @BASEBOARD_FAB2_LIB.BASEBOARD_FAB2(SCH_1):PAGE85
   256 M_L_DQS_DP<5> @BASEBOARD_FAB2_LIB.BASEBOARD_FAB2(SCH_1):M_L_DQS_DP(5)    I66 @BASEBOARD_FAB2_LIB.BASEBOARD_FAB2(SCH_1):PAGE85
   266 M_L_DQS_DN<6> @BASEBOARD_FAB2_LIB.BASEBOARD_FAB2(SCH_1):M_L_DQS_DN(6)    I66 @BASEBOARD_FAB2_LIB.BASEBOARD_FAB2(SCH_1):PAGE85
   267 M_L_DQS_DP<6> @BASEBOARD_FAB2_LIB.BASEBOARD_FAB2(SCH_1):M_L_DQS_DP(6)    I66 @BASEBOARD_FAB2_LIB.BASEBOARD_FAB2(SCH_1):PAGE85
   277 M_L_DQS_DN<7> @BASEBOARD_FAB2_LIB.BASEBOARD_FAB2(SCH_1):M_L_DQS_DN(7)    I66 @BASEBOARD_FAB2_LIB.BASEBOARD_FAB2(SCH_1):PAGE85
   278 M_L_DQS_DP<7> @BASEBOARD_FAB2_LIB.BASEBOARD_FAB2(SCH_1):M_L_DQS_DP(7)    I66 @BASEBOARD_FAB2_LIB.BASEBOARD_FAB2(SCH_1):PAGE85
   196 M_L_DQS_DN<8> @BASEBOARD_FAB2_LIB.BASEBOARD_FAB2(SCH_1):M_L_DQS_DN(8)    I66 @BASEBOARD_FAB2_LIB.BASEBOARD_FAB2(SCH_1):PAGE85
   197 M_L_DQS_DP<8> @BASEBOARD_FAB2_LIB.BASEBOARD_FAB2(SCH_1):M_L_DQS_DP(8)    I66 @BASEBOARD_FAB2_LIB.BASEBOARD_FAB2(SCH_1):PAGE85
     8 M_L_DQS_DN<9> @BASEBOARD_FAB2_LIB.BASEBOARD_FAB2(SCH_1):M_L_DQS_DN(9)    I66 @BASEBOARD_FAB2_LIB.BASEBOARD_FAB2(SCH_1):PAGE85
     7 M_L_DQS_DP<9> @BASEBOARD_FAB2_LIB.BASEBOARD_FAB2(SCH_1):M_L_DQS_DP(9)    I66 @BASEBOARD_FAB2_LIB.BASEBOARD_FAB2(SCH_1):PAGE85
     2    GND @BASEBOARD_FAB2_LIB.BASEBOARD_FAB2(SCH_1):GND    I43 @BASEBOARD_FAB2_LIB.BASEBOARD_FAB2(SCH_1):PAGE85
     4    GND @BASEBOARD_FAB2_LIB.BASEBOARD_FAB2(SCH_1):GND    I43 @BASEBOARD_FAB2_LIB.BASEBOARD_FAB2(SCH_1):PAGE85
     6    GND @BASEBOARD_FAB2_LIB.BASEBOARD_FAB2(SCH_1):GND    I43 @BASEBOARD_FAB2_LIB.BASEBOARD_FAB2(SCH_1):PAGE85
     9    GND @BASEBOARD_FAB2_LIB.BASEBOARD_FAB2(SCH_1):GND    I43 @BASEBOARD_FAB2_LIB.BASEBOARD_FAB2(SCH_1):PAGE85
    11    GND @BASEBOARD_FAB2_LIB.BASEBOARD_FAB2(SCH_1):GND    I43 @BASEBOARD_FAB2_LIB.BASEBOARD_FAB2(SCH_1):PAGE85
    13    GND @BASEBOARD_FAB2_LIB.BASEBOARD_FAB2(SCH_1):GND    I43 @BASEBOARD_FAB2_LIB.BASEBOARD_FAB2(SCH_1):PAGE85
    15    GND @BASEBOARD_FAB2_LIB.BASEBOARD_FAB2(SCH_1):GND    I43 @BASEBOARD_FAB2_LIB.BASEBOARD_FAB2(SCH_1):PAGE85
    17    GND @BASEBOARD_FAB2_LIB.BASEBOARD_FAB2(SCH_1):GND    I43 @BASEBOARD_FAB2_LIB.BASEBOARD_FAB2(SCH_1):PAGE85
    20    GND @BASEBOARD_FAB2_LIB.BASEBOARD_FAB2(SCH_1):GND    I43 @BASEBOARD_FAB2_LIB.BASEBOARD_FAB2(SCH_1):PAGE85
    22    GND @BASEBOARD_FAB2_LIB.BASEBOARD_FAB2(SCH_1):GND    I43 @BASEBOARD_FAB2_LIB.BASEBOARD_FAB2(SCH_1):PAGE85
    24    GND @BASEBOARD_FAB2_LIB.BASEBOARD_FAB2(SCH_1):GND    I43 @BASEBOARD_FAB2_LIB.BASEBOARD_FAB2(SCH_1):PAGE85
    26    GND @BASEBOARD_FAB2_LIB.BASEBOARD_FAB2(SCH_1):GND    I43 @BASEBOARD_FAB2_LIB.BASEBOARD_FAB2(SCH_1):PAGE85
    28    GND @BASEBOARD_FAB2_LIB.BASEBOARD_FAB2(SCH_1):GND    I43 @BASEBOARD_FAB2_LIB.BASEBOARD_FAB2(SCH_1):PAGE85
    31    GND @BASEBOARD_FAB2_LIB.BASEBOARD_FAB2(SCH_1):GND    I43 @BASEBOARD_FAB2_LIB.BASEBOARD_FAB2(SCH_1):PAGE85
    33    GND @BASEBOARD_FAB2_LIB.BASEBOARD_FAB2(SCH_1):GND    I43 @BASEBOARD_FAB2_LIB.BASEBOARD_FAB2(SCH_1):PAGE85
    35    GND @BASEBOARD_FAB2_LIB.BASEBOARD_FAB2(SCH_1):GND    I43 @BASEBOARD_FAB2_LIB.BASEBOARD_FAB2(SCH_1):PAGE85
    37    GND @BASEBOARD_FAB2_LIB.BASEBOARD_FAB2(SCH_1):GND    I43 @BASEBOARD_FAB2_LIB.BASEBOARD_FAB2(SCH_1):PAGE85
    39    GND @BASEBOARD_FAB2_LIB.BASEBOARD_FAB2(SCH_1):GND    I43 @BASEBOARD_FAB2_LIB.BASEBOARD_FAB2(SCH_1):PAGE85
    42    GND @BASEBOARD_FAB2_LIB.BASEBOARD_FAB2(SCH_1):GND    I43 @BASEBOARD_FAB2_LIB.BASEBOARD_FAB2(SCH_1):PAGE85
    44    GND @BASEBOARD_FAB2_LIB.BASEBOARD_FAB2(SCH_1):GND    I43 @BASEBOARD_FAB2_LIB.BASEBOARD_FAB2(SCH_1):PAGE85
    46    GND @BASEBOARD_FAB2_LIB.BASEBOARD_FAB2(SCH_1):GND    I43 @BASEBOARD_FAB2_LIB.BASEBOARD_FAB2(SCH_1):PAGE85
    48    GND @BASEBOARD_FAB2_LIB.BASEBOARD_FAB2(SCH_1):GND    I43 @BASEBOARD_FAB2_LIB.BASEBOARD_FAB2(SCH_1):PAGE85
    50    GND @BASEBOARD_FAB2_LIB.BASEBOARD_FAB2(SCH_1):GND    I43 @BASEBOARD_FAB2_LIB.BASEBOARD_FAB2(SCH_1):PAGE85
    53    GND @BASEBOARD_FAB2_LIB.BASEBOARD_FAB2(SCH_1):GND    I43 @BASEBOARD_FAB2_LIB.BASEBOARD_FAB2(SCH_1):PAGE85
    55    GND @BASEBOARD_FAB2_LIB.BASEBOARD_FAB2(SCH_1):GND    I43 @BASEBOARD_FAB2_LIB.BASEBOARD_FAB2(SCH_1):PAGE85
    57    GND @BASEBOARD_FAB2_LIB.BASEBOARD_FAB2(SCH_1):GND    I43 @BASEBOARD_FAB2_LIB.BASEBOARD_FAB2(SCH_1):PAGE85
    94    GND @BASEBOARD_FAB2_LIB.BASEBOARD_FAB2(SCH_1):GND    I43 @BASEBOARD_FAB2_LIB.BASEBOARD_FAB2(SCH_1):PAGE85
    96    GND @BASEBOARD_FAB2_LIB.BASEBOARD_FAB2(SCH_1):GND    I43 @BASEBOARD_FAB2_LIB.BASEBOARD_FAB2(SCH_1):PAGE85
    98    GND @BASEBOARD_FAB2_LIB.BASEBOARD_FAB2(SCH_1):GND    I43 @BASEBOARD_FAB2_LIB.BASEBOARD_FAB2(SCH_1):PAGE85
   101    GND @BASEBOARD_FAB2_LIB.BASEBOARD_FAB2(SCH_1):GND    I43 @BASEBOARD_FAB2_LIB.BASEBOARD_FAB2(SCH_1):PAGE85
   103    GND @BASEBOARD_FAB2_LIB.BASEBOARD_FAB2(SCH_1):GND    I43 @BASEBOARD_FAB2_LIB.BASEBOARD_FAB2(SCH_1):PAGE85
   105    GND @BASEBOARD_FAB2_LIB.BASEBOARD_FAB2(SCH_1):GND    I43 @BASEBOARD_FAB2_LIB.BASEBOARD_FAB2(SCH_1):PAGE85
   107    GND @BASEBOARD_FAB2_LIB.BASEBOARD_FAB2(SCH_1):GND    I43 @BASEBOARD_FAB2_LIB.BASEBOARD_FAB2(SCH_1):PAGE85
   109    GND @BASEBOARD_FAB2_LIB.BASEBOARD_FAB2(SCH_1):GND    I43 @BASEBOARD_FAB2_LIB.BASEBOARD_FAB2(SCH_1):PAGE85
   112    GND @BASEBOARD_FAB2_LIB.BASEBOARD_FAB2(SCH_1):GND    I43 @BASEBOARD_FAB2_LIB.BASEBOARD_FAB2(SCH_1):PAGE85
   114    GND @BASEBOARD_FAB2_LIB.BASEBOARD_FAB2(SCH_1):GND    I43 @BASEBOARD_FAB2_LIB.BASEBOARD_FAB2(SCH_1):PAGE85
   116    GND @BASEBOARD_FAB2_LIB.BASEBOARD_FAB2(SCH_1):GND    I43 @BASEBOARD_FAB2_LIB.BASEBOARD_FAB2(SCH_1):PAGE85
   118    GND @BASEBOARD_FAB2_LIB.BASEBOARD_FAB2(SCH_1):GND    I43 @BASEBOARD_FAB2_LIB.BASEBOARD_FAB2(SCH_1):PAGE85
   120    GND @BASEBOARD_FAB2_LIB.BASEBOARD_FAB2(SCH_1):GND    I43 @BASEBOARD_FAB2_LIB.BASEBOARD_FAB2(SCH_1):PAGE85
   123    GND @BASEBOARD_FAB2_LIB.BASEBOARD_FAB2(SCH_1):GND    I43 @BASEBOARD_FAB2_LIB.BASEBOARD_FAB2(SCH_1):PAGE85
   125    GND @BASEBOARD_FAB2_LIB.BASEBOARD_FAB2(SCH_1):GND    I43 @BASEBOARD_FAB2_LIB.BASEBOARD_FAB2(SCH_1):PAGE85
   127    GND @BASEBOARD_FAB2_LIB.BASEBOARD_FAB2(SCH_1):GND    I43 @BASEBOARD_FAB2_LIB.BASEBOARD_FAB2(SCH_1):PAGE85
   129    GND @BASEBOARD_FAB2_LIB.BASEBOARD_FAB2(SCH_1):GND    I43 @BASEBOARD_FAB2_LIB.BASEBOARD_FAB2(SCH_1):PAGE85
   131    GND @BASEBOARD_FAB2_LIB.BASEBOARD_FAB2(SCH_1):GND    I43 @BASEBOARD_FAB2_LIB.BASEBOARD_FAB2(SCH_1):PAGE85
   134    GND @BASEBOARD_FAB2_LIB.BASEBOARD_FAB2(SCH_1):GND    I43 @BASEBOARD_FAB2_LIB.BASEBOARD_FAB2(SCH_1):PAGE85
   136    GND @BASEBOARD_FAB2_LIB.BASEBOARD_FAB2(SCH_1):GND    I43 @BASEBOARD_FAB2_LIB.BASEBOARD_FAB2(SCH_1):PAGE85
   138    GND @BASEBOARD_FAB2_LIB.BASEBOARD_FAB2(SCH_1):GND    I43 @BASEBOARD_FAB2_LIB.BASEBOARD_FAB2(SCH_1):PAGE85
   147    GND @BASEBOARD_FAB2_LIB.BASEBOARD_FAB2(SCH_1):GND    I43 @BASEBOARD_FAB2_LIB.BASEBOARD_FAB2(SCH_1):PAGE85
   149    GND @BASEBOARD_FAB2_LIB.BASEBOARD_FAB2(SCH_1):GND    I43 @BASEBOARD_FAB2_LIB.BASEBOARD_FAB2(SCH_1):PAGE85
   151    GND @BASEBOARD_FAB2_LIB.BASEBOARD_FAB2(SCH_1):GND    I43 @BASEBOARD_FAB2_LIB.BASEBOARD_FAB2(SCH_1):PAGE85
   154    GND @BASEBOARD_FAB2_LIB.BASEBOARD_FAB2(SCH_1):GND    I43 @BASEBOARD_FAB2_LIB.BASEBOARD_FAB2(SCH_1):PAGE85
   156    GND @BASEBOARD_FAB2_LIB.BASEBOARD_FAB2(SCH_1):GND    I43 @BASEBOARD_FAB2_LIB.BASEBOARD_FAB2(SCH_1):PAGE85
   158    GND @BASEBOARD_FAB2_LIB.BASEBOARD_FAB2(SCH_1):GND    I43 @BASEBOARD_FAB2_LIB.BASEBOARD_FAB2(SCH_1):PAGE85
   160    GND @BASEBOARD_FAB2_LIB.BASEBOARD_FAB2(SCH_1):GND    I43 @BASEBOARD_FAB2_LIB.BASEBOARD_FAB2(SCH_1):PAGE85
   162    GND @BASEBOARD_FAB2_LIB.BASEBOARD_FAB2(SCH_1):GND    I43 @BASEBOARD_FAB2_LIB.BASEBOARD_FAB2(SCH_1):PAGE85
   165    GND @BASEBOARD_FAB2_LIB.BASEBOARD_FAB2(SCH_1):GND    I43 @BASEBOARD_FAB2_LIB.BASEBOARD_FAB2(SCH_1):PAGE85
   167    GND @BASEBOARD_FAB2_LIB.BASEBOARD_FAB2(SCH_1):GND    I43 @BASEBOARD_FAB2_LIB.BASEBOARD_FAB2(SCH_1):PAGE85
   169    GND @BASEBOARD_FAB2_LIB.BASEBOARD_FAB2(SCH_1):GND    I43 @BASEBOARD_FAB2_LIB.BASEBOARD_FAB2(SCH_1):PAGE85
   171    GND @BASEBOARD_FAB2_LIB.BASEBOARD_FAB2(SCH_1):GND    I43 @BASEBOARD_FAB2_LIB.BASEBOARD_FAB2(SCH_1):PAGE85
   173    GND @BASEBOARD_FAB2_LIB.BASEBOARD_FAB2(SCH_1):GND    I43 @BASEBOARD_FAB2_LIB.BASEBOARD_FAB2(SCH_1):PAGE85
   176    GND @BASEBOARD_FAB2_LIB.BASEBOARD_FAB2(SCH_1):GND    I43 @BASEBOARD_FAB2_LIB.BASEBOARD_FAB2(SCH_1):PAGE85
   178    GND @BASEBOARD_FAB2_LIB.BASEBOARD_FAB2(SCH_1):GND    I43 @BASEBOARD_FAB2_LIB.BASEBOARD_FAB2(SCH_1):PAGE85
   180    GND @BASEBOARD_FAB2_LIB.BASEBOARD_FAB2(SCH_1):GND    I43 @BASEBOARD_FAB2_LIB.BASEBOARD_FAB2(SCH_1):PAGE85
   182    GND @BASEBOARD_FAB2_LIB.BASEBOARD_FAB2(SCH_1):GND    I43 @BASEBOARD_FAB2_LIB.BASEBOARD_FAB2(SCH_1):PAGE85
   184    GND @BASEBOARD_FAB2_LIB.BASEBOARD_FAB2(SCH_1):GND    I43 @BASEBOARD_FAB2_LIB.BASEBOARD_FAB2(SCH_1):PAGE85
   187    GND @BASEBOARD_FAB2_LIB.BASEBOARD_FAB2(SCH_1):GND    I43 @BASEBOARD_FAB2_LIB.BASEBOARD_FAB2(SCH_1):PAGE85
   189    GND @BASEBOARD_FAB2_LIB.BASEBOARD_FAB2(SCH_1):GND    I43 @BASEBOARD_FAB2_LIB.BASEBOARD_FAB2(SCH_1):PAGE85
   191    GND @BASEBOARD_FAB2_LIB.BASEBOARD_FAB2(SCH_1):GND    I43 @BASEBOARD_FAB2_LIB.BASEBOARD_FAB2(SCH_1):PAGE85
   193    GND @BASEBOARD_FAB2_LIB.BASEBOARD_FAB2(SCH_1):GND    I43 @BASEBOARD_FAB2_LIB.BASEBOARD_FAB2(SCH_1):PAGE85
   195    GND @BASEBOARD_FAB2_LIB.BASEBOARD_FAB2(SCH_1):GND    I43 @BASEBOARD_FAB2_LIB.BASEBOARD_FAB2(SCH_1):PAGE85
   198    GND @BASEBOARD_FAB2_LIB.BASEBOARD_FAB2(SCH_1):GND    I43 @BASEBOARD_FAB2_LIB.BASEBOARD_FAB2(SCH_1):PAGE85
   200    GND @BASEBOARD_FAB2_LIB.BASEBOARD_FAB2(SCH_1):GND    I43 @BASEBOARD_FAB2_LIB.BASEBOARD_FAB2(SCH_1):PAGE85
   202    GND @BASEBOARD_FAB2_LIB.BASEBOARD_FAB2(SCH_1):GND    I43 @BASEBOARD_FAB2_LIB.BASEBOARD_FAB2(SCH_1):PAGE85
   239    GND @BASEBOARD_FAB2_LIB.BASEBOARD_FAB2(SCH_1):GND    I43 @BASEBOARD_FAB2_LIB.BASEBOARD_FAB2(SCH_1):PAGE85
   241    GND @BASEBOARD_FAB2_LIB.BASEBOARD_FAB2(SCH_1):GND    I43 @BASEBOARD_FAB2_LIB.BASEBOARD_FAB2(SCH_1):PAGE85
   243    GND @BASEBOARD_FAB2_LIB.BASEBOARD_FAB2(SCH_1):GND    I43 @BASEBOARD_FAB2_LIB.BASEBOARD_FAB2(SCH_1):PAGE85
   246    GND @BASEBOARD_FAB2_LIB.BASEBOARD_FAB2(SCH_1):GND    I43 @BASEBOARD_FAB2_LIB.BASEBOARD_FAB2(SCH_1):PAGE85
   248    GND @BASEBOARD_FAB2_LIB.BASEBOARD_FAB2(SCH_1):GND    I43 @BASEBOARD_FAB2_LIB.BASEBOARD_FAB2(SCH_1):PAGE85
   250    GND @BASEBOARD_FAB2_LIB.BASEBOARD_FAB2(SCH_1):GND    I43 @BASEBOARD_FAB2_LIB.BASEBOARD_FAB2(SCH_1):PAGE85
   252    GND @BASEBOARD_FAB2_LIB.BASEBOARD_FAB2(SCH_1):GND    I43 @BASEBOARD_FAB2_LIB.BASEBOARD_FAB2(SCH_1):PAGE85
   254    GND @BASEBOARD_FAB2_LIB.BASEBOARD_FAB2(SCH_1):GND    I43 @BASEBOARD_FAB2_LIB.BASEBOARD_FAB2(SCH_1):PAGE85
   257    GND @BASEBOARD_FAB2_LIB.BASEBOARD_FAB2(SCH_1):GND    I43 @BASEBOARD_FAB2_LIB.BASEBOARD_FAB2(SCH_1):PAGE85
   259    GND @BASEBOARD_FAB2_LIB.BASEBOARD_FAB2(SCH_1):GND    I43 @BASEBOARD_FAB2_LIB.BASEBOARD_FAB2(SCH_1):PAGE85
   261    GND @BASEBOARD_FAB2_LIB.BASEBOARD_FAB2(SCH_1):GND    I43 @BASEBOARD_FAB2_LIB.BASEBOARD_FAB2(SCH_1):PAGE85
   263    GND @BASEBOARD_FAB2_LIB.BASEBOARD_FAB2(SCH_1):GND    I43 @BASEBOARD_FAB2_LIB.BASEBOARD_FAB2(SCH_1):PAGE85
   265    GND @BASEBOARD_FAB2_LIB.BASEBOARD_FAB2(SCH_1):GND    I43 @BASEBOARD_FAB2_LIB.BASEBOARD_FAB2(SCH_1):PAGE85
   268    GND @BASEBOARD_FAB2_LIB.BASEBOARD_FAB2(SCH_1):GND    I43 @BASEBOARD_FAB2_LIB.BASEBOARD_FAB2(SCH_1):PAGE85
   270    GND @BASEBOARD_FAB2_LIB.BASEBOARD_FAB2(SCH_1):GND    I43 @BASEBOARD_FAB2_LIB.BASEBOARD_FAB2(SCH_1):PAGE85
   272    GND @BASEBOARD_FAB2_LIB.BASEBOARD_FAB2(SCH_1):GND    I43 @BASEBOARD_FAB2_LIB.BASEBOARD_FAB2(SCH_1):PAGE85
   274    GND @BASEBOARD_FAB2_LIB.BASEBOARD_FAB2(SCH_1):GND    I43 @BASEBOARD_FAB2_LIB.BASEBOARD_FAB2(SCH_1):PAGE85
   276    GND @BASEBOARD_FAB2_LIB.BASEBOARD_FAB2(SCH_1):GND    I43 @BASEBOARD_FAB2_LIB.BASEBOARD_FAB2(SCH_1):PAGE85
   279    GND @BASEBOARD_FAB2_LIB.BASEBOARD_FAB2(SCH_1):GND    I43 @BASEBOARD_FAB2_LIB.BASEBOARD_FAB2(SCH_1):PAGE85
   281    GND @BASEBOARD_FAB2_LIB.BASEBOARD_FAB2(SCH_1):GND    I43 @BASEBOARD_FAB2_LIB.BASEBOARD_FAB2(SCH_1):PAGE85
   283    GND @BASEBOARD_FAB2_LIB.BASEBOARD_FAB2(SCH_1):GND    I43 @BASEBOARD_FAB2_LIB.BASEBOARD_FAB2(SCH_1):PAGE85
     1 P12V_NVDIMM_KLM @BASEBOARD_FAB2_LIB.BASEBOARD_FAB2(SCH_1):P12V_NVDIMM_KLM   I172 @BASEBOARD_FAB2_LIB.BASEBOARD_FAB2(SCH_1):PAGE85
   145 P12V_NVDIMM_KLM @BASEBOARD_FAB2_LIB.BASEBOARD_FAB2(SCH_1):P12V_NVDIMM_KLM   I172 @BASEBOARD_FAB2_LIB.BASEBOARD_FAB2(SCH_1):PAGE85
    59 PVDDQ_KLM @BASEBOARD_FAB2_LIB.BASEBOARD_FAB2(SCH_1):PVDDQ_KLM   I172 @BASEBOARD_FAB2_LIB.BASEBOARD_FAB2(SCH_1):PAGE85
    61 PVDDQ_KLM @BASEBOARD_FAB2_LIB.BASEBOARD_FAB2(SCH_1):PVDDQ_KLM   I172 @BASEBOARD_FAB2_LIB.BASEBOARD_FAB2(SCH_1):PAGE85
    64 PVDDQ_KLM @BASEBOARD_FAB2_LIB.BASEBOARD_FAB2(SCH_1):PVDDQ_KLM   I172 @BASEBOARD_FAB2_LIB.BASEBOARD_FAB2(SCH_1):PAGE85
    67 PVDDQ_KLM @BASEBOARD_FAB2_LIB.BASEBOARD_FAB2(SCH_1):PVDDQ_KLM   I172 @BASEBOARD_FAB2_LIB.BASEBOARD_FAB2(SCH_1):PAGE85
    70 PVDDQ_KLM @BASEBOARD_FAB2_LIB.BASEBOARD_FAB2(SCH_1):PVDDQ_KLM   I172 @BASEBOARD_FAB2_LIB.BASEBOARD_FAB2(SCH_1):PAGE85
    73 PVDDQ_KLM @BASEBOARD_FAB2_LIB.BASEBOARD_FAB2(SCH_1):PVDDQ_KLM   I172 @BASEBOARD_FAB2_LIB.BASEBOARD_FAB2(SCH_1):PAGE85
    76 PVDDQ_KLM @BASEBOARD_FAB2_LIB.BASEBOARD_FAB2(SCH_1):PVDDQ_KLM   I172 @BASEBOARD_FAB2_LIB.BASEBOARD_FAB2(SCH_1):PAGE85
    80 PVDDQ_KLM @BASEBOARD_FAB2_LIB.BASEBOARD_FAB2(SCH_1):PVDDQ_KLM   I172 @BASEBOARD_FAB2_LIB.BASEBOARD_FAB2(SCH_1):PAGE85
    83 PVDDQ_KLM @BASEBOARD_FAB2_LIB.BASEBOARD_FAB2(SCH_1):PVDDQ_KLM   I172 @BASEBOARD_FAB2_LIB.BASEBOARD_FAB2(SCH_1):PAGE85
    85 PVDDQ_KLM @BASEBOARD_FAB2_LIB.BASEBOARD_FAB2(SCH_1):PVDDQ_KLM   I172 @BASEBOARD_FAB2_LIB.BASEBOARD_FAB2(SCH_1):PAGE85
    88 PVDDQ_KLM @BASEBOARD_FAB2_LIB.BASEBOARD_FAB2(SCH_1):PVDDQ_KLM   I172 @BASEBOARD_FAB2_LIB.BASEBOARD_FAB2(SCH_1):PAGE85
    90 PVDDQ_KLM @BASEBOARD_FAB2_LIB.BASEBOARD_FAB2(SCH_1):PVDDQ_KLM   I172 @BASEBOARD_FAB2_LIB.BASEBOARD_FAB2(SCH_1):PAGE85
    92 PVDDQ_KLM @BASEBOARD_FAB2_LIB.BASEBOARD_FAB2(SCH_1):PVDDQ_KLM   I172 @BASEBOARD_FAB2_LIB.BASEBOARD_FAB2(SCH_1):PAGE85
   204 PVDDQ_KLM @BASEBOARD_FAB2_LIB.BASEBOARD_FAB2(SCH_1):PVDDQ_KLM   I172 @BASEBOARD_FAB2_LIB.BASEBOARD_FAB2(SCH_1):PAGE85
   206 PVDDQ_KLM @BASEBOARD_FAB2_LIB.BASEBOARD_FAB2(SCH_1):PVDDQ_KLM   I172 @BASEBOARD_FAB2_LIB.BASEBOARD_FAB2(SCH_1):PAGE85
   209 PVDDQ_KLM @BASEBOARD_FAB2_LIB.BASEBOARD_FAB2(SCH_1):PVDDQ_KLM   I172 @BASEBOARD_FAB2_LIB.BASEBOARD_FAB2(SCH_1):PAGE85
   212 PVDDQ_KLM @BASEBOARD_FAB2_LIB.BASEBOARD_FAB2(SCH_1):PVDDQ_KLM   I172 @BASEBOARD_FAB2_LIB.BASEBOARD_FAB2(SCH_1):PAGE85
   215 PVDDQ_KLM @BASEBOARD_FAB2_LIB.BASEBOARD_FAB2(SCH_1):PVDDQ_KLM   I172 @BASEBOARD_FAB2_LIB.BASEBOARD_FAB2(SCH_1):PAGE85
   217 PVDDQ_KLM @BASEBOARD_FAB2_LIB.BASEBOARD_FAB2(SCH_1):PVDDQ_KLM   I172 @BASEBOARD_FAB2_LIB.BASEBOARD_FAB2(SCH_1):PAGE85
   220 PVDDQ_KLM @BASEBOARD_FAB2_LIB.BASEBOARD_FAB2(SCH_1):PVDDQ_KLM   I172 @BASEBOARD_FAB2_LIB.BASEBOARD_FAB2(SCH_1):PAGE85
   223 PVDDQ_KLM @BASEBOARD_FAB2_LIB.BASEBOARD_FAB2(SCH_1):PVDDQ_KLM   I172 @BASEBOARD_FAB2_LIB.BASEBOARD_FAB2(SCH_1):PAGE85
   226 PVDDQ_KLM @BASEBOARD_FAB2_LIB.BASEBOARD_FAB2(SCH_1):PVDDQ_KLM   I172 @BASEBOARD_FAB2_LIB.BASEBOARD_FAB2(SCH_1):PAGE85
   229 PVDDQ_KLM @BASEBOARD_FAB2_LIB.BASEBOARD_FAB2(SCH_1):PVDDQ_KLM   I172 @BASEBOARD_FAB2_LIB.BASEBOARD_FAB2(SCH_1):PAGE85
   231 PVDDQ_KLM @BASEBOARD_FAB2_LIB.BASEBOARD_FAB2(SCH_1):PVDDQ_KLM   I172 @BASEBOARD_FAB2_LIB.BASEBOARD_FAB2(SCH_1):PAGE85
   233 PVDDQ_KLM @BASEBOARD_FAB2_LIB.BASEBOARD_FAB2(SCH_1):PVDDQ_KLM   I172 @BASEBOARD_FAB2_LIB.BASEBOARD_FAB2(SCH_1):PAGE85
   236 PVDDQ_KLM @BASEBOARD_FAB2_LIB.BASEBOARD_FAB2(SCH_1):PVDDQ_KLM   I172 @BASEBOARD_FAB2_LIB.BASEBOARD_FAB2(SCH_1):PAGE85
   142 PVPP_KLM @BASEBOARD_FAB2_LIB.BASEBOARD_FAB2(SCH_1):PVPP_KLM   I172 @BASEBOARD_FAB2_LIB.BASEBOARD_FAB2(SCH_1):PAGE85
   143 PVPP_KLM @BASEBOARD_FAB2_LIB.BASEBOARD_FAB2(SCH_1):PVPP_KLM   I172 @BASEBOARD_FAB2_LIB.BASEBOARD_FAB2(SCH_1):PAGE85
   288 PVPP_KLM @BASEBOARD_FAB2_LIB.BASEBOARD_FAB2(SCH_1):PVPP_KLM   I172 @BASEBOARD_FAB2_LIB.BASEBOARD_FAB2(SCH_1):PAGE85
   286 PVPP_KLM @BASEBOARD_FAB2_LIB.BASEBOARD_FAB2(SCH_1):PVPP_KLM   I172 @BASEBOARD_FAB2_LIB.BASEBOARD_FAB2(SCH_1):PAGE85
   287 PVPP_KLM @BASEBOARD_FAB2_LIB.BASEBOARD_FAB2(SCH_1):PVPP_KLM   I172 @BASEBOARD_FAB2_LIB.BASEBOARD_FAB2(SCH_1):PAGE85
    77 PVTT_KLM @BASEBOARD_FAB2_LIB.BASEBOARD_FAB2(SCH_1):PVTT_KLM   I172 @BASEBOARD_FAB2_LIB.BASEBOARD_FAB2(SCH_1):PAGE85
   221 PVTT_KLM @BASEBOARD_FAB2_LIB.BASEBOARD_FAB2(SCH_1):PVTT_KLM   I172 @BASEBOARD_FAB2_LIB.BASEBOARD_FAB2(SCH_1):PAGE85

J1B1 SCONN288_H44441004_PIP-SCONN,HA
    79 M_K_MA<0> @BASEBOARD_FAB2_LIB.BASEBOARD_FAB2(SCH_1):M_K_MA(0)   I111 @BASEBOARD_FAB2_LIB.BASEBOARD_FAB2(SCH_1):PAGE83
    72 M_K_MA<1> @BASEBOARD_FAB2_LIB.BASEBOARD_FAB2(SCH_1):M_K_MA(1)   I111 @BASEBOARD_FAB2_LIB.BASEBOARD_FAB2(SCH_1):PAGE83
   225 M_K_MA<10> @BASEBOARD_FAB2_LIB.BASEBOARD_FAB2(SCH_1):M_K_MA(10)   I111 @BASEBOARD_FAB2_LIB.BASEBOARD_FAB2(SCH_1):PAGE83
   210 M_K_MA<11> @BASEBOARD_FAB2_LIB.BASEBOARD_FAB2(SCH_1):M_K_MA(11)   I111 @BASEBOARD_FAB2_LIB.BASEBOARD_FAB2(SCH_1):PAGE83
    65 M_K_MA<12> @BASEBOARD_FAB2_LIB.BASEBOARD_FAB2(SCH_1):M_K_MA(12)   I111 @BASEBOARD_FAB2_LIB.BASEBOARD_FAB2(SCH_1):PAGE83
   232 M_K_MA<13> @BASEBOARD_FAB2_LIB.BASEBOARD_FAB2(SCH_1):M_K_MA(13)   I111 @BASEBOARD_FAB2_LIB.BASEBOARD_FAB2(SCH_1):PAGE83
   228 M_K_MA<14> @BASEBOARD_FAB2_LIB.BASEBOARD_FAB2(SCH_1):M_K_MA(14)   I111 @BASEBOARD_FAB2_LIB.BASEBOARD_FAB2(SCH_1):PAGE83
    86 M_K_MA<15> @BASEBOARD_FAB2_LIB.BASEBOARD_FAB2(SCH_1):M_K_MA(15)   I111 @BASEBOARD_FAB2_LIB.BASEBOARD_FAB2(SCH_1):PAGE83
    82 M_K_MA<16> @BASEBOARD_FAB2_LIB.BASEBOARD_FAB2(SCH_1):M_K_MA(16)   I111 @BASEBOARD_FAB2_LIB.BASEBOARD_FAB2(SCH_1):PAGE83
   234 M_K_MA<17> @BASEBOARD_FAB2_LIB.BASEBOARD_FAB2(SCH_1):M_K_MA(17)   I111 @BASEBOARD_FAB2_LIB.BASEBOARD_FAB2(SCH_1):PAGE83
   216 M_K_MA<2> @BASEBOARD_FAB2_LIB.BASEBOARD_FAB2(SCH_1):M_K_MA(2)   I111 @BASEBOARD_FAB2_LIB.BASEBOARD_FAB2(SCH_1):PAGE83
    71 M_K_MA<3> @BASEBOARD_FAB2_LIB.BASEBOARD_FAB2(SCH_1):M_K_MA(3)   I111 @BASEBOARD_FAB2_LIB.BASEBOARD_FAB2(SCH_1):PAGE83
   214 M_K_MA<4> @BASEBOARD_FAB2_LIB.BASEBOARD_FAB2(SCH_1):M_K_MA(4)   I111 @BASEBOARD_FAB2_LIB.BASEBOARD_FAB2(SCH_1):PAGE83
   213 M_K_MA<5> @BASEBOARD_FAB2_LIB.BASEBOARD_FAB2(SCH_1):M_K_MA(5)   I111 @BASEBOARD_FAB2_LIB.BASEBOARD_FAB2(SCH_1):PAGE83
    69 M_K_MA<6> @BASEBOARD_FAB2_LIB.BASEBOARD_FAB2(SCH_1):M_K_MA(6)   I111 @BASEBOARD_FAB2_LIB.BASEBOARD_FAB2(SCH_1):PAGE83
   211 M_K_MA<7> @BASEBOARD_FAB2_LIB.BASEBOARD_FAB2(SCH_1):M_K_MA(7)   I111 @BASEBOARD_FAB2_LIB.BASEBOARD_FAB2(SCH_1):PAGE83
    68 M_K_MA<8> @BASEBOARD_FAB2_LIB.BASEBOARD_FAB2(SCH_1):M_K_MA(8)   I111 @BASEBOARD_FAB2_LIB.BASEBOARD_FAB2(SCH_1):PAGE83
    66 M_K_MA<9> @BASEBOARD_FAB2_LIB.BASEBOARD_FAB2(SCH_1):M_K_MA(9)   I111 @BASEBOARD_FAB2_LIB.BASEBOARD_FAB2(SCH_1):PAGE83
    62 M_K_ACT_N @BASEBOARD_FAB2_LIB.BASEBOARD_FAB2(SCH_1):M_K_ACT_N   I111 @BASEBOARD_FAB2_LIB.BASEBOARD_FAB2(SCH_1):PAGE83
   208 M_K_ALERT_N @BASEBOARD_FAB2_LIB.BASEBOARD_FAB2(SCH_1):M_K_ALERT_N   I111 @BASEBOARD_FAB2_LIB.BASEBOARD_FAB2(SCH_1):PAGE83
   224 M_K_BA<1> @BASEBOARD_FAB2_LIB.BASEBOARD_FAB2(SCH_1):M_K_BA(1)   I111 @BASEBOARD_FAB2_LIB.BASEBOARD_FAB2(SCH_1):PAGE83
    81 M_K_BA<0> @BASEBOARD_FAB2_LIB.BASEBOARD_FAB2(SCH_1):M_K_BA(0)   I111 @BASEBOARD_FAB2_LIB.BASEBOARD_FAB2(SCH_1):PAGE83
   207 M_K_BG<1> @BASEBOARD_FAB2_LIB.BASEBOARD_FAB2(SCH_1):M_K_BG(1)   I111 @BASEBOARD_FAB2_LIB.BASEBOARD_FAB2(SCH_1):PAGE83
    63 M_K_BG<0> @BASEBOARD_FAB2_LIB.BASEBOARD_FAB2(SCH_1):M_K_BG(0)   I111 @BASEBOARD_FAB2_LIB.BASEBOARD_FAB2(SCH_1):PAGE83
   235 M_K_C<2> @BASEBOARD_FAB2_LIB.BASEBOARD_FAB2(SCH_1):M_K_C(2)   I111 @BASEBOARD_FAB2_LIB.BASEBOARD_FAB2(SCH_1):PAGE83
   199 M_K_ECC<6> @BASEBOARD_FAB2_LIB.BASEBOARD_FAB2(SCH_1):M_K_ECC(6)   I111 @BASEBOARD_FAB2_LIB.BASEBOARD_FAB2(SCH_1):PAGE83
    54 M_K_ECC<7> @BASEBOARD_FAB2_LIB.BASEBOARD_FAB2(SCH_1):M_K_ECC(7)   I111 @BASEBOARD_FAB2_LIB.BASEBOARD_FAB2(SCH_1):PAGE83
   192 M_K_ECC<4> @BASEBOARD_FAB2_LIB.BASEBOARD_FAB2(SCH_1):M_K_ECC(4)   I111 @BASEBOARD_FAB2_LIB.BASEBOARD_FAB2(SCH_1):PAGE83
    47 M_K_ECC<5> @BASEBOARD_FAB2_LIB.BASEBOARD_FAB2(SCH_1):M_K_ECC(5)   I111 @BASEBOARD_FAB2_LIB.BASEBOARD_FAB2(SCH_1):PAGE83
   201 M_K_ECC<2> @BASEBOARD_FAB2_LIB.BASEBOARD_FAB2(SCH_1):M_K_ECC(2)   I111 @BASEBOARD_FAB2_LIB.BASEBOARD_FAB2(SCH_1):PAGE83
    56 M_K_ECC<3> @BASEBOARD_FAB2_LIB.BASEBOARD_FAB2(SCH_1):M_K_ECC(3)   I111 @BASEBOARD_FAB2_LIB.BASEBOARD_FAB2(SCH_1):PAGE83
   194 M_K_ECC<0> @BASEBOARD_FAB2_LIB.BASEBOARD_FAB2(SCH_1):M_K_ECC(0)   I111 @BASEBOARD_FAB2_LIB.BASEBOARD_FAB2(SCH_1):PAGE83
    49 M_K_ECC<1> @BASEBOARD_FAB2_LIB.BASEBOARD_FAB2(SCH_1):M_K_ECC(1)   I111 @BASEBOARD_FAB2_LIB.BASEBOARD_FAB2(SCH_1):PAGE83
    75 M_K_CLK_DN<0> @BASEBOARD_FAB2_LIB.BASEBOARD_FAB2(SCH_1):M_K_CLK_DN(0)   I111 @BASEBOARD_FAB2_LIB.BASEBOARD_FAB2(SCH_1):PAGE83
    74 M_K_CLK_DP<0> @BASEBOARD_FAB2_LIB.BASEBOARD_FAB2(SCH_1):M_K_CLK_DP(0)   I111 @BASEBOARD_FAB2_LIB.BASEBOARD_FAB2(SCH_1):PAGE83
   219 M_K_CLK_DN<1> @BASEBOARD_FAB2_LIB.BASEBOARD_FAB2(SCH_1):M_K_CLK_DN(1)   I111 @BASEBOARD_FAB2_LIB.BASEBOARD_FAB2(SCH_1):PAGE83
   218 M_K_CLK_DP<1> @BASEBOARD_FAB2_LIB.BASEBOARD_FAB2(SCH_1):M_K_CLK_DP(1)   I111 @BASEBOARD_FAB2_LIB.BASEBOARD_FAB2(SCH_1):PAGE83
   203 M_K_CKE<1> @BASEBOARD_FAB2_LIB.BASEBOARD_FAB2(SCH_1):M_K_CKE(1)   I111 @BASEBOARD_FAB2_LIB.BASEBOARD_FAB2(SCH_1):PAGE83
    60 M_K_CKE<0> @BASEBOARD_FAB2_LIB.BASEBOARD_FAB2(SCH_1):M_K_CKE(0)   I111 @BASEBOARD_FAB2_LIB.BASEBOARD_FAB2(SCH_1):PAGE83
   280 M_K_DQ<62> @BASEBOARD_FAB2_LIB.BASEBOARD_FAB2(SCH_1):M_K_DQ(62)   I111 @BASEBOARD_FAB2_LIB.BASEBOARD_FAB2(SCH_1):PAGE83
   135 M_K_DQ<63> @BASEBOARD_FAB2_LIB.BASEBOARD_FAB2(SCH_1):M_K_DQ(63)   I111 @BASEBOARD_FAB2_LIB.BASEBOARD_FAB2(SCH_1):PAGE83
   273 M_K_DQ<60> @BASEBOARD_FAB2_LIB.BASEBOARD_FAB2(SCH_1):M_K_DQ(60)   I111 @BASEBOARD_FAB2_LIB.BASEBOARD_FAB2(SCH_1):PAGE83
   128 M_K_DQ<61> @BASEBOARD_FAB2_LIB.BASEBOARD_FAB2(SCH_1):M_K_DQ(61)   I111 @BASEBOARD_FAB2_LIB.BASEBOARD_FAB2(SCH_1):PAGE83
   282 M_K_DQ<58> @BASEBOARD_FAB2_LIB.BASEBOARD_FAB2(SCH_1):M_K_DQ(58)   I111 @BASEBOARD_FAB2_LIB.BASEBOARD_FAB2(SCH_1):PAGE83
   137 M_K_DQ<59> @BASEBOARD_FAB2_LIB.BASEBOARD_FAB2(SCH_1):M_K_DQ(59)   I111 @BASEBOARD_FAB2_LIB.BASEBOARD_FAB2(SCH_1):PAGE83
   275 M_K_DQ<56> @BASEBOARD_FAB2_LIB.BASEBOARD_FAB2(SCH_1):M_K_DQ(56)   I111 @BASEBOARD_FAB2_LIB.BASEBOARD_FAB2(SCH_1):PAGE83
   130 M_K_DQ<57> @BASEBOARD_FAB2_LIB.BASEBOARD_FAB2(SCH_1):M_K_DQ(57)   I111 @BASEBOARD_FAB2_LIB.BASEBOARD_FAB2(SCH_1):PAGE83
   269 M_K_DQ<54> @BASEBOARD_FAB2_LIB.BASEBOARD_FAB2(SCH_1):M_K_DQ(54)   I111 @BASEBOARD_FAB2_LIB.BASEBOARD_FAB2(SCH_1):PAGE83
   124 M_K_DQ<55> @BASEBOARD_FAB2_LIB.BASEBOARD_FAB2(SCH_1):M_K_DQ(55)   I111 @BASEBOARD_FAB2_LIB.BASEBOARD_FAB2(SCH_1):PAGE83
   262 M_K_DQ<52> @BASEBOARD_FAB2_LIB.BASEBOARD_FAB2(SCH_1):M_K_DQ(52)   I111 @BASEBOARD_FAB2_LIB.BASEBOARD_FAB2(SCH_1):PAGE83
   117 M_K_DQ<53> @BASEBOARD_FAB2_LIB.BASEBOARD_FAB2(SCH_1):M_K_DQ(53)   I111 @BASEBOARD_FAB2_LIB.BASEBOARD_FAB2(SCH_1):PAGE83
   271 M_K_DQ<50> @BASEBOARD_FAB2_LIB.BASEBOARD_FAB2(SCH_1):M_K_DQ(50)   I111 @BASEBOARD_FAB2_LIB.BASEBOARD_FAB2(SCH_1):PAGE83
   126 M_K_DQ<51> @BASEBOARD_FAB2_LIB.BASEBOARD_FAB2(SCH_1):M_K_DQ(51)   I111 @BASEBOARD_FAB2_LIB.BASEBOARD_FAB2(SCH_1):PAGE83
   264 M_K_DQ<48> @BASEBOARD_FAB2_LIB.BASEBOARD_FAB2(SCH_1):M_K_DQ(48)   I111 @BASEBOARD_FAB2_LIB.BASEBOARD_FAB2(SCH_1):PAGE83
   119 M_K_DQ<49> @BASEBOARD_FAB2_LIB.BASEBOARD_FAB2(SCH_1):M_K_DQ(49)   I111 @BASEBOARD_FAB2_LIB.BASEBOARD_FAB2(SCH_1):PAGE83
   258 M_K_DQ<46> @BASEBOARD_FAB2_LIB.BASEBOARD_FAB2(SCH_1):M_K_DQ(46)   I111 @BASEBOARD_FAB2_LIB.BASEBOARD_FAB2(SCH_1):PAGE83
   113 M_K_DQ<47> @BASEBOARD_FAB2_LIB.BASEBOARD_FAB2(SCH_1):M_K_DQ(47)   I111 @BASEBOARD_FAB2_LIB.BASEBOARD_FAB2(SCH_1):PAGE83
   251 M_K_DQ<44> @BASEBOARD_FAB2_LIB.BASEBOARD_FAB2(SCH_1):M_K_DQ(44)   I111 @BASEBOARD_FAB2_LIB.BASEBOARD_FAB2(SCH_1):PAGE83
   106 M_K_DQ<45> @BASEBOARD_FAB2_LIB.BASEBOARD_FAB2(SCH_1):M_K_DQ(45)   I111 @BASEBOARD_FAB2_LIB.BASEBOARD_FAB2(SCH_1):PAGE83
   260 M_K_DQ<42> @BASEBOARD_FAB2_LIB.BASEBOARD_FAB2(SCH_1):M_K_DQ(42)   I111 @BASEBOARD_FAB2_LIB.BASEBOARD_FAB2(SCH_1):PAGE83
   115 M_K_DQ<43> @BASEBOARD_FAB2_LIB.BASEBOARD_FAB2(SCH_1):M_K_DQ(43)   I111 @BASEBOARD_FAB2_LIB.BASEBOARD_FAB2(SCH_1):PAGE83
   253 M_K_DQ<40> @BASEBOARD_FAB2_LIB.BASEBOARD_FAB2(SCH_1):M_K_DQ(40)   I111 @BASEBOARD_FAB2_LIB.BASEBOARD_FAB2(SCH_1):PAGE83
   108 M_K_DQ<41> @BASEBOARD_FAB2_LIB.BASEBOARD_FAB2(SCH_1):M_K_DQ(41)   I111 @BASEBOARD_FAB2_LIB.BASEBOARD_FAB2(SCH_1):PAGE83
   247 M_K_DQ<38> @BASEBOARD_FAB2_LIB.BASEBOARD_FAB2(SCH_1):M_K_DQ(38)   I111 @BASEBOARD_FAB2_LIB.BASEBOARD_FAB2(SCH_1):PAGE83
   102 M_K_DQ<39> @BASEBOARD_FAB2_LIB.BASEBOARD_FAB2(SCH_1):M_K_DQ(39)   I111 @BASEBOARD_FAB2_LIB.BASEBOARD_FAB2(SCH_1):PAGE83
   240 M_K_DQ<36> @BASEBOARD_FAB2_LIB.BASEBOARD_FAB2(SCH_1):M_K_DQ(36)   I111 @BASEBOARD_FAB2_LIB.BASEBOARD_FAB2(SCH_1):PAGE83
    95 M_K_DQ<37> @BASEBOARD_FAB2_LIB.BASEBOARD_FAB2(SCH_1):M_K_DQ(37)   I111 @BASEBOARD_FAB2_LIB.BASEBOARD_FAB2(SCH_1):PAGE83
   249 M_K_DQ<34> @BASEBOARD_FAB2_LIB.BASEBOARD_FAB2(SCH_1):M_K_DQ(34)   I111 @BASEBOARD_FAB2_LIB.BASEBOARD_FAB2(SCH_1):PAGE83
   104 M_K_DQ<35> @BASEBOARD_FAB2_LIB.BASEBOARD_FAB2(SCH_1):M_K_DQ(35)   I111 @BASEBOARD_FAB2_LIB.BASEBOARD_FAB2(SCH_1):PAGE83
   242 M_K_DQ<32> @BASEBOARD_FAB2_LIB.BASEBOARD_FAB2(SCH_1):M_K_DQ(32)   I111 @BASEBOARD_FAB2_LIB.BASEBOARD_FAB2(SCH_1):PAGE83
    97 M_K_DQ<33> @BASEBOARD_FAB2_LIB.BASEBOARD_FAB2(SCH_1):M_K_DQ(33)   I111 @BASEBOARD_FAB2_LIB.BASEBOARD_FAB2(SCH_1):PAGE83
   188 M_K_DQ<30> @BASEBOARD_FAB2_LIB.BASEBOARD_FAB2(SCH_1):M_K_DQ(30)   I111 @BASEBOARD_FAB2_LIB.BASEBOARD_FAB2(SCH_1):PAGE83
    43 M_K_DQ<31> @BASEBOARD_FAB2_LIB.BASEBOARD_FAB2(SCH_1):M_K_DQ(31)   I111 @BASEBOARD_FAB2_LIB.BASEBOARD_FAB2(SCH_1):PAGE83
   181 M_K_DQ<28> @BASEBOARD_FAB2_LIB.BASEBOARD_FAB2(SCH_1):M_K_DQ(28)   I111 @BASEBOARD_FAB2_LIB.BASEBOARD_FAB2(SCH_1):PAGE83
    36 M_K_DQ<29> @BASEBOARD_FAB2_LIB.BASEBOARD_FAB2(SCH_1):M_K_DQ(29)   I111 @BASEBOARD_FAB2_LIB.BASEBOARD_FAB2(SCH_1):PAGE83
   190 M_K_DQ<26> @BASEBOARD_FAB2_LIB.BASEBOARD_FAB2(SCH_1):M_K_DQ(26)   I111 @BASEBOARD_FAB2_LIB.BASEBOARD_FAB2(SCH_1):PAGE83
    45 M_K_DQ<27> @BASEBOARD_FAB2_LIB.BASEBOARD_FAB2(SCH_1):M_K_DQ(27)   I111 @BASEBOARD_FAB2_LIB.BASEBOARD_FAB2(SCH_1):PAGE83
   183 M_K_DQ<24> @BASEBOARD_FAB2_LIB.BASEBOARD_FAB2(SCH_1):M_K_DQ(24)   I111 @BASEBOARD_FAB2_LIB.BASEBOARD_FAB2(SCH_1):PAGE83
    38 M_K_DQ<25> @BASEBOARD_FAB2_LIB.BASEBOARD_FAB2(SCH_1):M_K_DQ(25)   I111 @BASEBOARD_FAB2_LIB.BASEBOARD_FAB2(SCH_1):PAGE83
   177 M_K_DQ<22> @BASEBOARD_FAB2_LIB.BASEBOARD_FAB2(SCH_1):M_K_DQ(22)   I111 @BASEBOARD_FAB2_LIB.BASEBOARD_FAB2(SCH_1):PAGE83
    32 M_K_DQ<23> @BASEBOARD_FAB2_LIB.BASEBOARD_FAB2(SCH_1):M_K_DQ(23)   I111 @BASEBOARD_FAB2_LIB.BASEBOARD_FAB2(SCH_1):PAGE83
   170 M_K_DQ<20> @BASEBOARD_FAB2_LIB.BASEBOARD_FAB2(SCH_1):M_K_DQ(20)   I111 @BASEBOARD_FAB2_LIB.BASEBOARD_FAB2(SCH_1):PAGE83
    25 M_K_DQ<21> @BASEBOARD_FAB2_LIB.BASEBOARD_FAB2(SCH_1):M_K_DQ(21)   I111 @BASEBOARD_FAB2_LIB.BASEBOARD_FAB2(SCH_1):PAGE83
   179 M_K_DQ<18> @BASEBOARD_FAB2_LIB.BASEBOARD_FAB2(SCH_1):M_K_DQ(18)   I111 @BASEBOARD_FAB2_LIB.BASEBOARD_FAB2(SCH_1):PAGE83
    34 M_K_DQ<19> @BASEBOARD_FAB2_LIB.BASEBOARD_FAB2(SCH_1):M_K_DQ(19)   I111 @BASEBOARD_FAB2_LIB.BASEBOARD_FAB2(SCH_1):PAGE83
   172 M_K_DQ<16> @BASEBOARD_FAB2_LIB.BASEBOARD_FAB2(SCH_1):M_K_DQ(16)   I111 @BASEBOARD_FAB2_LIB.BASEBOARD_FAB2(SCH_1):PAGE83
    27 M_K_DQ<17> @BASEBOARD_FAB2_LIB.BASEBOARD_FAB2(SCH_1):M_K_DQ(17)   I111 @BASEBOARD_FAB2_LIB.BASEBOARD_FAB2(SCH_1):PAGE83
   166 M_K_DQ<14> @BASEBOARD_FAB2_LIB.BASEBOARD_FAB2(SCH_1):M_K_DQ(14)   I111 @BASEBOARD_FAB2_LIB.BASEBOARD_FAB2(SCH_1):PAGE83
    21 M_K_DQ<15> @BASEBOARD_FAB2_LIB.BASEBOARD_FAB2(SCH_1):M_K_DQ(15)   I111 @BASEBOARD_FAB2_LIB.BASEBOARD_FAB2(SCH_1):PAGE83
   159 M_K_DQ<12> @BASEBOARD_FAB2_LIB.BASEBOARD_FAB2(SCH_1):M_K_DQ(12)   I111 @BASEBOARD_FAB2_LIB.BASEBOARD_FAB2(SCH_1):PAGE83
    14 M_K_DQ<13> @BASEBOARD_FAB2_LIB.BASEBOARD_FAB2(SCH_1):M_K_DQ(13)   I111 @BASEBOARD_FAB2_LIB.BASEBOARD_FAB2(SCH_1):PAGE83
   168 M_K_DQ<10> @BASEBOARD_FAB2_LIB.BASEBOARD_FAB2(SCH_1):M_K_DQ(10)   I111 @BASEBOARD_FAB2_LIB.BASEBOARD_FAB2(SCH_1):PAGE83
    23 M_K_DQ<11> @BASEBOARD_FAB2_LIB.BASEBOARD_FAB2(SCH_1):M_K_DQ(11)   I111 @BASEBOARD_FAB2_LIB.BASEBOARD_FAB2(SCH_1):PAGE83
   161 M_K_DQ<8> @BASEBOARD_FAB2_LIB.BASEBOARD_FAB2(SCH_1):M_K_DQ(8)   I111 @BASEBOARD_FAB2_LIB.BASEBOARD_FAB2(SCH_1):PAGE83
    16 M_K_DQ<9> @BASEBOARD_FAB2_LIB.BASEBOARD_FAB2(SCH_1):M_K_DQ(9)   I111 @BASEBOARD_FAB2_LIB.BASEBOARD_FAB2(SCH_1):PAGE83
   155 M_K_DQ<6> @BASEBOARD_FAB2_LIB.BASEBOARD_FAB2(SCH_1):M_K_DQ(6)   I111 @BASEBOARD_FAB2_LIB.BASEBOARD_FAB2(SCH_1):PAGE83
    10 M_K_DQ<7> @BASEBOARD_FAB2_LIB.BASEBOARD_FAB2(SCH_1):M_K_DQ(7)   I111 @BASEBOARD_FAB2_LIB.BASEBOARD_FAB2(SCH_1):PAGE83
   148 M_K_DQ<4> @BASEBOARD_FAB2_LIB.BASEBOARD_FAB2(SCH_1):M_K_DQ(4)   I111 @BASEBOARD_FAB2_LIB.BASEBOARD_FAB2(SCH_1):PAGE83
     3 M_K_DQ<5> @BASEBOARD_FAB2_LIB.BASEBOARD_FAB2(SCH_1):M_K_DQ(5)   I111 @BASEBOARD_FAB2_LIB.BASEBOARD_FAB2(SCH_1):PAGE83
   157 M_K_DQ<2> @BASEBOARD_FAB2_LIB.BASEBOARD_FAB2(SCH_1):M_K_DQ(2)   I111 @BASEBOARD_FAB2_LIB.BASEBOARD_FAB2(SCH_1):PAGE83
    12 M_K_DQ<3> @BASEBOARD_FAB2_LIB.BASEBOARD_FAB2(SCH_1):M_K_DQ(3)   I111 @BASEBOARD_FAB2_LIB.BASEBOARD_FAB2(SCH_1):PAGE83
   150 M_K_DQ<0> @BASEBOARD_FAB2_LIB.BASEBOARD_FAB2(SCH_1):M_K_DQ(0)   I111 @BASEBOARD_FAB2_LIB.BASEBOARD_FAB2(SCH_1):PAGE83
     5 M_K_DQ<1> @BASEBOARD_FAB2_LIB.BASEBOARD_FAB2(SCH_1):M_K_DQ(1)   I111 @BASEBOARD_FAB2_LIB.BASEBOARD_FAB2(SCH_1):PAGE83
    78 FM_DIMM_EVENT_COD_N @BASEBOARD_FAB2_LIB.BASEBOARD_FAB2(SCH_1):FM_DIMM_EVENT_COD_N   I111 @BASEBOARD_FAB2_LIB.BASEBOARD_FAB2(SCH_1):PAGE83
    91 M_K_ODT<1> @BASEBOARD_FAB2_LIB.BASEBOARD_FAB2(SCH_1):M_K_ODT(1)   I111 @BASEBOARD_FAB2_LIB.BASEBOARD_FAB2(SCH_1):PAGE83
    87 M_K_ODT<0> @BASEBOARD_FAB2_LIB.BASEBOARD_FAB2(SCH_1):M_K_ODT(0)   I111 @BASEBOARD_FAB2_LIB.BASEBOARD_FAB2(SCH_1):PAGE83
   222 M_K_PAR @BASEBOARD_FAB2_LIB.BASEBOARD_FAB2(SCH_1):M_K_PAR   I111 @BASEBOARD_FAB2_LIB.BASEBOARD_FAB2(SCH_1):PAGE83
    58 M_KLM_RST_N @BASEBOARD_FAB2_LIB.BASEBOARD_FAB2(SCH_1):M_KLM_RST_N   I111 @BASEBOARD_FAB2_LIB.BASEBOARD_FAB2(SCH_1):PAGE83
   144 TP_CH_K_DIMM_K0_RFU_2 @BASEBOARD_FAB2_LIB.BASEBOARD_FAB2(SCH_1):TP_CH_K_DIMM_K0_RFU_2   I111 @BASEBOARD_FAB2_LIB.BASEBOARD_FAB2(SCH_1):PAGE83
   227 TP_CH_K_DIMM_K0_RFU_1 @BASEBOARD_FAB2_LIB.BASEBOARD_FAB2(SCH_1):TP_CH_K_DIMM_K0_RFU_1   I111 @BASEBOARD_FAB2_LIB.BASEBOARD_FAB2(SCH_1):PAGE83
   205 TP_CH_K_DIMM_K0_RFU_0 @BASEBOARD_FAB2_LIB.BASEBOARD_FAB2(SCH_1):TP_CH_K_DIMM_K0_RFU_0   I111 @BASEBOARD_FAB2_LIB.BASEBOARD_FAB2(SCH_1):PAGE83
    84 M_K_CS_N<0> @BASEBOARD_FAB2_LIB.BASEBOARD_FAB2(SCH_1):M_K_CS_N(0)   I111 @BASEBOARD_FAB2_LIB.BASEBOARD_FAB2(SCH_1):PAGE83
    89 M_K_CS_N<1> @BASEBOARD_FAB2_LIB.BASEBOARD_FAB2(SCH_1):M_K_CS_N(1)   I111 @BASEBOARD_FAB2_LIB.BASEBOARD_FAB2(SCH_1):PAGE83
    93 M_K_CS_N<2> @BASEBOARD_FAB2_LIB.BASEBOARD_FAB2(SCH_1):M_K_CS_N(2)   I111 @BASEBOARD_FAB2_LIB.BASEBOARD_FAB2(SCH_1):PAGE83
   237 M_K_CS_N<3> @BASEBOARD_FAB2_LIB.BASEBOARD_FAB2(SCH_1):M_K_CS_N(3)   I111 @BASEBOARD_FAB2_LIB.BASEBOARD_FAB2(SCH_1):PAGE83
   238    GND @BASEBOARD_FAB2_LIB.BASEBOARD_FAB2(SCH_1):GND   I111 @BASEBOARD_FAB2_LIB.BASEBOARD_FAB2(SCH_1):PAGE83
   140    GND @BASEBOARD_FAB2_LIB.BASEBOARD_FAB2(SCH_1):GND   I111 @BASEBOARD_FAB2_LIB.BASEBOARD_FAB2(SCH_1):PAGE83
   139    GND @BASEBOARD_FAB2_LIB.BASEBOARD_FAB2(SCH_1):GND   I111 @BASEBOARD_FAB2_LIB.BASEBOARD_FAB2(SCH_1):PAGE83
   230 FM_ADR_COMPLETE_KLM_N @BASEBOARD_FAB2_LIB.BASEBOARD_FAB2(SCH_1):FM_ADR_COMPLETE_KLM_N   I111 @BASEBOARD_FAB2_LIB.BASEBOARD_FAB2(SCH_1):PAGE83
   141 SMB_DDR_KLM_VPP_SCL @BASEBOARD_FAB2_LIB.BASEBOARD_FAB2(SCH_1):SMB_DDR_KLM_VPP_SCL   I111 @BASEBOARD_FAB2_LIB.BASEBOARD_FAB2(SCH_1):PAGE83
   285 SMB_DDR_KLM_VPP_SDA @BASEBOARD_FAB2_LIB.BASEBOARD_FAB2(SCH_1):SMB_DDR_KLM_VPP_SDA   I111 @BASEBOARD_FAB2_LIB.BASEBOARD_FAB2(SCH_1):PAGE83
   284 PVPP_KLM @BASEBOARD_FAB2_LIB.BASEBOARD_FAB2(SCH_1):PVPP_KLM   I111 @BASEBOARD_FAB2_LIB.BASEBOARD_FAB2(SCH_1):PAGE83
   146 M_K_VREF @BASEBOARD_FAB2_LIB.BASEBOARD_FAB2(SCH_1):M_K_VREF   I111 @BASEBOARD_FAB2_LIB.BASEBOARD_FAB2(SCH_1):PAGE83
   152 M_K_DQS_DN<0> @BASEBOARD_FAB2_LIB.BASEBOARD_FAB2(SCH_1):M_K_DQS_DN(0)    I66 @BASEBOARD_FAB2_LIB.BASEBOARD_FAB2(SCH_1):PAGE83
   153 M_K_DQS_DP<0> @BASEBOARD_FAB2_LIB.BASEBOARD_FAB2(SCH_1):M_K_DQS_DP(0)    I66 @BASEBOARD_FAB2_LIB.BASEBOARD_FAB2(SCH_1):PAGE83
    19 M_K_DQS_DN<10> @BASEBOARD_FAB2_LIB.BASEBOARD_FAB2(SCH_1):M_K_DQS_DN(10)    I66 @BASEBOARD_FAB2_LIB.BASEBOARD_FAB2(SCH_1):PAGE83
    18 M_K_DQS_DP<10> @BASEBOARD_FAB2_LIB.BASEBOARD_FAB2(SCH_1):M_K_DQS_DP(10)    I66 @BASEBOARD_FAB2_LIB.BASEBOARD_FAB2(SCH_1):PAGE83
    30 M_K_DQS_DN<11> @BASEBOARD_FAB2_LIB.BASEBOARD_FAB2(SCH_1):M_K_DQS_DN(11)    I66 @BASEBOARD_FAB2_LIB.BASEBOARD_FAB2(SCH_1):PAGE83
    29 M_K_DQS_DP<11> @BASEBOARD_FAB2_LIB.BASEBOARD_FAB2(SCH_1):M_K_DQS_DP(11)    I66 @BASEBOARD_FAB2_LIB.BASEBOARD_FAB2(SCH_1):PAGE83
    41 M_K_DQS_DN<12> @BASEBOARD_FAB2_LIB.BASEBOARD_FAB2(SCH_1):M_K_DQS_DN(12)    I66 @BASEBOARD_FAB2_LIB.BASEBOARD_FAB2(SCH_1):PAGE83
    40 M_K_DQS_DP<12> @BASEBOARD_FAB2_LIB.BASEBOARD_FAB2(SCH_1):M_K_DQS_DP(12)    I66 @BASEBOARD_FAB2_LIB.BASEBOARD_FAB2(SCH_1):PAGE83
   100 M_K_DQS_DN<13> @BASEBOARD_FAB2_LIB.BASEBOARD_FAB2(SCH_1):M_K_DQS_DN(13)    I66 @BASEBOARD_FAB2_LIB.BASEBOARD_FAB2(SCH_1):PAGE83
    99 M_K_DQS_DP<13> @BASEBOARD_FAB2_LIB.BASEBOARD_FAB2(SCH_1):M_K_DQS_DP(13)    I66 @BASEBOARD_FAB2_LIB.BASEBOARD_FAB2(SCH_1):PAGE83
   111 M_K_DQS_DN<14> @BASEBOARD_FAB2_LIB.BASEBOARD_FAB2(SCH_1):M_K_DQS_DN(14)    I66 @BASEBOARD_FAB2_LIB.BASEBOARD_FAB2(SCH_1):PAGE83
   110 M_K_DQS_DP<14> @BASEBOARD_FAB2_LIB.BASEBOARD_FAB2(SCH_1):M_K_DQS_DP(14)    I66 @BASEBOARD_FAB2_LIB.BASEBOARD_FAB2(SCH_1):PAGE83
   122 M_K_DQS_DN<15> @BASEBOARD_FAB2_LIB.BASEBOARD_FAB2(SCH_1):M_K_DQS_DN(15)    I66 @BASEBOARD_FAB2_LIB.BASEBOARD_FAB2(SCH_1):PAGE83
   121 M_K_DQS_DP<15> @BASEBOARD_FAB2_LIB.BASEBOARD_FAB2(SCH_1):M_K_DQS_DP(15)    I66 @BASEBOARD_FAB2_LIB.BASEBOARD_FAB2(SCH_1):PAGE83
   133 M_K_DQS_DN<16> @BASEBOARD_FAB2_LIB.BASEBOARD_FAB2(SCH_1):M_K_DQS_DN(16)    I66 @BASEBOARD_FAB2_LIB.BASEBOARD_FAB2(SCH_1):PAGE83
   132 M_K_DQS_DP<16> @BASEBOARD_FAB2_LIB.BASEBOARD_FAB2(SCH_1):M_K_DQS_DP(16)    I66 @BASEBOARD_FAB2_LIB.BASEBOARD_FAB2(SCH_1):PAGE83
    52 M_K_DQS_DN<17> @BASEBOARD_FAB2_LIB.BASEBOARD_FAB2(SCH_1):M_K_DQS_DN(17)    I66 @BASEBOARD_FAB2_LIB.BASEBOARD_FAB2(SCH_1):PAGE83
    51 M_K_DQS_DP<17> @BASEBOARD_FAB2_LIB.BASEBOARD_FAB2(SCH_1):M_K_DQS_DP(17)    I66 @BASEBOARD_FAB2_LIB.BASEBOARD_FAB2(SCH_1):PAGE83
   163 M_K_DQS_DN<1> @BASEBOARD_FAB2_LIB.BASEBOARD_FAB2(SCH_1):M_K_DQS_DN(1)    I66 @BASEBOARD_FAB2_LIB.BASEBOARD_FAB2(SCH_1):PAGE83
   164 M_K_DQS_DP<1> @BASEBOARD_FAB2_LIB.BASEBOARD_FAB2(SCH_1):M_K_DQS_DP(1)    I66 @BASEBOARD_FAB2_LIB.BASEBOARD_FAB2(SCH_1):PAGE83
   174 M_K_DQS_DN<2> @BASEBOARD_FAB2_LIB.BASEBOARD_FAB2(SCH_1):M_K_DQS_DN(2)    I66 @BASEBOARD_FAB2_LIB.BASEBOARD_FAB2(SCH_1):PAGE83
   175 M_K_DQS_DP<2> @BASEBOARD_FAB2_LIB.BASEBOARD_FAB2(SCH_1):M_K_DQS_DP(2)    I66 @BASEBOARD_FAB2_LIB.BASEBOARD_FAB2(SCH_1):PAGE83
   185 M_K_DQS_DN<3> @BASEBOARD_FAB2_LIB.BASEBOARD_FAB2(SCH_1):M_K_DQS_DN(3)    I66 @BASEBOARD_FAB2_LIB.BASEBOARD_FAB2(SCH_1):PAGE83
   186 M_K_DQS_DP<3> @BASEBOARD_FAB2_LIB.BASEBOARD_FAB2(SCH_1):M_K_DQS_DP(3)    I66 @BASEBOARD_FAB2_LIB.BASEBOARD_FAB2(SCH_1):PAGE83
   244 M_K_DQS_DN<4> @BASEBOARD_FAB2_LIB.BASEBOARD_FAB2(SCH_1):M_K_DQS_DN(4)    I66 @BASEBOARD_FAB2_LIB.BASEBOARD_FAB2(SCH_1):PAGE83
   245 M_K_DQS_DP<4> @BASEBOARD_FAB2_LIB.BASEBOARD_FAB2(SCH_1):M_K_DQS_DP(4)    I66 @BASEBOARD_FAB2_LIB.BASEBOARD_FAB2(SCH_1):PAGE83
   255 M_K_DQS_DN<5> @BASEBOARD_FAB2_LIB.BASEBOARD_FAB2(SCH_1):M_K_DQS_DN(5)    I66 @BASEBOARD_FAB2_LIB.BASEBOARD_FAB2(SCH_1):PAGE83
   256 M_K_DQS_DP<5> @BASEBOARD_FAB2_LIB.BASEBOARD_FAB2(SCH_1):M_K_DQS_DP(5)    I66 @BASEBOARD_FAB2_LIB.BASEBOARD_FAB2(SCH_1):PAGE83
   266 M_K_DQS_DN<6> @BASEBOARD_FAB2_LIB.BASEBOARD_FAB2(SCH_1):M_K_DQS_DN(6)    I66 @BASEBOARD_FAB2_LIB.BASEBOARD_FAB2(SCH_1):PAGE83
   267 M_K_DQS_DP<6> @BASEBOARD_FAB2_LIB.BASEBOARD_FAB2(SCH_1):M_K_DQS_DP(6)    I66 @BASEBOARD_FAB2_LIB.BASEBOARD_FAB2(SCH_1):PAGE83
   277 M_K_DQS_DN<7> @BASEBOARD_FAB2_LIB.BASEBOARD_FAB2(SCH_1):M_K_DQS_DN(7)    I66 @BASEBOARD_FAB2_LIB.BASEBOARD_FAB2(SCH_1):PAGE83
   278 M_K_DQS_DP<7> @BASEBOARD_FAB2_LIB.BASEBOARD_FAB2(SCH_1):M_K_DQS_DP(7)    I66 @BASEBOARD_FAB2_LIB.BASEBOARD_FAB2(SCH_1):PAGE83
   196 M_K_DQS_DN<8> @BASEBOARD_FAB2_LIB.BASEBOARD_FAB2(SCH_1):M_K_DQS_DN(8)    I66 @BASEBOARD_FAB2_LIB.BASEBOARD_FAB2(SCH_1):PAGE83
   197 M_K_DQS_DP<8> @BASEBOARD_FAB2_LIB.BASEBOARD_FAB2(SCH_1):M_K_DQS_DP(8)    I66 @BASEBOARD_FAB2_LIB.BASEBOARD_FAB2(SCH_1):PAGE83
     8 M_K_DQS_DN<9> @BASEBOARD_FAB2_LIB.BASEBOARD_FAB2(SCH_1):M_K_DQS_DN(9)    I66 @BASEBOARD_FAB2_LIB.BASEBOARD_FAB2(SCH_1):PAGE83
     7 M_K_DQS_DP<9> @BASEBOARD_FAB2_LIB.BASEBOARD_FAB2(SCH_1):M_K_DQS_DP(9)    I66 @BASEBOARD_FAB2_LIB.BASEBOARD_FAB2(SCH_1):PAGE83
     2    GND @BASEBOARD_FAB2_LIB.BASEBOARD_FAB2(SCH_1):GND    I43 @BASEBOARD_FAB2_LIB.BASEBOARD_FAB2(SCH_1):PAGE83
     4    GND @BASEBOARD_FAB2_LIB.BASEBOARD_FAB2(SCH_1):GND    I43 @BASEBOARD_FAB2_LIB.BASEBOARD_FAB2(SCH_1):PAGE83
     6    GND @BASEBOARD_FAB2_LIB.BASEBOARD_FAB2(SCH_1):GND    I43 @BASEBOARD_FAB2_LIB.BASEBOARD_FAB2(SCH_1):PAGE83
     9    GND @BASEBOARD_FAB2_LIB.BASEBOARD_FAB2(SCH_1):GND    I43 @BASEBOARD_FAB2_LIB.BASEBOARD_FAB2(SCH_1):PAGE83
    11    GND @BASEBOARD_FAB2_LIB.BASEBOARD_FAB2(SCH_1):GND    I43 @BASEBOARD_FAB2_LIB.BASEBOARD_FAB2(SCH_1):PAGE83
    13    GND @BASEBOARD_FAB2_LIB.BASEBOARD_FAB2(SCH_1):GND    I43 @BASEBOARD_FAB2_LIB.BASEBOARD_FAB2(SCH_1):PAGE83
    15    GND @BASEBOARD_FAB2_LIB.BASEBOARD_FAB2(SCH_1):GND    I43 @BASEBOARD_FAB2_LIB.BASEBOARD_FAB2(SCH_1):PAGE83
    17    GND @BASEBOARD_FAB2_LIB.BASEBOARD_FAB2(SCH_1):GND    I43 @BASEBOARD_FAB2_LIB.BASEBOARD_FAB2(SCH_1):PAGE83
    20    GND @BASEBOARD_FAB2_LIB.BASEBOARD_FAB2(SCH_1):GND    I43 @BASEBOARD_FAB2_LIB.BASEBOARD_FAB2(SCH_1):PAGE83
    22    GND @BASEBOARD_FAB2_LIB.BASEBOARD_FAB2(SCH_1):GND    I43 @BASEBOARD_FAB2_LIB.BASEBOARD_FAB2(SCH_1):PAGE83
    24    GND @BASEBOARD_FAB2_LIB.BASEBOARD_FAB2(SCH_1):GND    I43 @BASEBOARD_FAB2_LIB.BASEBOARD_FAB2(SCH_1):PAGE83
    26    GND @BASEBOARD_FAB2_LIB.BASEBOARD_FAB2(SCH_1):GND    I43 @BASEBOARD_FAB2_LIB.BASEBOARD_FAB2(SCH_1):PAGE83
    28    GND @BASEBOARD_FAB2_LIB.BASEBOARD_FAB2(SCH_1):GND    I43 @BASEBOARD_FAB2_LIB.BASEBOARD_FAB2(SCH_1):PAGE83
    31    GND @BASEBOARD_FAB2_LIB.BASEBOARD_FAB2(SCH_1):GND    I43 @BASEBOARD_FAB2_LIB.BASEBOARD_FAB2(SCH_1):PAGE83
    33    GND @BASEBOARD_FAB2_LIB.BASEBOARD_FAB2(SCH_1):GND    I43 @BASEBOARD_FAB2_LIB.BASEBOARD_FAB2(SCH_1):PAGE83
    35    GND @BASEBOARD_FAB2_LIB.BASEBOARD_FAB2(SCH_1):GND    I43 @BASEBOARD_FAB2_LIB.BASEBOARD_FAB2(SCH_1):PAGE83
    37    GND @BASEBOARD_FAB2_LIB.BASEBOARD_FAB2(SCH_1):GND    I43 @BASEBOARD_FAB2_LIB.BASEBOARD_FAB2(SCH_1):PAGE83
    39    GND @BASEBOARD_FAB2_LIB.BASEBOARD_FAB2(SCH_1):GND    I43 @BASEBOARD_FAB2_LIB.BASEBOARD_FAB2(SCH_1):PAGE83
    42    GND @BASEBOARD_FAB2_LIB.BASEBOARD_FAB2(SCH_1):GND    I43 @BASEBOARD_FAB2_LIB.BASEBOARD_FAB2(SCH_1):PAGE83
    44    GND @BASEBOARD_FAB2_LIB.BASEBOARD_FAB2(SCH_1):GND    I43 @BASEBOARD_FAB2_LIB.BASEBOARD_FAB2(SCH_1):PAGE83
    46    GND @BASEBOARD_FAB2_LIB.BASEBOARD_FAB2(SCH_1):GND    I43 @BASEBOARD_FAB2_LIB.BASEBOARD_FAB2(SCH_1):PAGE83
    48    GND @BASEBOARD_FAB2_LIB.BASEBOARD_FAB2(SCH_1):GND    I43 @BASEBOARD_FAB2_LIB.BASEBOARD_FAB2(SCH_1):PAGE83
    50    GND @BASEBOARD_FAB2_LIB.BASEBOARD_FAB2(SCH_1):GND    I43 @BASEBOARD_FAB2_LIB.BASEBOARD_FAB2(SCH_1):PAGE83
    53    GND @BASEBOARD_FAB2_LIB.BASEBOARD_FAB2(SCH_1):GND    I43 @BASEBOARD_FAB2_LIB.BASEBOARD_FAB2(SCH_1):PAGE83
    55    GND @BASEBOARD_FAB2_LIB.BASEBOARD_FAB2(SCH_1):GND    I43 @BASEBOARD_FAB2_LIB.BASEBOARD_FAB2(SCH_1):PAGE83
    57    GND @BASEBOARD_FAB2_LIB.BASEBOARD_FAB2(SCH_1):GND    I43 @BASEBOARD_FAB2_LIB.BASEBOARD_FAB2(SCH_1):PAGE83
    94    GND @BASEBOARD_FAB2_LIB.BASEBOARD_FAB2(SCH_1):GND    I43 @BASEBOARD_FAB2_LIB.BASEBOARD_FAB2(SCH_1):PAGE83
    96    GND @BASEBOARD_FAB2_LIB.BASEBOARD_FAB2(SCH_1):GND    I43 @BASEBOARD_FAB2_LIB.BASEBOARD_FAB2(SCH_1):PAGE83
    98    GND @BASEBOARD_FAB2_LIB.BASEBOARD_FAB2(SCH_1):GND    I43 @BASEBOARD_FAB2_LIB.BASEBOARD_FAB2(SCH_1):PAGE83
   101    GND @BASEBOARD_FAB2_LIB.BASEBOARD_FAB2(SCH_1):GND    I43 @BASEBOARD_FAB2_LIB.BASEBOARD_FAB2(SCH_1):PAGE83
   103    GND @BASEBOARD_FAB2_LIB.BASEBOARD_FAB2(SCH_1):GND    I43 @BASEBOARD_FAB2_LIB.BASEBOARD_FAB2(SCH_1):PAGE83
   105    GND @BASEBOARD_FAB2_LIB.BASEBOARD_FAB2(SCH_1):GND    I43 @BASEBOARD_FAB2_LIB.BASEBOARD_FAB2(SCH_1):PAGE83
   107    GND @BASEBOARD_FAB2_LIB.BASEBOARD_FAB2(SCH_1):GND    I43 @BASEBOARD_FAB2_LIB.BASEBOARD_FAB2(SCH_1):PAGE83
   109    GND @BASEBOARD_FAB2_LIB.BASEBOARD_FAB2(SCH_1):GND    I43 @BASEBOARD_FAB2_LIB.BASEBOARD_FAB2(SCH_1):PAGE83
   112    GND @BASEBOARD_FAB2_LIB.BASEBOARD_FAB2(SCH_1):GND    I43 @BASEBOARD_FAB2_LIB.BASEBOARD_FAB2(SCH_1):PAGE83
   114    GND @BASEBOARD_FAB2_LIB.BASEBOARD_FAB2(SCH_1):GND    I43 @BASEBOARD_FAB2_LIB.BASEBOARD_FAB2(SCH_1):PAGE83
   116    GND @BASEBOARD_FAB2_LIB.BASEBOARD_FAB2(SCH_1):GND    I43 @BASEBOARD_FAB2_LIB.BASEBOARD_FAB2(SCH_1):PAGE83
   118    GND @BASEBOARD_FAB2_LIB.BASEBOARD_FAB2(SCH_1):GND    I43 @BASEBOARD_FAB2_LIB.BASEBOARD_FAB2(SCH_1):PAGE83
   120    GND @BASEBOARD_FAB2_LIB.BASEBOARD_FAB2(SCH_1):GND    I43 @BASEBOARD_FAB2_LIB.BASEBOARD_FAB2(SCH_1):PAGE83
   123    GND @BASEBOARD_FAB2_LIB.BASEBOARD_FAB2(SCH_1):GND    I43 @BASEBOARD_FAB2_LIB.BASEBOARD_FAB2(SCH_1):PAGE83
   125    GND @BASEBOARD_FAB2_LIB.BASEBOARD_FAB2(SCH_1):GND    I43 @BASEBOARD_FAB2_LIB.BASEBOARD_FAB2(SCH_1):PAGE83
   127    GND @BASEBOARD_FAB2_LIB.BASEBOARD_FAB2(SCH_1):GND    I43 @BASEBOARD_FAB2_LIB.BASEBOARD_FAB2(SCH_1):PAGE83
   129    GND @BASEBOARD_FAB2_LIB.BASEBOARD_FAB2(SCH_1):GND    I43 @BASEBOARD_FAB2_LIB.BASEBOARD_FAB2(SCH_1):PAGE83
   131    GND @BASEBOARD_FAB2_LIB.BASEBOARD_FAB2(SCH_1):GND    I43 @BASEBOARD_FAB2_LIB.BASEBOARD_FAB2(SCH_1):PAGE83
   134    GND @BASEBOARD_FAB2_LIB.BASEBOARD_FAB2(SCH_1):GND    I43 @BASEBOARD_FAB2_LIB.BASEBOARD_FAB2(SCH_1):PAGE83
   136    GND @BASEBOARD_FAB2_LIB.BASEBOARD_FAB2(SCH_1):GND    I43 @BASEBOARD_FAB2_LIB.BASEBOARD_FAB2(SCH_1):PAGE83
   138    GND @BASEBOARD_FAB2_LIB.BASEBOARD_FAB2(SCH_1):GND    I43 @BASEBOARD_FAB2_LIB.BASEBOARD_FAB2(SCH_1):PAGE83
   147    GND @BASEBOARD_FAB2_LIB.BASEBOARD_FAB2(SCH_1):GND    I43 @BASEBOARD_FAB2_LIB.BASEBOARD_FAB2(SCH_1):PAGE83
   149    GND @BASEBOARD_FAB2_LIB.BASEBOARD_FAB2(SCH_1):GND    I43 @BASEBOARD_FAB2_LIB.BASEBOARD_FAB2(SCH_1):PAGE83
   151    GND @BASEBOARD_FAB2_LIB.BASEBOARD_FAB2(SCH_1):GND    I43 @BASEBOARD_FAB2_LIB.BASEBOARD_FAB2(SCH_1):PAGE83
   154    GND @BASEBOARD_FAB2_LIB.BASEBOARD_FAB2(SCH_1):GND    I43 @BASEBOARD_FAB2_LIB.BASEBOARD_FAB2(SCH_1):PAGE83
   156    GND @BASEBOARD_FAB2_LIB.BASEBOARD_FAB2(SCH_1):GND    I43 @BASEBOARD_FAB2_LIB.BASEBOARD_FAB2(SCH_1):PAGE83
   158    GND @BASEBOARD_FAB2_LIB.BASEBOARD_FAB2(SCH_1):GND    I43 @BASEBOARD_FAB2_LIB.BASEBOARD_FAB2(SCH_1):PAGE83
   160    GND @BASEBOARD_FAB2_LIB.BASEBOARD_FAB2(SCH_1):GND    I43 @BASEBOARD_FAB2_LIB.BASEBOARD_FAB2(SCH_1):PAGE83
   162    GND @BASEBOARD_FAB2_LIB.BASEBOARD_FAB2(SCH_1):GND    I43 @BASEBOARD_FAB2_LIB.BASEBOARD_FAB2(SCH_1):PAGE83
   165    GND @BASEBOARD_FAB2_LIB.BASEBOARD_FAB2(SCH_1):GND    I43 @BASEBOARD_FAB2_LIB.BASEBOARD_FAB2(SCH_1):PAGE83
   167    GND @BASEBOARD_FAB2_LIB.BASEBOARD_FAB2(SCH_1):GND    I43 @BASEBOARD_FAB2_LIB.BASEBOARD_FAB2(SCH_1):PAGE83
   169    GND @BASEBOARD_FAB2_LIB.BASEBOARD_FAB2(SCH_1):GND    I43 @BASEBOARD_FAB2_LIB.BASEBOARD_FAB2(SCH_1):PAGE83
   171    GND @BASEBOARD_FAB2_LIB.BASEBOARD_FAB2(SCH_1):GND    I43 @BASEBOARD_FAB2_LIB.BASEBOARD_FAB2(SCH_1):PAGE83
   173    GND @BASEBOARD_FAB2_LIB.BASEBOARD_FAB2(SCH_1):GND    I43 @BASEBOARD_FAB2_LIB.BASEBOARD_FAB2(SCH_1):PAGE83
   176    GND @BASEBOARD_FAB2_LIB.BASEBOARD_FAB2(SCH_1):GND    I43 @BASEBOARD_FAB2_LIB.BASEBOARD_FAB2(SCH_1):PAGE83
   178    GND @BASEBOARD_FAB2_LIB.BASEBOARD_FAB2(SCH_1):GND    I43 @BASEBOARD_FAB2_LIB.BASEBOARD_FAB2(SCH_1):PAGE83
   180    GND @BASEBOARD_FAB2_LIB.BASEBOARD_FAB2(SCH_1):GND    I43 @BASEBOARD_FAB2_LIB.BASEBOARD_FAB2(SCH_1):PAGE83
   182    GND @BASEBOARD_FAB2_LIB.BASEBOARD_FAB2(SCH_1):GND    I43 @BASEBOARD_FAB2_LIB.BASEBOARD_FAB2(SCH_1):PAGE83
   184    GND @BASEBOARD_FAB2_LIB.BASEBOARD_FAB2(SCH_1):GND    I43 @BASEBOARD_FAB2_LIB.BASEBOARD_FAB2(SCH_1):PAGE83
   187    GND @BASEBOARD_FAB2_LIB.BASEBOARD_FAB2(SCH_1):GND    I43 @BASEBOARD_FAB2_LIB.BASEBOARD_FAB2(SCH_1):PAGE83
   189    GND @BASEBOARD_FAB2_LIB.BASEBOARD_FAB2(SCH_1):GND    I43 @BASEBOARD_FAB2_LIB.BASEBOARD_FAB2(SCH_1):PAGE83
   191    GND @BASEBOARD_FAB2_LIB.BASEBOARD_FAB2(SCH_1):GND    I43 @BASEBOARD_FAB2_LIB.BASEBOARD_FAB2(SCH_1):PAGE83
   193    GND @BASEBOARD_FAB2_LIB.BASEBOARD_FAB2(SCH_1):GND    I43 @BASEBOARD_FAB2_LIB.BASEBOARD_FAB2(SCH_1):PAGE83
   195    GND @BASEBOARD_FAB2_LIB.BASEBOARD_FAB2(SCH_1):GND    I43 @BASEBOARD_FAB2_LIB.BASEBOARD_FAB2(SCH_1):PAGE83
   198    GND @BASEBOARD_FAB2_LIB.BASEBOARD_FAB2(SCH_1):GND    I43 @BASEBOARD_FAB2_LIB.BASEBOARD_FAB2(SCH_1):PAGE83
   200    GND @BASEBOARD_FAB2_LIB.BASEBOARD_FAB2(SCH_1):GND    I43 @BASEBOARD_FAB2_LIB.BASEBOARD_FAB2(SCH_1):PAGE83
   202    GND @BASEBOARD_FAB2_LIB.BASEBOARD_FAB2(SCH_1):GND    I43 @BASEBOARD_FAB2_LIB.BASEBOARD_FAB2(SCH_1):PAGE83
   239    GND @BASEBOARD_FAB2_LIB.BASEBOARD_FAB2(SCH_1):GND    I43 @BASEBOARD_FAB2_LIB.BASEBOARD_FAB2(SCH_1):PAGE83
   241    GND @BASEBOARD_FAB2_LIB.BASEBOARD_FAB2(SCH_1):GND    I43 @BASEBOARD_FAB2_LIB.BASEBOARD_FAB2(SCH_1):PAGE83
   243    GND @BASEBOARD_FAB2_LIB.BASEBOARD_FAB2(SCH_1):GND    I43 @BASEBOARD_FAB2_LIB.BASEBOARD_FAB2(SCH_1):PAGE83
   246    GND @BASEBOARD_FAB2_LIB.BASEBOARD_FAB2(SCH_1):GND    I43 @BASEBOARD_FAB2_LIB.BASEBOARD_FAB2(SCH_1):PAGE83
   248    GND @BASEBOARD_FAB2_LIB.BASEBOARD_FAB2(SCH_1):GND    I43 @BASEBOARD_FAB2_LIB.BASEBOARD_FAB2(SCH_1):PAGE83
   250    GND @BASEBOARD_FAB2_LIB.BASEBOARD_FAB2(SCH_1):GND    I43 @BASEBOARD_FAB2_LIB.BASEBOARD_FAB2(SCH_1):PAGE83
   252    GND @BASEBOARD_FAB2_LIB.BASEBOARD_FAB2(SCH_1):GND    I43 @BASEBOARD_FAB2_LIB.BASEBOARD_FAB2(SCH_1):PAGE83
   254    GND @BASEBOARD_FAB2_LIB.BASEBOARD_FAB2(SCH_1):GND    I43 @BASEBOARD_FAB2_LIB.BASEBOARD_FAB2(SCH_1):PAGE83
   257    GND @BASEBOARD_FAB2_LIB.BASEBOARD_FAB2(SCH_1):GND    I43 @BASEBOARD_FAB2_LIB.BASEBOARD_FAB2(SCH_1):PAGE83
   259    GND @BASEBOARD_FAB2_LIB.BASEBOARD_FAB2(SCH_1):GND    I43 @BASEBOARD_FAB2_LIB.BASEBOARD_FAB2(SCH_1):PAGE83
   261    GND @BASEBOARD_FAB2_LIB.BASEBOARD_FAB2(SCH_1):GND    I43 @BASEBOARD_FAB2_LIB.BASEBOARD_FAB2(SCH_1):PAGE83
   263    GND @BASEBOARD_FAB2_LIB.BASEBOARD_FAB2(SCH_1):GND    I43 @BASEBOARD_FAB2_LIB.BASEBOARD_FAB2(SCH_1):PAGE83
   265    GND @BASEBOARD_FAB2_LIB.BASEBOARD_FAB2(SCH_1):GND    I43 @BASEBOARD_FAB2_LIB.BASEBOARD_FAB2(SCH_1):PAGE83
   268    GND @BASEBOARD_FAB2_LIB.BASEBOARD_FAB2(SCH_1):GND    I43 @BASEBOARD_FAB2_LIB.BASEBOARD_FAB2(SCH_1):PAGE83
   270    GND @BASEBOARD_FAB2_LIB.BASEBOARD_FAB2(SCH_1):GND    I43 @BASEBOARD_FAB2_LIB.BASEBOARD_FAB2(SCH_1):PAGE83
   272    GND @BASEBOARD_FAB2_LIB.BASEBOARD_FAB2(SCH_1):GND    I43 @BASEBOARD_FAB2_LIB.BASEBOARD_FAB2(SCH_1):PAGE83
   274    GND @BASEBOARD_FAB2_LIB.BASEBOARD_FAB2(SCH_1):GND    I43 @BASEBOARD_FAB2_LIB.BASEBOARD_FAB2(SCH_1):PAGE83
   276    GND @BASEBOARD_FAB2_LIB.BASEBOARD_FAB2(SCH_1):GND    I43 @BASEBOARD_FAB2_LIB.BASEBOARD_FAB2(SCH_1):PAGE83
   279    GND @BASEBOARD_FAB2_LIB.BASEBOARD_FAB2(SCH_1):GND    I43 @BASEBOARD_FAB2_LIB.BASEBOARD_FAB2(SCH_1):PAGE83
   281    GND @BASEBOARD_FAB2_LIB.BASEBOARD_FAB2(SCH_1):GND    I43 @BASEBOARD_FAB2_LIB.BASEBOARD_FAB2(SCH_1):PAGE83
   283    GND @BASEBOARD_FAB2_LIB.BASEBOARD_FAB2(SCH_1):GND    I43 @BASEBOARD_FAB2_LIB.BASEBOARD_FAB2(SCH_1):PAGE83
     1 P12V_NVDIMM_KLM @BASEBOARD_FAB2_LIB.BASEBOARD_FAB2(SCH_1):P12V_NVDIMM_KLM   I167 @BASEBOARD_FAB2_LIB.BASEBOARD_FAB2(SCH_1):PAGE83
   145 P12V_NVDIMM_KLM @BASEBOARD_FAB2_LIB.BASEBOARD_FAB2(SCH_1):P12V_NVDIMM_KLM   I167 @BASEBOARD_FAB2_LIB.BASEBOARD_FAB2(SCH_1):PAGE83
    59 PVDDQ_KLM @BASEBOARD_FAB2_LIB.BASEBOARD_FAB2(SCH_1):PVDDQ_KLM   I167 @BASEBOARD_FAB2_LIB.BASEBOARD_FAB2(SCH_1):PAGE83
    61 PVDDQ_KLM @BASEBOARD_FAB2_LIB.BASEBOARD_FAB2(SCH_1):PVDDQ_KLM   I167 @BASEBOARD_FAB2_LIB.BASEBOARD_FAB2(SCH_1):PAGE83
    64 PVDDQ_KLM @BASEBOARD_FAB2_LIB.BASEBOARD_FAB2(SCH_1):PVDDQ_KLM   I167 @BASEBOARD_FAB2_LIB.BASEBOARD_FAB2(SCH_1):PAGE83
    67 PVDDQ_KLM @BASEBOARD_FAB2_LIB.BASEBOARD_FAB2(SCH_1):PVDDQ_KLM   I167 @BASEBOARD_FAB2_LIB.BASEBOARD_FAB2(SCH_1):PAGE83
    70 PVDDQ_KLM @BASEBOARD_FAB2_LIB.BASEBOARD_FAB2(SCH_1):PVDDQ_KLM   I167 @BASEBOARD_FAB2_LIB.BASEBOARD_FAB2(SCH_1):PAGE83
    73 PVDDQ_KLM @BASEBOARD_FAB2_LIB.BASEBOARD_FAB2(SCH_1):PVDDQ_KLM   I167 @BASEBOARD_FAB2_LIB.BASEBOARD_FAB2(SCH_1):PAGE83
    76 PVDDQ_KLM @BASEBOARD_FAB2_LIB.BASEBOARD_FAB2(SCH_1):PVDDQ_KLM   I167 @BASEBOARD_FAB2_LIB.BASEBOARD_FAB2(SCH_1):PAGE83
    80 PVDDQ_KLM @BASEBOARD_FAB2_LIB.BASEBOARD_FAB2(SCH_1):PVDDQ_KLM   I167 @BASEBOARD_FAB2_LIB.BASEBOARD_FAB2(SCH_1):PAGE83
    83 PVDDQ_KLM @BASEBOARD_FAB2_LIB.BASEBOARD_FAB2(SCH_1):PVDDQ_KLM   I167 @BASEBOARD_FAB2_LIB.BASEBOARD_FAB2(SCH_1):PAGE83
    85 PVDDQ_KLM @BASEBOARD_FAB2_LIB.BASEBOARD_FAB2(SCH_1):PVDDQ_KLM   I167 @BASEBOARD_FAB2_LIB.BASEBOARD_FAB2(SCH_1):PAGE83
    88 PVDDQ_KLM @BASEBOARD_FAB2_LIB.BASEBOARD_FAB2(SCH_1):PVDDQ_KLM   I167 @BASEBOARD_FAB2_LIB.BASEBOARD_FAB2(SCH_1):PAGE83
    90 PVDDQ_KLM @BASEBOARD_FAB2_LIB.BASEBOARD_FAB2(SCH_1):PVDDQ_KLM   I167 @BASEBOARD_FAB2_LIB.BASEBOARD_FAB2(SCH_1):PAGE83
    92 PVDDQ_KLM @BASEBOARD_FAB2_LIB.BASEBOARD_FAB2(SCH_1):PVDDQ_KLM   I167 @BASEBOARD_FAB2_LIB.BASEBOARD_FAB2(SCH_1):PAGE83
   204 PVDDQ_KLM @BASEBOARD_FAB2_LIB.BASEBOARD_FAB2(SCH_1):PVDDQ_KLM   I167 @BASEBOARD_FAB2_LIB.BASEBOARD_FAB2(SCH_1):PAGE83
   206 PVDDQ_KLM @BASEBOARD_FAB2_LIB.BASEBOARD_FAB2(SCH_1):PVDDQ_KLM   I167 @BASEBOARD_FAB2_LIB.BASEBOARD_FAB2(SCH_1):PAGE83
   209 PVDDQ_KLM @BASEBOARD_FAB2_LIB.BASEBOARD_FAB2(SCH_1):PVDDQ_KLM   I167 @BASEBOARD_FAB2_LIB.BASEBOARD_FAB2(SCH_1):PAGE83
   212 PVDDQ_KLM @BASEBOARD_FAB2_LIB.BASEBOARD_FAB2(SCH_1):PVDDQ_KLM   I167 @BASEBOARD_FAB2_LIB.BASEBOARD_FAB2(SCH_1):PAGE83
   215 PVDDQ_KLM @BASEBOARD_FAB2_LIB.BASEBOARD_FAB2(SCH_1):PVDDQ_KLM   I167 @BASEBOARD_FAB2_LIB.BASEBOARD_FAB2(SCH_1):PAGE83
   217 PVDDQ_KLM @BASEBOARD_FAB2_LIB.BASEBOARD_FAB2(SCH_1):PVDDQ_KLM   I167 @BASEBOARD_FAB2_LIB.BASEBOARD_FAB2(SCH_1):PAGE83
   220 PVDDQ_KLM @BASEBOARD_FAB2_LIB.BASEBOARD_FAB2(SCH_1):PVDDQ_KLM   I167 @BASEBOARD_FAB2_LIB.BASEBOARD_FAB2(SCH_1):PAGE83
   223 PVDDQ_KLM @BASEBOARD_FAB2_LIB.BASEBOARD_FAB2(SCH_1):PVDDQ_KLM   I167 @BASEBOARD_FAB2_LIB.BASEBOARD_FAB2(SCH_1):PAGE83
   226 PVDDQ_KLM @BASEBOARD_FAB2_LIB.BASEBOARD_FAB2(SCH_1):PVDDQ_KLM   I167 @BASEBOARD_FAB2_LIB.BASEBOARD_FAB2(SCH_1):PAGE83
   229 PVDDQ_KLM @BASEBOARD_FAB2_LIB.BASEBOARD_FAB2(SCH_1):PVDDQ_KLM   I167 @BASEBOARD_FAB2_LIB.BASEBOARD_FAB2(SCH_1):PAGE83
   231 PVDDQ_KLM @BASEBOARD_FAB2_LIB.BASEBOARD_FAB2(SCH_1):PVDDQ_KLM   I167 @BASEBOARD_FAB2_LIB.BASEBOARD_FAB2(SCH_1):PAGE83
   233 PVDDQ_KLM @BASEBOARD_FAB2_LIB.BASEBOARD_FAB2(SCH_1):PVDDQ_KLM   I167 @BASEBOARD_FAB2_LIB.BASEBOARD_FAB2(SCH_1):PAGE83
   236 PVDDQ_KLM @BASEBOARD_FAB2_LIB.BASEBOARD_FAB2(SCH_1):PVDDQ_KLM   I167 @BASEBOARD_FAB2_LIB.BASEBOARD_FAB2(SCH_1):PAGE83
   142 PVPP_KLM @BASEBOARD_FAB2_LIB.BASEBOARD_FAB2(SCH_1):PVPP_KLM   I167 @BASEBOARD_FAB2_LIB.BASEBOARD_FAB2(SCH_1):PAGE83
   143 PVPP_KLM @BASEBOARD_FAB2_LIB.BASEBOARD_FAB2(SCH_1):PVPP_KLM   I167 @BASEBOARD_FAB2_LIB.BASEBOARD_FAB2(SCH_1):PAGE83
   288 PVPP_KLM @BASEBOARD_FAB2_LIB.BASEBOARD_FAB2(SCH_1):PVPP_KLM   I167 @BASEBOARD_FAB2_LIB.BASEBOARD_FAB2(SCH_1):PAGE83
   286 PVPP_KLM @BASEBOARD_FAB2_LIB.BASEBOARD_FAB2(SCH_1):PVPP_KLM   I167 @BASEBOARD_FAB2_LIB.BASEBOARD_FAB2(SCH_1):PAGE83
   287 PVPP_KLM @BASEBOARD_FAB2_LIB.BASEBOARD_FAB2(SCH_1):PVPP_KLM   I167 @BASEBOARD_FAB2_LIB.BASEBOARD_FAB2(SCH_1):PAGE83
    77 PVTT_KLM @BASEBOARD_FAB2_LIB.BASEBOARD_FAB2(SCH_1):PVTT_KLM   I167 @BASEBOARD_FAB2_LIB.BASEBOARD_FAB2(SCH_1):PAGE83
   221 PVTT_KLM @BASEBOARD_FAB2_LIB.BASEBOARD_FAB2(SCH_1):PVTT_KLM   I167 @BASEBOARD_FAB2_LIB.BASEBOARD_FAB2(SCH_1):PAGE83

J1B2 CONN6_C74770005_PIP-HDR,C74770A
     1    GND @BASEBOARD_FAB2_LIB.BASEBOARD_FAB2(SCH_1):GND    I25 @BASEBOARD_FAB2_LIB.BASEBOARD_FAB2(SCH_1):PAGE251
     2 P12V_PUMP @BASEBOARD_FAB2_LIB.BASEBOARD_FAB2(SCH_1):P12V_PUMP    I25 @BASEBOARD_FAB2_LIB.BASEBOARD_FAB2(SCH_1):PAGE251
     3 PUMP_TACH_D @BASEBOARD_FAB2_LIB.BASEBOARD_FAB2(SCH_1):PUMP_TACH_D    I25 @BASEBOARD_FAB2_LIB.BASEBOARD_FAB2(SCH_1):PAGE251
     4 PUMP_PWM_OUT_R @BASEBOARD_FAB2_LIB.BASEBOARD_FAB2(SCH_1):PUMP_PWM_OUT_R    I25 @BASEBOARD_FAB2_LIB.BASEBOARD_FAB2(SCH_1):PAGE251
     5 PUMP_TACH1_D @BASEBOARD_FAB2_LIB.BASEBOARD_FAB2(SCH_1):PUMP_TACH1_D    I25 @BASEBOARD_FAB2_LIB.BASEBOARD_FAB2(SCH_1):PAGE251
     6 TP_PUMP @BASEBOARD_FAB2_LIB.BASEBOARD_FAB2(SCH_1):TP_PUMP    I25 @BASEBOARD_FAB2_LIB.BASEBOARD_FAB2(SCH_1):PAGE251

J1B4 CLX-CONN3A-1-GP_CONN-G3-CLX-COA
     1 A_HSC_HIGH_EN @BASEBOARD_FAB2_LIB.BASEBOARD_FAB2(SCH_1):A_HSC_HIGH_EN   I131 @BASEBOARD_FAB2_LIB.BASEBOARD_FAB2(SCH_1):PAGE199
     2 A_HSC_OCP_SEL @BASEBOARD_FAB2_LIB.BASEBOARD_FAB2(SCH_1):A_HSC_OCP_SEL   I131 @BASEBOARD_FAB2_LIB.BASEBOARD_FAB2(SCH_1):PAGE199
     3 A_HSC_LOW_EN @BASEBOARD_FAB2_LIB.BASEBOARD_FAB2(SCH_1):A_HSC_LOW_EN   I131 @BASEBOARD_FAB2_LIB.BASEBOARD_FAB2(SCH_1):PAGE199

J1C1 DM-FCI-CONN76-8R-GP-U-01_CONN-A
    A1 P3E_CPU1_PE3_MP_RXN<8> @BASEBOARD_FAB2_LIB.BASEBOARD_FAB2(SCH_1):P3E_CPU1_PE3_MP_RXN(8)    I79 @BASEBOARD_FAB2_LIB.BASEBOARD_FAB2(SCH_1):PAGE182
    A2    GND @BASEBOARD_FAB2_LIB.BASEBOARD_FAB2(SCH_1):GND    I79 @BASEBOARD_FAB2_LIB.BASEBOARD_FAB2(SCH_1):PAGE182
    A3 P3E_CPU1_PE3_MP_RXP<14> @BASEBOARD_FAB2_LIB.BASEBOARD_FAB2(SCH_1):P3E_CPU1_PE3_MP_RXP(14)    I79 @BASEBOARD_FAB2_LIB.BASEBOARD_FAB2(SCH_1):PAGE182
    A4    GND @BASEBOARD_FAB2_LIB.BASEBOARD_FAB2(SCH_1):GND    I79 @BASEBOARD_FAB2_LIB.BASEBOARD_FAB2(SCH_1):PAGE182
    A5 TP_IOA5 @BASEBOARD_FAB2_LIB.BASEBOARD_FAB2(SCH_1):TP_IOA5    I79 @BASEBOARD_FAB2_LIB.BASEBOARD_FAB2(SCH_1):PAGE182
    A6    GND @BASEBOARD_FAB2_LIB.BASEBOARD_FAB2(SCH_1):GND    I79 @BASEBOARD_FAB2_LIB.BASEBOARD_FAB2(SCH_1):PAGE182
    A7 P3E_CPU1_PE3_MP_C_TXN<11> @BASEBOARD_FAB2_LIB.BASEBOARD_FAB2(SCH_1):P3E_CPU1_PE3_MP_C_TXN(11)    I79 @BASEBOARD_FAB2_LIB.BASEBOARD_FAB2(SCH_1):PAGE182
    A8    GND @BASEBOARD_FAB2_LIB.BASEBOARD_FAB2(SCH_1):GND    I79 @BASEBOARD_FAB2_LIB.BASEBOARD_FAB2(SCH_1):PAGE182
    B1 P3E_CPU1_PE3_MP_RXP<8> @BASEBOARD_FAB2_LIB.BASEBOARD_FAB2(SCH_1):P3E_CPU1_PE3_MP_RXP(8)    I79 @BASEBOARD_FAB2_LIB.BASEBOARD_FAB2(SCH_1):PAGE182
    B2 P3E_CPU1_PE3_MP_RXN<11> @BASEBOARD_FAB2_LIB.BASEBOARD_FAB2(SCH_1):P3E_CPU1_PE3_MP_RXN(11)    I79 @BASEBOARD_FAB2_LIB.BASEBOARD_FAB2(SCH_1):PAGE182
    B3 P3E_CPU1_PE3_MP_RXN<14> @BASEBOARD_FAB2_LIB.BASEBOARD_FAB2(SCH_1):P3E_CPU1_PE3_MP_RXN(14)    I79 @BASEBOARD_FAB2_LIB.BASEBOARD_FAB2(SCH_1):PAGE182
    B4 TP_FM_WAKE_N @BASEBOARD_FAB2_LIB.BASEBOARD_FAB2(SCH_1):TP_FM_WAKE_N    I79 @BASEBOARD_FAB2_LIB.BASEBOARD_FAB2(SCH_1):PAGE182
    B5 IRQ_BOARD_BMC_ALERT_N @BASEBOARD_FAB2_LIB.BASEBOARD_FAB2(SCH_1):IRQ_BOARD_BMC_ALERT_N    I79 @BASEBOARD_FAB2_LIB.BASEBOARD_FAB2(SCH_1):PAGE182
    B6 SMB_PEHPCPU1_STBY_LVC3_SDA @BASEBOARD_FAB2_LIB.BASEBOARD_FAB2(SCH_1):SMB_PEHPCPU1_STBY_LVC3_SDA    I79 @BASEBOARD_FAB2_LIB.BASEBOARD_FAB2(SCH_1):PAGE182
    B7 P3E_CPU1_PE3_MP_C_TXP<11> @BASEBOARD_FAB2_LIB.BASEBOARD_FAB2(SCH_1):P3E_CPU1_PE3_MP_C_TXP(11)    I79 @BASEBOARD_FAB2_LIB.BASEBOARD_FAB2(SCH_1):PAGE182
    B8 P3E_CPU1_PE3_MP_C_TXN<8> @BASEBOARD_FAB2_LIB.BASEBOARD_FAB2(SCH_1):P3E_CPU1_PE3_MP_C_TXN(8)    I79 @BASEBOARD_FAB2_LIB.BASEBOARD_FAB2(SCH_1):PAGE182
    C1    GND @BASEBOARD_FAB2_LIB.BASEBOARD_FAB2(SCH_1):GND    I79 @BASEBOARD_FAB2_LIB.BASEBOARD_FAB2(SCH_1):PAGE182
    C2 P3E_CPU1_PE3_MP_RXP<11> @BASEBOARD_FAB2_LIB.BASEBOARD_FAB2(SCH_1):P3E_CPU1_PE3_MP_RXP(11)    I79 @BASEBOARD_FAB2_LIB.BASEBOARD_FAB2(SCH_1):PAGE182
    C3    GND @BASEBOARD_FAB2_LIB.BASEBOARD_FAB2(SCH_1):GND    I79 @BASEBOARD_FAB2_LIB.BASEBOARD_FAB2(SCH_1):PAGE182
    C4 FM_BB_BMC_MP_GPIO @BASEBOARD_FAB2_LIB.BASEBOARD_FAB2(SCH_1):FM_BB_BMC_MP_GPIO    I79 @BASEBOARD_FAB2_LIB.BASEBOARD_FAB2(SCH_1):PAGE182
    C5    GND @BASEBOARD_FAB2_LIB.BASEBOARD_FAB2(SCH_1):GND    I79 @BASEBOARD_FAB2_LIB.BASEBOARD_FAB2(SCH_1):PAGE182
    C6 SMB_PEHPCPU1_STBY_LVC3_SCL @BASEBOARD_FAB2_LIB.BASEBOARD_FAB2(SCH_1):SMB_PEHPCPU1_STBY_LVC3_SCL    I79 @BASEBOARD_FAB2_LIB.BASEBOARD_FAB2(SCH_1):PAGE182
    C7    GND @BASEBOARD_FAB2_LIB.BASEBOARD_FAB2(SCH_1):GND    I79 @BASEBOARD_FAB2_LIB.BASEBOARD_FAB2(SCH_1):PAGE182
    C8 P3E_CPU1_PE3_MP_C_TXP<8> @BASEBOARD_FAB2_LIB.BASEBOARD_FAB2(SCH_1):P3E_CPU1_PE3_MP_C_TXP(8)    I79 @BASEBOARD_FAB2_LIB.BASEBOARD_FAB2(SCH_1):PAGE182
    D1 P3E_CPU1_PE3_MP_RXN<9> @BASEBOARD_FAB2_LIB.BASEBOARD_FAB2(SCH_1):P3E_CPU1_PE3_MP_RXN(9)    I79 @BASEBOARD_FAB2_LIB.BASEBOARD_FAB2(SCH_1):PAGE182
    D2    GND @BASEBOARD_FAB2_LIB.BASEBOARD_FAB2(SCH_1):GND    I79 @BASEBOARD_FAB2_LIB.BASEBOARD_FAB2(SCH_1):PAGE182
    D3 P3E_CPU1_PE3_MP_RXN<15> @BASEBOARD_FAB2_LIB.BASEBOARD_FAB2(SCH_1):P3E_CPU1_PE3_MP_RXN(15)    I79 @BASEBOARD_FAB2_LIB.BASEBOARD_FAB2(SCH_1):PAGE182
    D4    GND @BASEBOARD_FAB2_LIB.BASEBOARD_FAB2(SCH_1):GND    I79 @BASEBOARD_FAB2_LIB.BASEBOARD_FAB2(SCH_1):PAGE182
    D5 SMB_LAN_STBY_LVC3_SDA @BASEBOARD_FAB2_LIB.BASEBOARD_FAB2(SCH_1):SMB_LAN_STBY_LVC3_SDA    I79 @BASEBOARD_FAB2_LIB.BASEBOARD_FAB2(SCH_1):PAGE182
    D6    GND @BASEBOARD_FAB2_LIB.BASEBOARD_FAB2(SCH_1):GND    I79 @BASEBOARD_FAB2_LIB.BASEBOARD_FAB2(SCH_1):PAGE182
    D7 P3E_CPU1_PE3_MP_C_TXN<12> @BASEBOARD_FAB2_LIB.BASEBOARD_FAB2(SCH_1):P3E_CPU1_PE3_MP_C_TXN(12)    I79 @BASEBOARD_FAB2_LIB.BASEBOARD_FAB2(SCH_1):PAGE182
    D8    GND @BASEBOARD_FAB2_LIB.BASEBOARD_FAB2(SCH_1):GND    I79 @BASEBOARD_FAB2_LIB.BASEBOARD_FAB2(SCH_1):PAGE182
    E1 P3E_CPU1_PE3_MP_RXP<9> @BASEBOARD_FAB2_LIB.BASEBOARD_FAB2(SCH_1):P3E_CPU1_PE3_MP_RXP(9)    I79 @BASEBOARD_FAB2_LIB.BASEBOARD_FAB2(SCH_1):PAGE182
    E2 P3E_CPU1_PE3_MP_RXN<12> @BASEBOARD_FAB2_LIB.BASEBOARD_FAB2(SCH_1):P3E_CPU1_PE3_MP_RXN(12)    I79 @BASEBOARD_FAB2_LIB.BASEBOARD_FAB2(SCH_1):PAGE182
    E3 P3E_CPU1_PE3_MP_RXP<15> @BASEBOARD_FAB2_LIB.BASEBOARD_FAB2(SCH_1):P3E_CPU1_PE3_MP_RXP(15)    I79 @BASEBOARD_FAB2_LIB.BASEBOARD_FAB2(SCH_1):PAGE182
    E4 TP_IOE4 @BASEBOARD_FAB2_LIB.BASEBOARD_FAB2(SCH_1):TP_IOE4    I79 @BASEBOARD_FAB2_LIB.BASEBOARD_FAB2(SCH_1):PAGE182
    E5 SMB_LAN_STBY_LVC3_SCL @BASEBOARD_FAB2_LIB.BASEBOARD_FAB2(SCH_1):SMB_LAN_STBY_LVC3_SCL    I79 @BASEBOARD_FAB2_LIB.BASEBOARD_FAB2(SCH_1):PAGE182
    E6 P3E_CPU1_PE3_MP_C_TXN<14> @BASEBOARD_FAB2_LIB.BASEBOARD_FAB2(SCH_1):P3E_CPU1_PE3_MP_C_TXN(14)    I79 @BASEBOARD_FAB2_LIB.BASEBOARD_FAB2(SCH_1):PAGE182
    E7 P3E_CPU1_PE3_MP_C_TXP<12> @BASEBOARD_FAB2_LIB.BASEBOARD_FAB2(SCH_1):P3E_CPU1_PE3_MP_C_TXP(12)    I79 @BASEBOARD_FAB2_LIB.BASEBOARD_FAB2(SCH_1):PAGE182
    E8 P3E_CPU1_PE3_MP_C_TXN<9> @BASEBOARD_FAB2_LIB.BASEBOARD_FAB2(SCH_1):P3E_CPU1_PE3_MP_C_TXN(9)    I79 @BASEBOARD_FAB2_LIB.BASEBOARD_FAB2(SCH_1):PAGE182
    F1    GND @BASEBOARD_FAB2_LIB.BASEBOARD_FAB2(SCH_1):GND    I79 @BASEBOARD_FAB2_LIB.BASEBOARD_FAB2(SCH_1):PAGE182
    F2 P3E_CPU1_PE3_MP_RXP<12> @BASEBOARD_FAB2_LIB.BASEBOARD_FAB2(SCH_1):P3E_CPU1_PE3_MP_RXP(12)    I79 @BASEBOARD_FAB2_LIB.BASEBOARD_FAB2(SCH_1):PAGE182
    F3    GND @BASEBOARD_FAB2_LIB.BASEBOARD_FAB2(SCH_1):GND    I79 @BASEBOARD_FAB2_LIB.BASEBOARD_FAB2(SCH_1):PAGE182
    F4 TP_IOF4 @BASEBOARD_FAB2_LIB.BASEBOARD_FAB2(SCH_1):TP_IOF4    I79 @BASEBOARD_FAB2_LIB.BASEBOARD_FAB2(SCH_1):PAGE182
    F5    GND @BASEBOARD_FAB2_LIB.BASEBOARD_FAB2(SCH_1):GND    I79 @BASEBOARD_FAB2_LIB.BASEBOARD_FAB2(SCH_1):PAGE182
    F6 P3E_CPU1_PE3_MP_C_TXP<14> @BASEBOARD_FAB2_LIB.BASEBOARD_FAB2(SCH_1):P3E_CPU1_PE3_MP_C_TXP(14)    I79 @BASEBOARD_FAB2_LIB.BASEBOARD_FAB2(SCH_1):PAGE182
    F7    GND @BASEBOARD_FAB2_LIB.BASEBOARD_FAB2(SCH_1):GND    I79 @BASEBOARD_FAB2_LIB.BASEBOARD_FAB2(SCH_1):PAGE182
    F8 P3E_CPU1_PE3_MP_C_TXP<9> @BASEBOARD_FAB2_LIB.BASEBOARD_FAB2(SCH_1):P3E_CPU1_PE3_MP_C_TXP(9)    I79 @BASEBOARD_FAB2_LIB.BASEBOARD_FAB2(SCH_1):PAGE182
    G1 P3E_CPU1_PE3_MP_RXP<10> @BASEBOARD_FAB2_LIB.BASEBOARD_FAB2(SCH_1):P3E_CPU1_PE3_MP_RXP(10)    I79 @BASEBOARD_FAB2_LIB.BASEBOARD_FAB2(SCH_1):PAGE182
    G2    GND @BASEBOARD_FAB2_LIB.BASEBOARD_FAB2(SCH_1):GND    I79 @BASEBOARD_FAB2_LIB.BASEBOARD_FAB2(SCH_1):PAGE182
    G3 TP_IOG3 @BASEBOARD_FAB2_LIB.BASEBOARD_FAB2(SCH_1):TP_IOG3    I79 @BASEBOARD_FAB2_LIB.BASEBOARD_FAB2(SCH_1):PAGE182
    G4    GND @BASEBOARD_FAB2_LIB.BASEBOARD_FAB2(SCH_1):GND    I79 @BASEBOARD_FAB2_LIB.BASEBOARD_FAB2(SCH_1):PAGE182
    G5 FM_XRC_PRESENT_N @BASEBOARD_FAB2_LIB.BASEBOARD_FAB2(SCH_1):FM_XRC_PRESENT_N    I79 @BASEBOARD_FAB2_LIB.BASEBOARD_FAB2(SCH_1):PAGE182
    G6    GND @BASEBOARD_FAB2_LIB.BASEBOARD_FAB2(SCH_1):GND    I79 @BASEBOARD_FAB2_LIB.BASEBOARD_FAB2(SCH_1):PAGE182
    G7 P3E_CPU1_PE3_MP_C_TXN<13> @BASEBOARD_FAB2_LIB.BASEBOARD_FAB2(SCH_1):P3E_CPU1_PE3_MP_C_TXN(13)    I79 @BASEBOARD_FAB2_LIB.BASEBOARD_FAB2(SCH_1):PAGE182
    G8    GND @BASEBOARD_FAB2_LIB.BASEBOARD_FAB2(SCH_1):GND    I79 @BASEBOARD_FAB2_LIB.BASEBOARD_FAB2(SCH_1):PAGE182
    H1 P3E_CPU1_PE3_MP_RXN<10> @BASEBOARD_FAB2_LIB.BASEBOARD_FAB2(SCH_1):P3E_CPU1_PE3_MP_RXN(10)    I79 @BASEBOARD_FAB2_LIB.BASEBOARD_FAB2(SCH_1):PAGE182
    H2 P3E_CPU1_PE3_MP_RXP<13> @BASEBOARD_FAB2_LIB.BASEBOARD_FAB2(SCH_1):P3E_CPU1_PE3_MP_RXP(13)    I79 @BASEBOARD_FAB2_LIB.BASEBOARD_FAB2(SCH_1):PAGE182
    H3 TP_IOH3 @BASEBOARD_FAB2_LIB.BASEBOARD_FAB2(SCH_1):TP_IOH3    I79 @BASEBOARD_FAB2_LIB.BASEBOARD_FAB2(SCH_1):PAGE182
    H4 TP_IOH4 @BASEBOARD_FAB2_LIB.BASEBOARD_FAB2(SCH_1):TP_IOH4    I79 @BASEBOARD_FAB2_LIB.BASEBOARD_FAB2(SCH_1):PAGE182
    H5 FM_XRC_READY_N @BASEBOARD_FAB2_LIB.BASEBOARD_FAB2(SCH_1):FM_XRC_READY_N    I79 @BASEBOARD_FAB2_LIB.BASEBOARD_FAB2(SCH_1):PAGE182
    H6 P3E_CPU1_PE3_MP_C_TXN<15> @BASEBOARD_FAB2_LIB.BASEBOARD_FAB2(SCH_1):P3E_CPU1_PE3_MP_C_TXN(15)    I79 @BASEBOARD_FAB2_LIB.BASEBOARD_FAB2(SCH_1):PAGE182
    H7 P3E_CPU1_PE3_MP_C_TXP<13> @BASEBOARD_FAB2_LIB.BASEBOARD_FAB2(SCH_1):P3E_CPU1_PE3_MP_C_TXP(13)    I79 @BASEBOARD_FAB2_LIB.BASEBOARD_FAB2(SCH_1):PAGE182
    H8 P3E_CPU1_PE3_MP_C_TXP<10> @BASEBOARD_FAB2_LIB.BASEBOARD_FAB2(SCH_1):P3E_CPU1_PE3_MP_C_TXP(10)    I79 @BASEBOARD_FAB2_LIB.BASEBOARD_FAB2(SCH_1):PAGE182
    I1    GND @BASEBOARD_FAB2_LIB.BASEBOARD_FAB2(SCH_1):GND    I79 @BASEBOARD_FAB2_LIB.BASEBOARD_FAB2(SCH_1):PAGE182
    I2 P3E_CPU1_PE3_MP_RXN<13> @BASEBOARD_FAB2_LIB.BASEBOARD_FAB2(SCH_1):P3E_CPU1_PE3_MP_RXN(13)    I79 @BASEBOARD_FAB2_LIB.BASEBOARD_FAB2(SCH_1):PAGE182
    I3    GND @BASEBOARD_FAB2_LIB.BASEBOARD_FAB2(SCH_1):GND    I79 @BASEBOARD_FAB2_LIB.BASEBOARD_FAB2(SCH_1):PAGE182
    I4 TP_IOI4 @BASEBOARD_FAB2_LIB.BASEBOARD_FAB2(SCH_1):TP_IOI4    I79 @BASEBOARD_FAB2_LIB.BASEBOARD_FAB2(SCH_1):PAGE182
    I5    GND @BASEBOARD_FAB2_LIB.BASEBOARD_FAB2(SCH_1):GND    I79 @BASEBOARD_FAB2_LIB.BASEBOARD_FAB2(SCH_1):PAGE182
    I6 P3E_CPU1_PE3_MP_C_TXP<15> @BASEBOARD_FAB2_LIB.BASEBOARD_FAB2(SCH_1):P3E_CPU1_PE3_MP_C_TXP(15)    I79 @BASEBOARD_FAB2_LIB.BASEBOARD_FAB2(SCH_1):PAGE182
    I7    GND @BASEBOARD_FAB2_LIB.BASEBOARD_FAB2(SCH_1):GND    I79 @BASEBOARD_FAB2_LIB.BASEBOARD_FAB2(SCH_1):PAGE182
    I8 P3E_CPU1_PE3_MP_C_TXN<10> @BASEBOARD_FAB2_LIB.BASEBOARD_FAB2(SCH_1):P3E_CPU1_PE3_MP_C_TXN(10)    I79 @BASEBOARD_FAB2_LIB.BASEBOARD_FAB2(SCH_1):PAGE182
    J2    GND @BASEBOARD_FAB2_LIB.BASEBOARD_FAB2(SCH_1):GND    I79 @BASEBOARD_FAB2_LIB.BASEBOARD_FAB2(SCH_1):PAGE182
    J4    GND @BASEBOARD_FAB2_LIB.BASEBOARD_FAB2(SCH_1):GND    I79 @BASEBOARD_FAB2_LIB.BASEBOARD_FAB2(SCH_1):PAGE182
    J6    GND @BASEBOARD_FAB2_LIB.BASEBOARD_FAB2(SCH_1):GND    I79 @BASEBOARD_FAB2_LIB.BASEBOARD_FAB2(SCH_1):PAGE182
    J8    GND @BASEBOARD_FAB2_LIB.BASEBOARD_FAB2(SCH_1):GND    I79 @BASEBOARD_FAB2_LIB.BASEBOARD_FAB2(SCH_1):PAGE182

J1D1 FCI-CONN12-2R-GP_CONN-G5-FCI-CA
   2_1 P12V_PSU @BASEBOARD_FAB2_LIB.BASEBOARD_FAB2(SCH_1):P12V_PSU   I115 @BASEBOARD_FAB2_LIB.BASEBOARD_FAB2(SCH_1):PAGE195
   2_2 P12V_PSU @BASEBOARD_FAB2_LIB.BASEBOARD_FAB2(SCH_1):P12V_PSU   I115 @BASEBOARD_FAB2_LIB.BASEBOARD_FAB2(SCH_1):PAGE195
   2_3 P12V_PSU @BASEBOARD_FAB2_LIB.BASEBOARD_FAB2(SCH_1):P12V_PSU   I115 @BASEBOARD_FAB2_LIB.BASEBOARD_FAB2(SCH_1):PAGE195
   3_1    GND @BASEBOARD_FAB2_LIB.BASEBOARD_FAB2(SCH_1):GND   I115 @BASEBOARD_FAB2_LIB.BASEBOARD_FAB2(SCH_1):PAGE195
   3_2    GND @BASEBOARD_FAB2_LIB.BASEBOARD_FAB2(SCH_1):GND   I115 @BASEBOARD_FAB2_LIB.BASEBOARD_FAB2(SCH_1):PAGE195
   3_3    GND @BASEBOARD_FAB2_LIB.BASEBOARD_FAB2(SCH_1):GND   I115 @BASEBOARD_FAB2_LIB.BASEBOARD_FAB2(SCH_1):PAGE195
   NP1     NC     NC   I115 @BASEBOARD_FAB2_LIB.BASEBOARD_FAB2(SCH_1):PAGE195
   1_1 P12V_PSU @BASEBOARD_FAB2_LIB.BASEBOARD_FAB2(SCH_1):P12V_PSU   I115 @BASEBOARD_FAB2_LIB.BASEBOARD_FAB2(SCH_1):PAGE195
   1_2 P12V_PSU @BASEBOARD_FAB2_LIB.BASEBOARD_FAB2(SCH_1):P12V_PSU   I115 @BASEBOARD_FAB2_LIB.BASEBOARD_FAB2(SCH_1):PAGE195
   1_3 P12V_PSU @BASEBOARD_FAB2_LIB.BASEBOARD_FAB2(SCH_1):P12V_PSU   I115 @BASEBOARD_FAB2_LIB.BASEBOARD_FAB2(SCH_1):PAGE195
   4_1    GND @BASEBOARD_FAB2_LIB.BASEBOARD_FAB2(SCH_1):GND   I115 @BASEBOARD_FAB2_LIB.BASEBOARD_FAB2(SCH_1):PAGE195
   4_2    GND @BASEBOARD_FAB2_LIB.BASEBOARD_FAB2(SCH_1):GND   I115 @BASEBOARD_FAB2_LIB.BASEBOARD_FAB2(SCH_1):PAGE195
   4_3    GND @BASEBOARD_FAB2_LIB.BASEBOARD_FAB2(SCH_1):GND   I115 @BASEBOARD_FAB2_LIB.BASEBOARD_FAB2(SCH_1):PAGE195

J1E1 FCI-CONN12-2R-GP_CONN-G5-FCI-CA
   2_1 P12V_PSU @BASEBOARD_FAB2_LIB.BASEBOARD_FAB2(SCH_1):P12V_PSU   I114 @BASEBOARD_FAB2_LIB.BASEBOARD_FAB2(SCH_1):PAGE195
   2_2 P12V_PSU @BASEBOARD_FAB2_LIB.BASEBOARD_FAB2(SCH_1):P12V_PSU   I114 @BASEBOARD_FAB2_LIB.BASEBOARD_FAB2(SCH_1):PAGE195
   2_3 P12V_PSU @BASEBOARD_FAB2_LIB.BASEBOARD_FAB2(SCH_1):P12V_PSU   I114 @BASEBOARD_FAB2_LIB.BASEBOARD_FAB2(SCH_1):PAGE195
   3_1    GND @BASEBOARD_FAB2_LIB.BASEBOARD_FAB2(SCH_1):GND   I114 @BASEBOARD_FAB2_LIB.BASEBOARD_FAB2(SCH_1):PAGE195
   3_2    GND @BASEBOARD_FAB2_LIB.BASEBOARD_FAB2(SCH_1):GND   I114 @BASEBOARD_FAB2_LIB.BASEBOARD_FAB2(SCH_1):PAGE195
   3_3    GND @BASEBOARD_FAB2_LIB.BASEBOARD_FAB2(SCH_1):GND   I114 @BASEBOARD_FAB2_LIB.BASEBOARD_FAB2(SCH_1):PAGE195
   NP1     NC     NC   I114 @BASEBOARD_FAB2_LIB.BASEBOARD_FAB2(SCH_1):PAGE195
   1_1 P12V_PSU @BASEBOARD_FAB2_LIB.BASEBOARD_FAB2(SCH_1):P12V_PSU   I114 @BASEBOARD_FAB2_LIB.BASEBOARD_FAB2(SCH_1):PAGE195
   1_2 P12V_PSU @BASEBOARD_FAB2_LIB.BASEBOARD_FAB2(SCH_1):P12V_PSU   I114 @BASEBOARD_FAB2_LIB.BASEBOARD_FAB2(SCH_1):PAGE195
   1_3 P12V_PSU @BASEBOARD_FAB2_LIB.BASEBOARD_FAB2(SCH_1):P12V_PSU   I114 @BASEBOARD_FAB2_LIB.BASEBOARD_FAB2(SCH_1):PAGE195
   4_1    GND @BASEBOARD_FAB2_LIB.BASEBOARD_FAB2(SCH_1):GND   I114 @BASEBOARD_FAB2_LIB.BASEBOARD_FAB2(SCH_1):PAGE195
   4_2    GND @BASEBOARD_FAB2_LIB.BASEBOARD_FAB2(SCH_1):GND   I114 @BASEBOARD_FAB2_LIB.BASEBOARD_FAB2(SCH_1):PAGE195
   4_3    GND @BASEBOARD_FAB2_LIB.BASEBOARD_FAB2(SCH_1):GND   I114 @BASEBOARD_FAB2_LIB.BASEBOARD_FAB2(SCH_1):PAGE195

J1F1 DM-FCI-CONN76-8R-GP-U-01_CONN-A
    A1 P3E_CPU1_PE3_MP_RXN<0> @BASEBOARD_FAB2_LIB.BASEBOARD_FAB2(SCH_1):P3E_CPU1_PE3_MP_RXN(0)   I134 @BASEBOARD_FAB2_LIB.BASEBOARD_FAB2(SCH_1):PAGE181
    A2    GND @BASEBOARD_FAB2_LIB.BASEBOARD_FAB2(SCH_1):GND   I134 @BASEBOARD_FAB2_LIB.BASEBOARD_FAB2(SCH_1):PAGE181
    A3 P3E_CPU1_PE3_MP_RXP<6> @BASEBOARD_FAB2_LIB.BASEBOARD_FAB2(SCH_1):P3E_CPU1_PE3_MP_RXP(6)   I134 @BASEBOARD_FAB2_LIB.BASEBOARD_FAB2(SCH_1):PAGE181
    A4 FAN_TACH3_R @BASEBOARD_FAB2_LIB.BASEBOARD_FAB2(SCH_1):FAN_TACH3_R   I134 @BASEBOARD_FAB2_LIB.BASEBOARD_FAB2(SCH_1):PAGE181
    A5 NIC_MDI_MNG_TX_DP @BASEBOARD_FAB2_LIB.BASEBOARD_FAB2(SCH_1):NIC_MDI_MNG_TX_DP   I134 @BASEBOARD_FAB2_LIB.BASEBOARD_FAB2(SCH_1):PAGE181
    A6 IRQ_SML1_PMBUS_ALERT_R_N @BASEBOARD_FAB2_LIB.BASEBOARD_FAB2(SCH_1):IRQ_SML1_PMBUS_ALERT_R_N   I134 @BASEBOARD_FAB2_LIB.BASEBOARD_FAB2(SCH_1):PAGE181
    A7 P3E_CPU1_PE3_MP_C_TXN<3> @BASEBOARD_FAB2_LIB.BASEBOARD_FAB2(SCH_1):P3E_CPU1_PE3_MP_C_TXN(3)   I134 @BASEBOARD_FAB2_LIB.BASEBOARD_FAB2(SCH_1):PAGE181
    A8    GND @BASEBOARD_FAB2_LIB.BASEBOARD_FAB2(SCH_1):GND   I134 @BASEBOARD_FAB2_LIB.BASEBOARD_FAB2(SCH_1):PAGE181
    B1 P3E_CPU1_PE3_MP_RXP<0> @BASEBOARD_FAB2_LIB.BASEBOARD_FAB2(SCH_1):P3E_CPU1_PE3_MP_RXP(0)   I134 @BASEBOARD_FAB2_LIB.BASEBOARD_FAB2(SCH_1):PAGE181
    B2 P3E_CPU1_PE3_MP_RXN<3> @BASEBOARD_FAB2_LIB.BASEBOARD_FAB2(SCH_1):P3E_CPU1_PE3_MP_RXN(3)   I134 @BASEBOARD_FAB2_LIB.BASEBOARD_FAB2(SCH_1):PAGE181
    B3 P3E_CPU1_PE3_MP_RXN<6> @BASEBOARD_FAB2_LIB.BASEBOARD_FAB2(SCH_1):P3E_CPU1_PE3_MP_RXN(6)   I134 @BASEBOARD_FAB2_LIB.BASEBOARD_FAB2(SCH_1):PAGE181
    B4 FAN_TACH2_R @BASEBOARD_FAB2_LIB.BASEBOARD_FAB2(SCH_1):FAN_TACH2_R   I134 @BASEBOARD_FAB2_LIB.BASEBOARD_FAB2(SCH_1):PAGE181
    B5 NIC_MDI_MNG_TX_DN @BASEBOARD_FAB2_LIB.BASEBOARD_FAB2(SCH_1):NIC_MDI_MNG_TX_DN   I134 @BASEBOARD_FAB2_LIB.BASEBOARD_FAB2(SCH_1):PAGE181
    B6 SMB_BMC_PMBUS_STBY_LVC3_SDA @BASEBOARD_FAB2_LIB.BASEBOARD_FAB2(SCH_1):SMB_BMC_PMBUS_STBY_LVC3_SDA   I134 @BASEBOARD_FAB2_LIB.BASEBOARD_FAB2(SCH_1):PAGE181
    B7 P3E_CPU1_PE3_MP_C_TXP<3> @BASEBOARD_FAB2_LIB.BASEBOARD_FAB2(SCH_1):P3E_CPU1_PE3_MP_C_TXP(3)   I134 @BASEBOARD_FAB2_LIB.BASEBOARD_FAB2(SCH_1):PAGE181
    B8 P3E_CPU1_PE3_MP_C_TXN<0> @BASEBOARD_FAB2_LIB.BASEBOARD_FAB2(SCH_1):P3E_CPU1_PE3_MP_C_TXN(0)   I134 @BASEBOARD_FAB2_LIB.BASEBOARD_FAB2(SCH_1):PAGE181
    C1    GND @BASEBOARD_FAB2_LIB.BASEBOARD_FAB2(SCH_1):GND   I134 @BASEBOARD_FAB2_LIB.BASEBOARD_FAB2(SCH_1):PAGE181
    C2 P3E_CPU1_PE3_MP_RXP<3> @BASEBOARD_FAB2_LIB.BASEBOARD_FAB2(SCH_1):P3E_CPU1_PE3_MP_RXP(3)   I134 @BASEBOARD_FAB2_LIB.BASEBOARD_FAB2(SCH_1):PAGE181
    C3    GND @BASEBOARD_FAB2_LIB.BASEBOARD_FAB2(SCH_1):GND   I134 @BASEBOARD_FAB2_LIB.BASEBOARD_FAB2(SCH_1):PAGE181
    C4 FAN_TACH1_R @BASEBOARD_FAB2_LIB.BASEBOARD_FAB2(SCH_1):FAN_TACH1_R   I134 @BASEBOARD_FAB2_LIB.BASEBOARD_FAB2(SCH_1):PAGE181
    C5    GND @BASEBOARD_FAB2_LIB.BASEBOARD_FAB2(SCH_1):GND   I134 @BASEBOARD_FAB2_LIB.BASEBOARD_FAB2(SCH_1):PAGE181
    C6 SMB_BMC_PMBUS_STBY_LVC3_SCL @BASEBOARD_FAB2_LIB.BASEBOARD_FAB2(SCH_1):SMB_BMC_PMBUS_STBY_LVC3_SCL   I134 @BASEBOARD_FAB2_LIB.BASEBOARD_FAB2(SCH_1):PAGE181
    C7    GND @BASEBOARD_FAB2_LIB.BASEBOARD_FAB2(SCH_1):GND   I134 @BASEBOARD_FAB2_LIB.BASEBOARD_FAB2(SCH_1):PAGE181
    C8 P3E_CPU1_PE3_MP_C_TXP<0> @BASEBOARD_FAB2_LIB.BASEBOARD_FAB2(SCH_1):P3E_CPU1_PE3_MP_C_TXP(0)   I134 @BASEBOARD_FAB2_LIB.BASEBOARD_FAB2(SCH_1):PAGE181
    D1 P3E_CPU1_PE3_MP_RXN<1> @BASEBOARD_FAB2_LIB.BASEBOARD_FAB2(SCH_1):P3E_CPU1_PE3_MP_RXN(1)   I134 @BASEBOARD_FAB2_LIB.BASEBOARD_FAB2(SCH_1):PAGE181
    D2    GND @BASEBOARD_FAB2_LIB.BASEBOARD_FAB2(SCH_1):GND   I134 @BASEBOARD_FAB2_LIB.BASEBOARD_FAB2(SCH_1):PAGE181
    D3 P3E_CPU1_PE3_MP_RXN<7> @BASEBOARD_FAB2_LIB.BASEBOARD_FAB2(SCH_1):P3E_CPU1_PE3_MP_RXN(7)   I134 @BASEBOARD_FAB2_LIB.BASEBOARD_FAB2(SCH_1):PAGE181
    D4 FAN_TACH0_R @BASEBOARD_FAB2_LIB.BASEBOARD_FAB2(SCH_1):FAN_TACH0_R   I134 @BASEBOARD_FAB2_LIB.BASEBOARD_FAB2(SCH_1):PAGE181
    D5 NIC_MDI_MNG_RX_DP @BASEBOARD_FAB2_LIB.BASEBOARD_FAB2(SCH_1):NIC_MDI_MNG_RX_DP   I134 @BASEBOARD_FAB2_LIB.BASEBOARD_FAB2(SCH_1):PAGE181
    D6    GND @BASEBOARD_FAB2_LIB.BASEBOARD_FAB2(SCH_1):GND   I134 @BASEBOARD_FAB2_LIB.BASEBOARD_FAB2(SCH_1):PAGE181
    D7 P3E_CPU1_PE3_MP_C_TXN<4> @BASEBOARD_FAB2_LIB.BASEBOARD_FAB2(SCH_1):P3E_CPU1_PE3_MP_C_TXN(4)   I134 @BASEBOARD_FAB2_LIB.BASEBOARD_FAB2(SCH_1):PAGE181
    D8    GND @BASEBOARD_FAB2_LIB.BASEBOARD_FAB2(SCH_1):GND   I134 @BASEBOARD_FAB2_LIB.BASEBOARD_FAB2(SCH_1):PAGE181
    E1 P3E_CPU1_PE3_MP_RXP<1> @BASEBOARD_FAB2_LIB.BASEBOARD_FAB2(SCH_1):P3E_CPU1_PE3_MP_RXP(1)   I134 @BASEBOARD_FAB2_LIB.BASEBOARD_FAB2(SCH_1):PAGE181
    E2 P3E_CPU1_PE3_MP_RXN<4> @BASEBOARD_FAB2_LIB.BASEBOARD_FAB2(SCH_1):P3E_CPU1_PE3_MP_RXN(4)   I134 @BASEBOARD_FAB2_LIB.BASEBOARD_FAB2(SCH_1):PAGE181
    E3 P3E_CPU1_PE3_MP_RXP<7> @BASEBOARD_FAB2_LIB.BASEBOARD_FAB2(SCH_1):P3E_CPU1_PE3_MP_RXP(7)   I134 @BASEBOARD_FAB2_LIB.BASEBOARD_FAB2(SCH_1):PAGE181
    E4 FM_MATED_IN_N @BASEBOARD_FAB2_LIB.BASEBOARD_FAB2(SCH_1):FM_MATED_IN_N   I134 @BASEBOARD_FAB2_LIB.BASEBOARD_FAB2(SCH_1):PAGE181
    E5 NIC_MDI_MNG_RX_DN @BASEBOARD_FAB2_LIB.BASEBOARD_FAB2(SCH_1):NIC_MDI_MNG_RX_DN   I134 @BASEBOARD_FAB2_LIB.BASEBOARD_FAB2(SCH_1):PAGE181
    E6 P3E_CPU1_PE3_MP_C_TXN<6> @BASEBOARD_FAB2_LIB.BASEBOARD_FAB2(SCH_1):P3E_CPU1_PE3_MP_C_TXN(6)   I134 @BASEBOARD_FAB2_LIB.BASEBOARD_FAB2(SCH_1):PAGE181
    E7 P3E_CPU1_PE3_MP_C_TXP<4> @BASEBOARD_FAB2_LIB.BASEBOARD_FAB2(SCH_1):P3E_CPU1_PE3_MP_C_TXP(4)   I134 @BASEBOARD_FAB2_LIB.BASEBOARD_FAB2(SCH_1):PAGE181
    E8 P3E_CPU1_PE3_MP_C_TXN<1> @BASEBOARD_FAB2_LIB.BASEBOARD_FAB2(SCH_1):P3E_CPU1_PE3_MP_C_TXN(1)   I134 @BASEBOARD_FAB2_LIB.BASEBOARD_FAB2(SCH_1):PAGE181
    F1    GND @BASEBOARD_FAB2_LIB.BASEBOARD_FAB2(SCH_1):GND   I134 @BASEBOARD_FAB2_LIB.BASEBOARD_FAB2(SCH_1):PAGE181
    F2 P3E_CPU1_PE3_MP_RXP<4> @BASEBOARD_FAB2_LIB.BASEBOARD_FAB2(SCH_1):P3E_CPU1_PE3_MP_RXP(4)   I134 @BASEBOARD_FAB2_LIB.BASEBOARD_FAB2(SCH_1):PAGE181
    F3    GND @BASEBOARD_FAB2_LIB.BASEBOARD_FAB2(SCH_1):GND   I134 @BASEBOARD_FAB2_LIB.BASEBOARD_FAB2(SCH_1):PAGE181
    F4 FAN_PWM_OUT_SYS0_R1 @BASEBOARD_FAB2_LIB.BASEBOARD_FAB2(SCH_1):FAN_PWM_OUT_SYS0_R1   I134 @BASEBOARD_FAB2_LIB.BASEBOARD_FAB2(SCH_1):PAGE181
    F5 FM_MB_SLOT_ID0 @BASEBOARD_FAB2_LIB.BASEBOARD_FAB2(SCH_1):FM_MB_SLOT_ID0   I134 @BASEBOARD_FAB2_LIB.BASEBOARD_FAB2(SCH_1):PAGE181
    F6 P3E_CPU1_PE3_MP_C_TXP<6> @BASEBOARD_FAB2_LIB.BASEBOARD_FAB2(SCH_1):P3E_CPU1_PE3_MP_C_TXP(6)   I134 @BASEBOARD_FAB2_LIB.BASEBOARD_FAB2(SCH_1):PAGE181
    F7    GND @BASEBOARD_FAB2_LIB.BASEBOARD_FAB2(SCH_1):GND   I134 @BASEBOARD_FAB2_LIB.BASEBOARD_FAB2(SCH_1):PAGE181
    F8 P3E_CPU1_PE3_MP_C_TXP<1> @BASEBOARD_FAB2_LIB.BASEBOARD_FAB2(SCH_1):P3E_CPU1_PE3_MP_C_TXP(1)   I134 @BASEBOARD_FAB2_LIB.BASEBOARD_FAB2(SCH_1):PAGE181
    G1 P3E_CPU1_PE3_MP_RXP<2> @BASEBOARD_FAB2_LIB.BASEBOARD_FAB2(SCH_1):P3E_CPU1_PE3_MP_RXP(2)   I134 @BASEBOARD_FAB2_LIB.BASEBOARD_FAB2(SCH_1):PAGE181
    G2    GND @BASEBOARD_FAB2_LIB.BASEBOARD_FAB2(SCH_1):GND   I134 @BASEBOARD_FAB2_LIB.BASEBOARD_FAB2(SCH_1):PAGE181
    G3 SPA_MID_DBG_TX_R @BASEBOARD_FAB2_LIB.BASEBOARD_FAB2(SCH_1):SPA_MID_DBG_TX_R   I134 @BASEBOARD_FAB2_LIB.BASEBOARD_FAB2(SCH_1):PAGE181
    G4    GND @BASEBOARD_FAB2_LIB.BASEBOARD_FAB2(SCH_1):GND   I134 @BASEBOARD_FAB2_LIB.BASEBOARD_FAB2(SCH_1):PAGE181
    G5 FM_MB_SLOT_ID1 @BASEBOARD_FAB2_LIB.BASEBOARD_FAB2(SCH_1):FM_MB_SLOT_ID1   I134 @BASEBOARD_FAB2_LIB.BASEBOARD_FAB2(SCH_1):PAGE181
    G6    GND @BASEBOARD_FAB2_LIB.BASEBOARD_FAB2(SCH_1):GND   I134 @BASEBOARD_FAB2_LIB.BASEBOARD_FAB2(SCH_1):PAGE181
    G7 P3E_CPU1_PE3_MP_C_TXP<5> @BASEBOARD_FAB2_LIB.BASEBOARD_FAB2(SCH_1):P3E_CPU1_PE3_MP_C_TXP(5)   I134 @BASEBOARD_FAB2_LIB.BASEBOARD_FAB2(SCH_1):PAGE181
    G8    GND @BASEBOARD_FAB2_LIB.BASEBOARD_FAB2(SCH_1):GND   I134 @BASEBOARD_FAB2_LIB.BASEBOARD_FAB2(SCH_1):PAGE181
    H1 P3E_CPU1_PE3_MP_RXN<2> @BASEBOARD_FAB2_LIB.BASEBOARD_FAB2(SCH_1):P3E_CPU1_PE3_MP_RXN(2)   I134 @BASEBOARD_FAB2_LIB.BASEBOARD_FAB2(SCH_1):PAGE181
    H2 P3E_CPU1_PE3_MP_RXP<5> @BASEBOARD_FAB2_LIB.BASEBOARD_FAB2(SCH_1):P3E_CPU1_PE3_MP_RXP(5)   I134 @BASEBOARD_FAB2_LIB.BASEBOARD_FAB2(SCH_1):PAGE181
    H3 SPA_MID_DBG_RX_R @BASEBOARD_FAB2_LIB.BASEBOARD_FAB2(SCH_1):SPA_MID_DBG_RX_R   I134 @BASEBOARD_FAB2_LIB.BASEBOARD_FAB2(SCH_1):PAGE181
    H4 CLK_100M_AIRMAX8_PE1_DP @BASEBOARD_FAB2_LIB.BASEBOARD_FAB2(SCH_1):CLK_100M_AIRMAX8_PE1_DP   I134 @BASEBOARD_FAB2_LIB.BASEBOARD_FAB2(SCH_1):PAGE181
    H5 FM_MB_SLOT_ID2 @BASEBOARD_FAB2_LIB.BASEBOARD_FAB2(SCH_1):FM_MB_SLOT_ID2   I134 @BASEBOARD_FAB2_LIB.BASEBOARD_FAB2(SCH_1):PAGE181
    H6 P3E_CPU1_PE3_MP_C_TXP<7> @BASEBOARD_FAB2_LIB.BASEBOARD_FAB2(SCH_1):P3E_CPU1_PE3_MP_C_TXP(7)   I134 @BASEBOARD_FAB2_LIB.BASEBOARD_FAB2(SCH_1):PAGE181
    H7 P3E_CPU1_PE3_MP_C_TXN<5> @BASEBOARD_FAB2_LIB.BASEBOARD_FAB2(SCH_1):P3E_CPU1_PE3_MP_C_TXN(5)   I134 @BASEBOARD_FAB2_LIB.BASEBOARD_FAB2(SCH_1):PAGE181
    H8 P3E_CPU1_PE3_MP_C_TXN<2> @BASEBOARD_FAB2_LIB.BASEBOARD_FAB2(SCH_1):P3E_CPU1_PE3_MP_C_TXN(2)   I134 @BASEBOARD_FAB2_LIB.BASEBOARD_FAB2(SCH_1):PAGE181
    I1    GND @BASEBOARD_FAB2_LIB.BASEBOARD_FAB2(SCH_1):GND   I134 @BASEBOARD_FAB2_LIB.BASEBOARD_FAB2(SCH_1):PAGE181
    I2 P3E_CPU1_PE3_MP_RXN<5> @BASEBOARD_FAB2_LIB.BASEBOARD_FAB2(SCH_1):P3E_CPU1_PE3_MP_RXN(5)   I134 @BASEBOARD_FAB2_LIB.BASEBOARD_FAB2(SCH_1):PAGE181
    I3 FM_ENABLE_FAN_POWER @BASEBOARD_FAB2_LIB.BASEBOARD_FAB2(SCH_1):FM_ENABLE_FAN_POWER   I134 @BASEBOARD_FAB2_LIB.BASEBOARD_FAB2(SCH_1):PAGE181
    I4 CLK_100M_AIRMAX8_PE1_DN @BASEBOARD_FAB2_LIB.BASEBOARD_FAB2(SCH_1):CLK_100M_AIRMAX8_PE1_DN   I134 @BASEBOARD_FAB2_LIB.BASEBOARD_FAB2(SCH_1):PAGE181
    I5 RST_PCIE_MIDPLANE_N @BASEBOARD_FAB2_LIB.BASEBOARD_FAB2(SCH_1):RST_PCIE_MIDPLANE_N   I134 @BASEBOARD_FAB2_LIB.BASEBOARD_FAB2(SCH_1):PAGE181
    I6 P3E_CPU1_PE3_MP_C_TXN<7> @BASEBOARD_FAB2_LIB.BASEBOARD_FAB2(SCH_1):P3E_CPU1_PE3_MP_C_TXN(7)   I134 @BASEBOARD_FAB2_LIB.BASEBOARD_FAB2(SCH_1):PAGE181
    I7    GND @BASEBOARD_FAB2_LIB.BASEBOARD_FAB2(SCH_1):GND   I134 @BASEBOARD_FAB2_LIB.BASEBOARD_FAB2(SCH_1):PAGE181
    I8 P3E_CPU1_PE3_MP_C_TXP<2> @BASEBOARD_FAB2_LIB.BASEBOARD_FAB2(SCH_1):P3E_CPU1_PE3_MP_C_TXP(2)   I134 @BASEBOARD_FAB2_LIB.BASEBOARD_FAB2(SCH_1):PAGE181
    J2    GND @BASEBOARD_FAB2_LIB.BASEBOARD_FAB2(SCH_1):GND   I134 @BASEBOARD_FAB2_LIB.BASEBOARD_FAB2(SCH_1):PAGE181
    J4    GND @BASEBOARD_FAB2_LIB.BASEBOARD_FAB2(SCH_1):GND   I134 @BASEBOARD_FAB2_LIB.BASEBOARD_FAB2(SCH_1):PAGE181
    J6    GND @BASEBOARD_FAB2_LIB.BASEBOARD_FAB2(SCH_1):GND   I134 @BASEBOARD_FAB2_LIB.BASEBOARD_FAB2(SCH_1):PAGE181
    J8    GND @BASEBOARD_FAB2_LIB.BASEBOARD_FAB2(SCH_1):GND   I134 @BASEBOARD_FAB2_LIB.BASEBOARD_FAB2(SCH_1):PAGE181

J1F2 LOTES-CON4-S1-GP_CONN-G7-LOTESA
     1    GND @BASEBOARD_FAB2_LIB.BASEBOARD_FAB2(SCH_1):GND   I139 @BASEBOARD_FAB2_LIB.BASEBOARD_FAB2(SCH_1):PAGE161
     2 P12V_FAN @BASEBOARD_FAB2_LIB.BASEBOARD_FAB2(SCH_1):P12V_FAN   I139 @BASEBOARD_FAB2_LIB.BASEBOARD_FAB2(SCH_1):PAGE161
     3 FAN_TACH0_CPU0_D1 @BASEBOARD_FAB2_LIB.BASEBOARD_FAB2(SCH_1):FAN_TACH0_CPU0_D1   I139 @BASEBOARD_FAB2_LIB.BASEBOARD_FAB2(SCH_1):PAGE161
     4 FAN_PWM_OUT_SYS0_R @BASEBOARD_FAB2_LIB.BASEBOARD_FAB2(SCH_1):FAN_PWM_OUT_SYS0_R   I139 @BASEBOARD_FAB2_LIB.BASEBOARD_FAB2(SCH_1):PAGE161
   NP1     NC     NC   I139 @BASEBOARD_FAB2_LIB.BASEBOARD_FAB2(SCH_1):PAGE161

J1F3 CONN8_H62179001_PIP-CONN,H6217A
     1 P3V3_STBY @BASEBOARD_FAB2_LIB.BASEBOARD_FAB2(SCH_1):P3V3_STBY   I106 @BASEBOARD_FAB2_LIB.BASEBOARD_FAB2(SCH_1):PAGE181
     2 FM_MP_PS_REDUNDANT_LOST_N @BASEBOARD_FAB2_LIB.BASEBOARD_FAB2(SCH_1):FM_MP_PS_REDUNDANT_LOST_N   I106 @BASEBOARD_FAB2_LIB.BASEBOARD_FAB2(SCH_1):PAGE181
     3 FM_MP_PS_FAIL_N @BASEBOARD_FAB2_LIB.BASEBOARD_FAB2(SCH_1):FM_MP_PS_FAIL_N   I106 @BASEBOARD_FAB2_LIB.BASEBOARD_FAB2(SCH_1):PAGE181
     4 FM_MATED_IN_N @BASEBOARD_FAB2_LIB.BASEBOARD_FAB2(SCH_1):FM_MATED_IN_N   I106 @BASEBOARD_FAB2_LIB.BASEBOARD_FAB2(SCH_1):PAGE181
     5 IRQ_SML1_PMBUS_ALERT_R_N @BASEBOARD_FAB2_LIB.BASEBOARD_FAB2(SCH_1):IRQ_SML1_PMBUS_ALERT_R_N   I106 @BASEBOARD_FAB2_LIB.BASEBOARD_FAB2(SCH_1):PAGE181
     6 SMB_BMC_PMBUS_STBY_LVC3_SDA @BASEBOARD_FAB2_LIB.BASEBOARD_FAB2(SCH_1):SMB_BMC_PMBUS_STBY_LVC3_SDA   I106 @BASEBOARD_FAB2_LIB.BASEBOARD_FAB2(SCH_1):PAGE181
     7 SMB_BMC_PMBUS_STBY_LVC3_SCL @BASEBOARD_FAB2_LIB.BASEBOARD_FAB2(SCH_1):SMB_BMC_PMBUS_STBY_LVC3_SCL   I106 @BASEBOARD_FAB2_LIB.BASEBOARD_FAB2(SCH_1):PAGE181
     8    GND @BASEBOARD_FAB2_LIB.BASEBOARD_FAB2(SCH_1):GND   I106 @BASEBOARD_FAB2_LIB.BASEBOARD_FAB2(SCH_1):PAGE181

J1G1 SCONN288_H44441004_PIP-SCONN,HA
    79 M_G_MA<0> @BASEBOARD_FAB2_LIB.BASEBOARD_FAB2(SCH_1):M_G_MA(0)   I111 @BASEBOARD_FAB2_LIB.BASEBOARD_FAB2(SCH_1):PAGE77
    72 M_G_MA<1> @BASEBOARD_FAB2_LIB.BASEBOARD_FAB2(SCH_1):M_G_MA(1)   I111 @BASEBOARD_FAB2_LIB.BASEBOARD_FAB2(SCH_1):PAGE77
   225 M_G_MA<10> @BASEBOARD_FAB2_LIB.BASEBOARD_FAB2(SCH_1):M_G_MA(10)   I111 @BASEBOARD_FAB2_LIB.BASEBOARD_FAB2(SCH_1):PAGE77
   210 M_G_MA<11> @BASEBOARD_FAB2_LIB.BASEBOARD_FAB2(SCH_1):M_G_MA(11)   I111 @BASEBOARD_FAB2_LIB.BASEBOARD_FAB2(SCH_1):PAGE77
    65 M_G_MA<12> @BASEBOARD_FAB2_LIB.BASEBOARD_FAB2(SCH_1):M_G_MA(12)   I111 @BASEBOARD_FAB2_LIB.BASEBOARD_FAB2(SCH_1):PAGE77
   232 M_G_MA<13> @BASEBOARD_FAB2_LIB.BASEBOARD_FAB2(SCH_1):M_G_MA(13)   I111 @BASEBOARD_FAB2_LIB.BASEBOARD_FAB2(SCH_1):PAGE77
   228 M_G_MA<14> @BASEBOARD_FAB2_LIB.BASEBOARD_FAB2(SCH_1):M_G_MA(14)   I111 @BASEBOARD_FAB2_LIB.BASEBOARD_FAB2(SCH_1):PAGE77
    86 M_G_MA<15> @BASEBOARD_FAB2_LIB.BASEBOARD_FAB2(SCH_1):M_G_MA(15)   I111 @BASEBOARD_FAB2_LIB.BASEBOARD_FAB2(SCH_1):PAGE77
    82 M_G_MA<16> @BASEBOARD_FAB2_LIB.BASEBOARD_FAB2(SCH_1):M_G_MA(16)   I111 @BASEBOARD_FAB2_LIB.BASEBOARD_FAB2(SCH_1):PAGE77
   234 M_G_MA<17> @BASEBOARD_FAB2_LIB.BASEBOARD_FAB2(SCH_1):M_G_MA(17)   I111 @BASEBOARD_FAB2_LIB.BASEBOARD_FAB2(SCH_1):PAGE77
   216 M_G_MA<2> @BASEBOARD_FAB2_LIB.BASEBOARD_FAB2(SCH_1):M_G_MA(2)   I111 @BASEBOARD_FAB2_LIB.BASEBOARD_FAB2(SCH_1):PAGE77
    71 M_G_MA<3> @BASEBOARD_FAB2_LIB.BASEBOARD_FAB2(SCH_1):M_G_MA(3)   I111 @BASEBOARD_FAB2_LIB.BASEBOARD_FAB2(SCH_1):PAGE77
   214 M_G_MA<4> @BASEBOARD_FAB2_LIB.BASEBOARD_FAB2(SCH_1):M_G_MA(4)   I111 @BASEBOARD_FAB2_LIB.BASEBOARD_FAB2(SCH_1):PAGE77
   213 M_G_MA<5> @BASEBOARD_FAB2_LIB.BASEBOARD_FAB2(SCH_1):M_G_MA(5)   I111 @BASEBOARD_FAB2_LIB.BASEBOARD_FAB2(SCH_1):PAGE77
    69 M_G_MA<6> @BASEBOARD_FAB2_LIB.BASEBOARD_FAB2(SCH_1):M_G_MA(6)   I111 @BASEBOARD_FAB2_LIB.BASEBOARD_FAB2(SCH_1):PAGE77
   211 M_G_MA<7> @BASEBOARD_FAB2_LIB.BASEBOARD_FAB2(SCH_1):M_G_MA(7)   I111 @BASEBOARD_FAB2_LIB.BASEBOARD_FAB2(SCH_1):PAGE77
    68 M_G_MA<8> @BASEBOARD_FAB2_LIB.BASEBOARD_FAB2(SCH_1):M_G_MA(8)   I111 @BASEBOARD_FAB2_LIB.BASEBOARD_FAB2(SCH_1):PAGE77
    66 M_G_MA<9> @BASEBOARD_FAB2_LIB.BASEBOARD_FAB2(SCH_1):M_G_MA(9)   I111 @BASEBOARD_FAB2_LIB.BASEBOARD_FAB2(SCH_1):PAGE77
    62 M_G_ACT_N @BASEBOARD_FAB2_LIB.BASEBOARD_FAB2(SCH_1):M_G_ACT_N   I111 @BASEBOARD_FAB2_LIB.BASEBOARD_FAB2(SCH_1):PAGE77
   208 M_G_ALERT_N @BASEBOARD_FAB2_LIB.BASEBOARD_FAB2(SCH_1):M_G_ALERT_N   I111 @BASEBOARD_FAB2_LIB.BASEBOARD_FAB2(SCH_1):PAGE77
   224 M_G_BA<1> @BASEBOARD_FAB2_LIB.BASEBOARD_FAB2(SCH_1):M_G_BA(1)   I111 @BASEBOARD_FAB2_LIB.BASEBOARD_FAB2(SCH_1):PAGE77
    81 M_G_BA<0> @BASEBOARD_FAB2_LIB.BASEBOARD_FAB2(SCH_1):M_G_BA(0)   I111 @BASEBOARD_FAB2_LIB.BASEBOARD_FAB2(SCH_1):PAGE77
   207 M_G_BG<1> @BASEBOARD_FAB2_LIB.BASEBOARD_FAB2(SCH_1):M_G_BG(1)   I111 @BASEBOARD_FAB2_LIB.BASEBOARD_FAB2(SCH_1):PAGE77
    63 M_G_BG<0> @BASEBOARD_FAB2_LIB.BASEBOARD_FAB2(SCH_1):M_G_BG(0)   I111 @BASEBOARD_FAB2_LIB.BASEBOARD_FAB2(SCH_1):PAGE77
   235 M_G_C<2> @BASEBOARD_FAB2_LIB.BASEBOARD_FAB2(SCH_1):M_G_C(2)   I111 @BASEBOARD_FAB2_LIB.BASEBOARD_FAB2(SCH_1):PAGE77
   199 M_G_ECC<6> @BASEBOARD_FAB2_LIB.BASEBOARD_FAB2(SCH_1):M_G_ECC(6)   I111 @BASEBOARD_FAB2_LIB.BASEBOARD_FAB2(SCH_1):PAGE77
    54 M_G_ECC<7> @BASEBOARD_FAB2_LIB.BASEBOARD_FAB2(SCH_1):M_G_ECC(7)   I111 @BASEBOARD_FAB2_LIB.BASEBOARD_FAB2(SCH_1):PAGE77
   192 M_G_ECC<4> @BASEBOARD_FAB2_LIB.BASEBOARD_FAB2(SCH_1):M_G_ECC(4)   I111 @BASEBOARD_FAB2_LIB.BASEBOARD_FAB2(SCH_1):PAGE77
    47 M_G_ECC<5> @BASEBOARD_FAB2_LIB.BASEBOARD_FAB2(SCH_1):M_G_ECC(5)   I111 @BASEBOARD_FAB2_LIB.BASEBOARD_FAB2(SCH_1):PAGE77
   201 M_G_ECC<2> @BASEBOARD_FAB2_LIB.BASEBOARD_FAB2(SCH_1):M_G_ECC(2)   I111 @BASEBOARD_FAB2_LIB.BASEBOARD_FAB2(SCH_1):PAGE77
    56 M_G_ECC<3> @BASEBOARD_FAB2_LIB.BASEBOARD_FAB2(SCH_1):M_G_ECC(3)   I111 @BASEBOARD_FAB2_LIB.BASEBOARD_FAB2(SCH_1):PAGE77
   194 M_G_ECC<0> @BASEBOARD_FAB2_LIB.BASEBOARD_FAB2(SCH_1):M_G_ECC(0)   I111 @BASEBOARD_FAB2_LIB.BASEBOARD_FAB2(SCH_1):PAGE77
    49 M_G_ECC<1> @BASEBOARD_FAB2_LIB.BASEBOARD_FAB2(SCH_1):M_G_ECC(1)   I111 @BASEBOARD_FAB2_LIB.BASEBOARD_FAB2(SCH_1):PAGE77
    75 M_G_CLK_DN<0> @BASEBOARD_FAB2_LIB.BASEBOARD_FAB2(SCH_1):M_G_CLK_DN(0)   I111 @BASEBOARD_FAB2_LIB.BASEBOARD_FAB2(SCH_1):PAGE77
    74 M_G_CLK_DP<0> @BASEBOARD_FAB2_LIB.BASEBOARD_FAB2(SCH_1):M_G_CLK_DP(0)   I111 @BASEBOARD_FAB2_LIB.BASEBOARD_FAB2(SCH_1):PAGE77
   219 M_G_CLK_DN<1> @BASEBOARD_FAB2_LIB.BASEBOARD_FAB2(SCH_1):M_G_CLK_DN(1)   I111 @BASEBOARD_FAB2_LIB.BASEBOARD_FAB2(SCH_1):PAGE77
   218 M_G_CLK_DP<1> @BASEBOARD_FAB2_LIB.BASEBOARD_FAB2(SCH_1):M_G_CLK_DP(1)   I111 @BASEBOARD_FAB2_LIB.BASEBOARD_FAB2(SCH_1):PAGE77
   203 M_G_CKE<1> @BASEBOARD_FAB2_LIB.BASEBOARD_FAB2(SCH_1):M_G_CKE(1)   I111 @BASEBOARD_FAB2_LIB.BASEBOARD_FAB2(SCH_1):PAGE77
    60 M_G_CKE<0> @BASEBOARD_FAB2_LIB.BASEBOARD_FAB2(SCH_1):M_G_CKE(0)   I111 @BASEBOARD_FAB2_LIB.BASEBOARD_FAB2(SCH_1):PAGE77
   280 M_G_DQ<62> @BASEBOARD_FAB2_LIB.BASEBOARD_FAB2(SCH_1):M_G_DQ(62)   I111 @BASEBOARD_FAB2_LIB.BASEBOARD_FAB2(SCH_1):PAGE77
   135 M_G_DQ<63> @BASEBOARD_FAB2_LIB.BASEBOARD_FAB2(SCH_1):M_G_DQ(63)   I111 @BASEBOARD_FAB2_LIB.BASEBOARD_FAB2(SCH_1):PAGE77
   273 M_G_DQ<60> @BASEBOARD_FAB2_LIB.BASEBOARD_FAB2(SCH_1):M_G_DQ(60)   I111 @BASEBOARD_FAB2_LIB.BASEBOARD_FAB2(SCH_1):PAGE77
   128 M_G_DQ<61> @BASEBOARD_FAB2_LIB.BASEBOARD_FAB2(SCH_1):M_G_DQ(61)   I111 @BASEBOARD_FAB2_LIB.BASEBOARD_FAB2(SCH_1):PAGE77
   282 M_G_DQ<58> @BASEBOARD_FAB2_LIB.BASEBOARD_FAB2(SCH_1):M_G_DQ(58)   I111 @BASEBOARD_FAB2_LIB.BASEBOARD_FAB2(SCH_1):PAGE77
   137 M_G_DQ<59> @BASEBOARD_FAB2_LIB.BASEBOARD_FAB2(SCH_1):M_G_DQ(59)   I111 @BASEBOARD_FAB2_LIB.BASEBOARD_FAB2(SCH_1):PAGE77
   275 M_G_DQ<56> @BASEBOARD_FAB2_LIB.BASEBOARD_FAB2(SCH_1):M_G_DQ(56)   I111 @BASEBOARD_FAB2_LIB.BASEBOARD_FAB2(SCH_1):PAGE77
   130 M_G_DQ<57> @BASEBOARD_FAB2_LIB.BASEBOARD_FAB2(SCH_1):M_G_DQ(57)   I111 @BASEBOARD_FAB2_LIB.BASEBOARD_FAB2(SCH_1):PAGE77
   269 M_G_DQ<54> @BASEBOARD_FAB2_LIB.BASEBOARD_FAB2(SCH_1):M_G_DQ(54)   I111 @BASEBOARD_FAB2_LIB.BASEBOARD_FAB2(SCH_1):PAGE77
   124 M_G_DQ<55> @BASEBOARD_FAB2_LIB.BASEBOARD_FAB2(SCH_1):M_G_DQ(55)   I111 @BASEBOARD_FAB2_LIB.BASEBOARD_FAB2(SCH_1):PAGE77
   262 M_G_DQ<52> @BASEBOARD_FAB2_LIB.BASEBOARD_FAB2(SCH_1):M_G_DQ(52)   I111 @BASEBOARD_FAB2_LIB.BASEBOARD_FAB2(SCH_1):PAGE77
   117 M_G_DQ<53> @BASEBOARD_FAB2_LIB.BASEBOARD_FAB2(SCH_1):M_G_DQ(53)   I111 @BASEBOARD_FAB2_LIB.BASEBOARD_FAB2(SCH_1):PAGE77
   271 M_G_DQ<50> @BASEBOARD_FAB2_LIB.BASEBOARD_FAB2(SCH_1):M_G_DQ(50)   I111 @BASEBOARD_FAB2_LIB.BASEBOARD_FAB2(SCH_1):PAGE77
   126 M_G_DQ<51> @BASEBOARD_FAB2_LIB.BASEBOARD_FAB2(SCH_1):M_G_DQ(51)   I111 @BASEBOARD_FAB2_LIB.BASEBOARD_FAB2(SCH_1):PAGE77
   264 M_G_DQ<48> @BASEBOARD_FAB2_LIB.BASEBOARD_FAB2(SCH_1):M_G_DQ(48)   I111 @BASEBOARD_FAB2_LIB.BASEBOARD_FAB2(SCH_1):PAGE77
   119 M_G_DQ<49> @BASEBOARD_FAB2_LIB.BASEBOARD_FAB2(SCH_1):M_G_DQ(49)   I111 @BASEBOARD_FAB2_LIB.BASEBOARD_FAB2(SCH_1):PAGE77
   258 M_G_DQ<46> @BASEBOARD_FAB2_LIB.BASEBOARD_FAB2(SCH_1):M_G_DQ(46)   I111 @BASEBOARD_FAB2_LIB.BASEBOARD_FAB2(SCH_1):PAGE77
   113 M_G_DQ<47> @BASEBOARD_FAB2_LIB.BASEBOARD_FAB2(SCH_1):M_G_DQ(47)   I111 @BASEBOARD_FAB2_LIB.BASEBOARD_FAB2(SCH_1):PAGE77
   251 M_G_DQ<44> @BASEBOARD_FAB2_LIB.BASEBOARD_FAB2(SCH_1):M_G_DQ(44)   I111 @BASEBOARD_FAB2_LIB.BASEBOARD_FAB2(SCH_1):PAGE77
   106 M_G_DQ<45> @BASEBOARD_FAB2_LIB.BASEBOARD_FAB2(SCH_1):M_G_DQ(45)   I111 @BASEBOARD_FAB2_LIB.BASEBOARD_FAB2(SCH_1):PAGE77
   260 M_G_DQ<42> @BASEBOARD_FAB2_LIB.BASEBOARD_FAB2(SCH_1):M_G_DQ(42)   I111 @BASEBOARD_FAB2_LIB.BASEBOARD_FAB2(SCH_1):PAGE77
   115 M_G_DQ<43> @BASEBOARD_FAB2_LIB.BASEBOARD_FAB2(SCH_1):M_G_DQ(43)   I111 @BASEBOARD_FAB2_LIB.BASEBOARD_FAB2(SCH_1):PAGE77
   253 M_G_DQ<40> @BASEBOARD_FAB2_LIB.BASEBOARD_FAB2(SCH_1):M_G_DQ(40)   I111 @BASEBOARD_FAB2_LIB.BASEBOARD_FAB2(SCH_1):PAGE77
   108 M_G_DQ<41> @BASEBOARD_FAB2_LIB.BASEBOARD_FAB2(SCH_1):M_G_DQ(41)   I111 @BASEBOARD_FAB2_LIB.BASEBOARD_FAB2(SCH_1):PAGE77
   247 M_G_DQ<38> @BASEBOARD_FAB2_LIB.BASEBOARD_FAB2(SCH_1):M_G_DQ(38)   I111 @BASEBOARD_FAB2_LIB.BASEBOARD_FAB2(SCH_1):PAGE77
   102 M_G_DQ<39> @BASEBOARD_FAB2_LIB.BASEBOARD_FAB2(SCH_1):M_G_DQ(39)   I111 @BASEBOARD_FAB2_LIB.BASEBOARD_FAB2(SCH_1):PAGE77
   240 M_G_DQ<36> @BASEBOARD_FAB2_LIB.BASEBOARD_FAB2(SCH_1):M_G_DQ(36)   I111 @BASEBOARD_FAB2_LIB.BASEBOARD_FAB2(SCH_1):PAGE77
    95 M_G_DQ<37> @BASEBOARD_FAB2_LIB.BASEBOARD_FAB2(SCH_1):M_G_DQ(37)   I111 @BASEBOARD_FAB2_LIB.BASEBOARD_FAB2(SCH_1):PAGE77
   249 M_G_DQ<34> @BASEBOARD_FAB2_LIB.BASEBOARD_FAB2(SCH_1):M_G_DQ(34)   I111 @BASEBOARD_FAB2_LIB.BASEBOARD_FAB2(SCH_1):PAGE77
   104 M_G_DQ<35> @BASEBOARD_FAB2_LIB.BASEBOARD_FAB2(SCH_1):M_G_DQ(35)   I111 @BASEBOARD_FAB2_LIB.BASEBOARD_FAB2(SCH_1):PAGE77
   242 M_G_DQ<32> @BASEBOARD_FAB2_LIB.BASEBOARD_FAB2(SCH_1):M_G_DQ(32)   I111 @BASEBOARD_FAB2_LIB.BASEBOARD_FAB2(SCH_1):PAGE77
    97 M_G_DQ<33> @BASEBOARD_FAB2_LIB.BASEBOARD_FAB2(SCH_1):M_G_DQ(33)   I111 @BASEBOARD_FAB2_LIB.BASEBOARD_FAB2(SCH_1):PAGE77
   188 M_G_DQ<30> @BASEBOARD_FAB2_LIB.BASEBOARD_FAB2(SCH_1):M_G_DQ(30)   I111 @BASEBOARD_FAB2_LIB.BASEBOARD_FAB2(SCH_1):PAGE77
    43 M_G_DQ<31> @BASEBOARD_FAB2_LIB.BASEBOARD_FAB2(SCH_1):M_G_DQ(31)   I111 @BASEBOARD_FAB2_LIB.BASEBOARD_FAB2(SCH_1):PAGE77
   181 M_G_DQ<28> @BASEBOARD_FAB2_LIB.BASEBOARD_FAB2(SCH_1):M_G_DQ(28)   I111 @BASEBOARD_FAB2_LIB.BASEBOARD_FAB2(SCH_1):PAGE77
    36 M_G_DQ<29> @BASEBOARD_FAB2_LIB.BASEBOARD_FAB2(SCH_1):M_G_DQ(29)   I111 @BASEBOARD_FAB2_LIB.BASEBOARD_FAB2(SCH_1):PAGE77
   190 M_G_DQ<26> @BASEBOARD_FAB2_LIB.BASEBOARD_FAB2(SCH_1):M_G_DQ(26)   I111 @BASEBOARD_FAB2_LIB.BASEBOARD_FAB2(SCH_1):PAGE77
    45 M_G_DQ<27> @BASEBOARD_FAB2_LIB.BASEBOARD_FAB2(SCH_1):M_G_DQ(27)   I111 @BASEBOARD_FAB2_LIB.BASEBOARD_FAB2(SCH_1):PAGE77
   183 M_G_DQ<24> @BASEBOARD_FAB2_LIB.BASEBOARD_FAB2(SCH_1):M_G_DQ(24)   I111 @BASEBOARD_FAB2_LIB.BASEBOARD_FAB2(SCH_1):PAGE77
    38 M_G_DQ<25> @BASEBOARD_FAB2_LIB.BASEBOARD_FAB2(SCH_1):M_G_DQ(25)   I111 @BASEBOARD_FAB2_LIB.BASEBOARD_FAB2(SCH_1):PAGE77
   177 M_G_DQ<22> @BASEBOARD_FAB2_LIB.BASEBOARD_FAB2(SCH_1):M_G_DQ(22)   I111 @BASEBOARD_FAB2_LIB.BASEBOARD_FAB2(SCH_1):PAGE77
    32 M_G_DQ<23> @BASEBOARD_FAB2_LIB.BASEBOARD_FAB2(SCH_1):M_G_DQ(23)   I111 @BASEBOARD_FAB2_LIB.BASEBOARD_FAB2(SCH_1):PAGE77
   170 M_G_DQ<20> @BASEBOARD_FAB2_LIB.BASEBOARD_FAB2(SCH_1):M_G_DQ(20)   I111 @BASEBOARD_FAB2_LIB.BASEBOARD_FAB2(SCH_1):PAGE77
    25 M_G_DQ<21> @BASEBOARD_FAB2_LIB.BASEBOARD_FAB2(SCH_1):M_G_DQ(21)   I111 @BASEBOARD_FAB2_LIB.BASEBOARD_FAB2(SCH_1):PAGE77
   179 M_G_DQ<18> @BASEBOARD_FAB2_LIB.BASEBOARD_FAB2(SCH_1):M_G_DQ(18)   I111 @BASEBOARD_FAB2_LIB.BASEBOARD_FAB2(SCH_1):PAGE77
    34 M_G_DQ<19> @BASEBOARD_FAB2_LIB.BASEBOARD_FAB2(SCH_1):M_G_DQ(19)   I111 @BASEBOARD_FAB2_LIB.BASEBOARD_FAB2(SCH_1):PAGE77
   172 M_G_DQ<16> @BASEBOARD_FAB2_LIB.BASEBOARD_FAB2(SCH_1):M_G_DQ(16)   I111 @BASEBOARD_FAB2_LIB.BASEBOARD_FAB2(SCH_1):PAGE77
    27 M_G_DQ<17> @BASEBOARD_FAB2_LIB.BASEBOARD_FAB2(SCH_1):M_G_DQ(17)   I111 @BASEBOARD_FAB2_LIB.BASEBOARD_FAB2(SCH_1):PAGE77
   166 M_G_DQ<14> @BASEBOARD_FAB2_LIB.BASEBOARD_FAB2(SCH_1):M_G_DQ(14)   I111 @BASEBOARD_FAB2_LIB.BASEBOARD_FAB2(SCH_1):PAGE77
    21 M_G_DQ<15> @BASEBOARD_FAB2_LIB.BASEBOARD_FAB2(SCH_1):M_G_DQ(15)   I111 @BASEBOARD_FAB2_LIB.BASEBOARD_FAB2(SCH_1):PAGE77
   159 M_G_DQ<12> @BASEBOARD_FAB2_LIB.BASEBOARD_FAB2(SCH_1):M_G_DQ(12)   I111 @BASEBOARD_FAB2_LIB.BASEBOARD_FAB2(SCH_1):PAGE77
    14 M_G_DQ<13> @BASEBOARD_FAB2_LIB.BASEBOARD_FAB2(SCH_1):M_G_DQ(13)   I111 @BASEBOARD_FAB2_LIB.BASEBOARD_FAB2(SCH_1):PAGE77
   168 M_G_DQ<10> @BASEBOARD_FAB2_LIB.BASEBOARD_FAB2(SCH_1):M_G_DQ(10)   I111 @BASEBOARD_FAB2_LIB.BASEBOARD_FAB2(SCH_1):PAGE77
    23 M_G_DQ<11> @BASEBOARD_FAB2_LIB.BASEBOARD_FAB2(SCH_1):M_G_DQ(11)   I111 @BASEBOARD_FAB2_LIB.BASEBOARD_FAB2(SCH_1):PAGE77
   161 M_G_DQ<8> @BASEBOARD_FAB2_LIB.BASEBOARD_FAB2(SCH_1):M_G_DQ(8)   I111 @BASEBOARD_FAB2_LIB.BASEBOARD_FAB2(SCH_1):PAGE77
    16 M_G_DQ<9> @BASEBOARD_FAB2_LIB.BASEBOARD_FAB2(SCH_1):M_G_DQ(9)   I111 @BASEBOARD_FAB2_LIB.BASEBOARD_FAB2(SCH_1):PAGE77
   155 M_G_DQ<6> @BASEBOARD_FAB2_LIB.BASEBOARD_FAB2(SCH_1):M_G_DQ(6)   I111 @BASEBOARD_FAB2_LIB.BASEBOARD_FAB2(SCH_1):PAGE77
    10 M_G_DQ<7> @BASEBOARD_FAB2_LIB.BASEBOARD_FAB2(SCH_1):M_G_DQ(7)   I111 @BASEBOARD_FAB2_LIB.BASEBOARD_FAB2(SCH_1):PAGE77
   148 M_G_DQ<4> @BASEBOARD_FAB2_LIB.BASEBOARD_FAB2(SCH_1):M_G_DQ(4)   I111 @BASEBOARD_FAB2_LIB.BASEBOARD_FAB2(SCH_1):PAGE77
     3 M_G_DQ<5> @BASEBOARD_FAB2_LIB.BASEBOARD_FAB2(SCH_1):M_G_DQ(5)   I111 @BASEBOARD_FAB2_LIB.BASEBOARD_FAB2(SCH_1):PAGE77
   157 M_G_DQ<2> @BASEBOARD_FAB2_LIB.BASEBOARD_FAB2(SCH_1):M_G_DQ(2)   I111 @BASEBOARD_FAB2_LIB.BASEBOARD_FAB2(SCH_1):PAGE77
    12 M_G_DQ<3> @BASEBOARD_FAB2_LIB.BASEBOARD_FAB2(SCH_1):M_G_DQ(3)   I111 @BASEBOARD_FAB2_LIB.BASEBOARD_FAB2(SCH_1):PAGE77
   150 M_G_DQ<0> @BASEBOARD_FAB2_LIB.BASEBOARD_FAB2(SCH_1):M_G_DQ(0)   I111 @BASEBOARD_FAB2_LIB.BASEBOARD_FAB2(SCH_1):PAGE77
     5 M_G_DQ<1> @BASEBOARD_FAB2_LIB.BASEBOARD_FAB2(SCH_1):M_G_DQ(1)   I111 @BASEBOARD_FAB2_LIB.BASEBOARD_FAB2(SCH_1):PAGE77
    78 FM_DIMM_EVENT_COD_N @BASEBOARD_FAB2_LIB.BASEBOARD_FAB2(SCH_1):FM_DIMM_EVENT_COD_N   I111 @BASEBOARD_FAB2_LIB.BASEBOARD_FAB2(SCH_1):PAGE77
    91 M_G_ODT<1> @BASEBOARD_FAB2_LIB.BASEBOARD_FAB2(SCH_1):M_G_ODT(1)   I111 @BASEBOARD_FAB2_LIB.BASEBOARD_FAB2(SCH_1):PAGE77
    87 M_G_ODT<0> @BASEBOARD_FAB2_LIB.BASEBOARD_FAB2(SCH_1):M_G_ODT(0)   I111 @BASEBOARD_FAB2_LIB.BASEBOARD_FAB2(SCH_1):PAGE77
   222 M_G_PAR @BASEBOARD_FAB2_LIB.BASEBOARD_FAB2(SCH_1):M_G_PAR   I111 @BASEBOARD_FAB2_LIB.BASEBOARD_FAB2(SCH_1):PAGE77
    58 M_GHJ_RST_N @BASEBOARD_FAB2_LIB.BASEBOARD_FAB2(SCH_1):M_GHJ_RST_N   I111 @BASEBOARD_FAB2_LIB.BASEBOARD_FAB2(SCH_1):PAGE77
   144 TP_CH_G_DIMM_G0_RFU_2 @BASEBOARD_FAB2_LIB.BASEBOARD_FAB2(SCH_1):TP_CH_G_DIMM_G0_RFU_2   I111 @BASEBOARD_FAB2_LIB.BASEBOARD_FAB2(SCH_1):PAGE77
   227 TP_CH_G_DIMM_G0_RFU_1 @BASEBOARD_FAB2_LIB.BASEBOARD_FAB2(SCH_1):TP_CH_G_DIMM_G0_RFU_1   I111 @BASEBOARD_FAB2_LIB.BASEBOARD_FAB2(SCH_1):PAGE77
   205 TP_CH_G_DIMM_G0_RFU_0 @BASEBOARD_FAB2_LIB.BASEBOARD_FAB2(SCH_1):TP_CH_G_DIMM_G0_RFU_0   I111 @BASEBOARD_FAB2_LIB.BASEBOARD_FAB2(SCH_1):PAGE77
    84 M_G_CS_N<0> @BASEBOARD_FAB2_LIB.BASEBOARD_FAB2(SCH_1):M_G_CS_N(0)   I111 @BASEBOARD_FAB2_LIB.BASEBOARD_FAB2(SCH_1):PAGE77
    89 M_G_CS_N<1> @BASEBOARD_FAB2_LIB.BASEBOARD_FAB2(SCH_1):M_G_CS_N(1)   I111 @BASEBOARD_FAB2_LIB.BASEBOARD_FAB2(SCH_1):PAGE77
    93 M_G_CS_N<2> @BASEBOARD_FAB2_LIB.BASEBOARD_FAB2(SCH_1):M_G_CS_N(2)   I111 @BASEBOARD_FAB2_LIB.BASEBOARD_FAB2(SCH_1):PAGE77
   237 M_G_CS_N<3> @BASEBOARD_FAB2_LIB.BASEBOARD_FAB2(SCH_1):M_G_CS_N(3)   I111 @BASEBOARD_FAB2_LIB.BASEBOARD_FAB2(SCH_1):PAGE77
   238    GND @BASEBOARD_FAB2_LIB.BASEBOARD_FAB2(SCH_1):GND   I111 @BASEBOARD_FAB2_LIB.BASEBOARD_FAB2(SCH_1):PAGE77
   140    GND @BASEBOARD_FAB2_LIB.BASEBOARD_FAB2(SCH_1):GND   I111 @BASEBOARD_FAB2_LIB.BASEBOARD_FAB2(SCH_1):PAGE77
   139    GND @BASEBOARD_FAB2_LIB.BASEBOARD_FAB2(SCH_1):GND   I111 @BASEBOARD_FAB2_LIB.BASEBOARD_FAB2(SCH_1):PAGE77
   230 FM_ADR_COMPLETE_GHJ_N @BASEBOARD_FAB2_LIB.BASEBOARD_FAB2(SCH_1):FM_ADR_COMPLETE_GHJ_N   I111 @BASEBOARD_FAB2_LIB.BASEBOARD_FAB2(SCH_1):PAGE77
   141 SMB_DDR_GHJ_VPP_SCL @BASEBOARD_FAB2_LIB.BASEBOARD_FAB2(SCH_1):SMB_DDR_GHJ_VPP_SCL   I111 @BASEBOARD_FAB2_LIB.BASEBOARD_FAB2(SCH_1):PAGE77
   285 SMB_DDR_GHJ_VPP_SDA @BASEBOARD_FAB2_LIB.BASEBOARD_FAB2(SCH_1):SMB_DDR_GHJ_VPP_SDA   I111 @BASEBOARD_FAB2_LIB.BASEBOARD_FAB2(SCH_1):PAGE77
   284 PVPP_GHJ @BASEBOARD_FAB2_LIB.BASEBOARD_FAB2(SCH_1):PVPP_GHJ   I111 @BASEBOARD_FAB2_LIB.BASEBOARD_FAB2(SCH_1):PAGE77
   146 M_G_VREF @BASEBOARD_FAB2_LIB.BASEBOARD_FAB2(SCH_1):M_G_VREF   I111 @BASEBOARD_FAB2_LIB.BASEBOARD_FAB2(SCH_1):PAGE77
   152 M_G_DQS_DN<0> @BASEBOARD_FAB2_LIB.BASEBOARD_FAB2(SCH_1):M_G_DQS_DN(0)    I66 @BASEBOARD_FAB2_LIB.BASEBOARD_FAB2(SCH_1):PAGE77
   153 M_G_DQS_DP<0> @BASEBOARD_FAB2_LIB.BASEBOARD_FAB2(SCH_1):M_G_DQS_DP(0)    I66 @BASEBOARD_FAB2_LIB.BASEBOARD_FAB2(SCH_1):PAGE77
    19 M_G_DQS_DN<10> @BASEBOARD_FAB2_LIB.BASEBOARD_FAB2(SCH_1):M_G_DQS_DN(10)    I66 @BASEBOARD_FAB2_LIB.BASEBOARD_FAB2(SCH_1):PAGE77
    18 M_G_DQS_DP<10> @BASEBOARD_FAB2_LIB.BASEBOARD_FAB2(SCH_1):M_G_DQS_DP(10)    I66 @BASEBOARD_FAB2_LIB.BASEBOARD_FAB2(SCH_1):PAGE77
    30 M_G_DQS_DN<11> @BASEBOARD_FAB2_LIB.BASEBOARD_FAB2(SCH_1):M_G_DQS_DN(11)    I66 @BASEBOARD_FAB2_LIB.BASEBOARD_FAB2(SCH_1):PAGE77
    29 M_G_DQS_DP<11> @BASEBOARD_FAB2_LIB.BASEBOARD_FAB2(SCH_1):M_G_DQS_DP(11)    I66 @BASEBOARD_FAB2_LIB.BASEBOARD_FAB2(SCH_1):PAGE77
    41 M_G_DQS_DN<12> @BASEBOARD_FAB2_LIB.BASEBOARD_FAB2(SCH_1):M_G_DQS_DN(12)    I66 @BASEBOARD_FAB2_LIB.BASEBOARD_FAB2(SCH_1):PAGE77
    40 M_G_DQS_DP<12> @BASEBOARD_FAB2_LIB.BASEBOARD_FAB2(SCH_1):M_G_DQS_DP(12)    I66 @BASEBOARD_FAB2_LIB.BASEBOARD_FAB2(SCH_1):PAGE77
   100 M_G_DQS_DN<13> @BASEBOARD_FAB2_LIB.BASEBOARD_FAB2(SCH_1):M_G_DQS_DN(13)    I66 @BASEBOARD_FAB2_LIB.BASEBOARD_FAB2(SCH_1):PAGE77
    99 M_G_DQS_DP<13> @BASEBOARD_FAB2_LIB.BASEBOARD_FAB2(SCH_1):M_G_DQS_DP(13)    I66 @BASEBOARD_FAB2_LIB.BASEBOARD_FAB2(SCH_1):PAGE77
   111 M_G_DQS_DN<14> @BASEBOARD_FAB2_LIB.BASEBOARD_FAB2(SCH_1):M_G_DQS_DN(14)    I66 @BASEBOARD_FAB2_LIB.BASEBOARD_FAB2(SCH_1):PAGE77
   110 M_G_DQS_DP<14> @BASEBOARD_FAB2_LIB.BASEBOARD_FAB2(SCH_1):M_G_DQS_DP(14)    I66 @BASEBOARD_FAB2_LIB.BASEBOARD_FAB2(SCH_1):PAGE77
   122 M_G_DQS_DN<15> @BASEBOARD_FAB2_LIB.BASEBOARD_FAB2(SCH_1):M_G_DQS_DN(15)    I66 @BASEBOARD_FAB2_LIB.BASEBOARD_FAB2(SCH_1):PAGE77
   121 M_G_DQS_DP<15> @BASEBOARD_FAB2_LIB.BASEBOARD_FAB2(SCH_1):M_G_DQS_DP(15)    I66 @BASEBOARD_FAB2_LIB.BASEBOARD_FAB2(SCH_1):PAGE77
   133 M_G_DQS_DN<16> @BASEBOARD_FAB2_LIB.BASEBOARD_FAB2(SCH_1):M_G_DQS_DN(16)    I66 @BASEBOARD_FAB2_LIB.BASEBOARD_FAB2(SCH_1):PAGE77
   132 M_G_DQS_DP<16> @BASEBOARD_FAB2_LIB.BASEBOARD_FAB2(SCH_1):M_G_DQS_DP(16)    I66 @BASEBOARD_FAB2_LIB.BASEBOARD_FAB2(SCH_1):PAGE77
    52 M_G_DQS_DN<17> @BASEBOARD_FAB2_LIB.BASEBOARD_FAB2(SCH_1):M_G_DQS_DN(17)    I66 @BASEBOARD_FAB2_LIB.BASEBOARD_FAB2(SCH_1):PAGE77
    51 M_G_DQS_DP<17> @BASEBOARD_FAB2_LIB.BASEBOARD_FAB2(SCH_1):M_G_DQS_DP(17)    I66 @BASEBOARD_FAB2_LIB.BASEBOARD_FAB2(SCH_1):PAGE77
   163 M_G_DQS_DN<1> @BASEBOARD_FAB2_LIB.BASEBOARD_FAB2(SCH_1):M_G_DQS_DN(1)    I66 @BASEBOARD_FAB2_LIB.BASEBOARD_FAB2(SCH_1):PAGE77
   164 M_G_DQS_DP<1> @BASEBOARD_FAB2_LIB.BASEBOARD_FAB2(SCH_1):M_G_DQS_DP(1)    I66 @BASEBOARD_FAB2_LIB.BASEBOARD_FAB2(SCH_1):PAGE77
   174 M_G_DQS_DN<2> @BASEBOARD_FAB2_LIB.BASEBOARD_FAB2(SCH_1):M_G_DQS_DN(2)    I66 @BASEBOARD_FAB2_LIB.BASEBOARD_FAB2(SCH_1):PAGE77
   175 M_G_DQS_DP<2> @BASEBOARD_FAB2_LIB.BASEBOARD_FAB2(SCH_1):M_G_DQS_DP(2)    I66 @BASEBOARD_FAB2_LIB.BASEBOARD_FAB2(SCH_1):PAGE77
   185 M_G_DQS_DN<3> @BASEBOARD_FAB2_LIB.BASEBOARD_FAB2(SCH_1):M_G_DQS_DN(3)    I66 @BASEBOARD_FAB2_LIB.BASEBOARD_FAB2(SCH_1):PAGE77
   186 M_G_DQS_DP<3> @BASEBOARD_FAB2_LIB.BASEBOARD_FAB2(SCH_1):M_G_DQS_DP(3)    I66 @BASEBOARD_FAB2_LIB.BASEBOARD_FAB2(SCH_1):PAGE77
   244 M_G_DQS_DN<4> @BASEBOARD_FAB2_LIB.BASEBOARD_FAB2(SCH_1):M_G_DQS_DN(4)    I66 @BASEBOARD_FAB2_LIB.BASEBOARD_FAB2(SCH_1):PAGE77
   245 M_G_DQS_DP<4> @BASEBOARD_FAB2_LIB.BASEBOARD_FAB2(SCH_1):M_G_DQS_DP(4)    I66 @BASEBOARD_FAB2_LIB.BASEBOARD_FAB2(SCH_1):PAGE77
   255 M_G_DQS_DN<5> @BASEBOARD_FAB2_LIB.BASEBOARD_FAB2(SCH_1):M_G_DQS_DN(5)    I66 @BASEBOARD_FAB2_LIB.BASEBOARD_FAB2(SCH_1):PAGE77
   256 M_G_DQS_DP<5> @BASEBOARD_FAB2_LIB.BASEBOARD_FAB2(SCH_1):M_G_DQS_DP(5)    I66 @BASEBOARD_FAB2_LIB.BASEBOARD_FAB2(SCH_1):PAGE77
   266 M_G_DQS_DN<6> @BASEBOARD_FAB2_LIB.BASEBOARD_FAB2(SCH_1):M_G_DQS_DN(6)    I66 @BASEBOARD_FAB2_LIB.BASEBOARD_FAB2(SCH_1):PAGE77
   267 M_G_DQS_DP<6> @BASEBOARD_FAB2_LIB.BASEBOARD_FAB2(SCH_1):M_G_DQS_DP(6)    I66 @BASEBOARD_FAB2_LIB.BASEBOARD_FAB2(SCH_1):PAGE77
   277 M_G_DQS_DN<7> @BASEBOARD_FAB2_LIB.BASEBOARD_FAB2(SCH_1):M_G_DQS_DN(7)    I66 @BASEBOARD_FAB2_LIB.BASEBOARD_FAB2(SCH_1):PAGE77
   278 M_G_DQS_DP<7> @BASEBOARD_FAB2_LIB.BASEBOARD_FAB2(SCH_1):M_G_DQS_DP(7)    I66 @BASEBOARD_FAB2_LIB.BASEBOARD_FAB2(SCH_1):PAGE77
   196 M_G_DQS_DN<8> @BASEBOARD_FAB2_LIB.BASEBOARD_FAB2(SCH_1):M_G_DQS_DN(8)    I66 @BASEBOARD_FAB2_LIB.BASEBOARD_FAB2(SCH_1):PAGE77
   197 M_G_DQS_DP<8> @BASEBOARD_FAB2_LIB.BASEBOARD_FAB2(SCH_1):M_G_DQS_DP(8)    I66 @BASEBOARD_FAB2_LIB.BASEBOARD_FAB2(SCH_1):PAGE77
     8 M_G_DQS_DN<9> @BASEBOARD_FAB2_LIB.BASEBOARD_FAB2(SCH_1):M_G_DQS_DN(9)    I66 @BASEBOARD_FAB2_LIB.BASEBOARD_FAB2(SCH_1):PAGE77
     7 M_G_DQS_DP<9> @BASEBOARD_FAB2_LIB.BASEBOARD_FAB2(SCH_1):M_G_DQS_DP(9)    I66 @BASEBOARD_FAB2_LIB.BASEBOARD_FAB2(SCH_1):PAGE77
     2    GND @BASEBOARD_FAB2_LIB.BASEBOARD_FAB2(SCH_1):GND    I43 @BASEBOARD_FAB2_LIB.BASEBOARD_FAB2(SCH_1):PAGE77
     4    GND @BASEBOARD_FAB2_LIB.BASEBOARD_FAB2(SCH_1):GND    I43 @BASEBOARD_FAB2_LIB.BASEBOARD_FAB2(SCH_1):PAGE77
     6    GND @BASEBOARD_FAB2_LIB.BASEBOARD_FAB2(SCH_1):GND    I43 @BASEBOARD_FAB2_LIB.BASEBOARD_FAB2(SCH_1):PAGE77
     9    GND @BASEBOARD_FAB2_LIB.BASEBOARD_FAB2(SCH_1):GND    I43 @BASEBOARD_FAB2_LIB.BASEBOARD_FAB2(SCH_1):PAGE77
    11    GND @BASEBOARD_FAB2_LIB.BASEBOARD_FAB2(SCH_1):GND    I43 @BASEBOARD_FAB2_LIB.BASEBOARD_FAB2(SCH_1):PAGE77
    13    GND @BASEBOARD_FAB2_LIB.BASEBOARD_FAB2(SCH_1):GND    I43 @BASEBOARD_FAB2_LIB.BASEBOARD_FAB2(SCH_1):PAGE77
    15    GND @BASEBOARD_FAB2_LIB.BASEBOARD_FAB2(SCH_1):GND    I43 @BASEBOARD_FAB2_LIB.BASEBOARD_FAB2(SCH_1):PAGE77
    17    GND @BASEBOARD_FAB2_LIB.BASEBOARD_FAB2(SCH_1):GND    I43 @BASEBOARD_FAB2_LIB.BASEBOARD_FAB2(SCH_1):PAGE77
    20    GND @BASEBOARD_FAB2_LIB.BASEBOARD_FAB2(SCH_1):GND    I43 @BASEBOARD_FAB2_LIB.BASEBOARD_FAB2(SCH_1):PAGE77
    22    GND @BASEBOARD_FAB2_LIB.BASEBOARD_FAB2(SCH_1):GND    I43 @BASEBOARD_FAB2_LIB.BASEBOARD_FAB2(SCH_1):PAGE77
    24    GND @BASEBOARD_FAB2_LIB.BASEBOARD_FAB2(SCH_1):GND    I43 @BASEBOARD_FAB2_LIB.BASEBOARD_FAB2(SCH_1):PAGE77
    26    GND @BASEBOARD_FAB2_LIB.BASEBOARD_FAB2(SCH_1):GND    I43 @BASEBOARD_FAB2_LIB.BASEBOARD_FAB2(SCH_1):PAGE77
    28    GND @BASEBOARD_FAB2_LIB.BASEBOARD_FAB2(SCH_1):GND    I43 @BASEBOARD_FAB2_LIB.BASEBOARD_FAB2(SCH_1):PAGE77
    31    GND @BASEBOARD_FAB2_LIB.BASEBOARD_FAB2(SCH_1):GND    I43 @BASEBOARD_FAB2_LIB.BASEBOARD_FAB2(SCH_1):PAGE77
    33    GND @BASEBOARD_FAB2_LIB.BASEBOARD_FAB2(SCH_1):GND    I43 @BASEBOARD_FAB2_LIB.BASEBOARD_FAB2(SCH_1):PAGE77
    35    GND @BASEBOARD_FAB2_LIB.BASEBOARD_FAB2(SCH_1):GND    I43 @BASEBOARD_FAB2_LIB.BASEBOARD_FAB2(SCH_1):PAGE77
    37    GND @BASEBOARD_FAB2_LIB.BASEBOARD_FAB2(SCH_1):GND    I43 @BASEBOARD_FAB2_LIB.BASEBOARD_FAB2(SCH_1):PAGE77
    39    GND @BASEBOARD_FAB2_LIB.BASEBOARD_FAB2(SCH_1):GND    I43 @BASEBOARD_FAB2_LIB.BASEBOARD_FAB2(SCH_1):PAGE77
    42    GND @BASEBOARD_FAB2_LIB.BASEBOARD_FAB2(SCH_1):GND    I43 @BASEBOARD_FAB2_LIB.BASEBOARD_FAB2(SCH_1):PAGE77
    44    GND @BASEBOARD_FAB2_LIB.BASEBOARD_FAB2(SCH_1):GND    I43 @BASEBOARD_FAB2_LIB.BASEBOARD_FAB2(SCH_1):PAGE77
    46    GND @BASEBOARD_FAB2_LIB.BASEBOARD_FAB2(SCH_1):GND    I43 @BASEBOARD_FAB2_LIB.BASEBOARD_FAB2(SCH_1):PAGE77
    48    GND @BASEBOARD_FAB2_LIB.BASEBOARD_FAB2(SCH_1):GND    I43 @BASEBOARD_FAB2_LIB.BASEBOARD_FAB2(SCH_1):PAGE77
    50    GND @BASEBOARD_FAB2_LIB.BASEBOARD_FAB2(SCH_1):GND    I43 @BASEBOARD_FAB2_LIB.BASEBOARD_FAB2(SCH_1):PAGE77
    53    GND @BASEBOARD_FAB2_LIB.BASEBOARD_FAB2(SCH_1):GND    I43 @BASEBOARD_FAB2_LIB.BASEBOARD_FAB2(SCH_1):PAGE77
    55    GND @BASEBOARD_FAB2_LIB.BASEBOARD_FAB2(SCH_1):GND    I43 @BASEBOARD_FAB2_LIB.BASEBOARD_FAB2(SCH_1):PAGE77
    57    GND @BASEBOARD_FAB2_LIB.BASEBOARD_FAB2(SCH_1):GND    I43 @BASEBOARD_FAB2_LIB.BASEBOARD_FAB2(SCH_1):PAGE77
    94    GND @BASEBOARD_FAB2_LIB.BASEBOARD_FAB2(SCH_1):GND    I43 @BASEBOARD_FAB2_LIB.BASEBOARD_FAB2(SCH_1):PAGE77
    96    GND @BASEBOARD_FAB2_LIB.BASEBOARD_FAB2(SCH_1):GND    I43 @BASEBOARD_FAB2_LIB.BASEBOARD_FAB2(SCH_1):PAGE77
    98    GND @BASEBOARD_FAB2_LIB.BASEBOARD_FAB2(SCH_1):GND    I43 @BASEBOARD_FAB2_LIB.BASEBOARD_FAB2(SCH_1):PAGE77
   101    GND @BASEBOARD_FAB2_LIB.BASEBOARD_FAB2(SCH_1):GND    I43 @BASEBOARD_FAB2_LIB.BASEBOARD_FAB2(SCH_1):PAGE77
   103    GND @BASEBOARD_FAB2_LIB.BASEBOARD_FAB2(SCH_1):GND    I43 @BASEBOARD_FAB2_LIB.BASEBOARD_FAB2(SCH_1):PAGE77
   105    GND @BASEBOARD_FAB2_LIB.BASEBOARD_FAB2(SCH_1):GND    I43 @BASEBOARD_FAB2_LIB.BASEBOARD_FAB2(SCH_1):PAGE77
   107    GND @BASEBOARD_FAB2_LIB.BASEBOARD_FAB2(SCH_1):GND    I43 @BASEBOARD_FAB2_LIB.BASEBOARD_FAB2(SCH_1):PAGE77
   109    GND @BASEBOARD_FAB2_LIB.BASEBOARD_FAB2(SCH_1):GND    I43 @BASEBOARD_FAB2_LIB.BASEBOARD_FAB2(SCH_1):PAGE77
   112    GND @BASEBOARD_FAB2_LIB.BASEBOARD_FAB2(SCH_1):GND    I43 @BASEBOARD_FAB2_LIB.BASEBOARD_FAB2(SCH_1):PAGE77
   114    GND @BASEBOARD_FAB2_LIB.BASEBOARD_FAB2(SCH_1):GND    I43 @BASEBOARD_FAB2_LIB.BASEBOARD_FAB2(SCH_1):PAGE77
   116    GND @BASEBOARD_FAB2_LIB.BASEBOARD_FAB2(SCH_1):GND    I43 @BASEBOARD_FAB2_LIB.BASEBOARD_FAB2(SCH_1):PAGE77
   118    GND @BASEBOARD_FAB2_LIB.BASEBOARD_FAB2(SCH_1):GND    I43 @BASEBOARD_FAB2_LIB.BASEBOARD_FAB2(SCH_1):PAGE77
   120    GND @BASEBOARD_FAB2_LIB.BASEBOARD_FAB2(SCH_1):GND    I43 @BASEBOARD_FAB2_LIB.BASEBOARD_FAB2(SCH_1):PAGE77
   123    GND @BASEBOARD_FAB2_LIB.BASEBOARD_FAB2(SCH_1):GND    I43 @BASEBOARD_FAB2_LIB.BASEBOARD_FAB2(SCH_1):PAGE77
   125    GND @BASEBOARD_FAB2_LIB.BASEBOARD_FAB2(SCH_1):GND    I43 @BASEBOARD_FAB2_LIB.BASEBOARD_FAB2(SCH_1):PAGE77
   127    GND @BASEBOARD_FAB2_LIB.BASEBOARD_FAB2(SCH_1):GND    I43 @BASEBOARD_FAB2_LIB.BASEBOARD_FAB2(SCH_1):PAGE77
   129    GND @BASEBOARD_FAB2_LIB.BASEBOARD_FAB2(SCH_1):GND    I43 @BASEBOARD_FAB2_LIB.BASEBOARD_FAB2(SCH_1):PAGE77
   131    GND @BASEBOARD_FAB2_LIB.BASEBOARD_FAB2(SCH_1):GND    I43 @BASEBOARD_FAB2_LIB.BASEBOARD_FAB2(SCH_1):PAGE77
   134    GND @BASEBOARD_FAB2_LIB.BASEBOARD_FAB2(SCH_1):GND    I43 @BASEBOARD_FAB2_LIB.BASEBOARD_FAB2(SCH_1):PAGE77
   136    GND @BASEBOARD_FAB2_LIB.BASEBOARD_FAB2(SCH_1):GND    I43 @BASEBOARD_FAB2_LIB.BASEBOARD_FAB2(SCH_1):PAGE77
   138    GND @BASEBOARD_FAB2_LIB.BASEBOARD_FAB2(SCH_1):GND    I43 @BASEBOARD_FAB2_LIB.BASEBOARD_FAB2(SCH_1):PAGE77
   147    GND @BASEBOARD_FAB2_LIB.BASEBOARD_FAB2(SCH_1):GND    I43 @BASEBOARD_FAB2_LIB.BASEBOARD_FAB2(SCH_1):PAGE77
   149    GND @BASEBOARD_FAB2_LIB.BASEBOARD_FAB2(SCH_1):GND    I43 @BASEBOARD_FAB2_LIB.BASEBOARD_FAB2(SCH_1):PAGE77
   151    GND @BASEBOARD_FAB2_LIB.BASEBOARD_FAB2(SCH_1):GND    I43 @BASEBOARD_FAB2_LIB.BASEBOARD_FAB2(SCH_1):PAGE77
   154    GND @BASEBOARD_FAB2_LIB.BASEBOARD_FAB2(SCH_1):GND    I43 @BASEBOARD_FAB2_LIB.BASEBOARD_FAB2(SCH_1):PAGE77
   156    GND @BASEBOARD_FAB2_LIB.BASEBOARD_FAB2(SCH_1):GND    I43 @BASEBOARD_FAB2_LIB.BASEBOARD_FAB2(SCH_1):PAGE77
   158    GND @BASEBOARD_FAB2_LIB.BASEBOARD_FAB2(SCH_1):GND    I43 @BASEBOARD_FAB2_LIB.BASEBOARD_FAB2(SCH_1):PAGE77
   160    GND @BASEBOARD_FAB2_LIB.BASEBOARD_FAB2(SCH_1):GND    I43 @BASEBOARD_FAB2_LIB.BASEBOARD_FAB2(SCH_1):PAGE77
   162    GND @BASEBOARD_FAB2_LIB.BASEBOARD_FAB2(SCH_1):GND    I43 @BASEBOARD_FAB2_LIB.BASEBOARD_FAB2(SCH_1):PAGE77
   165    GND @BASEBOARD_FAB2_LIB.BASEBOARD_FAB2(SCH_1):GND    I43 @BASEBOARD_FAB2_LIB.BASEBOARD_FAB2(SCH_1):PAGE77
   167    GND @BASEBOARD_FAB2_LIB.BASEBOARD_FAB2(SCH_1):GND    I43 @BASEBOARD_FAB2_LIB.BASEBOARD_FAB2(SCH_1):PAGE77
   169    GND @BASEBOARD_FAB2_LIB.BASEBOARD_FAB2(SCH_1):GND    I43 @BASEBOARD_FAB2_LIB.BASEBOARD_FAB2(SCH_1):PAGE77
   171    GND @BASEBOARD_FAB2_LIB.BASEBOARD_FAB2(SCH_1):GND    I43 @BASEBOARD_FAB2_LIB.BASEBOARD_FAB2(SCH_1):PAGE77
   173    GND @BASEBOARD_FAB2_LIB.BASEBOARD_FAB2(SCH_1):GND    I43 @BASEBOARD_FAB2_LIB.BASEBOARD_FAB2(SCH_1):PAGE77
   176    GND @BASEBOARD_FAB2_LIB.BASEBOARD_FAB2(SCH_1):GND    I43 @BASEBOARD_FAB2_LIB.BASEBOARD_FAB2(SCH_1):PAGE77
   178    GND @BASEBOARD_FAB2_LIB.BASEBOARD_FAB2(SCH_1):GND    I43 @BASEBOARD_FAB2_LIB.BASEBOARD_FAB2(SCH_1):PAGE77
   180    GND @BASEBOARD_FAB2_LIB.BASEBOARD_FAB2(SCH_1):GND    I43 @BASEBOARD_FAB2_LIB.BASEBOARD_FAB2(SCH_1):PAGE77
   182    GND @BASEBOARD_FAB2_LIB.BASEBOARD_FAB2(SCH_1):GND    I43 @BASEBOARD_FAB2_LIB.BASEBOARD_FAB2(SCH_1):PAGE77
   184    GND @BASEBOARD_FAB2_LIB.BASEBOARD_FAB2(SCH_1):GND    I43 @BASEBOARD_FAB2_LIB.BASEBOARD_FAB2(SCH_1):PAGE77
   187    GND @BASEBOARD_FAB2_LIB.BASEBOARD_FAB2(SCH_1):GND    I43 @BASEBOARD_FAB2_LIB.BASEBOARD_FAB2(SCH_1):PAGE77
   189    GND @BASEBOARD_FAB2_LIB.BASEBOARD_FAB2(SCH_1):GND    I43 @BASEBOARD_FAB2_LIB.BASEBOARD_FAB2(SCH_1):PAGE77
   191    GND @BASEBOARD_FAB2_LIB.BASEBOARD_FAB2(SCH_1):GND    I43 @BASEBOARD_FAB2_LIB.BASEBOARD_FAB2(SCH_1):PAGE77
   193    GND @BASEBOARD_FAB2_LIB.BASEBOARD_FAB2(SCH_1):GND    I43 @BASEBOARD_FAB2_LIB.BASEBOARD_FAB2(SCH_1):PAGE77
   195    GND @BASEBOARD_FAB2_LIB.BASEBOARD_FAB2(SCH_1):GND    I43 @BASEBOARD_FAB2_LIB.BASEBOARD_FAB2(SCH_1):PAGE77
   198    GND @BASEBOARD_FAB2_LIB.BASEBOARD_FAB2(SCH_1):GND    I43 @BASEBOARD_FAB2_LIB.BASEBOARD_FAB2(SCH_1):PAGE77
   200    GND @BASEBOARD_FAB2_LIB.BASEBOARD_FAB2(SCH_1):GND    I43 @BASEBOARD_FAB2_LIB.BASEBOARD_FAB2(SCH_1):PAGE77
   202    GND @BASEBOARD_FAB2_LIB.BASEBOARD_FAB2(SCH_1):GND    I43 @BASEBOARD_FAB2_LIB.BASEBOARD_FAB2(SCH_1):PAGE77
   239    GND @BASEBOARD_FAB2_LIB.BASEBOARD_FAB2(SCH_1):GND    I43 @BASEBOARD_FAB2_LIB.BASEBOARD_FAB2(SCH_1):PAGE77
   241    GND @BASEBOARD_FAB2_LIB.BASEBOARD_FAB2(SCH_1):GND    I43 @BASEBOARD_FAB2_LIB.BASEBOARD_FAB2(SCH_1):PAGE77
   243    GND @BASEBOARD_FAB2_LIB.BASEBOARD_FAB2(SCH_1):GND    I43 @BASEBOARD_FAB2_LIB.BASEBOARD_FAB2(SCH_1):PAGE77
   246    GND @BASEBOARD_FAB2_LIB.BASEBOARD_FAB2(SCH_1):GND    I43 @BASEBOARD_FAB2_LIB.BASEBOARD_FAB2(SCH_1):PAGE77
   248    GND @BASEBOARD_FAB2_LIB.BASEBOARD_FAB2(SCH_1):GND    I43 @BASEBOARD_FAB2_LIB.BASEBOARD_FAB2(SCH_1):PAGE77
   250    GND @BASEBOARD_FAB2_LIB.BASEBOARD_FAB2(SCH_1):GND    I43 @BASEBOARD_FAB2_LIB.BASEBOARD_FAB2(SCH_1):PAGE77
   252    GND @BASEBOARD_FAB2_LIB.BASEBOARD_FAB2(SCH_1):GND    I43 @BASEBOARD_FAB2_LIB.BASEBOARD_FAB2(SCH_1):PAGE77
   254    GND @BASEBOARD_FAB2_LIB.BASEBOARD_FAB2(SCH_1):GND    I43 @BASEBOARD_FAB2_LIB.BASEBOARD_FAB2(SCH_1):PAGE77
   257    GND @BASEBOARD_FAB2_LIB.BASEBOARD_FAB2(SCH_1):GND    I43 @BASEBOARD_FAB2_LIB.BASEBOARD_FAB2(SCH_1):PAGE77
   259    GND @BASEBOARD_FAB2_LIB.BASEBOARD_FAB2(SCH_1):GND    I43 @BASEBOARD_FAB2_LIB.BASEBOARD_FAB2(SCH_1):PAGE77
   261    GND @BASEBOARD_FAB2_LIB.BASEBOARD_FAB2(SCH_1):GND    I43 @BASEBOARD_FAB2_LIB.BASEBOARD_FAB2(SCH_1):PAGE77
   263    GND @BASEBOARD_FAB2_LIB.BASEBOARD_FAB2(SCH_1):GND    I43 @BASEBOARD_FAB2_LIB.BASEBOARD_FAB2(SCH_1):PAGE77
   265    GND @BASEBOARD_FAB2_LIB.BASEBOARD_FAB2(SCH_1):GND    I43 @BASEBOARD_FAB2_LIB.BASEBOARD_FAB2(SCH_1):PAGE77
   268    GND @BASEBOARD_FAB2_LIB.BASEBOARD_FAB2(SCH_1):GND    I43 @BASEBOARD_FAB2_LIB.BASEBOARD_FAB2(SCH_1):PAGE77
   270    GND @BASEBOARD_FAB2_LIB.BASEBOARD_FAB2(SCH_1):GND    I43 @BASEBOARD_FAB2_LIB.BASEBOARD_FAB2(SCH_1):PAGE77
   272    GND @BASEBOARD_FAB2_LIB.BASEBOARD_FAB2(SCH_1):GND    I43 @BASEBOARD_FAB2_LIB.BASEBOARD_FAB2(SCH_1):PAGE77
   274    GND @BASEBOARD_FAB2_LIB.BASEBOARD_FAB2(SCH_1):GND    I43 @BASEBOARD_FAB2_LIB.BASEBOARD_FAB2(SCH_1):PAGE77
   276    GND @BASEBOARD_FAB2_LIB.BASEBOARD_FAB2(SCH_1):GND    I43 @BASEBOARD_FAB2_LIB.BASEBOARD_FAB2(SCH_1):PAGE77
   279    GND @BASEBOARD_FAB2_LIB.BASEBOARD_FAB2(SCH_1):GND    I43 @BASEBOARD_FAB2_LIB.BASEBOARD_FAB2(SCH_1):PAGE77
   281    GND @BASEBOARD_FAB2_LIB.BASEBOARD_FAB2(SCH_1):GND    I43 @BASEBOARD_FAB2_LIB.BASEBOARD_FAB2(SCH_1):PAGE77
   283    GND @BASEBOARD_FAB2_LIB.BASEBOARD_FAB2(SCH_1):GND    I43 @BASEBOARD_FAB2_LIB.BASEBOARD_FAB2(SCH_1):PAGE77
     1 P12V_NVDIMM_GHJ @BASEBOARD_FAB2_LIB.BASEBOARD_FAB2(SCH_1):P12V_NVDIMM_GHJ   I171 @BASEBOARD_FAB2_LIB.BASEBOARD_FAB2(SCH_1):PAGE77
   145 P12V_NVDIMM_GHJ @BASEBOARD_FAB2_LIB.BASEBOARD_FAB2(SCH_1):P12V_NVDIMM_GHJ   I171 @BASEBOARD_FAB2_LIB.BASEBOARD_FAB2(SCH_1):PAGE77
    59 PVDDQ_GHJ @BASEBOARD_FAB2_LIB.BASEBOARD_FAB2(SCH_1):PVDDQ_GHJ   I171 @BASEBOARD_FAB2_LIB.BASEBOARD_FAB2(SCH_1):PAGE77
    61 PVDDQ_GHJ @BASEBOARD_FAB2_LIB.BASEBOARD_FAB2(SCH_1):PVDDQ_GHJ   I171 @BASEBOARD_FAB2_LIB.BASEBOARD_FAB2(SCH_1):PAGE77
    64 PVDDQ_GHJ @BASEBOARD_FAB2_LIB.BASEBOARD_FAB2(SCH_1):PVDDQ_GHJ   I171 @BASEBOARD_FAB2_LIB.BASEBOARD_FAB2(SCH_1):PAGE77
    67 PVDDQ_GHJ @BASEBOARD_FAB2_LIB.BASEBOARD_FAB2(SCH_1):PVDDQ_GHJ   I171 @BASEBOARD_FAB2_LIB.BASEBOARD_FAB2(SCH_1):PAGE77
    70 PVDDQ_GHJ @BASEBOARD_FAB2_LIB.BASEBOARD_FAB2(SCH_1):PVDDQ_GHJ   I171 @BASEBOARD_FAB2_LIB.BASEBOARD_FAB2(SCH_1):PAGE77
    73 PVDDQ_GHJ @BASEBOARD_FAB2_LIB.BASEBOARD_FAB2(SCH_1):PVDDQ_GHJ   I171 @BASEBOARD_FAB2_LIB.BASEBOARD_FAB2(SCH_1):PAGE77
    76 PVDDQ_GHJ @BASEBOARD_FAB2_LIB.BASEBOARD_FAB2(SCH_1):PVDDQ_GHJ   I171 @BASEBOARD_FAB2_LIB.BASEBOARD_FAB2(SCH_1):PAGE77
    80 PVDDQ_GHJ @BASEBOARD_FAB2_LIB.BASEBOARD_FAB2(SCH_1):PVDDQ_GHJ   I171 @BASEBOARD_FAB2_LIB.BASEBOARD_FAB2(SCH_1):PAGE77
    83 PVDDQ_GHJ @BASEBOARD_FAB2_LIB.BASEBOARD_FAB2(SCH_1):PVDDQ_GHJ   I171 @BASEBOARD_FAB2_LIB.BASEBOARD_FAB2(SCH_1):PAGE77
    85 PVDDQ_GHJ @BASEBOARD_FAB2_LIB.BASEBOARD_FAB2(SCH_1):PVDDQ_GHJ   I171 @BASEBOARD_FAB2_LIB.BASEBOARD_FAB2(SCH_1):PAGE77
    88 PVDDQ_GHJ @BASEBOARD_FAB2_LIB.BASEBOARD_FAB2(SCH_1):PVDDQ_GHJ   I171 @BASEBOARD_FAB2_LIB.BASEBOARD_FAB2(SCH_1):PAGE77
    90 PVDDQ_GHJ @BASEBOARD_FAB2_LIB.BASEBOARD_FAB2(SCH_1):PVDDQ_GHJ   I171 @BASEBOARD_FAB2_LIB.BASEBOARD_FAB2(SCH_1):PAGE77
    92 PVDDQ_GHJ @BASEBOARD_FAB2_LIB.BASEBOARD_FAB2(SCH_1):PVDDQ_GHJ   I171 @BASEBOARD_FAB2_LIB.BASEBOARD_FAB2(SCH_1):PAGE77
   204 PVDDQ_GHJ @BASEBOARD_FAB2_LIB.BASEBOARD_FAB2(SCH_1):PVDDQ_GHJ   I171 @BASEBOARD_FAB2_LIB.BASEBOARD_FAB2(SCH_1):PAGE77
   206 PVDDQ_GHJ @BASEBOARD_FAB2_LIB.BASEBOARD_FAB2(SCH_1):PVDDQ_GHJ   I171 @BASEBOARD_FAB2_LIB.BASEBOARD_FAB2(SCH_1):PAGE77
   209 PVDDQ_GHJ @BASEBOARD_FAB2_LIB.BASEBOARD_FAB2(SCH_1):PVDDQ_GHJ   I171 @BASEBOARD_FAB2_LIB.BASEBOARD_FAB2(SCH_1):PAGE77
   212 PVDDQ_GHJ @BASEBOARD_FAB2_LIB.BASEBOARD_FAB2(SCH_1):PVDDQ_GHJ   I171 @BASEBOARD_FAB2_LIB.BASEBOARD_FAB2(SCH_1):PAGE77
   215 PVDDQ_GHJ @BASEBOARD_FAB2_LIB.BASEBOARD_FAB2(SCH_1):PVDDQ_GHJ   I171 @BASEBOARD_FAB2_LIB.BASEBOARD_FAB2(SCH_1):PAGE77
   217 PVDDQ_GHJ @BASEBOARD_FAB2_LIB.BASEBOARD_FAB2(SCH_1):PVDDQ_GHJ   I171 @BASEBOARD_FAB2_LIB.BASEBOARD_FAB2(SCH_1):PAGE77
   220 PVDDQ_GHJ @BASEBOARD_FAB2_LIB.BASEBOARD_FAB2(SCH_1):PVDDQ_GHJ   I171 @BASEBOARD_FAB2_LIB.BASEBOARD_FAB2(SCH_1):PAGE77
   223 PVDDQ_GHJ @BASEBOARD_FAB2_LIB.BASEBOARD_FAB2(SCH_1):PVDDQ_GHJ   I171 @BASEBOARD_FAB2_LIB.BASEBOARD_FAB2(SCH_1):PAGE77
   226 PVDDQ_GHJ @BASEBOARD_FAB2_LIB.BASEBOARD_FAB2(SCH_1):PVDDQ_GHJ   I171 @BASEBOARD_FAB2_LIB.BASEBOARD_FAB2(SCH_1):PAGE77
   229 PVDDQ_GHJ @BASEBOARD_FAB2_LIB.BASEBOARD_FAB2(SCH_1):PVDDQ_GHJ   I171 @BASEBOARD_FAB2_LIB.BASEBOARD_FAB2(SCH_1):PAGE77
   231 PVDDQ_GHJ @BASEBOARD_FAB2_LIB.BASEBOARD_FAB2(SCH_1):PVDDQ_GHJ   I171 @BASEBOARD_FAB2_LIB.BASEBOARD_FAB2(SCH_1):PAGE77
   233 PVDDQ_GHJ @BASEBOARD_FAB2_LIB.BASEBOARD_FAB2(SCH_1):PVDDQ_GHJ   I171 @BASEBOARD_FAB2_LIB.BASEBOARD_FAB2(SCH_1):PAGE77
   236 PVDDQ_GHJ @BASEBOARD_FAB2_LIB.BASEBOARD_FAB2(SCH_1):PVDDQ_GHJ   I171 @BASEBOARD_FAB2_LIB.BASEBOARD_FAB2(SCH_1):PAGE77
   142 PVPP_GHJ @BASEBOARD_FAB2_LIB.BASEBOARD_FAB2(SCH_1):PVPP_GHJ   I171 @BASEBOARD_FAB2_LIB.BASEBOARD_FAB2(SCH_1):PAGE77
   143 PVPP_GHJ @BASEBOARD_FAB2_LIB.BASEBOARD_FAB2(SCH_1):PVPP_GHJ   I171 @BASEBOARD_FAB2_LIB.BASEBOARD_FAB2(SCH_1):PAGE77
   288 PVPP_GHJ @BASEBOARD_FAB2_LIB.BASEBOARD_FAB2(SCH_1):PVPP_GHJ   I171 @BASEBOARD_FAB2_LIB.BASEBOARD_FAB2(SCH_1):PAGE77
   286 PVPP_GHJ @BASEBOARD_FAB2_LIB.BASEBOARD_FAB2(SCH_1):PVPP_GHJ   I171 @BASEBOARD_FAB2_LIB.BASEBOARD_FAB2(SCH_1):PAGE77
   287 PVPP_GHJ @BASEBOARD_FAB2_LIB.BASEBOARD_FAB2(SCH_1):PVPP_GHJ   I171 @BASEBOARD_FAB2_LIB.BASEBOARD_FAB2(SCH_1):PAGE77
    77 PVTT_GHJ @BASEBOARD_FAB2_LIB.BASEBOARD_FAB2(SCH_1):PVTT_GHJ   I171 @BASEBOARD_FAB2_LIB.BASEBOARD_FAB2(SCH_1):PAGE77
   221 PVTT_GHJ @BASEBOARD_FAB2_LIB.BASEBOARD_FAB2(SCH_1):PVTT_GHJ   I171 @BASEBOARD_FAB2_LIB.BASEBOARD_FAB2(SCH_1):PAGE77

J1G2 SCONN288_H44441004_PIP-SCONN,HA
    79 M_H_MA<0> @BASEBOARD_FAB2_LIB.BASEBOARD_FAB2(SCH_1):M_H_MA(0)   I111 @BASEBOARD_FAB2_LIB.BASEBOARD_FAB2(SCH_1):PAGE79
    72 M_H_MA<1> @BASEBOARD_FAB2_LIB.BASEBOARD_FAB2(SCH_1):M_H_MA(1)   I111 @BASEBOARD_FAB2_LIB.BASEBOARD_FAB2(SCH_1):PAGE79
   225 M_H_MA<10> @BASEBOARD_FAB2_LIB.BASEBOARD_FAB2(SCH_1):M_H_MA(10)   I111 @BASEBOARD_FAB2_LIB.BASEBOARD_FAB2(SCH_1):PAGE79
   210 M_H_MA<11> @BASEBOARD_FAB2_LIB.BASEBOARD_FAB2(SCH_1):M_H_MA(11)   I111 @BASEBOARD_FAB2_LIB.BASEBOARD_FAB2(SCH_1):PAGE79
    65 M_H_MA<12> @BASEBOARD_FAB2_LIB.BASEBOARD_FAB2(SCH_1):M_H_MA(12)   I111 @BASEBOARD_FAB2_LIB.BASEBOARD_FAB2(SCH_1):PAGE79
   232 M_H_MA<13> @BASEBOARD_FAB2_LIB.BASEBOARD_FAB2(SCH_1):M_H_MA(13)   I111 @BASEBOARD_FAB2_LIB.BASEBOARD_FAB2(SCH_1):PAGE79
   228 M_H_MA<14> @BASEBOARD_FAB2_LIB.BASEBOARD_FAB2(SCH_1):M_H_MA(14)   I111 @BASEBOARD_FAB2_LIB.BASEBOARD_FAB2(SCH_1):PAGE79
    86 M_H_MA<15> @BASEBOARD_FAB2_LIB.BASEBOARD_FAB2(SCH_1):M_H_MA(15)   I111 @BASEBOARD_FAB2_LIB.BASEBOARD_FAB2(SCH_1):PAGE79
    82 M_H_MA<16> @BASEBOARD_FAB2_LIB.BASEBOARD_FAB2(SCH_1):M_H_MA(16)   I111 @BASEBOARD_FAB2_LIB.BASEBOARD_FAB2(SCH_1):PAGE79
   234 M_H_MA<17> @BASEBOARD_FAB2_LIB.BASEBOARD_FAB2(SCH_1):M_H_MA(17)   I111 @BASEBOARD_FAB2_LIB.BASEBOARD_FAB2(SCH_1):PAGE79
   216 M_H_MA<2> @BASEBOARD_FAB2_LIB.BASEBOARD_FAB2(SCH_1):M_H_MA(2)   I111 @BASEBOARD_FAB2_LIB.BASEBOARD_FAB2(SCH_1):PAGE79
    71 M_H_MA<3> @BASEBOARD_FAB2_LIB.BASEBOARD_FAB2(SCH_1):M_H_MA(3)   I111 @BASEBOARD_FAB2_LIB.BASEBOARD_FAB2(SCH_1):PAGE79
   214 M_H_MA<4> @BASEBOARD_FAB2_LIB.BASEBOARD_FAB2(SCH_1):M_H_MA(4)   I111 @BASEBOARD_FAB2_LIB.BASEBOARD_FAB2(SCH_1):PAGE79
   213 M_H_MA<5> @BASEBOARD_FAB2_LIB.BASEBOARD_FAB2(SCH_1):M_H_MA(5)   I111 @BASEBOARD_FAB2_LIB.BASEBOARD_FAB2(SCH_1):PAGE79
    69 M_H_MA<6> @BASEBOARD_FAB2_LIB.BASEBOARD_FAB2(SCH_1):M_H_MA(6)   I111 @BASEBOARD_FAB2_LIB.BASEBOARD_FAB2(SCH_1):PAGE79
   211 M_H_MA<7> @BASEBOARD_FAB2_LIB.BASEBOARD_FAB2(SCH_1):M_H_MA(7)   I111 @BASEBOARD_FAB2_LIB.BASEBOARD_FAB2(SCH_1):PAGE79
    68 M_H_MA<8> @BASEBOARD_FAB2_LIB.BASEBOARD_FAB2(SCH_1):M_H_MA(8)   I111 @BASEBOARD_FAB2_LIB.BASEBOARD_FAB2(SCH_1):PAGE79
    66 M_H_MA<9> @BASEBOARD_FAB2_LIB.BASEBOARD_FAB2(SCH_1):M_H_MA(9)   I111 @BASEBOARD_FAB2_LIB.BASEBOARD_FAB2(SCH_1):PAGE79
    62 M_H_ACT_N @BASEBOARD_FAB2_LIB.BASEBOARD_FAB2(SCH_1):M_H_ACT_N   I111 @BASEBOARD_FAB2_LIB.BASEBOARD_FAB2(SCH_1):PAGE79
   208 M_H_ALERT_N @BASEBOARD_FAB2_LIB.BASEBOARD_FAB2(SCH_1):M_H_ALERT_N   I111 @BASEBOARD_FAB2_LIB.BASEBOARD_FAB2(SCH_1):PAGE79
   224 M_H_BA<1> @BASEBOARD_FAB2_LIB.BASEBOARD_FAB2(SCH_1):M_H_BA(1)   I111 @BASEBOARD_FAB2_LIB.BASEBOARD_FAB2(SCH_1):PAGE79
    81 M_H_BA<0> @BASEBOARD_FAB2_LIB.BASEBOARD_FAB2(SCH_1):M_H_BA(0)   I111 @BASEBOARD_FAB2_LIB.BASEBOARD_FAB2(SCH_1):PAGE79
   207 M_H_BG<1> @BASEBOARD_FAB2_LIB.BASEBOARD_FAB2(SCH_1):M_H_BG(1)   I111 @BASEBOARD_FAB2_LIB.BASEBOARD_FAB2(SCH_1):PAGE79
    63 M_H_BG<0> @BASEBOARD_FAB2_LIB.BASEBOARD_FAB2(SCH_1):M_H_BG(0)   I111 @BASEBOARD_FAB2_LIB.BASEBOARD_FAB2(SCH_1):PAGE79
   235 M_H_C<2> @BASEBOARD_FAB2_LIB.BASEBOARD_FAB2(SCH_1):M_H_C(2)   I111 @BASEBOARD_FAB2_LIB.BASEBOARD_FAB2(SCH_1):PAGE79
   199 M_H_ECC<6> @BASEBOARD_FAB2_LIB.BASEBOARD_FAB2(SCH_1):M_H_ECC(6)   I111 @BASEBOARD_FAB2_LIB.BASEBOARD_FAB2(SCH_1):PAGE79
    54 M_H_ECC<7> @BASEBOARD_FAB2_LIB.BASEBOARD_FAB2(SCH_1):M_H_ECC(7)   I111 @BASEBOARD_FAB2_LIB.BASEBOARD_FAB2(SCH_1):PAGE79
   192 M_H_ECC<4> @BASEBOARD_FAB2_LIB.BASEBOARD_FAB2(SCH_1):M_H_ECC(4)   I111 @BASEBOARD_FAB2_LIB.BASEBOARD_FAB2(SCH_1):PAGE79
    47 M_H_ECC<5> @BASEBOARD_FAB2_LIB.BASEBOARD_FAB2(SCH_1):M_H_ECC(5)   I111 @BASEBOARD_FAB2_LIB.BASEBOARD_FAB2(SCH_1):PAGE79
   201 M_H_ECC<2> @BASEBOARD_FAB2_LIB.BASEBOARD_FAB2(SCH_1):M_H_ECC(2)   I111 @BASEBOARD_FAB2_LIB.BASEBOARD_FAB2(SCH_1):PAGE79
    56 M_H_ECC<3> @BASEBOARD_FAB2_LIB.BASEBOARD_FAB2(SCH_1):M_H_ECC(3)   I111 @BASEBOARD_FAB2_LIB.BASEBOARD_FAB2(SCH_1):PAGE79
   194 M_H_ECC<0> @BASEBOARD_FAB2_LIB.BASEBOARD_FAB2(SCH_1):M_H_ECC(0)   I111 @BASEBOARD_FAB2_LIB.BASEBOARD_FAB2(SCH_1):PAGE79
    49 M_H_ECC<1> @BASEBOARD_FAB2_LIB.BASEBOARD_FAB2(SCH_1):M_H_ECC(1)   I111 @BASEBOARD_FAB2_LIB.BASEBOARD_FAB2(SCH_1):PAGE79
    75 M_H_CLK_DN<0> @BASEBOARD_FAB2_LIB.BASEBOARD_FAB2(SCH_1):M_H_CLK_DN(0)   I111 @BASEBOARD_FAB2_LIB.BASEBOARD_FAB2(SCH_1):PAGE79
    74 M_H_CLK_DP<0> @BASEBOARD_FAB2_LIB.BASEBOARD_FAB2(SCH_1):M_H_CLK_DP(0)   I111 @BASEBOARD_FAB2_LIB.BASEBOARD_FAB2(SCH_1):PAGE79
   219 M_H_CLK_DN<1> @BASEBOARD_FAB2_LIB.BASEBOARD_FAB2(SCH_1):M_H_CLK_DN(1)   I111 @BASEBOARD_FAB2_LIB.BASEBOARD_FAB2(SCH_1):PAGE79
   218 M_H_CLK_DP<1> @BASEBOARD_FAB2_LIB.BASEBOARD_FAB2(SCH_1):M_H_CLK_DP(1)   I111 @BASEBOARD_FAB2_LIB.BASEBOARD_FAB2(SCH_1):PAGE79
   203 M_H_CKE<1> @BASEBOARD_FAB2_LIB.BASEBOARD_FAB2(SCH_1):M_H_CKE(1)   I111 @BASEBOARD_FAB2_LIB.BASEBOARD_FAB2(SCH_1):PAGE79
    60 M_H_CKE<0> @BASEBOARD_FAB2_LIB.BASEBOARD_FAB2(SCH_1):M_H_CKE(0)   I111 @BASEBOARD_FAB2_LIB.BASEBOARD_FAB2(SCH_1):PAGE79
   280 M_H_DQ<62> @BASEBOARD_FAB2_LIB.BASEBOARD_FAB2(SCH_1):M_H_DQ(62)   I111 @BASEBOARD_FAB2_LIB.BASEBOARD_FAB2(SCH_1):PAGE79
   135 M_H_DQ<63> @BASEBOARD_FAB2_LIB.BASEBOARD_FAB2(SCH_1):M_H_DQ(63)   I111 @BASEBOARD_FAB2_LIB.BASEBOARD_FAB2(SCH_1):PAGE79
   273 M_H_DQ<60> @BASEBOARD_FAB2_LIB.BASEBOARD_FAB2(SCH_1):M_H_DQ(60)   I111 @BASEBOARD_FAB2_LIB.BASEBOARD_FAB2(SCH_1):PAGE79
   128 M_H_DQ<61> @BASEBOARD_FAB2_LIB.BASEBOARD_FAB2(SCH_1):M_H_DQ(61)   I111 @BASEBOARD_FAB2_LIB.BASEBOARD_FAB2(SCH_1):PAGE79
   282 M_H_DQ<58> @BASEBOARD_FAB2_LIB.BASEBOARD_FAB2(SCH_1):M_H_DQ(58)   I111 @BASEBOARD_FAB2_LIB.BASEBOARD_FAB2(SCH_1):PAGE79
   137 M_H_DQ<59> @BASEBOARD_FAB2_LIB.BASEBOARD_FAB2(SCH_1):M_H_DQ(59)   I111 @BASEBOARD_FAB2_LIB.BASEBOARD_FAB2(SCH_1):PAGE79
   275 M_H_DQ<56> @BASEBOARD_FAB2_LIB.BASEBOARD_FAB2(SCH_1):M_H_DQ(56)   I111 @BASEBOARD_FAB2_LIB.BASEBOARD_FAB2(SCH_1):PAGE79
   130 M_H_DQ<57> @BASEBOARD_FAB2_LIB.BASEBOARD_FAB2(SCH_1):M_H_DQ(57)   I111 @BASEBOARD_FAB2_LIB.BASEBOARD_FAB2(SCH_1):PAGE79
   269 M_H_DQ<54> @BASEBOARD_FAB2_LIB.BASEBOARD_FAB2(SCH_1):M_H_DQ(54)   I111 @BASEBOARD_FAB2_LIB.BASEBOARD_FAB2(SCH_1):PAGE79
   124 M_H_DQ<55> @BASEBOARD_FAB2_LIB.BASEBOARD_FAB2(SCH_1):M_H_DQ(55)   I111 @BASEBOARD_FAB2_LIB.BASEBOARD_FAB2(SCH_1):PAGE79
   262 M_H_DQ<52> @BASEBOARD_FAB2_LIB.BASEBOARD_FAB2(SCH_1):M_H_DQ(52)   I111 @BASEBOARD_FAB2_LIB.BASEBOARD_FAB2(SCH_1):PAGE79
   117 M_H_DQ<53> @BASEBOARD_FAB2_LIB.BASEBOARD_FAB2(SCH_1):M_H_DQ(53)   I111 @BASEBOARD_FAB2_LIB.BASEBOARD_FAB2(SCH_1):PAGE79
   271 M_H_DQ<50> @BASEBOARD_FAB2_LIB.BASEBOARD_FAB2(SCH_1):M_H_DQ(50)   I111 @BASEBOARD_FAB2_LIB.BASEBOARD_FAB2(SCH_1):PAGE79
   126 M_H_DQ<51> @BASEBOARD_FAB2_LIB.BASEBOARD_FAB2(SCH_1):M_H_DQ(51)   I111 @BASEBOARD_FAB2_LIB.BASEBOARD_FAB2(SCH_1):PAGE79
   264 M_H_DQ<48> @BASEBOARD_FAB2_LIB.BASEBOARD_FAB2(SCH_1):M_H_DQ(48)   I111 @BASEBOARD_FAB2_LIB.BASEBOARD_FAB2(SCH_1):PAGE79
   119 M_H_DQ<49> @BASEBOARD_FAB2_LIB.BASEBOARD_FAB2(SCH_1):M_H_DQ(49)   I111 @BASEBOARD_FAB2_LIB.BASEBOARD_FAB2(SCH_1):PAGE79
   258 M_H_DQ<46> @BASEBOARD_FAB2_LIB.BASEBOARD_FAB2(SCH_1):M_H_DQ(46)   I111 @BASEBOARD_FAB2_LIB.BASEBOARD_FAB2(SCH_1):PAGE79
   113 M_H_DQ<47> @BASEBOARD_FAB2_LIB.BASEBOARD_FAB2(SCH_1):M_H_DQ(47)   I111 @BASEBOARD_FAB2_LIB.BASEBOARD_FAB2(SCH_1):PAGE79
   251 M_H_DQ<44> @BASEBOARD_FAB2_LIB.BASEBOARD_FAB2(SCH_1):M_H_DQ(44)   I111 @BASEBOARD_FAB2_LIB.BASEBOARD_FAB2(SCH_1):PAGE79
   106 M_H_DQ<45> @BASEBOARD_FAB2_LIB.BASEBOARD_FAB2(SCH_1):M_H_DQ(45)   I111 @BASEBOARD_FAB2_LIB.BASEBOARD_FAB2(SCH_1):PAGE79
   260 M_H_DQ<42> @BASEBOARD_FAB2_LIB.BASEBOARD_FAB2(SCH_1):M_H_DQ(42)   I111 @BASEBOARD_FAB2_LIB.BASEBOARD_FAB2(SCH_1):PAGE79
   115 M_H_DQ<43> @BASEBOARD_FAB2_LIB.BASEBOARD_FAB2(SCH_1):M_H_DQ(43)   I111 @BASEBOARD_FAB2_LIB.BASEBOARD_FAB2(SCH_1):PAGE79
   253 M_H_DQ<40> @BASEBOARD_FAB2_LIB.BASEBOARD_FAB2(SCH_1):M_H_DQ(40)   I111 @BASEBOARD_FAB2_LIB.BASEBOARD_FAB2(SCH_1):PAGE79
   108 M_H_DQ<41> @BASEBOARD_FAB2_LIB.BASEBOARD_FAB2(SCH_1):M_H_DQ(41)   I111 @BASEBOARD_FAB2_LIB.BASEBOARD_FAB2(SCH_1):PAGE79
   247 M_H_DQ<38> @BASEBOARD_FAB2_LIB.BASEBOARD_FAB2(SCH_1):M_H_DQ(38)   I111 @BASEBOARD_FAB2_LIB.BASEBOARD_FAB2(SCH_1):PAGE79
   102 M_H_DQ<39> @BASEBOARD_FAB2_LIB.BASEBOARD_FAB2(SCH_1):M_H_DQ(39)   I111 @BASEBOARD_FAB2_LIB.BASEBOARD_FAB2(SCH_1):PAGE79
   240 M_H_DQ<36> @BASEBOARD_FAB2_LIB.BASEBOARD_FAB2(SCH_1):M_H_DQ(36)   I111 @BASEBOARD_FAB2_LIB.BASEBOARD_FAB2(SCH_1):PAGE79
    95 M_H_DQ<37> @BASEBOARD_FAB2_LIB.BASEBOARD_FAB2(SCH_1):M_H_DQ(37)   I111 @BASEBOARD_FAB2_LIB.BASEBOARD_FAB2(SCH_1):PAGE79
   249 M_H_DQ<34> @BASEBOARD_FAB2_LIB.BASEBOARD_FAB2(SCH_1):M_H_DQ(34)   I111 @BASEBOARD_FAB2_LIB.BASEBOARD_FAB2(SCH_1):PAGE79
   104 M_H_DQ<35> @BASEBOARD_FAB2_LIB.BASEBOARD_FAB2(SCH_1):M_H_DQ(35)   I111 @BASEBOARD_FAB2_LIB.BASEBOARD_FAB2(SCH_1):PAGE79
   242 M_H_DQ<32> @BASEBOARD_FAB2_LIB.BASEBOARD_FAB2(SCH_1):M_H_DQ(32)   I111 @BASEBOARD_FAB2_LIB.BASEBOARD_FAB2(SCH_1):PAGE79
    97 M_H_DQ<33> @BASEBOARD_FAB2_LIB.BASEBOARD_FAB2(SCH_1):M_H_DQ(33)   I111 @BASEBOARD_FAB2_LIB.BASEBOARD_FAB2(SCH_1):PAGE79
   188 M_H_DQ<30> @BASEBOARD_FAB2_LIB.BASEBOARD_FAB2(SCH_1):M_H_DQ(30)   I111 @BASEBOARD_FAB2_LIB.BASEBOARD_FAB2(SCH_1):PAGE79
    43 M_H_DQ<31> @BASEBOARD_FAB2_LIB.BASEBOARD_FAB2(SCH_1):M_H_DQ(31)   I111 @BASEBOARD_FAB2_LIB.BASEBOARD_FAB2(SCH_1):PAGE79
   181 M_H_DQ<28> @BASEBOARD_FAB2_LIB.BASEBOARD_FAB2(SCH_1):M_H_DQ(28)   I111 @BASEBOARD_FAB2_LIB.BASEBOARD_FAB2(SCH_1):PAGE79
    36 M_H_DQ<29> @BASEBOARD_FAB2_LIB.BASEBOARD_FAB2(SCH_1):M_H_DQ(29)   I111 @BASEBOARD_FAB2_LIB.BASEBOARD_FAB2(SCH_1):PAGE79
   190 M_H_DQ<26> @BASEBOARD_FAB2_LIB.BASEBOARD_FAB2(SCH_1):M_H_DQ(26)   I111 @BASEBOARD_FAB2_LIB.BASEBOARD_FAB2(SCH_1):PAGE79
    45 M_H_DQ<27> @BASEBOARD_FAB2_LIB.BASEBOARD_FAB2(SCH_1):M_H_DQ(27)   I111 @BASEBOARD_FAB2_LIB.BASEBOARD_FAB2(SCH_1):PAGE79
   183 M_H_DQ<24> @BASEBOARD_FAB2_LIB.BASEBOARD_FAB2(SCH_1):M_H_DQ(24)   I111 @BASEBOARD_FAB2_LIB.BASEBOARD_FAB2(SCH_1):PAGE79
    38 M_H_DQ<25> @BASEBOARD_FAB2_LIB.BASEBOARD_FAB2(SCH_1):M_H_DQ(25)   I111 @BASEBOARD_FAB2_LIB.BASEBOARD_FAB2(SCH_1):PAGE79
   177 M_H_DQ<22> @BASEBOARD_FAB2_LIB.BASEBOARD_FAB2(SCH_1):M_H_DQ(22)   I111 @BASEBOARD_FAB2_LIB.BASEBOARD_FAB2(SCH_1):PAGE79
    32 M_H_DQ<23> @BASEBOARD_FAB2_LIB.BASEBOARD_FAB2(SCH_1):M_H_DQ(23)   I111 @BASEBOARD_FAB2_LIB.BASEBOARD_FAB2(SCH_1):PAGE79
   170 M_H_DQ<20> @BASEBOARD_FAB2_LIB.BASEBOARD_FAB2(SCH_1):M_H_DQ(20)   I111 @BASEBOARD_FAB2_LIB.BASEBOARD_FAB2(SCH_1):PAGE79
    25 M_H_DQ<21> @BASEBOARD_FAB2_LIB.BASEBOARD_FAB2(SCH_1):M_H_DQ(21)   I111 @BASEBOARD_FAB2_LIB.BASEBOARD_FAB2(SCH_1):PAGE79
   179 M_H_DQ<18> @BASEBOARD_FAB2_LIB.BASEBOARD_FAB2(SCH_1):M_H_DQ(18)   I111 @BASEBOARD_FAB2_LIB.BASEBOARD_FAB2(SCH_1):PAGE79
    34 M_H_DQ<19> @BASEBOARD_FAB2_LIB.BASEBOARD_FAB2(SCH_1):M_H_DQ(19)   I111 @BASEBOARD_FAB2_LIB.BASEBOARD_FAB2(SCH_1):PAGE79
   172 M_H_DQ<16> @BASEBOARD_FAB2_LIB.BASEBOARD_FAB2(SCH_1):M_H_DQ(16)   I111 @BASEBOARD_FAB2_LIB.BASEBOARD_FAB2(SCH_1):PAGE79
    27 M_H_DQ<17> @BASEBOARD_FAB2_LIB.BASEBOARD_FAB2(SCH_1):M_H_DQ(17)   I111 @BASEBOARD_FAB2_LIB.BASEBOARD_FAB2(SCH_1):PAGE79
   166 M_H_DQ<14> @BASEBOARD_FAB2_LIB.BASEBOARD_FAB2(SCH_1):M_H_DQ(14)   I111 @BASEBOARD_FAB2_LIB.BASEBOARD_FAB2(SCH_1):PAGE79
    21 M_H_DQ<15> @BASEBOARD_FAB2_LIB.BASEBOARD_FAB2(SCH_1):M_H_DQ(15)   I111 @BASEBOARD_FAB2_LIB.BASEBOARD_FAB2(SCH_1):PAGE79
   159 M_H_DQ<12> @BASEBOARD_FAB2_LIB.BASEBOARD_FAB2(SCH_1):M_H_DQ(12)   I111 @BASEBOARD_FAB2_LIB.BASEBOARD_FAB2(SCH_1):PAGE79
    14 M_H_DQ<13> @BASEBOARD_FAB2_LIB.BASEBOARD_FAB2(SCH_1):M_H_DQ(13)   I111 @BASEBOARD_FAB2_LIB.BASEBOARD_FAB2(SCH_1):PAGE79
   168 M_H_DQ<10> @BASEBOARD_FAB2_LIB.BASEBOARD_FAB2(SCH_1):M_H_DQ(10)   I111 @BASEBOARD_FAB2_LIB.BASEBOARD_FAB2(SCH_1):PAGE79
    23 M_H_DQ<11> @BASEBOARD_FAB2_LIB.BASEBOARD_FAB2(SCH_1):M_H_DQ(11)   I111 @BASEBOARD_FAB2_LIB.BASEBOARD_FAB2(SCH_1):PAGE79
   161 M_H_DQ<8> @BASEBOARD_FAB2_LIB.BASEBOARD_FAB2(SCH_1):M_H_DQ(8)   I111 @BASEBOARD_FAB2_LIB.BASEBOARD_FAB2(SCH_1):PAGE79
    16 M_H_DQ<9> @BASEBOARD_FAB2_LIB.BASEBOARD_FAB2(SCH_1):M_H_DQ(9)   I111 @BASEBOARD_FAB2_LIB.BASEBOARD_FAB2(SCH_1):PAGE79
   155 M_H_DQ<6> @BASEBOARD_FAB2_LIB.BASEBOARD_FAB2(SCH_1):M_H_DQ(6)   I111 @BASEBOARD_FAB2_LIB.BASEBOARD_FAB2(SCH_1):PAGE79
    10 M_H_DQ<7> @BASEBOARD_FAB2_LIB.BASEBOARD_FAB2(SCH_1):M_H_DQ(7)   I111 @BASEBOARD_FAB2_LIB.BASEBOARD_FAB2(SCH_1):PAGE79
   148 M_H_DQ<4> @BASEBOARD_FAB2_LIB.BASEBOARD_FAB2(SCH_1):M_H_DQ(4)   I111 @BASEBOARD_FAB2_LIB.BASEBOARD_FAB2(SCH_1):PAGE79
     3 M_H_DQ<5> @BASEBOARD_FAB2_LIB.BASEBOARD_FAB2(SCH_1):M_H_DQ(5)   I111 @BASEBOARD_FAB2_LIB.BASEBOARD_FAB2(SCH_1):PAGE79
   157 M_H_DQ<2> @BASEBOARD_FAB2_LIB.BASEBOARD_FAB2(SCH_1):M_H_DQ(2)   I111 @BASEBOARD_FAB2_LIB.BASEBOARD_FAB2(SCH_1):PAGE79
    12 M_H_DQ<3> @BASEBOARD_FAB2_LIB.BASEBOARD_FAB2(SCH_1):M_H_DQ(3)   I111 @BASEBOARD_FAB2_LIB.BASEBOARD_FAB2(SCH_1):PAGE79
   150 M_H_DQ<0> @BASEBOARD_FAB2_LIB.BASEBOARD_FAB2(SCH_1):M_H_DQ(0)   I111 @BASEBOARD_FAB2_LIB.BASEBOARD_FAB2(SCH_1):PAGE79
     5 M_H_DQ<1> @BASEBOARD_FAB2_LIB.BASEBOARD_FAB2(SCH_1):M_H_DQ(1)   I111 @BASEBOARD_FAB2_LIB.BASEBOARD_FAB2(SCH_1):PAGE79
    78 FM_DIMM_EVENT_COD_N @BASEBOARD_FAB2_LIB.BASEBOARD_FAB2(SCH_1):FM_DIMM_EVENT_COD_N   I111 @BASEBOARD_FAB2_LIB.BASEBOARD_FAB2(SCH_1):PAGE79
    91 M_H_ODT<1> @BASEBOARD_FAB2_LIB.BASEBOARD_FAB2(SCH_1):M_H_ODT(1)   I111 @BASEBOARD_FAB2_LIB.BASEBOARD_FAB2(SCH_1):PAGE79
    87 M_H_ODT<0> @BASEBOARD_FAB2_LIB.BASEBOARD_FAB2(SCH_1):M_H_ODT(0)   I111 @BASEBOARD_FAB2_LIB.BASEBOARD_FAB2(SCH_1):PAGE79
   222 M_H_PAR @BASEBOARD_FAB2_LIB.BASEBOARD_FAB2(SCH_1):M_H_PAR   I111 @BASEBOARD_FAB2_LIB.BASEBOARD_FAB2(SCH_1):PAGE79
    58 M_GHJ_RST_N @BASEBOARD_FAB2_LIB.BASEBOARD_FAB2(SCH_1):M_GHJ_RST_N   I111 @BASEBOARD_FAB2_LIB.BASEBOARD_FAB2(SCH_1):PAGE79
   144 TP_CH_H_DIMM_H0_RFU_2 @BASEBOARD_FAB2_LIB.BASEBOARD_FAB2(SCH_1):TP_CH_H_DIMM_H0_RFU_2   I111 @BASEBOARD_FAB2_LIB.BASEBOARD_FAB2(SCH_1):PAGE79
   227 TP_CH_H_DIMM_H0_RFU_1 @BASEBOARD_FAB2_LIB.BASEBOARD_FAB2(SCH_1):TP_CH_H_DIMM_H0_RFU_1   I111 @BASEBOARD_FAB2_LIB.BASEBOARD_FAB2(SCH_1):PAGE79
   205 TP_CH_H_DIMM_H0_RFU_0 @BASEBOARD_FAB2_LIB.BASEBOARD_FAB2(SCH_1):TP_CH_H_DIMM_H0_RFU_0   I111 @BASEBOARD_FAB2_LIB.BASEBOARD_FAB2(SCH_1):PAGE79
    84 M_H_CS_N<0> @BASEBOARD_FAB2_LIB.BASEBOARD_FAB2(SCH_1):M_H_CS_N(0)   I111 @BASEBOARD_FAB2_LIB.BASEBOARD_FAB2(SCH_1):PAGE79
    89 M_H_CS_N<1> @BASEBOARD_FAB2_LIB.BASEBOARD_FAB2(SCH_1):M_H_CS_N(1)   I111 @BASEBOARD_FAB2_LIB.BASEBOARD_FAB2(SCH_1):PAGE79
    93 M_H_CS_N<2> @BASEBOARD_FAB2_LIB.BASEBOARD_FAB2(SCH_1):M_H_CS_N(2)   I111 @BASEBOARD_FAB2_LIB.BASEBOARD_FAB2(SCH_1):PAGE79
   237 M_H_CS_N<3> @BASEBOARD_FAB2_LIB.BASEBOARD_FAB2(SCH_1):M_H_CS_N(3)   I111 @BASEBOARD_FAB2_LIB.BASEBOARD_FAB2(SCH_1):PAGE79
   238    GND @BASEBOARD_FAB2_LIB.BASEBOARD_FAB2(SCH_1):GND   I111 @BASEBOARD_FAB2_LIB.BASEBOARD_FAB2(SCH_1):PAGE79
   140 PVPP_GHJ @BASEBOARD_FAB2_LIB.BASEBOARD_FAB2(SCH_1):PVPP_GHJ   I111 @BASEBOARD_FAB2_LIB.BASEBOARD_FAB2(SCH_1):PAGE79
   139    GND @BASEBOARD_FAB2_LIB.BASEBOARD_FAB2(SCH_1):GND   I111 @BASEBOARD_FAB2_LIB.BASEBOARD_FAB2(SCH_1):PAGE79
   230 FM_ADR_COMPLETE_GHJ_N @BASEBOARD_FAB2_LIB.BASEBOARD_FAB2(SCH_1):FM_ADR_COMPLETE_GHJ_N   I111 @BASEBOARD_FAB2_LIB.BASEBOARD_FAB2(SCH_1):PAGE79
   141 SMB_DDR_GHJ_VPP_SCL @BASEBOARD_FAB2_LIB.BASEBOARD_FAB2(SCH_1):SMB_DDR_GHJ_VPP_SCL   I111 @BASEBOARD_FAB2_LIB.BASEBOARD_FAB2(SCH_1):PAGE79
   285 SMB_DDR_GHJ_VPP_SDA @BASEBOARD_FAB2_LIB.BASEBOARD_FAB2(SCH_1):SMB_DDR_GHJ_VPP_SDA   I111 @BASEBOARD_FAB2_LIB.BASEBOARD_FAB2(SCH_1):PAGE79
   284 PVPP_GHJ @BASEBOARD_FAB2_LIB.BASEBOARD_FAB2(SCH_1):PVPP_GHJ   I111 @BASEBOARD_FAB2_LIB.BASEBOARD_FAB2(SCH_1):PAGE79
   146 M_H_VREF @BASEBOARD_FAB2_LIB.BASEBOARD_FAB2(SCH_1):M_H_VREF   I111 @BASEBOARD_FAB2_LIB.BASEBOARD_FAB2(SCH_1):PAGE79
   152 M_H_DQS_DN<0> @BASEBOARD_FAB2_LIB.BASEBOARD_FAB2(SCH_1):M_H_DQS_DN(0)    I64 @BASEBOARD_FAB2_LIB.BASEBOARD_FAB2(SCH_1):PAGE79
   153 M_H_DQS_DP<0> @BASEBOARD_FAB2_LIB.BASEBOARD_FAB2(SCH_1):M_H_DQS_DP(0)    I64 @BASEBOARD_FAB2_LIB.BASEBOARD_FAB2(SCH_1):PAGE79
    19 M_H_DQS_DN<10> @BASEBOARD_FAB2_LIB.BASEBOARD_FAB2(SCH_1):M_H_DQS_DN(10)    I64 @BASEBOARD_FAB2_LIB.BASEBOARD_FAB2(SCH_1):PAGE79
    18 M_H_DQS_DP<10> @BASEBOARD_FAB2_LIB.BASEBOARD_FAB2(SCH_1):M_H_DQS_DP(10)    I64 @BASEBOARD_FAB2_LIB.BASEBOARD_FAB2(SCH_1):PAGE79
    30 M_H_DQS_DN<11> @BASEBOARD_FAB2_LIB.BASEBOARD_FAB2(SCH_1):M_H_DQS_DN(11)    I64 @BASEBOARD_FAB2_LIB.BASEBOARD_FAB2(SCH_1):PAGE79
    29 M_H_DQS_DP<11> @BASEBOARD_FAB2_LIB.BASEBOARD_FAB2(SCH_1):M_H_DQS_DP(11)    I64 @BASEBOARD_FAB2_LIB.BASEBOARD_FAB2(SCH_1):PAGE79
    41 M_H_DQS_DN<12> @BASEBOARD_FAB2_LIB.BASEBOARD_FAB2(SCH_1):M_H_DQS_DN(12)    I64 @BASEBOARD_FAB2_LIB.BASEBOARD_FAB2(SCH_1):PAGE79
    40 M_H_DQS_DP<12> @BASEBOARD_FAB2_LIB.BASEBOARD_FAB2(SCH_1):M_H_DQS_DP(12)    I64 @BASEBOARD_FAB2_LIB.BASEBOARD_FAB2(SCH_1):PAGE79
   100 M_H_DQS_DN<13> @BASEBOARD_FAB2_LIB.BASEBOARD_FAB2(SCH_1):M_H_DQS_DN(13)    I64 @BASEBOARD_FAB2_LIB.BASEBOARD_FAB2(SCH_1):PAGE79
    99 M_H_DQS_DP<13> @BASEBOARD_FAB2_LIB.BASEBOARD_FAB2(SCH_1):M_H_DQS_DP(13)    I64 @BASEBOARD_FAB2_LIB.BASEBOARD_FAB2(SCH_1):PAGE79
   111 M_H_DQS_DN<14> @BASEBOARD_FAB2_LIB.BASEBOARD_FAB2(SCH_1):M_H_DQS_DN(14)    I64 @BASEBOARD_FAB2_LIB.BASEBOARD_FAB2(SCH_1):PAGE79
   110 M_H_DQS_DP<14> @BASEBOARD_FAB2_LIB.BASEBOARD_FAB2(SCH_1):M_H_DQS_DP(14)    I64 @BASEBOARD_FAB2_LIB.BASEBOARD_FAB2(SCH_1):PAGE79
   122 M_H_DQS_DN<15> @BASEBOARD_FAB2_LIB.BASEBOARD_FAB2(SCH_1):M_H_DQS_DN(15)    I64 @BASEBOARD_FAB2_LIB.BASEBOARD_FAB2(SCH_1):PAGE79
   121 M_H_DQS_DP<15> @BASEBOARD_FAB2_LIB.BASEBOARD_FAB2(SCH_1):M_H_DQS_DP(15)    I64 @BASEBOARD_FAB2_LIB.BASEBOARD_FAB2(SCH_1):PAGE79
   133 M_H_DQS_DN<16> @BASEBOARD_FAB2_LIB.BASEBOARD_FAB2(SCH_1):M_H_DQS_DN(16)    I64 @BASEBOARD_FAB2_LIB.BASEBOARD_FAB2(SCH_1):PAGE79
   132 M_H_DQS_DP<16> @BASEBOARD_FAB2_LIB.BASEBOARD_FAB2(SCH_1):M_H_DQS_DP(16)    I64 @BASEBOARD_FAB2_LIB.BASEBOARD_FAB2(SCH_1):PAGE79
    52 M_H_DQS_DN<17> @BASEBOARD_FAB2_LIB.BASEBOARD_FAB2(SCH_1):M_H_DQS_DN(17)    I64 @BASEBOARD_FAB2_LIB.BASEBOARD_FAB2(SCH_1):PAGE79
    51 M_H_DQS_DP<17> @BASEBOARD_FAB2_LIB.BASEBOARD_FAB2(SCH_1):M_H_DQS_DP(17)    I64 @BASEBOARD_FAB2_LIB.BASEBOARD_FAB2(SCH_1):PAGE79
   163 M_H_DQS_DN<1> @BASEBOARD_FAB2_LIB.BASEBOARD_FAB2(SCH_1):M_H_DQS_DN(1)    I64 @BASEBOARD_FAB2_LIB.BASEBOARD_FAB2(SCH_1):PAGE79
   164 M_H_DQS_DP<1> @BASEBOARD_FAB2_LIB.BASEBOARD_FAB2(SCH_1):M_H_DQS_DP(1)    I64 @BASEBOARD_FAB2_LIB.BASEBOARD_FAB2(SCH_1):PAGE79
   174 M_H_DQS_DN<2> @BASEBOARD_FAB2_LIB.BASEBOARD_FAB2(SCH_1):M_H_DQS_DN(2)    I64 @BASEBOARD_FAB2_LIB.BASEBOARD_FAB2(SCH_1):PAGE79
   175 M_H_DQS_DP<2> @BASEBOARD_FAB2_LIB.BASEBOARD_FAB2(SCH_1):M_H_DQS_DP(2)    I64 @BASEBOARD_FAB2_LIB.BASEBOARD_FAB2(SCH_1):PAGE79
   185 M_H_DQS_DN<3> @BASEBOARD_FAB2_LIB.BASEBOARD_FAB2(SCH_1):M_H_DQS_DN(3)    I64 @BASEBOARD_FAB2_LIB.BASEBOARD_FAB2(SCH_1):PAGE79
   186 M_H_DQS_DP<3> @BASEBOARD_FAB2_LIB.BASEBOARD_FAB2(SCH_1):M_H_DQS_DP(3)    I64 @BASEBOARD_FAB2_LIB.BASEBOARD_FAB2(SCH_1):PAGE79
   244 M_H_DQS_DN<4> @BASEBOARD_FAB2_LIB.BASEBOARD_FAB2(SCH_1):M_H_DQS_DN(4)    I64 @BASEBOARD_FAB2_LIB.BASEBOARD_FAB2(SCH_1):PAGE79
   245 M_H_DQS_DP<4> @BASEBOARD_FAB2_LIB.BASEBOARD_FAB2(SCH_1):M_H_DQS_DP(4)    I64 @BASEBOARD_FAB2_LIB.BASEBOARD_FAB2(SCH_1):PAGE79
   255 M_H_DQS_DN<5> @BASEBOARD_FAB2_LIB.BASEBOARD_FAB2(SCH_1):M_H_DQS_DN(5)    I64 @BASEBOARD_FAB2_LIB.BASEBOARD_FAB2(SCH_1):PAGE79
   256 M_H_DQS_DP<5> @BASEBOARD_FAB2_LIB.BASEBOARD_FAB2(SCH_1):M_H_DQS_DP(5)    I64 @BASEBOARD_FAB2_LIB.BASEBOARD_FAB2(SCH_1):PAGE79
   266 M_H_DQS_DN<6> @BASEBOARD_FAB2_LIB.BASEBOARD_FAB2(SCH_1):M_H_DQS_DN(6)    I64 @BASEBOARD_FAB2_LIB.BASEBOARD_FAB2(SCH_1):PAGE79
   267 M_H_DQS_DP<6> @BASEBOARD_FAB2_LIB.BASEBOARD_FAB2(SCH_1):M_H_DQS_DP(6)    I64 @BASEBOARD_FAB2_LIB.BASEBOARD_FAB2(SCH_1):PAGE79
   277 M_H_DQS_DN<7> @BASEBOARD_FAB2_LIB.BASEBOARD_FAB2(SCH_1):M_H_DQS_DN(7)    I64 @BASEBOARD_FAB2_LIB.BASEBOARD_FAB2(SCH_1):PAGE79
   278 M_H_DQS_DP<7> @BASEBOARD_FAB2_LIB.BASEBOARD_FAB2(SCH_1):M_H_DQS_DP(7)    I64 @BASEBOARD_FAB2_LIB.BASEBOARD_FAB2(SCH_1):PAGE79
   196 M_H_DQS_DN<8> @BASEBOARD_FAB2_LIB.BASEBOARD_FAB2(SCH_1):M_H_DQS_DN(8)    I64 @BASEBOARD_FAB2_LIB.BASEBOARD_FAB2(SCH_1):PAGE79
   197 M_H_DQS_DP<8> @BASEBOARD_FAB2_LIB.BASEBOARD_FAB2(SCH_1):M_H_DQS_DP(8)    I64 @BASEBOARD_FAB2_LIB.BASEBOARD_FAB2(SCH_1):PAGE79
     8 M_H_DQS_DN<9> @BASEBOARD_FAB2_LIB.BASEBOARD_FAB2(SCH_1):M_H_DQS_DN(9)    I64 @BASEBOARD_FAB2_LIB.BASEBOARD_FAB2(SCH_1):PAGE79
     7 M_H_DQS_DP<9> @BASEBOARD_FAB2_LIB.BASEBOARD_FAB2(SCH_1):M_H_DQS_DP(9)    I64 @BASEBOARD_FAB2_LIB.BASEBOARD_FAB2(SCH_1):PAGE79
     2    GND @BASEBOARD_FAB2_LIB.BASEBOARD_FAB2(SCH_1):GND    I43 @BASEBOARD_FAB2_LIB.BASEBOARD_FAB2(SCH_1):PAGE79
     4    GND @BASEBOARD_FAB2_LIB.BASEBOARD_FAB2(SCH_1):GND    I43 @BASEBOARD_FAB2_LIB.BASEBOARD_FAB2(SCH_1):PAGE79
     6    GND @BASEBOARD_FAB2_LIB.BASEBOARD_FAB2(SCH_1):GND    I43 @BASEBOARD_FAB2_LIB.BASEBOARD_FAB2(SCH_1):PAGE79
     9    GND @BASEBOARD_FAB2_LIB.BASEBOARD_FAB2(SCH_1):GND    I43 @BASEBOARD_FAB2_LIB.BASEBOARD_FAB2(SCH_1):PAGE79
    11    GND @BASEBOARD_FAB2_LIB.BASEBOARD_FAB2(SCH_1):GND    I43 @BASEBOARD_FAB2_LIB.BASEBOARD_FAB2(SCH_1):PAGE79
    13    GND @BASEBOARD_FAB2_LIB.BASEBOARD_FAB2(SCH_1):GND    I43 @BASEBOARD_FAB2_LIB.BASEBOARD_FAB2(SCH_1):PAGE79
    15    GND @BASEBOARD_FAB2_LIB.BASEBOARD_FAB2(SCH_1):GND    I43 @BASEBOARD_FAB2_LIB.BASEBOARD_FAB2(SCH_1):PAGE79
    17    GND @BASEBOARD_FAB2_LIB.BASEBOARD_FAB2(SCH_1):GND    I43 @BASEBOARD_FAB2_LIB.BASEBOARD_FAB2(SCH_1):PAGE79
    20    GND @BASEBOARD_FAB2_LIB.BASEBOARD_FAB2(SCH_1):GND    I43 @BASEBOARD_FAB2_LIB.BASEBOARD_FAB2(SCH_1):PAGE79
    22    GND @BASEBOARD_FAB2_LIB.BASEBOARD_FAB2(SCH_1):GND    I43 @BASEBOARD_FAB2_LIB.BASEBOARD_FAB2(SCH_1):PAGE79
    24    GND @BASEBOARD_FAB2_LIB.BASEBOARD_FAB2(SCH_1):GND    I43 @BASEBOARD_FAB2_LIB.BASEBOARD_FAB2(SCH_1):PAGE79
    26    GND @BASEBOARD_FAB2_LIB.BASEBOARD_FAB2(SCH_1):GND    I43 @BASEBOARD_FAB2_LIB.BASEBOARD_FAB2(SCH_1):PAGE79
    28    GND @BASEBOARD_FAB2_LIB.BASEBOARD_FAB2(SCH_1):GND    I43 @BASEBOARD_FAB2_LIB.BASEBOARD_FAB2(SCH_1):PAGE79
    31    GND @BASEBOARD_FAB2_LIB.BASEBOARD_FAB2(SCH_1):GND    I43 @BASEBOARD_FAB2_LIB.BASEBOARD_FAB2(SCH_1):PAGE79
    33    GND @BASEBOARD_FAB2_LIB.BASEBOARD_FAB2(SCH_1):GND    I43 @BASEBOARD_FAB2_LIB.BASEBOARD_FAB2(SCH_1):PAGE79
    35    GND @BASEBOARD_FAB2_LIB.BASEBOARD_FAB2(SCH_1):GND    I43 @BASEBOARD_FAB2_LIB.BASEBOARD_FAB2(SCH_1):PAGE79
    37    GND @BASEBOARD_FAB2_LIB.BASEBOARD_FAB2(SCH_1):GND    I43 @BASEBOARD_FAB2_LIB.BASEBOARD_FAB2(SCH_1):PAGE79
    39    GND @BASEBOARD_FAB2_LIB.BASEBOARD_FAB2(SCH_1):GND    I43 @BASEBOARD_FAB2_LIB.BASEBOARD_FAB2(SCH_1):PAGE79
    42    GND @BASEBOARD_FAB2_LIB.BASEBOARD_FAB2(SCH_1):GND    I43 @BASEBOARD_FAB2_LIB.BASEBOARD_FAB2(SCH_1):PAGE79
    44    GND @BASEBOARD_FAB2_LIB.BASEBOARD_FAB2(SCH_1):GND    I43 @BASEBOARD_FAB2_LIB.BASEBOARD_FAB2(SCH_1):PAGE79
    46    GND @BASEBOARD_FAB2_LIB.BASEBOARD_FAB2(SCH_1):GND    I43 @BASEBOARD_FAB2_LIB.BASEBOARD_FAB2(SCH_1):PAGE79
    48    GND @BASEBOARD_FAB2_LIB.BASEBOARD_FAB2(SCH_1):GND    I43 @BASEBOARD_FAB2_LIB.BASEBOARD_FAB2(SCH_1):PAGE79
    50    GND @BASEBOARD_FAB2_LIB.BASEBOARD_FAB2(SCH_1):GND    I43 @BASEBOARD_FAB2_LIB.BASEBOARD_FAB2(SCH_1):PAGE79
    53    GND @BASEBOARD_FAB2_LIB.BASEBOARD_FAB2(SCH_1):GND    I43 @BASEBOARD_FAB2_LIB.BASEBOARD_FAB2(SCH_1):PAGE79
    55    GND @BASEBOARD_FAB2_LIB.BASEBOARD_FAB2(SCH_1):GND    I43 @BASEBOARD_FAB2_LIB.BASEBOARD_FAB2(SCH_1):PAGE79
    57    GND @BASEBOARD_FAB2_LIB.BASEBOARD_FAB2(SCH_1):GND    I43 @BASEBOARD_FAB2_LIB.BASEBOARD_FAB2(SCH_1):PAGE79
    94    GND @BASEBOARD_FAB2_LIB.BASEBOARD_FAB2(SCH_1):GND    I43 @BASEBOARD_FAB2_LIB.BASEBOARD_FAB2(SCH_1):PAGE79
    96    GND @BASEBOARD_FAB2_LIB.BASEBOARD_FAB2(SCH_1):GND    I43 @BASEBOARD_FAB2_LIB.BASEBOARD_FAB2(SCH_1):PAGE79
    98    GND @BASEBOARD_FAB2_LIB.BASEBOARD_FAB2(SCH_1):GND    I43 @BASEBOARD_FAB2_LIB.BASEBOARD_FAB2(SCH_1):PAGE79
   101    GND @BASEBOARD_FAB2_LIB.BASEBOARD_FAB2(SCH_1):GND    I43 @BASEBOARD_FAB2_LIB.BASEBOARD_FAB2(SCH_1):PAGE79
   103    GND @BASEBOARD_FAB2_LIB.BASEBOARD_FAB2(SCH_1):GND    I43 @BASEBOARD_FAB2_LIB.BASEBOARD_FAB2(SCH_1):PAGE79
   105    GND @BASEBOARD_FAB2_LIB.BASEBOARD_FAB2(SCH_1):GND    I43 @BASEBOARD_FAB2_LIB.BASEBOARD_FAB2(SCH_1):PAGE79
   107    GND @BASEBOARD_FAB2_LIB.BASEBOARD_FAB2(SCH_1):GND    I43 @BASEBOARD_FAB2_LIB.BASEBOARD_FAB2(SCH_1):PAGE79
   109    GND @BASEBOARD_FAB2_LIB.BASEBOARD_FAB2(SCH_1):GND    I43 @BASEBOARD_FAB2_LIB.BASEBOARD_FAB2(SCH_1):PAGE79
   112    GND @BASEBOARD_FAB2_LIB.BASEBOARD_FAB2(SCH_1):GND    I43 @BASEBOARD_FAB2_LIB.BASEBOARD_FAB2(SCH_1):PAGE79
   114    GND @BASEBOARD_FAB2_LIB.BASEBOARD_FAB2(SCH_1):GND    I43 @BASEBOARD_FAB2_LIB.BASEBOARD_FAB2(SCH_1):PAGE79
   116    GND @BASEBOARD_FAB2_LIB.BASEBOARD_FAB2(SCH_1):GND    I43 @BASEBOARD_FAB2_LIB.BASEBOARD_FAB2(SCH_1):PAGE79
   118    GND @BASEBOARD_FAB2_LIB.BASEBOARD_FAB2(SCH_1):GND    I43 @BASEBOARD_FAB2_LIB.BASEBOARD_FAB2(SCH_1):PAGE79
   120    GND @BASEBOARD_FAB2_LIB.BASEBOARD_FAB2(SCH_1):GND    I43 @BASEBOARD_FAB2_LIB.BASEBOARD_FAB2(SCH_1):PAGE79
   123    GND @BASEBOARD_FAB2_LIB.BASEBOARD_FAB2(SCH_1):GND    I43 @BASEBOARD_FAB2_LIB.BASEBOARD_FAB2(SCH_1):PAGE79
   125    GND @BASEBOARD_FAB2_LIB.BASEBOARD_FAB2(SCH_1):GND    I43 @BASEBOARD_FAB2_LIB.BASEBOARD_FAB2(SCH_1):PAGE79
   127    GND @BASEBOARD_FAB2_LIB.BASEBOARD_FAB2(SCH_1):GND    I43 @BASEBOARD_FAB2_LIB.BASEBOARD_FAB2(SCH_1):PAGE79
   129    GND @BASEBOARD_FAB2_LIB.BASEBOARD_FAB2(SCH_1):GND    I43 @BASEBOARD_FAB2_LIB.BASEBOARD_FAB2(SCH_1):PAGE79
   131    GND @BASEBOARD_FAB2_LIB.BASEBOARD_FAB2(SCH_1):GND    I43 @BASEBOARD_FAB2_LIB.BASEBOARD_FAB2(SCH_1):PAGE79
   134    GND @BASEBOARD_FAB2_LIB.BASEBOARD_FAB2(SCH_1):GND    I43 @BASEBOARD_FAB2_LIB.BASEBOARD_FAB2(SCH_1):PAGE79
   136    GND @BASEBOARD_FAB2_LIB.BASEBOARD_FAB2(SCH_1):GND    I43 @BASEBOARD_FAB2_LIB.BASEBOARD_FAB2(SCH_1):PAGE79
   138    GND @BASEBOARD_FAB2_LIB.BASEBOARD_FAB2(SCH_1):GND    I43 @BASEBOARD_FAB2_LIB.BASEBOARD_FAB2(SCH_1):PAGE79
   147    GND @BASEBOARD_FAB2_LIB.BASEBOARD_FAB2(SCH_1):GND    I43 @BASEBOARD_FAB2_LIB.BASEBOARD_FAB2(SCH_1):PAGE79
   149    GND @BASEBOARD_FAB2_LIB.BASEBOARD_FAB2(SCH_1):GND    I43 @BASEBOARD_FAB2_LIB.BASEBOARD_FAB2(SCH_1):PAGE79
   151    GND @BASEBOARD_FAB2_LIB.BASEBOARD_FAB2(SCH_1):GND    I43 @BASEBOARD_FAB2_LIB.BASEBOARD_FAB2(SCH_1):PAGE79
   154    GND @BASEBOARD_FAB2_LIB.BASEBOARD_FAB2(SCH_1):GND    I43 @BASEBOARD_FAB2_LIB.BASEBOARD_FAB2(SCH_1):PAGE79
   156    GND @BASEBOARD_FAB2_LIB.BASEBOARD_FAB2(SCH_1):GND    I43 @BASEBOARD_FAB2_LIB.BASEBOARD_FAB2(SCH_1):PAGE79
   158    GND @BASEBOARD_FAB2_LIB.BASEBOARD_FAB2(SCH_1):GND    I43 @BASEBOARD_FAB2_LIB.BASEBOARD_FAB2(SCH_1):PAGE79
   160    GND @BASEBOARD_FAB2_LIB.BASEBOARD_FAB2(SCH_1):GND    I43 @BASEBOARD_FAB2_LIB.BASEBOARD_FAB2(SCH_1):PAGE79
   162    GND @BASEBOARD_FAB2_LIB.BASEBOARD_FAB2(SCH_1):GND    I43 @BASEBOARD_FAB2_LIB.BASEBOARD_FAB2(SCH_1):PAGE79
   165    GND @BASEBOARD_FAB2_LIB.BASEBOARD_FAB2(SCH_1):GND    I43 @BASEBOARD_FAB2_LIB.BASEBOARD_FAB2(SCH_1):PAGE79
   167    GND @BASEBOARD_FAB2_LIB.BASEBOARD_FAB2(SCH_1):GND    I43 @BASEBOARD_FAB2_LIB.BASEBOARD_FAB2(SCH_1):PAGE79
   169    GND @BASEBOARD_FAB2_LIB.BASEBOARD_FAB2(SCH_1):GND    I43 @BASEBOARD_FAB2_LIB.BASEBOARD_FAB2(SCH_1):PAGE79
   171    GND @BASEBOARD_FAB2_LIB.BASEBOARD_FAB2(SCH_1):GND    I43 @BASEBOARD_FAB2_LIB.BASEBOARD_FAB2(SCH_1):PAGE79
   173    GND @BASEBOARD_FAB2_LIB.BASEBOARD_FAB2(SCH_1):GND    I43 @BASEBOARD_FAB2_LIB.BASEBOARD_FAB2(SCH_1):PAGE79
   176    GND @BASEBOARD_FAB2_LIB.BASEBOARD_FAB2(SCH_1):GND    I43 @BASEBOARD_FAB2_LIB.BASEBOARD_FAB2(SCH_1):PAGE79
   178    GND @BASEBOARD_FAB2_LIB.BASEBOARD_FAB2(SCH_1):GND    I43 @BASEBOARD_FAB2_LIB.BASEBOARD_FAB2(SCH_1):PAGE79
   180    GND @BASEBOARD_FAB2_LIB.BASEBOARD_FAB2(SCH_1):GND    I43 @BASEBOARD_FAB2_LIB.BASEBOARD_FAB2(SCH_1):PAGE79
   182    GND @BASEBOARD_FAB2_LIB.BASEBOARD_FAB2(SCH_1):GND    I43 @BASEBOARD_FAB2_LIB.BASEBOARD_FAB2(SCH_1):PAGE79
   184    GND @BASEBOARD_FAB2_LIB.BASEBOARD_FAB2(SCH_1):GND    I43 @BASEBOARD_FAB2_LIB.BASEBOARD_FAB2(SCH_1):PAGE79
   187    GND @BASEBOARD_FAB2_LIB.BASEBOARD_FAB2(SCH_1):GND    I43 @BASEBOARD_FAB2_LIB.BASEBOARD_FAB2(SCH_1):PAGE79
   189    GND @BASEBOARD_FAB2_LIB.BASEBOARD_FAB2(SCH_1):GND    I43 @BASEBOARD_FAB2_LIB.BASEBOARD_FAB2(SCH_1):PAGE79
   191    GND @BASEBOARD_FAB2_LIB.BASEBOARD_FAB2(SCH_1):GND    I43 @BASEBOARD_FAB2_LIB.BASEBOARD_FAB2(SCH_1):PAGE79
   193    GND @BASEBOARD_FAB2_LIB.BASEBOARD_FAB2(SCH_1):GND    I43 @BASEBOARD_FAB2_LIB.BASEBOARD_FAB2(SCH_1):PAGE79
   195    GND @BASEBOARD_FAB2_LIB.BASEBOARD_FAB2(SCH_1):GND    I43 @BASEBOARD_FAB2_LIB.BASEBOARD_FAB2(SCH_1):PAGE79
   198    GND @BASEBOARD_FAB2_LIB.BASEBOARD_FAB2(SCH_1):GND    I43 @BASEBOARD_FAB2_LIB.BASEBOARD_FAB2(SCH_1):PAGE79
   200    GND @BASEBOARD_FAB2_LIB.BASEBOARD_FAB2(SCH_1):GND    I43 @BASEBOARD_FAB2_LIB.BASEBOARD_FAB2(SCH_1):PAGE79
   202    GND @BASEBOARD_FAB2_LIB.BASEBOARD_FAB2(SCH_1):GND    I43 @BASEBOARD_FAB2_LIB.BASEBOARD_FAB2(SCH_1):PAGE79
   239    GND @BASEBOARD_FAB2_LIB.BASEBOARD_FAB2(SCH_1):GND    I43 @BASEBOARD_FAB2_LIB.BASEBOARD_FAB2(SCH_1):PAGE79
   241    GND @BASEBOARD_FAB2_LIB.BASEBOARD_FAB2(SCH_1):GND    I43 @BASEBOARD_FAB2_LIB.BASEBOARD_FAB2(SCH_1):PAGE79
   243    GND @BASEBOARD_FAB2_LIB.BASEBOARD_FAB2(SCH_1):GND    I43 @BASEBOARD_FAB2_LIB.BASEBOARD_FAB2(SCH_1):PAGE79
   246    GND @BASEBOARD_FAB2_LIB.BASEBOARD_FAB2(SCH_1):GND    I43 @BASEBOARD_FAB2_LIB.BASEBOARD_FAB2(SCH_1):PAGE79
   248    GND @BASEBOARD_FAB2_LIB.BASEBOARD_FAB2(SCH_1):GND    I43 @BASEBOARD_FAB2_LIB.BASEBOARD_FAB2(SCH_1):PAGE79
   250    GND @BASEBOARD_FAB2_LIB.BASEBOARD_FAB2(SCH_1):GND    I43 @BASEBOARD_FAB2_LIB.BASEBOARD_FAB2(SCH_1):PAGE79
   252    GND @BASEBOARD_FAB2_LIB.BASEBOARD_FAB2(SCH_1):GND    I43 @BASEBOARD_FAB2_LIB.BASEBOARD_FAB2(SCH_1):PAGE79
   254    GND @BASEBOARD_FAB2_LIB.BASEBOARD_FAB2(SCH_1):GND    I43 @BASEBOARD_FAB2_LIB.BASEBOARD_FAB2(SCH_1):PAGE79
   257    GND @BASEBOARD_FAB2_LIB.BASEBOARD_FAB2(SCH_1):GND    I43 @BASEBOARD_FAB2_LIB.BASEBOARD_FAB2(SCH_1):PAGE79
   259    GND @BASEBOARD_FAB2_LIB.BASEBOARD_FAB2(SCH_1):GND    I43 @BASEBOARD_FAB2_LIB.BASEBOARD_FAB2(SCH_1):PAGE79
   261    GND @BASEBOARD_FAB2_LIB.BASEBOARD_FAB2(SCH_1):GND    I43 @BASEBOARD_FAB2_LIB.BASEBOARD_FAB2(SCH_1):PAGE79
   263    GND @BASEBOARD_FAB2_LIB.BASEBOARD_FAB2(SCH_1):GND    I43 @BASEBOARD_FAB2_LIB.BASEBOARD_FAB2(SCH_1):PAGE79
   265    GND @BASEBOARD_FAB2_LIB.BASEBOARD_FAB2(SCH_1):GND    I43 @BASEBOARD_FAB2_LIB.BASEBOARD_FAB2(SCH_1):PAGE79
   268    GND @BASEBOARD_FAB2_LIB.BASEBOARD_FAB2(SCH_1):GND    I43 @BASEBOARD_FAB2_LIB.BASEBOARD_FAB2(SCH_1):PAGE79
   270    GND @BASEBOARD_FAB2_LIB.BASEBOARD_FAB2(SCH_1):GND    I43 @BASEBOARD_FAB2_LIB.BASEBOARD_FAB2(SCH_1):PAGE79
   272    GND @BASEBOARD_FAB2_LIB.BASEBOARD_FAB2(SCH_1):GND    I43 @BASEBOARD_FAB2_LIB.BASEBOARD_FAB2(SCH_1):PAGE79
   274    GND @BASEBOARD_FAB2_LIB.BASEBOARD_FAB2(SCH_1):GND    I43 @BASEBOARD_FAB2_LIB.BASEBOARD_FAB2(SCH_1):PAGE79
   276    GND @BASEBOARD_FAB2_LIB.BASEBOARD_FAB2(SCH_1):GND    I43 @BASEBOARD_FAB2_LIB.BASEBOARD_FAB2(SCH_1):PAGE79
   279    GND @BASEBOARD_FAB2_LIB.BASEBOARD_FAB2(SCH_1):GND    I43 @BASEBOARD_FAB2_LIB.BASEBOARD_FAB2(SCH_1):PAGE79
   281    GND @BASEBOARD_FAB2_LIB.BASEBOARD_FAB2(SCH_1):GND    I43 @BASEBOARD_FAB2_LIB.BASEBOARD_FAB2(SCH_1):PAGE79
   283    GND @BASEBOARD_FAB2_LIB.BASEBOARD_FAB2(SCH_1):GND    I43 @BASEBOARD_FAB2_LIB.BASEBOARD_FAB2(SCH_1):PAGE79
     1 P12V_NVDIMM_GHJ @BASEBOARD_FAB2_LIB.BASEBOARD_FAB2(SCH_1):P12V_NVDIMM_GHJ   I169 @BASEBOARD_FAB2_LIB.BASEBOARD_FAB2(SCH_1):PAGE79
   145 P12V_NVDIMM_GHJ @BASEBOARD_FAB2_LIB.BASEBOARD_FAB2(SCH_1):P12V_NVDIMM_GHJ   I169 @BASEBOARD_FAB2_LIB.BASEBOARD_FAB2(SCH_1):PAGE79
    59 PVDDQ_GHJ @BASEBOARD_FAB2_LIB.BASEBOARD_FAB2(SCH_1):PVDDQ_GHJ   I169 @BASEBOARD_FAB2_LIB.BASEBOARD_FAB2(SCH_1):PAGE79
    61 PVDDQ_GHJ @BASEBOARD_FAB2_LIB.BASEBOARD_FAB2(SCH_1):PVDDQ_GHJ   I169 @BASEBOARD_FAB2_LIB.BASEBOARD_FAB2(SCH_1):PAGE79
    64 PVDDQ_GHJ @BASEBOARD_FAB2_LIB.BASEBOARD_FAB2(SCH_1):PVDDQ_GHJ   I169 @BASEBOARD_FAB2_LIB.BASEBOARD_FAB2(SCH_1):PAGE79
    67 PVDDQ_GHJ @BASEBOARD_FAB2_LIB.BASEBOARD_FAB2(SCH_1):PVDDQ_GHJ   I169 @BASEBOARD_FAB2_LIB.BASEBOARD_FAB2(SCH_1):PAGE79
    70 PVDDQ_GHJ @BASEBOARD_FAB2_LIB.BASEBOARD_FAB2(SCH_1):PVDDQ_GHJ   I169 @BASEBOARD_FAB2_LIB.BASEBOARD_FAB2(SCH_1):PAGE79
    73 PVDDQ_GHJ @BASEBOARD_FAB2_LIB.BASEBOARD_FAB2(SCH_1):PVDDQ_GHJ   I169 @BASEBOARD_FAB2_LIB.BASEBOARD_FAB2(SCH_1):PAGE79
    76 PVDDQ_GHJ @BASEBOARD_FAB2_LIB.BASEBOARD_FAB2(SCH_1):PVDDQ_GHJ   I169 @BASEBOARD_FAB2_LIB.BASEBOARD_FAB2(SCH_1):PAGE79
    80 PVDDQ_GHJ @BASEBOARD_FAB2_LIB.BASEBOARD_FAB2(SCH_1):PVDDQ_GHJ   I169 @BASEBOARD_FAB2_LIB.BASEBOARD_FAB2(SCH_1):PAGE79
    83 PVDDQ_GHJ @BASEBOARD_FAB2_LIB.BASEBOARD_FAB2(SCH_1):PVDDQ_GHJ   I169 @BASEBOARD_FAB2_LIB.BASEBOARD_FAB2(SCH_1):PAGE79
    85 PVDDQ_GHJ @BASEBOARD_FAB2_LIB.BASEBOARD_FAB2(SCH_1):PVDDQ_GHJ   I169 @BASEBOARD_FAB2_LIB.BASEBOARD_FAB2(SCH_1):PAGE79
    88 PVDDQ_GHJ @BASEBOARD_FAB2_LIB.BASEBOARD_FAB2(SCH_1):PVDDQ_GHJ   I169 @BASEBOARD_FAB2_LIB.BASEBOARD_FAB2(SCH_1):PAGE79
    90 PVDDQ_GHJ @BASEBOARD_FAB2_LIB.BASEBOARD_FAB2(SCH_1):PVDDQ_GHJ   I169 @BASEBOARD_FAB2_LIB.BASEBOARD_FAB2(SCH_1):PAGE79
    92 PVDDQ_GHJ @BASEBOARD_FAB2_LIB.BASEBOARD_FAB2(SCH_1):PVDDQ_GHJ   I169 @BASEBOARD_FAB2_LIB.BASEBOARD_FAB2(SCH_1):PAGE79
   204 PVDDQ_GHJ @BASEBOARD_FAB2_LIB.BASEBOARD_FAB2(SCH_1):PVDDQ_GHJ   I169 @BASEBOARD_FAB2_LIB.BASEBOARD_FAB2(SCH_1):PAGE79
   206 PVDDQ_GHJ @BASEBOARD_FAB2_LIB.BASEBOARD_FAB2(SCH_1):PVDDQ_GHJ   I169 @BASEBOARD_FAB2_LIB.BASEBOARD_FAB2(SCH_1):PAGE79
   209 PVDDQ_GHJ @BASEBOARD_FAB2_LIB.BASEBOARD_FAB2(SCH_1):PVDDQ_GHJ   I169 @BASEBOARD_FAB2_LIB.BASEBOARD_FAB2(SCH_1):PAGE79
   212 PVDDQ_GHJ @BASEBOARD_FAB2_LIB.BASEBOARD_FAB2(SCH_1):PVDDQ_GHJ   I169 @BASEBOARD_FAB2_LIB.BASEBOARD_FAB2(SCH_1):PAGE79
   215 PVDDQ_GHJ @BASEBOARD_FAB2_LIB.BASEBOARD_FAB2(SCH_1):PVDDQ_GHJ   I169 @BASEBOARD_FAB2_LIB.BASEBOARD_FAB2(SCH_1):PAGE79
   217 PVDDQ_GHJ @BASEBOARD_FAB2_LIB.BASEBOARD_FAB2(SCH_1):PVDDQ_GHJ   I169 @BASEBOARD_FAB2_LIB.BASEBOARD_FAB2(SCH_1):PAGE79
   220 PVDDQ_GHJ @BASEBOARD_FAB2_LIB.BASEBOARD_FAB2(SCH_1):PVDDQ_GHJ   I169 @BASEBOARD_FAB2_LIB.BASEBOARD_FAB2(SCH_1):PAGE79
   223 PVDDQ_GHJ @BASEBOARD_FAB2_LIB.BASEBOARD_FAB2(SCH_1):PVDDQ_GHJ   I169 @BASEBOARD_FAB2_LIB.BASEBOARD_FAB2(SCH_1):PAGE79
   226 PVDDQ_GHJ @BASEBOARD_FAB2_LIB.BASEBOARD_FAB2(SCH_1):PVDDQ_GHJ   I169 @BASEBOARD_FAB2_LIB.BASEBOARD_FAB2(SCH_1):PAGE79
   229 PVDDQ_GHJ @BASEBOARD_FAB2_LIB.BASEBOARD_FAB2(SCH_1):PVDDQ_GHJ   I169 @BASEBOARD_FAB2_LIB.BASEBOARD_FAB2(SCH_1):PAGE79
   231 PVDDQ_GHJ @BASEBOARD_FAB2_LIB.BASEBOARD_FAB2(SCH_1):PVDDQ_GHJ   I169 @BASEBOARD_FAB2_LIB.BASEBOARD_FAB2(SCH_1):PAGE79
   233 PVDDQ_GHJ @BASEBOARD_FAB2_LIB.BASEBOARD_FAB2(SCH_1):PVDDQ_GHJ   I169 @BASEBOARD_FAB2_LIB.BASEBOARD_FAB2(SCH_1):PAGE79
   236 PVDDQ_GHJ @BASEBOARD_FAB2_LIB.BASEBOARD_FAB2(SCH_1):PVDDQ_GHJ   I169 @BASEBOARD_FAB2_LIB.BASEBOARD_FAB2(SCH_1):PAGE79
   142 PVPP_GHJ @BASEBOARD_FAB2_LIB.BASEBOARD_FAB2(SCH_1):PVPP_GHJ   I169 @BASEBOARD_FAB2_LIB.BASEBOARD_FAB2(SCH_1):PAGE79
   143 PVPP_GHJ @BASEBOARD_FAB2_LIB.BASEBOARD_FAB2(SCH_1):PVPP_GHJ   I169 @BASEBOARD_FAB2_LIB.BASEBOARD_FAB2(SCH_1):PAGE79
   288 PVPP_GHJ @BASEBOARD_FAB2_LIB.BASEBOARD_FAB2(SCH_1):PVPP_GHJ   I169 @BASEBOARD_FAB2_LIB.BASEBOARD_FAB2(SCH_1):PAGE79
   286 PVPP_GHJ @BASEBOARD_FAB2_LIB.BASEBOARD_FAB2(SCH_1):PVPP_GHJ   I169 @BASEBOARD_FAB2_LIB.BASEBOARD_FAB2(SCH_1):PAGE79
   287 PVPP_GHJ @BASEBOARD_FAB2_LIB.BASEBOARD_FAB2(SCH_1):PVPP_GHJ   I169 @BASEBOARD_FAB2_LIB.BASEBOARD_FAB2(SCH_1):PAGE79
    77 PVTT_GHJ @BASEBOARD_FAB2_LIB.BASEBOARD_FAB2(SCH_1):PVTT_GHJ   I169 @BASEBOARD_FAB2_LIB.BASEBOARD_FAB2(SCH_1):PAGE79
   221 PVTT_GHJ @BASEBOARD_FAB2_LIB.BASEBOARD_FAB2(SCH_1):PVTT_GHJ   I169 @BASEBOARD_FAB2_LIB.BASEBOARD_FAB2(SCH_1):PAGE79

J1G3 SCONN288_H44441004_PIP-SCONN,HA
    79 M_J_MA<0> @BASEBOARD_FAB2_LIB.BASEBOARD_FAB2(SCH_1):M_J_MA(0)   I186 @BASEBOARD_FAB2_LIB.BASEBOARD_FAB2(SCH_1):PAGE81
    72 M_J_MA<1> @BASEBOARD_FAB2_LIB.BASEBOARD_FAB2(SCH_1):M_J_MA(1)   I186 @BASEBOARD_FAB2_LIB.BASEBOARD_FAB2(SCH_1):PAGE81
   225 M_J_MA<10> @BASEBOARD_FAB2_LIB.BASEBOARD_FAB2(SCH_1):M_J_MA(10)   I186 @BASEBOARD_FAB2_LIB.BASEBOARD_FAB2(SCH_1):PAGE81
   210 M_J_MA<11> @BASEBOARD_FAB2_LIB.BASEBOARD_FAB2(SCH_1):M_J_MA(11)   I186 @BASEBOARD_FAB2_LIB.BASEBOARD_FAB2(SCH_1):PAGE81
    65 M_J_MA<12> @BASEBOARD_FAB2_LIB.BASEBOARD_FAB2(SCH_1):M_J_MA(12)   I186 @BASEBOARD_FAB2_LIB.BASEBOARD_FAB2(SCH_1):PAGE81
   232 M_J_MA<13> @BASEBOARD_FAB2_LIB.BASEBOARD_FAB2(SCH_1):M_J_MA(13)   I186 @BASEBOARD_FAB2_LIB.BASEBOARD_FAB2(SCH_1):PAGE81
   228 M_J_MA<14> @BASEBOARD_FAB2_LIB.BASEBOARD_FAB2(SCH_1):M_J_MA(14)   I186 @BASEBOARD_FAB2_LIB.BASEBOARD_FAB2(SCH_1):PAGE81
    86 M_J_MA<15> @BASEBOARD_FAB2_LIB.BASEBOARD_FAB2(SCH_1):M_J_MA(15)   I186 @BASEBOARD_FAB2_LIB.BASEBOARD_FAB2(SCH_1):PAGE81
    82 M_J_MA<16> @BASEBOARD_FAB2_LIB.BASEBOARD_FAB2(SCH_1):M_J_MA(16)   I186 @BASEBOARD_FAB2_LIB.BASEBOARD_FAB2(SCH_1):PAGE81
   234 M_J_MA<17> @BASEBOARD_FAB2_LIB.BASEBOARD_FAB2(SCH_1):M_J_MA(17)   I186 @BASEBOARD_FAB2_LIB.BASEBOARD_FAB2(SCH_1):PAGE81
   216 M_J_MA<2> @BASEBOARD_FAB2_LIB.BASEBOARD_FAB2(SCH_1):M_J_MA(2)   I186 @BASEBOARD_FAB2_LIB.BASEBOARD_FAB2(SCH_1):PAGE81
    71 M_J_MA<3> @BASEBOARD_FAB2_LIB.BASEBOARD_FAB2(SCH_1):M_J_MA(3)   I186 @BASEBOARD_FAB2_LIB.BASEBOARD_FAB2(SCH_1):PAGE81
   214 M_J_MA<4> @BASEBOARD_FAB2_LIB.BASEBOARD_FAB2(SCH_1):M_J_MA(4)   I186 @BASEBOARD_FAB2_LIB.BASEBOARD_FAB2(SCH_1):PAGE81
   213 M_J_MA<5> @BASEBOARD_FAB2_LIB.BASEBOARD_FAB2(SCH_1):M_J_MA(5)   I186 @BASEBOARD_FAB2_LIB.BASEBOARD_FAB2(SCH_1):PAGE81
    69 M_J_MA<6> @BASEBOARD_FAB2_LIB.BASEBOARD_FAB2(SCH_1):M_J_MA(6)   I186 @BASEBOARD_FAB2_LIB.BASEBOARD_FAB2(SCH_1):PAGE81
   211 M_J_MA<7> @BASEBOARD_FAB2_LIB.BASEBOARD_FAB2(SCH_1):M_J_MA(7)   I186 @BASEBOARD_FAB2_LIB.BASEBOARD_FAB2(SCH_1):PAGE81
    68 M_J_MA<8> @BASEBOARD_FAB2_LIB.BASEBOARD_FAB2(SCH_1):M_J_MA(8)   I186 @BASEBOARD_FAB2_LIB.BASEBOARD_FAB2(SCH_1):PAGE81
    66 M_J_MA<9> @BASEBOARD_FAB2_LIB.BASEBOARD_FAB2(SCH_1):M_J_MA(9)   I186 @BASEBOARD_FAB2_LIB.BASEBOARD_FAB2(SCH_1):PAGE81
    62 M_J_ACT_N @BASEBOARD_FAB2_LIB.BASEBOARD_FAB2(SCH_1):M_J_ACT_N   I186 @BASEBOARD_FAB2_LIB.BASEBOARD_FAB2(SCH_1):PAGE81
   208 M_J_ALERT_N @BASEBOARD_FAB2_LIB.BASEBOARD_FAB2(SCH_1):M_J_ALERT_N   I186 @BASEBOARD_FAB2_LIB.BASEBOARD_FAB2(SCH_1):PAGE81
   224 M_J_BA<1> @BASEBOARD_FAB2_LIB.BASEBOARD_FAB2(SCH_1):M_J_BA(1)   I186 @BASEBOARD_FAB2_LIB.BASEBOARD_FAB2(SCH_1):PAGE81
    81 M_J_BA<0> @BASEBOARD_FAB2_LIB.BASEBOARD_FAB2(SCH_1):M_J_BA(0)   I186 @BASEBOARD_FAB2_LIB.BASEBOARD_FAB2(SCH_1):PAGE81
   207 M_J_BG<1> @BASEBOARD_FAB2_LIB.BASEBOARD_FAB2(SCH_1):M_J_BG(1)   I186 @BASEBOARD_FAB2_LIB.BASEBOARD_FAB2(SCH_1):PAGE81
    63 M_J_BG<0> @BASEBOARD_FAB2_LIB.BASEBOARD_FAB2(SCH_1):M_J_BG(0)   I186 @BASEBOARD_FAB2_LIB.BASEBOARD_FAB2(SCH_1):PAGE81
   235 M_J_C<2> @BASEBOARD_FAB2_LIB.BASEBOARD_FAB2(SCH_1):M_J_C(2)   I186 @BASEBOARD_FAB2_LIB.BASEBOARD_FAB2(SCH_1):PAGE81
   199 M_J_ECC<6> @BASEBOARD_FAB2_LIB.BASEBOARD_FAB2(SCH_1):M_J_ECC(6)   I186 @BASEBOARD_FAB2_LIB.BASEBOARD_FAB2(SCH_1):PAGE81
    54 M_J_ECC<7> @BASEBOARD_FAB2_LIB.BASEBOARD_FAB2(SCH_1):M_J_ECC(7)   I186 @BASEBOARD_FAB2_LIB.BASEBOARD_FAB2(SCH_1):PAGE81
   192 M_J_ECC<4> @BASEBOARD_FAB2_LIB.BASEBOARD_FAB2(SCH_1):M_J_ECC(4)   I186 @BASEBOARD_FAB2_LIB.BASEBOARD_FAB2(SCH_1):PAGE81
    47 M_J_ECC<5> @BASEBOARD_FAB2_LIB.BASEBOARD_FAB2(SCH_1):M_J_ECC(5)   I186 @BASEBOARD_FAB2_LIB.BASEBOARD_FAB2(SCH_1):PAGE81
   201 M_J_ECC<2> @BASEBOARD_FAB2_LIB.BASEBOARD_FAB2(SCH_1):M_J_ECC(2)   I186 @BASEBOARD_FAB2_LIB.BASEBOARD_FAB2(SCH_1):PAGE81
    56 M_J_ECC<3> @BASEBOARD_FAB2_LIB.BASEBOARD_FAB2(SCH_1):M_J_ECC(3)   I186 @BASEBOARD_FAB2_LIB.BASEBOARD_FAB2(SCH_1):PAGE81
   194 M_J_ECC<0> @BASEBOARD_FAB2_LIB.BASEBOARD_FAB2(SCH_1):M_J_ECC(0)   I186 @BASEBOARD_FAB2_LIB.BASEBOARD_FAB2(SCH_1):PAGE81
    49 M_J_ECC<1> @BASEBOARD_FAB2_LIB.BASEBOARD_FAB2(SCH_1):M_J_ECC(1)   I186 @BASEBOARD_FAB2_LIB.BASEBOARD_FAB2(SCH_1):PAGE81
    75 M_J_CLK_DN<0> @BASEBOARD_FAB2_LIB.BASEBOARD_FAB2(SCH_1):M_J_CLK_DN(0)   I186 @BASEBOARD_FAB2_LIB.BASEBOARD_FAB2(SCH_1):PAGE81
    74 M_J_CLK_DP<0> @BASEBOARD_FAB2_LIB.BASEBOARD_FAB2(SCH_1):M_J_CLK_DP(0)   I186 @BASEBOARD_FAB2_LIB.BASEBOARD_FAB2(SCH_1):PAGE81
   219 M_J_CLK_DN<1> @BASEBOARD_FAB2_LIB.BASEBOARD_FAB2(SCH_1):M_J_CLK_DN(1)   I186 @BASEBOARD_FAB2_LIB.BASEBOARD_FAB2(SCH_1):PAGE81
   218 M_J_CLK_DP<1> @BASEBOARD_FAB2_LIB.BASEBOARD_FAB2(SCH_1):M_J_CLK_DP(1)   I186 @BASEBOARD_FAB2_LIB.BASEBOARD_FAB2(SCH_1):PAGE81
   203 M_J_CKE<1> @BASEBOARD_FAB2_LIB.BASEBOARD_FAB2(SCH_1):M_J_CKE(1)   I186 @BASEBOARD_FAB2_LIB.BASEBOARD_FAB2(SCH_1):PAGE81
    60 M_J_CKE<0> @BASEBOARD_FAB2_LIB.BASEBOARD_FAB2(SCH_1):M_J_CKE(0)   I186 @BASEBOARD_FAB2_LIB.BASEBOARD_FAB2(SCH_1):PAGE81
   280 M_J_DQ<62> @BASEBOARD_FAB2_LIB.BASEBOARD_FAB2(SCH_1):M_J_DQ(62)   I186 @BASEBOARD_FAB2_LIB.BASEBOARD_FAB2(SCH_1):PAGE81
   135 M_J_DQ<63> @BASEBOARD_FAB2_LIB.BASEBOARD_FAB2(SCH_1):M_J_DQ(63)   I186 @BASEBOARD_FAB2_LIB.BASEBOARD_FAB2(SCH_1):PAGE81
   273 M_J_DQ<60> @BASEBOARD_FAB2_LIB.BASEBOARD_FAB2(SCH_1):M_J_DQ(60)   I186 @BASEBOARD_FAB2_LIB.BASEBOARD_FAB2(SCH_1):PAGE81
   128 M_J_DQ<61> @BASEBOARD_FAB2_LIB.BASEBOARD_FAB2(SCH_1):M_J_DQ(61)   I186 @BASEBOARD_FAB2_LIB.BASEBOARD_FAB2(SCH_1):PAGE81
   282 M_J_DQ<58> @BASEBOARD_FAB2_LIB.BASEBOARD_FAB2(SCH_1):M_J_DQ(58)   I186 @BASEBOARD_FAB2_LIB.BASEBOARD_FAB2(SCH_1):PAGE81
   137 M_J_DQ<59> @BASEBOARD_FAB2_LIB.BASEBOARD_FAB2(SCH_1):M_J_DQ(59)   I186 @BASEBOARD_FAB2_LIB.BASEBOARD_FAB2(SCH_1):PAGE81
   275 M_J_DQ<56> @BASEBOARD_FAB2_LIB.BASEBOARD_FAB2(SCH_1):M_J_DQ(56)   I186 @BASEBOARD_FAB2_LIB.BASEBOARD_FAB2(SCH_1):PAGE81
   130 M_J_DQ<57> @BASEBOARD_FAB2_LIB.BASEBOARD_FAB2(SCH_1):M_J_DQ(57)   I186 @BASEBOARD_FAB2_LIB.BASEBOARD_FAB2(SCH_1):PAGE81
   269 M_J_DQ<54> @BASEBOARD_FAB2_LIB.BASEBOARD_FAB2(SCH_1):M_J_DQ(54)   I186 @BASEBOARD_FAB2_LIB.BASEBOARD_FAB2(SCH_1):PAGE81
   124 M_J_DQ<55> @BASEBOARD_FAB2_LIB.BASEBOARD_FAB2(SCH_1):M_J_DQ(55)   I186 @BASEBOARD_FAB2_LIB.BASEBOARD_FAB2(SCH_1):PAGE81
   262 M_J_DQ<52> @BASEBOARD_FAB2_LIB.BASEBOARD_FAB2(SCH_1):M_J_DQ(52)   I186 @BASEBOARD_FAB2_LIB.BASEBOARD_FAB2(SCH_1):PAGE81
   117 M_J_DQ<53> @BASEBOARD_FAB2_LIB.BASEBOARD_FAB2(SCH_1):M_J_DQ(53)   I186 @BASEBOARD_FAB2_LIB.BASEBOARD_FAB2(SCH_1):PAGE81
   271 M_J_DQ<50> @BASEBOARD_FAB2_LIB.BASEBOARD_FAB2(SCH_1):M_J_DQ(50)   I186 @BASEBOARD_FAB2_LIB.BASEBOARD_FAB2(SCH_1):PAGE81
   126 M_J_DQ<51> @BASEBOARD_FAB2_LIB.BASEBOARD_FAB2(SCH_1):M_J_DQ(51)   I186 @BASEBOARD_FAB2_LIB.BASEBOARD_FAB2(SCH_1):PAGE81
   264 M_J_DQ<48> @BASEBOARD_FAB2_LIB.BASEBOARD_FAB2(SCH_1):M_J_DQ(48)   I186 @BASEBOARD_FAB2_LIB.BASEBOARD_FAB2(SCH_1):PAGE81
   119 M_J_DQ<49> @BASEBOARD_FAB2_LIB.BASEBOARD_FAB2(SCH_1):M_J_DQ(49)   I186 @BASEBOARD_FAB2_LIB.BASEBOARD_FAB2(SCH_1):PAGE81
   258 M_J_DQ<46> @BASEBOARD_FAB2_LIB.BASEBOARD_FAB2(SCH_1):M_J_DQ(46)   I186 @BASEBOARD_FAB2_LIB.BASEBOARD_FAB2(SCH_1):PAGE81
   113 M_J_DQ<47> @BASEBOARD_FAB2_LIB.BASEBOARD_FAB2(SCH_1):M_J_DQ(47)   I186 @BASEBOARD_FAB2_LIB.BASEBOARD_FAB2(SCH_1):PAGE81
   251 M_J_DQ<44> @BASEBOARD_FAB2_LIB.BASEBOARD_FAB2(SCH_1):M_J_DQ(44)   I186 @BASEBOARD_FAB2_LIB.BASEBOARD_FAB2(SCH_1):PAGE81
   106 M_J_DQ<45> @BASEBOARD_FAB2_LIB.BASEBOARD_FAB2(SCH_1):M_J_DQ(45)   I186 @BASEBOARD_FAB2_LIB.BASEBOARD_FAB2(SCH_1):PAGE81
   260 M_J_DQ<42> @BASEBOARD_FAB2_LIB.BASEBOARD_FAB2(SCH_1):M_J_DQ(42)   I186 @BASEBOARD_FAB2_LIB.BASEBOARD_FAB2(SCH_1):PAGE81
   115 M_J_DQ<43> @BASEBOARD_FAB2_LIB.BASEBOARD_FAB2(SCH_1):M_J_DQ(43)   I186 @BASEBOARD_FAB2_LIB.BASEBOARD_FAB2(SCH_1):PAGE81
   253 M_J_DQ<40> @BASEBOARD_FAB2_LIB.BASEBOARD_FAB2(SCH_1):M_J_DQ(40)   I186 @BASEBOARD_FAB2_LIB.BASEBOARD_FAB2(SCH_1):PAGE81
   108 M_J_DQ<41> @BASEBOARD_FAB2_LIB.BASEBOARD_FAB2(SCH_1):M_J_DQ(41)   I186 @BASEBOARD_FAB2_LIB.BASEBOARD_FAB2(SCH_1):PAGE81
   247 M_J_DQ<38> @BASEBOARD_FAB2_LIB.BASEBOARD_FAB2(SCH_1):M_J_DQ(38)   I186 @BASEBOARD_FAB2_LIB.BASEBOARD_FAB2(SCH_1):PAGE81
   102 M_J_DQ<39> @BASEBOARD_FAB2_LIB.BASEBOARD_FAB2(SCH_1):M_J_DQ(39)   I186 @BASEBOARD_FAB2_LIB.BASEBOARD_FAB2(SCH_1):PAGE81
   240 M_J_DQ<36> @BASEBOARD_FAB2_LIB.BASEBOARD_FAB2(SCH_1):M_J_DQ(36)   I186 @BASEBOARD_FAB2_LIB.BASEBOARD_FAB2(SCH_1):PAGE81
    95 M_J_DQ<37> @BASEBOARD_FAB2_LIB.BASEBOARD_FAB2(SCH_1):M_J_DQ(37)   I186 @BASEBOARD_FAB2_LIB.BASEBOARD_FAB2(SCH_1):PAGE81
   249 M_J_DQ<34> @BASEBOARD_FAB2_LIB.BASEBOARD_FAB2(SCH_1):M_J_DQ(34)   I186 @BASEBOARD_FAB2_LIB.BASEBOARD_FAB2(SCH_1):PAGE81
   104 M_J_DQ<35> @BASEBOARD_FAB2_LIB.BASEBOARD_FAB2(SCH_1):M_J_DQ(35)   I186 @BASEBOARD_FAB2_LIB.BASEBOARD_FAB2(SCH_1):PAGE81
   242 M_J_DQ<32> @BASEBOARD_FAB2_LIB.BASEBOARD_FAB2(SCH_1):M_J_DQ(32)   I186 @BASEBOARD_FAB2_LIB.BASEBOARD_FAB2(SCH_1):PAGE81
    97 M_J_DQ<33> @BASEBOARD_FAB2_LIB.BASEBOARD_FAB2(SCH_1):M_J_DQ(33)   I186 @BASEBOARD_FAB2_LIB.BASEBOARD_FAB2(SCH_1):PAGE81
   188 M_J_DQ<30> @BASEBOARD_FAB2_LIB.BASEBOARD_FAB2(SCH_1):M_J_DQ(30)   I186 @BASEBOARD_FAB2_LIB.BASEBOARD_FAB2(SCH_1):PAGE81
    43 M_J_DQ<31> @BASEBOARD_FAB2_LIB.BASEBOARD_FAB2(SCH_1):M_J_DQ(31)   I186 @BASEBOARD_FAB2_LIB.BASEBOARD_FAB2(SCH_1):PAGE81
   181 M_J_DQ<28> @BASEBOARD_FAB2_LIB.BASEBOARD_FAB2(SCH_1):M_J_DQ(28)   I186 @BASEBOARD_FAB2_LIB.BASEBOARD_FAB2(SCH_1):PAGE81
    36 M_J_DQ<29> @BASEBOARD_FAB2_LIB.BASEBOARD_FAB2(SCH_1):M_J_DQ(29)   I186 @BASEBOARD_FAB2_LIB.BASEBOARD_FAB2(SCH_1):PAGE81
   190 M_J_DQ<26> @BASEBOARD_FAB2_LIB.BASEBOARD_FAB2(SCH_1):M_J_DQ(26)   I186 @BASEBOARD_FAB2_LIB.BASEBOARD_FAB2(SCH_1):PAGE81
    45 M_J_DQ<27> @BASEBOARD_FAB2_LIB.BASEBOARD_FAB2(SCH_1):M_J_DQ(27)   I186 @BASEBOARD_FAB2_LIB.BASEBOARD_FAB2(SCH_1):PAGE81
   183 M_J_DQ<24> @BASEBOARD_FAB2_LIB.BASEBOARD_FAB2(SCH_1):M_J_DQ(24)   I186 @BASEBOARD_FAB2_LIB.BASEBOARD_FAB2(SCH_1):PAGE81
    38 M_J_DQ<25> @BASEBOARD_FAB2_LIB.BASEBOARD_FAB2(SCH_1):M_J_DQ(25)   I186 @BASEBOARD_FAB2_LIB.BASEBOARD_FAB2(SCH_1):PAGE81
   177 M_J_DQ<22> @BASEBOARD_FAB2_LIB.BASEBOARD_FAB2(SCH_1):M_J_DQ(22)   I186 @BASEBOARD_FAB2_LIB.BASEBOARD_FAB2(SCH_1):PAGE81
    32 M_J_DQ<23> @BASEBOARD_FAB2_LIB.BASEBOARD_FAB2(SCH_1):M_J_DQ(23)   I186 @BASEBOARD_FAB2_LIB.BASEBOARD_FAB2(SCH_1):PAGE81
   170 M_J_DQ<20> @BASEBOARD_FAB2_LIB.BASEBOARD_FAB2(SCH_1):M_J_DQ(20)   I186 @BASEBOARD_FAB2_LIB.BASEBOARD_FAB2(SCH_1):PAGE81
    25 M_J_DQ<21> @BASEBOARD_FAB2_LIB.BASEBOARD_FAB2(SCH_1):M_J_DQ(21)   I186 @BASEBOARD_FAB2_LIB.BASEBOARD_FAB2(SCH_1):PAGE81
   179 M_J_DQ<18> @BASEBOARD_FAB2_LIB.BASEBOARD_FAB2(SCH_1):M_J_DQ(18)   I186 @BASEBOARD_FAB2_LIB.BASEBOARD_FAB2(SCH_1):PAGE81
    34 M_J_DQ<19> @BASEBOARD_FAB2_LIB.BASEBOARD_FAB2(SCH_1):M_J_DQ(19)   I186 @BASEBOARD_FAB2_LIB.BASEBOARD_FAB2(SCH_1):PAGE81
   172 M_J_DQ<16> @BASEBOARD_FAB2_LIB.BASEBOARD_FAB2(SCH_1):M_J_DQ(16)   I186 @BASEBOARD_FAB2_LIB.BASEBOARD_FAB2(SCH_1):PAGE81
    27 M_J_DQ<17> @BASEBOARD_FAB2_LIB.BASEBOARD_FAB2(SCH_1):M_J_DQ(17)   I186 @BASEBOARD_FAB2_LIB.BASEBOARD_FAB2(SCH_1):PAGE81
   166 M_J_DQ<14> @BASEBOARD_FAB2_LIB.BASEBOARD_FAB2(SCH_1):M_J_DQ(14)   I186 @BASEBOARD_FAB2_LIB.BASEBOARD_FAB2(SCH_1):PAGE81
    21 M_J_DQ<15> @BASEBOARD_FAB2_LIB.BASEBOARD_FAB2(SCH_1):M_J_DQ(15)   I186 @BASEBOARD_FAB2_LIB.BASEBOARD_FAB2(SCH_1):PAGE81
   159 M_J_DQ<12> @BASEBOARD_FAB2_LIB.BASEBOARD_FAB2(SCH_1):M_J_DQ(12)   I186 @BASEBOARD_FAB2_LIB.BASEBOARD_FAB2(SCH_1):PAGE81
    14 M_J_DQ<13> @BASEBOARD_FAB2_LIB.BASEBOARD_FAB2(SCH_1):M_J_DQ(13)   I186 @BASEBOARD_FAB2_LIB.BASEBOARD_FAB2(SCH_1):PAGE81
   168 M_J_DQ<10> @BASEBOARD_FAB2_LIB.BASEBOARD_FAB2(SCH_1):M_J_DQ(10)   I186 @BASEBOARD_FAB2_LIB.BASEBOARD_FAB2(SCH_1):PAGE81
    23 M_J_DQ<11> @BASEBOARD_FAB2_LIB.BASEBOARD_FAB2(SCH_1):M_J_DQ(11)   I186 @BASEBOARD_FAB2_LIB.BASEBOARD_FAB2(SCH_1):PAGE81
   161 M_J_DQ<8> @BASEBOARD_FAB2_LIB.BASEBOARD_FAB2(SCH_1):M_J_DQ(8)   I186 @BASEBOARD_FAB2_LIB.BASEBOARD_FAB2(SCH_1):PAGE81
    16 M_J_DQ<9> @BASEBOARD_FAB2_LIB.BASEBOARD_FAB2(SCH_1):M_J_DQ(9)   I186 @BASEBOARD_FAB2_LIB.BASEBOARD_FAB2(SCH_1):PAGE81
   155 M_J_DQ<6> @BASEBOARD_FAB2_LIB.BASEBOARD_FAB2(SCH_1):M_J_DQ(6)   I186 @BASEBOARD_FAB2_LIB.BASEBOARD_FAB2(SCH_1):PAGE81
    10 M_J_DQ<7> @BASEBOARD_FAB2_LIB.BASEBOARD_FAB2(SCH_1):M_J_DQ(7)   I186 @BASEBOARD_FAB2_LIB.BASEBOARD_FAB2(SCH_1):PAGE81
   148 M_J_DQ<4> @BASEBOARD_FAB2_LIB.BASEBOARD_FAB2(SCH_1):M_J_DQ(4)   I186 @BASEBOARD_FAB2_LIB.BASEBOARD_FAB2(SCH_1):PAGE81
     3 M_J_DQ<5> @BASEBOARD_FAB2_LIB.BASEBOARD_FAB2(SCH_1):M_J_DQ(5)   I186 @BASEBOARD_FAB2_LIB.BASEBOARD_FAB2(SCH_1):PAGE81
   157 M_J_DQ<2> @BASEBOARD_FAB2_LIB.BASEBOARD_FAB2(SCH_1):M_J_DQ(2)   I186 @BASEBOARD_FAB2_LIB.BASEBOARD_FAB2(SCH_1):PAGE81
    12 M_J_DQ<3> @BASEBOARD_FAB2_LIB.BASEBOARD_FAB2(SCH_1):M_J_DQ(3)   I186 @BASEBOARD_FAB2_LIB.BASEBOARD_FAB2(SCH_1):PAGE81
   150 M_J_DQ<0> @BASEBOARD_FAB2_LIB.BASEBOARD_FAB2(SCH_1):M_J_DQ(0)   I186 @BASEBOARD_FAB2_LIB.BASEBOARD_FAB2(SCH_1):PAGE81
     5 M_J_DQ<1> @BASEBOARD_FAB2_LIB.BASEBOARD_FAB2(SCH_1):M_J_DQ(1)   I186 @BASEBOARD_FAB2_LIB.BASEBOARD_FAB2(SCH_1):PAGE81
    78 FM_DIMM_EVENT_COD_N @BASEBOARD_FAB2_LIB.BASEBOARD_FAB2(SCH_1):FM_DIMM_EVENT_COD_N   I186 @BASEBOARD_FAB2_LIB.BASEBOARD_FAB2(SCH_1):PAGE81
    91 M_J_ODT<1> @BASEBOARD_FAB2_LIB.BASEBOARD_FAB2(SCH_1):M_J_ODT(1)   I186 @BASEBOARD_FAB2_LIB.BASEBOARD_FAB2(SCH_1):PAGE81
    87 M_J_ODT<0> @BASEBOARD_FAB2_LIB.BASEBOARD_FAB2(SCH_1):M_J_ODT(0)   I186 @BASEBOARD_FAB2_LIB.BASEBOARD_FAB2(SCH_1):PAGE81
   222 M_J_PAR @BASEBOARD_FAB2_LIB.BASEBOARD_FAB2(SCH_1):M_J_PAR   I186 @BASEBOARD_FAB2_LIB.BASEBOARD_FAB2(SCH_1):PAGE81
    58 M_GHJ_RST_N @BASEBOARD_FAB2_LIB.BASEBOARD_FAB2(SCH_1):M_GHJ_RST_N   I186 @BASEBOARD_FAB2_LIB.BASEBOARD_FAB2(SCH_1):PAGE81
   144 TP_CH_J_DIMM_J0_RFU_2 @BASEBOARD_FAB2_LIB.BASEBOARD_FAB2(SCH_1):TP_CH_J_DIMM_J0_RFU_2   I186 @BASEBOARD_FAB2_LIB.BASEBOARD_FAB2(SCH_1):PAGE81
   227 TP_CH_J_DIMM_J0_RFU_1 @BASEBOARD_FAB2_LIB.BASEBOARD_FAB2(SCH_1):TP_CH_J_DIMM_J0_RFU_1   I186 @BASEBOARD_FAB2_LIB.BASEBOARD_FAB2(SCH_1):PAGE81
   205 TP_CH_J_DIMM_J0_RFU_0 @BASEBOARD_FAB2_LIB.BASEBOARD_FAB2(SCH_1):TP_CH_J_DIMM_J0_RFU_0   I186 @BASEBOARD_FAB2_LIB.BASEBOARD_FAB2(SCH_1):PAGE81
    84 M_J_CS_N<0> @BASEBOARD_FAB2_LIB.BASEBOARD_FAB2(SCH_1):M_J_CS_N(0)   I186 @BASEBOARD_FAB2_LIB.BASEBOARD_FAB2(SCH_1):PAGE81
    89 M_J_CS_N<1> @BASEBOARD_FAB2_LIB.BASEBOARD_FAB2(SCH_1):M_J_CS_N(1)   I186 @BASEBOARD_FAB2_LIB.BASEBOARD_FAB2(SCH_1):PAGE81
    93 M_J_CS_N<2> @BASEBOARD_FAB2_LIB.BASEBOARD_FAB2(SCH_1):M_J_CS_N(2)   I186 @BASEBOARD_FAB2_LIB.BASEBOARD_FAB2(SCH_1):PAGE81
   237 M_J_CS_N<3> @BASEBOARD_FAB2_LIB.BASEBOARD_FAB2(SCH_1):M_J_CS_N(3)   I186 @BASEBOARD_FAB2_LIB.BASEBOARD_FAB2(SCH_1):PAGE81
   238 PVPP_GHJ @BASEBOARD_FAB2_LIB.BASEBOARD_FAB2(SCH_1):PVPP_GHJ   I186 @BASEBOARD_FAB2_LIB.BASEBOARD_FAB2(SCH_1):PAGE81
   140    GND @BASEBOARD_FAB2_LIB.BASEBOARD_FAB2(SCH_1):GND   I186 @BASEBOARD_FAB2_LIB.BASEBOARD_FAB2(SCH_1):PAGE81
   139    GND @BASEBOARD_FAB2_LIB.BASEBOARD_FAB2(SCH_1):GND   I186 @BASEBOARD_FAB2_LIB.BASEBOARD_FAB2(SCH_1):PAGE81
   230 FM_ADR_COMPLETE_GHJ_N @BASEBOARD_FAB2_LIB.BASEBOARD_FAB2(SCH_1):FM_ADR_COMPLETE_GHJ_N   I186 @BASEBOARD_FAB2_LIB.BASEBOARD_FAB2(SCH_1):PAGE81
   141 SMB_DDR_GHJ_VPP_SCL @BASEBOARD_FAB2_LIB.BASEBOARD_FAB2(SCH_1):SMB_DDR_GHJ_VPP_SCL   I186 @BASEBOARD_FAB2_LIB.BASEBOARD_FAB2(SCH_1):PAGE81
   285 SMB_DDR_GHJ_VPP_SDA @BASEBOARD_FAB2_LIB.BASEBOARD_FAB2(SCH_1):SMB_DDR_GHJ_VPP_SDA   I186 @BASEBOARD_FAB2_LIB.BASEBOARD_FAB2(SCH_1):PAGE81
   284 PVPP_GHJ @BASEBOARD_FAB2_LIB.BASEBOARD_FAB2(SCH_1):PVPP_GHJ   I186 @BASEBOARD_FAB2_LIB.BASEBOARD_FAB2(SCH_1):PAGE81
   146 M_J_VREF @BASEBOARD_FAB2_LIB.BASEBOARD_FAB2(SCH_1):M_J_VREF   I186 @BASEBOARD_FAB2_LIB.BASEBOARD_FAB2(SCH_1):PAGE81
   152 M_J_DQS_DN<0> @BASEBOARD_FAB2_LIB.BASEBOARD_FAB2(SCH_1):M_J_DQS_DN(0)    I67 @BASEBOARD_FAB2_LIB.BASEBOARD_FAB2(SCH_1):PAGE81
   153 M_J_DQS_DP<0> @BASEBOARD_FAB2_LIB.BASEBOARD_FAB2(SCH_1):M_J_DQS_DP(0)    I67 @BASEBOARD_FAB2_LIB.BASEBOARD_FAB2(SCH_1):PAGE81
    19 M_J_DQS_DN<10> @BASEBOARD_FAB2_LIB.BASEBOARD_FAB2(SCH_1):M_J_DQS_DN(10)    I67 @BASEBOARD_FAB2_LIB.BASEBOARD_FAB2(SCH_1):PAGE81
    18 M_J_DQS_DP<10> @BASEBOARD_FAB2_LIB.BASEBOARD_FAB2(SCH_1):M_J_DQS_DP(10)    I67 @BASEBOARD_FAB2_LIB.BASEBOARD_FAB2(SCH_1):PAGE81
    30 M_J_DQS_DN<11> @BASEBOARD_FAB2_LIB.BASEBOARD_FAB2(SCH_1):M_J_DQS_DN(11)    I67 @BASEBOARD_FAB2_LIB.BASEBOARD_FAB2(SCH_1):PAGE81
    29 M_J_DQS_DP<11> @BASEBOARD_FAB2_LIB.BASEBOARD_FAB2(SCH_1):M_J_DQS_DP(11)    I67 @BASEBOARD_FAB2_LIB.BASEBOARD_FAB2(SCH_1):PAGE81
    41 M_J_DQS_DN<12> @BASEBOARD_FAB2_LIB.BASEBOARD_FAB2(SCH_1):M_J_DQS_DN(12)    I67 @BASEBOARD_FAB2_LIB.BASEBOARD_FAB2(SCH_1):PAGE81
    40 M_J_DQS_DP<12> @BASEBOARD_FAB2_LIB.BASEBOARD_FAB2(SCH_1):M_J_DQS_DP(12)    I67 @BASEBOARD_FAB2_LIB.BASEBOARD_FAB2(SCH_1):PAGE81
   100 M_J_DQS_DN<13> @BASEBOARD_FAB2_LIB.BASEBOARD_FAB2(SCH_1):M_J_DQS_DN(13)    I67 @BASEBOARD_FAB2_LIB.BASEBOARD_FAB2(SCH_1):PAGE81
    99 M_J_DQS_DP<13> @BASEBOARD_FAB2_LIB.BASEBOARD_FAB2(SCH_1):M_J_DQS_DP(13)    I67 @BASEBOARD_FAB2_LIB.BASEBOARD_FAB2(SCH_1):PAGE81
   111 M_J_DQS_DN<14> @BASEBOARD_FAB2_LIB.BASEBOARD_FAB2(SCH_1):M_J_DQS_DN(14)    I67 @BASEBOARD_FAB2_LIB.BASEBOARD_FAB2(SCH_1):PAGE81
   110 M_J_DQS_DP<14> @BASEBOARD_FAB2_LIB.BASEBOARD_FAB2(SCH_1):M_J_DQS_DP(14)    I67 @BASEBOARD_FAB2_LIB.BASEBOARD_FAB2(SCH_1):PAGE81
   122 M_J_DQS_DN<15> @BASEBOARD_FAB2_LIB.BASEBOARD_FAB2(SCH_1):M_J_DQS_DN(15)    I67 @BASEBOARD_FAB2_LIB.BASEBOARD_FAB2(SCH_1):PAGE81
   121 M_J_DQS_DP<15> @BASEBOARD_FAB2_LIB.BASEBOARD_FAB2(SCH_1):M_J_DQS_DP(15)    I67 @BASEBOARD_FAB2_LIB.BASEBOARD_FAB2(SCH_1):PAGE81
   133 M_J_DQS_DN<16> @BASEBOARD_FAB2_LIB.BASEBOARD_FAB2(SCH_1):M_J_DQS_DN(16)    I67 @BASEBOARD_FAB2_LIB.BASEBOARD_FAB2(SCH_1):PAGE81
   132 M_J_DQS_DP<16> @BASEBOARD_FAB2_LIB.BASEBOARD_FAB2(SCH_1):M_J_DQS_DP(16)    I67 @BASEBOARD_FAB2_LIB.BASEBOARD_FAB2(SCH_1):PAGE81
    52 M_J_DQS_DN<17> @BASEBOARD_FAB2_LIB.BASEBOARD_FAB2(SCH_1):M_J_DQS_DN(17)    I67 @BASEBOARD_FAB2_LIB.BASEBOARD_FAB2(SCH_1):PAGE81
    51 M_J_DQS_DP<17> @BASEBOARD_FAB2_LIB.BASEBOARD_FAB2(SCH_1):M_J_DQS_DP(17)    I67 @BASEBOARD_FAB2_LIB.BASEBOARD_FAB2(SCH_1):PAGE81
   163 M_J_DQS_DN<1> @BASEBOARD_FAB2_LIB.BASEBOARD_FAB2(SCH_1):M_J_DQS_DN(1)    I67 @BASEBOARD_FAB2_LIB.BASEBOARD_FAB2(SCH_1):PAGE81
   164 M_J_DQS_DP<1> @BASEBOARD_FAB2_LIB.BASEBOARD_FAB2(SCH_1):M_J_DQS_DP(1)    I67 @BASEBOARD_FAB2_LIB.BASEBOARD_FAB2(SCH_1):PAGE81
   174 M_J_DQS_DN<2> @BASEBOARD_FAB2_LIB.BASEBOARD_FAB2(SCH_1):M_J_DQS_DN(2)    I67 @BASEBOARD_FAB2_LIB.BASEBOARD_FAB2(SCH_1):PAGE81
   175 M_J_DQS_DP<2> @BASEBOARD_FAB2_LIB.BASEBOARD_FAB2(SCH_1):M_J_DQS_DP(2)    I67 @BASEBOARD_FAB2_LIB.BASEBOARD_FAB2(SCH_1):PAGE81
   185 M_J_DQS_DN<3> @BASEBOARD_FAB2_LIB.BASEBOARD_FAB2(SCH_1):M_J_DQS_DN(3)    I67 @BASEBOARD_FAB2_LIB.BASEBOARD_FAB2(SCH_1):PAGE81
   186 M_J_DQS_DP<3> @BASEBOARD_FAB2_LIB.BASEBOARD_FAB2(SCH_1):M_J_DQS_DP(3)    I67 @BASEBOARD_FAB2_LIB.BASEBOARD_FAB2(SCH_1):PAGE81
   244 M_J_DQS_DN<4> @BASEBOARD_FAB2_LIB.BASEBOARD_FAB2(SCH_1):M_J_DQS_DN(4)    I67 @BASEBOARD_FAB2_LIB.BASEBOARD_FAB2(SCH_1):PAGE81
   245 M_J_DQS_DP<4> @BASEBOARD_FAB2_LIB.BASEBOARD_FAB2(SCH_1):M_J_DQS_DP(4)    I67 @BASEBOARD_FAB2_LIB.BASEBOARD_FAB2(SCH_1):PAGE81
   255 M_J_DQS_DN<5> @BASEBOARD_FAB2_LIB.BASEBOARD_FAB2(SCH_1):M_J_DQS_DN(5)    I67 @BASEBOARD_FAB2_LIB.BASEBOARD_FAB2(SCH_1):PAGE81
   256 M_J_DQS_DP<5> @BASEBOARD_FAB2_LIB.BASEBOARD_FAB2(SCH_1):M_J_DQS_DP(5)    I67 @BASEBOARD_FAB2_LIB.BASEBOARD_FAB2(SCH_1):PAGE81
   266 M_J_DQS_DN<6> @BASEBOARD_FAB2_LIB.BASEBOARD_FAB2(SCH_1):M_J_DQS_DN(6)    I67 @BASEBOARD_FAB2_LIB.BASEBOARD_FAB2(SCH_1):PAGE81
   267 M_J_DQS_DP<6> @BASEBOARD_FAB2_LIB.BASEBOARD_FAB2(SCH_1):M_J_DQS_DP(6)    I67 @BASEBOARD_FAB2_LIB.BASEBOARD_FAB2(SCH_1):PAGE81
   277 M_J_DQS_DN<7> @BASEBOARD_FAB2_LIB.BASEBOARD_FAB2(SCH_1):M_J_DQS_DN(7)    I67 @BASEBOARD_FAB2_LIB.BASEBOARD_FAB2(SCH_1):PAGE81
   278 M_J_DQS_DP<7> @BASEBOARD_FAB2_LIB.BASEBOARD_FAB2(SCH_1):M_J_DQS_DP(7)    I67 @BASEBOARD_FAB2_LIB.BASEBOARD_FAB2(SCH_1):PAGE81
   196 M_J_DQS_DN<8> @BASEBOARD_FAB2_LIB.BASEBOARD_FAB2(SCH_1):M_J_DQS_DN(8)    I67 @BASEBOARD_FAB2_LIB.BASEBOARD_FAB2(SCH_1):PAGE81
   197 M_J_DQS_DP<8> @BASEBOARD_FAB2_LIB.BASEBOARD_FAB2(SCH_1):M_J_DQS_DP(8)    I67 @BASEBOARD_FAB2_LIB.BASEBOARD_FAB2(SCH_1):PAGE81
     8 M_J_DQS_DN<9> @BASEBOARD_FAB2_LIB.BASEBOARD_FAB2(SCH_1):M_J_DQS_DN(9)    I67 @BASEBOARD_FAB2_LIB.BASEBOARD_FAB2(SCH_1):PAGE81
     7 M_J_DQS_DP<9> @BASEBOARD_FAB2_LIB.BASEBOARD_FAB2(SCH_1):M_J_DQS_DP(9)    I67 @BASEBOARD_FAB2_LIB.BASEBOARD_FAB2(SCH_1):PAGE81
     2    GND @BASEBOARD_FAB2_LIB.BASEBOARD_FAB2(SCH_1):GND   I185 @BASEBOARD_FAB2_LIB.BASEBOARD_FAB2(SCH_1):PAGE81
     4    GND @BASEBOARD_FAB2_LIB.BASEBOARD_FAB2(SCH_1):GND   I185 @BASEBOARD_FAB2_LIB.BASEBOARD_FAB2(SCH_1):PAGE81
     6    GND @BASEBOARD_FAB2_LIB.BASEBOARD_FAB2(SCH_1):GND   I185 @BASEBOARD_FAB2_LIB.BASEBOARD_FAB2(SCH_1):PAGE81
     9    GND @BASEBOARD_FAB2_LIB.BASEBOARD_FAB2(SCH_1):GND   I185 @BASEBOARD_FAB2_LIB.BASEBOARD_FAB2(SCH_1):PAGE81
    11    GND @BASEBOARD_FAB2_LIB.BASEBOARD_FAB2(SCH_1):GND   I185 @BASEBOARD_FAB2_LIB.BASEBOARD_FAB2(SCH_1):PAGE81
    13    GND @BASEBOARD_FAB2_LIB.BASEBOARD_FAB2(SCH_1):GND   I185 @BASEBOARD_FAB2_LIB.BASEBOARD_FAB2(SCH_1):PAGE81
    15    GND @BASEBOARD_FAB2_LIB.BASEBOARD_FAB2(SCH_1):GND   I185 @BASEBOARD_FAB2_LIB.BASEBOARD_FAB2(SCH_1):PAGE81
    17    GND @BASEBOARD_FAB2_LIB.BASEBOARD_FAB2(SCH_1):GND   I185 @BASEBOARD_FAB2_LIB.BASEBOARD_FAB2(SCH_1):PAGE81
    20    GND @BASEBOARD_FAB2_LIB.BASEBOARD_FAB2(SCH_1):GND   I185 @BASEBOARD_FAB2_LIB.BASEBOARD_FAB2(SCH_1):PAGE81
    22    GND @BASEBOARD_FAB2_LIB.BASEBOARD_FAB2(SCH_1):GND   I185 @BASEBOARD_FAB2_LIB.BASEBOARD_FAB2(SCH_1):PAGE81
    24    GND @BASEBOARD_FAB2_LIB.BASEBOARD_FAB2(SCH_1):GND   I185 @BASEBOARD_FAB2_LIB.BASEBOARD_FAB2(SCH_1):PAGE81
    26    GND @BASEBOARD_FAB2_LIB.BASEBOARD_FAB2(SCH_1):GND   I185 @BASEBOARD_FAB2_LIB.BASEBOARD_FAB2(SCH_1):PAGE81
    28    GND @BASEBOARD_FAB2_LIB.BASEBOARD_FAB2(SCH_1):GND   I185 @BASEBOARD_FAB2_LIB.BASEBOARD_FAB2(SCH_1):PAGE81
    31    GND @BASEBOARD_FAB2_LIB.BASEBOARD_FAB2(SCH_1):GND   I185 @BASEBOARD_FAB2_LIB.BASEBOARD_FAB2(SCH_1):PAGE81
    33    GND @BASEBOARD_FAB2_LIB.BASEBOARD_FAB2(SCH_1):GND   I185 @BASEBOARD_FAB2_LIB.BASEBOARD_FAB2(SCH_1):PAGE81
    35    GND @BASEBOARD_FAB2_LIB.BASEBOARD_FAB2(SCH_1):GND   I185 @BASEBOARD_FAB2_LIB.BASEBOARD_FAB2(SCH_1):PAGE81
    37    GND @BASEBOARD_FAB2_LIB.BASEBOARD_FAB2(SCH_1):GND   I185 @BASEBOARD_FAB2_LIB.BASEBOARD_FAB2(SCH_1):PAGE81
    39    GND @BASEBOARD_FAB2_LIB.BASEBOARD_FAB2(SCH_1):GND   I185 @BASEBOARD_FAB2_LIB.BASEBOARD_FAB2(SCH_1):PAGE81
    42    GND @BASEBOARD_FAB2_LIB.BASEBOARD_FAB2(SCH_1):GND   I185 @BASEBOARD_FAB2_LIB.BASEBOARD_FAB2(SCH_1):PAGE81
    44    GND @BASEBOARD_FAB2_LIB.BASEBOARD_FAB2(SCH_1):GND   I185 @BASEBOARD_FAB2_LIB.BASEBOARD_FAB2(SCH_1):PAGE81
    46    GND @BASEBOARD_FAB2_LIB.BASEBOARD_FAB2(SCH_1):GND   I185 @BASEBOARD_FAB2_LIB.BASEBOARD_FAB2(SCH_1):PAGE81
    48    GND @BASEBOARD_FAB2_LIB.BASEBOARD_FAB2(SCH_1):GND   I185 @BASEBOARD_FAB2_LIB.BASEBOARD_FAB2(SCH_1):PAGE81
    50    GND @BASEBOARD_FAB2_LIB.BASEBOARD_FAB2(SCH_1):GND   I185 @BASEBOARD_FAB2_LIB.BASEBOARD_FAB2(SCH_1):PAGE81
    53    GND @BASEBOARD_FAB2_LIB.BASEBOARD_FAB2(SCH_1):GND   I185 @BASEBOARD_FAB2_LIB.BASEBOARD_FAB2(SCH_1):PAGE81
    55    GND @BASEBOARD_FAB2_LIB.BASEBOARD_FAB2(SCH_1):GND   I185 @BASEBOARD_FAB2_LIB.BASEBOARD_FAB2(SCH_1):PAGE81
    57    GND @BASEBOARD_FAB2_LIB.BASEBOARD_FAB2(SCH_1):GND   I185 @BASEBOARD_FAB2_LIB.BASEBOARD_FAB2(SCH_1):PAGE81
    94    GND @BASEBOARD_FAB2_LIB.BASEBOARD_FAB2(SCH_1):GND   I185 @BASEBOARD_FAB2_LIB.BASEBOARD_FAB2(SCH_1):PAGE81
    96    GND @BASEBOARD_FAB2_LIB.BASEBOARD_FAB2(SCH_1):GND   I185 @BASEBOARD_FAB2_LIB.BASEBOARD_FAB2(SCH_1):PAGE81
    98    GND @BASEBOARD_FAB2_LIB.BASEBOARD_FAB2(SCH_1):GND   I185 @BASEBOARD_FAB2_LIB.BASEBOARD_FAB2(SCH_1):PAGE81
   101    GND @BASEBOARD_FAB2_LIB.BASEBOARD_FAB2(SCH_1):GND   I185 @BASEBOARD_FAB2_LIB.BASEBOARD_FAB2(SCH_1):PAGE81
   103    GND @BASEBOARD_FAB2_LIB.BASEBOARD_FAB2(SCH_1):GND   I185 @BASEBOARD_FAB2_LIB.BASEBOARD_FAB2(SCH_1):PAGE81
   105    GND @BASEBOARD_FAB2_LIB.BASEBOARD_FAB2(SCH_1):GND   I185 @BASEBOARD_FAB2_LIB.BASEBOARD_FAB2(SCH_1):PAGE81
   107    GND @BASEBOARD_FAB2_LIB.BASEBOARD_FAB2(SCH_1):GND   I185 @BASEBOARD_FAB2_LIB.BASEBOARD_FAB2(SCH_1):PAGE81
   109    GND @BASEBOARD_FAB2_LIB.BASEBOARD_FAB2(SCH_1):GND   I185 @BASEBOARD_FAB2_LIB.BASEBOARD_FAB2(SCH_1):PAGE81
   112    GND @BASEBOARD_FAB2_LIB.BASEBOARD_FAB2(SCH_1):GND   I185 @BASEBOARD_FAB2_LIB.BASEBOARD_FAB2(SCH_1):PAGE81
   114    GND @BASEBOARD_FAB2_LIB.BASEBOARD_FAB2(SCH_1):GND   I185 @BASEBOARD_FAB2_LIB.BASEBOARD_FAB2(SCH_1):PAGE81
   116    GND @BASEBOARD_FAB2_LIB.BASEBOARD_FAB2(SCH_1):GND   I185 @BASEBOARD_FAB2_LIB.BASEBOARD_FAB2(SCH_1):PAGE81
   118    GND @BASEBOARD_FAB2_LIB.BASEBOARD_FAB2(SCH_1):GND   I185 @BASEBOARD_FAB2_LIB.BASEBOARD_FAB2(SCH_1):PAGE81
   120    GND @BASEBOARD_FAB2_LIB.BASEBOARD_FAB2(SCH_1):GND   I185 @BASEBOARD_FAB2_LIB.BASEBOARD_FAB2(SCH_1):PAGE81
   123    GND @BASEBOARD_FAB2_LIB.BASEBOARD_FAB2(SCH_1):GND   I185 @BASEBOARD_FAB2_LIB.BASEBOARD_FAB2(SCH_1):PAGE81
   125    GND @BASEBOARD_FAB2_LIB.BASEBOARD_FAB2(SCH_1):GND   I185 @BASEBOARD_FAB2_LIB.BASEBOARD_FAB2(SCH_1):PAGE81
   127    GND @BASEBOARD_FAB2_LIB.BASEBOARD_FAB2(SCH_1):GND   I185 @BASEBOARD_FAB2_LIB.BASEBOARD_FAB2(SCH_1):PAGE81
   129    GND @BASEBOARD_FAB2_LIB.BASEBOARD_FAB2(SCH_1):GND   I185 @BASEBOARD_FAB2_LIB.BASEBOARD_FAB2(SCH_1):PAGE81
   131    GND @BASEBOARD_FAB2_LIB.BASEBOARD_FAB2(SCH_1):GND   I185 @BASEBOARD_FAB2_LIB.BASEBOARD_FAB2(SCH_1):PAGE81
   134    GND @BASEBOARD_FAB2_LIB.BASEBOARD_FAB2(SCH_1):GND   I185 @BASEBOARD_FAB2_LIB.BASEBOARD_FAB2(SCH_1):PAGE81
   136    GND @BASEBOARD_FAB2_LIB.BASEBOARD_FAB2(SCH_1):GND   I185 @BASEBOARD_FAB2_LIB.BASEBOARD_FAB2(SCH_1):PAGE81
   138    GND @BASEBOARD_FAB2_LIB.BASEBOARD_FAB2(SCH_1):GND   I185 @BASEBOARD_FAB2_LIB.BASEBOARD_FAB2(SCH_1):PAGE81
   147    GND @BASEBOARD_FAB2_LIB.BASEBOARD_FAB2(SCH_1):GND   I185 @BASEBOARD_FAB2_LIB.BASEBOARD_FAB2(SCH_1):PAGE81
   149    GND @BASEBOARD_FAB2_LIB.BASEBOARD_FAB2(SCH_1):GND   I185 @BASEBOARD_FAB2_LIB.BASEBOARD_FAB2(SCH_1):PAGE81
   151    GND @BASEBOARD_FAB2_LIB.BASEBOARD_FAB2(SCH_1):GND   I185 @BASEBOARD_FAB2_LIB.BASEBOARD_FAB2(SCH_1):PAGE81
   154    GND @BASEBOARD_FAB2_LIB.BASEBOARD_FAB2(SCH_1):GND   I185 @BASEBOARD_FAB2_LIB.BASEBOARD_FAB2(SCH_1):PAGE81
   156    GND @BASEBOARD_FAB2_LIB.BASEBOARD_FAB2(SCH_1):GND   I185 @BASEBOARD_FAB2_LIB.BASEBOARD_FAB2(SCH_1):PAGE81
   158    GND @BASEBOARD_FAB2_LIB.BASEBOARD_FAB2(SCH_1):GND   I185 @BASEBOARD_FAB2_LIB.BASEBOARD_FAB2(SCH_1):PAGE81
   160    GND @BASEBOARD_FAB2_LIB.BASEBOARD_FAB2(SCH_1):GND   I185 @BASEBOARD_FAB2_LIB.BASEBOARD_FAB2(SCH_1):PAGE81
   162    GND @BASEBOARD_FAB2_LIB.BASEBOARD_FAB2(SCH_1):GND   I185 @BASEBOARD_FAB2_LIB.BASEBOARD_FAB2(SCH_1):PAGE81
   165    GND @BASEBOARD_FAB2_LIB.BASEBOARD_FAB2(SCH_1):GND   I185 @BASEBOARD_FAB2_LIB.BASEBOARD_FAB2(SCH_1):PAGE81
   167    GND @BASEBOARD_FAB2_LIB.BASEBOARD_FAB2(SCH_1):GND   I185 @BASEBOARD_FAB2_LIB.BASEBOARD_FAB2(SCH_1):PAGE81
   169    GND @BASEBOARD_FAB2_LIB.BASEBOARD_FAB2(SCH_1):GND   I185 @BASEBOARD_FAB2_LIB.BASEBOARD_FAB2(SCH_1):PAGE81
   171    GND @BASEBOARD_FAB2_LIB.BASEBOARD_FAB2(SCH_1):GND   I185 @BASEBOARD_FAB2_LIB.BASEBOARD_FAB2(SCH_1):PAGE81
   173    GND @BASEBOARD_FAB2_LIB.BASEBOARD_FAB2(SCH_1):GND   I185 @BASEBOARD_FAB2_LIB.BASEBOARD_FAB2(SCH_1):PAGE81
   176    GND @BASEBOARD_FAB2_LIB.BASEBOARD_FAB2(SCH_1):GND   I185 @BASEBOARD_FAB2_LIB.BASEBOARD_FAB2(SCH_1):PAGE81
   178    GND @BASEBOARD_FAB2_LIB.BASEBOARD_FAB2(SCH_1):GND   I185 @BASEBOARD_FAB2_LIB.BASEBOARD_FAB2(SCH_1):PAGE81
   180    GND @BASEBOARD_FAB2_LIB.BASEBOARD_FAB2(SCH_1):GND   I185 @BASEBOARD_FAB2_LIB.BASEBOARD_FAB2(SCH_1):PAGE81
   182    GND @BASEBOARD_FAB2_LIB.BASEBOARD_FAB2(SCH_1):GND   I185 @BASEBOARD_FAB2_LIB.BASEBOARD_FAB2(SCH_1):PAGE81
   184    GND @BASEBOARD_FAB2_LIB.BASEBOARD_FAB2(SCH_1):GND   I185 @BASEBOARD_FAB2_LIB.BASEBOARD_FAB2(SCH_1):PAGE81
   187    GND @BASEBOARD_FAB2_LIB.BASEBOARD_FAB2(SCH_1):GND   I185 @BASEBOARD_FAB2_LIB.BASEBOARD_FAB2(SCH_1):PAGE81
   189    GND @BASEBOARD_FAB2_LIB.BASEBOARD_FAB2(SCH_1):GND   I185 @BASEBOARD_FAB2_LIB.BASEBOARD_FAB2(SCH_1):PAGE81
   191    GND @BASEBOARD_FAB2_LIB.BASEBOARD_FAB2(SCH_1):GND   I185 @BASEBOARD_FAB2_LIB.BASEBOARD_FAB2(SCH_1):PAGE81
   193    GND @BASEBOARD_FAB2_LIB.BASEBOARD_FAB2(SCH_1):GND   I185 @BASEBOARD_FAB2_LIB.BASEBOARD_FAB2(SCH_1):PAGE81
   195    GND @BASEBOARD_FAB2_LIB.BASEBOARD_FAB2(SCH_1):GND   I185 @BASEBOARD_FAB2_LIB.BASEBOARD_FAB2(SCH_1):PAGE81
   198    GND @BASEBOARD_FAB2_LIB.BASEBOARD_FAB2(SCH_1):GND   I185 @BASEBOARD_FAB2_LIB.BASEBOARD_FAB2(SCH_1):PAGE81
   200    GND @BASEBOARD_FAB2_LIB.BASEBOARD_FAB2(SCH_1):GND   I185 @BASEBOARD_FAB2_LIB.BASEBOARD_FAB2(SCH_1):PAGE81
   202    GND @BASEBOARD_FAB2_LIB.BASEBOARD_FAB2(SCH_1):GND   I185 @BASEBOARD_FAB2_LIB.BASEBOARD_FAB2(SCH_1):PAGE81
   239    GND @BASEBOARD_FAB2_LIB.BASEBOARD_FAB2(SCH_1):GND   I185 @BASEBOARD_FAB2_LIB.BASEBOARD_FAB2(SCH_1):PAGE81
   241    GND @BASEBOARD_FAB2_LIB.BASEBOARD_FAB2(SCH_1):GND   I185 @BASEBOARD_FAB2_LIB.BASEBOARD_FAB2(SCH_1):PAGE81
   243    GND @BASEBOARD_FAB2_LIB.BASEBOARD_FAB2(SCH_1):GND   I185 @BASEBOARD_FAB2_LIB.BASEBOARD_FAB2(SCH_1):PAGE81
   246    GND @BASEBOARD_FAB2_LIB.BASEBOARD_FAB2(SCH_1):GND   I185 @BASEBOARD_FAB2_LIB.BASEBOARD_FAB2(SCH_1):PAGE81
   248    GND @BASEBOARD_FAB2_LIB.BASEBOARD_FAB2(SCH_1):GND   I185 @BASEBOARD_FAB2_LIB.BASEBOARD_FAB2(SCH_1):PAGE81
   250    GND @BASEBOARD_FAB2_LIB.BASEBOARD_FAB2(SCH_1):GND   I185 @BASEBOARD_FAB2_LIB.BASEBOARD_FAB2(SCH_1):PAGE81
   252    GND @BASEBOARD_FAB2_LIB.BASEBOARD_FAB2(SCH_1):GND   I185 @BASEBOARD_FAB2_LIB.BASEBOARD_FAB2(SCH_1):PAGE81
   254    GND @BASEBOARD_FAB2_LIB.BASEBOARD_FAB2(SCH_1):GND   I185 @BASEBOARD_FAB2_LIB.BASEBOARD_FAB2(SCH_1):PAGE81
   257    GND @BASEBOARD_FAB2_LIB.BASEBOARD_FAB2(SCH_1):GND   I185 @BASEBOARD_FAB2_LIB.BASEBOARD_FAB2(SCH_1):PAGE81
   259    GND @BASEBOARD_FAB2_LIB.BASEBOARD_FAB2(SCH_1):GND   I185 @BASEBOARD_FAB2_LIB.BASEBOARD_FAB2(SCH_1):PAGE81
   261    GND @BASEBOARD_FAB2_LIB.BASEBOARD_FAB2(SCH_1):GND   I185 @BASEBOARD_FAB2_LIB.BASEBOARD_FAB2(SCH_1):PAGE81
   263    GND @BASEBOARD_FAB2_LIB.BASEBOARD_FAB2(SCH_1):GND   I185 @BASEBOARD_FAB2_LIB.BASEBOARD_FAB2(SCH_1):PAGE81
   265    GND @BASEBOARD_FAB2_LIB.BASEBOARD_FAB2(SCH_1):GND   I185 @BASEBOARD_FAB2_LIB.BASEBOARD_FAB2(SCH_1):PAGE81
   268    GND @BASEBOARD_FAB2_LIB.BASEBOARD_FAB2(SCH_1):GND   I185 @BASEBOARD_FAB2_LIB.BASEBOARD_FAB2(SCH_1):PAGE81
   270    GND @BASEBOARD_FAB2_LIB.BASEBOARD_FAB2(SCH_1):GND   I185 @BASEBOARD_FAB2_LIB.BASEBOARD_FAB2(SCH_1):PAGE81
   272    GND @BASEBOARD_FAB2_LIB.BASEBOARD_FAB2(SCH_1):GND   I185 @BASEBOARD_FAB2_LIB.BASEBOARD_FAB2(SCH_1):PAGE81
   274    GND @BASEBOARD_FAB2_LIB.BASEBOARD_FAB2(SCH_1):GND   I185 @BASEBOARD_FAB2_LIB.BASEBOARD_FAB2(SCH_1):PAGE81
   276    GND @BASEBOARD_FAB2_LIB.BASEBOARD_FAB2(SCH_1):GND   I185 @BASEBOARD_FAB2_LIB.BASEBOARD_FAB2(SCH_1):PAGE81
   279    GND @BASEBOARD_FAB2_LIB.BASEBOARD_FAB2(SCH_1):GND   I185 @BASEBOARD_FAB2_LIB.BASEBOARD_FAB2(SCH_1):PAGE81
   281    GND @BASEBOARD_FAB2_LIB.BASEBOARD_FAB2(SCH_1):GND   I185 @BASEBOARD_FAB2_LIB.BASEBOARD_FAB2(SCH_1):PAGE81
   283    GND @BASEBOARD_FAB2_LIB.BASEBOARD_FAB2(SCH_1):GND   I185 @BASEBOARD_FAB2_LIB.BASEBOARD_FAB2(SCH_1):PAGE81
     1 P12V_NVDIMM_GHJ @BASEBOARD_FAB2_LIB.BASEBOARD_FAB2(SCH_1):P12V_NVDIMM_GHJ   I169 @BASEBOARD_FAB2_LIB.BASEBOARD_FAB2(SCH_1):PAGE81
   145 P12V_NVDIMM_GHJ @BASEBOARD_FAB2_LIB.BASEBOARD_FAB2(SCH_1):P12V_NVDIMM_GHJ   I169 @BASEBOARD_FAB2_LIB.BASEBOARD_FAB2(SCH_1):PAGE81
    59 PVDDQ_GHJ @BASEBOARD_FAB2_LIB.BASEBOARD_FAB2(SCH_1):PVDDQ_GHJ   I169 @BASEBOARD_FAB2_LIB.BASEBOARD_FAB2(SCH_1):PAGE81
    61 PVDDQ_GHJ @BASEBOARD_FAB2_LIB.BASEBOARD_FAB2(SCH_1):PVDDQ_GHJ   I169 @BASEBOARD_FAB2_LIB.BASEBOARD_FAB2(SCH_1):PAGE81
    64 PVDDQ_GHJ @BASEBOARD_FAB2_LIB.BASEBOARD_FAB2(SCH_1):PVDDQ_GHJ   I169 @BASEBOARD_FAB2_LIB.BASEBOARD_FAB2(SCH_1):PAGE81
    67 PVDDQ_GHJ @BASEBOARD_FAB2_LIB.BASEBOARD_FAB2(SCH_1):PVDDQ_GHJ   I169 @BASEBOARD_FAB2_LIB.BASEBOARD_FAB2(SCH_1):PAGE81
    70 PVDDQ_GHJ @BASEBOARD_FAB2_LIB.BASEBOARD_FAB2(SCH_1):PVDDQ_GHJ   I169 @BASEBOARD_FAB2_LIB.BASEBOARD_FAB2(SCH_1):PAGE81
    73 PVDDQ_GHJ @BASEBOARD_FAB2_LIB.BASEBOARD_FAB2(SCH_1):PVDDQ_GHJ   I169 @BASEBOARD_FAB2_LIB.BASEBOARD_FAB2(SCH_1):PAGE81
    76 PVDDQ_GHJ @BASEBOARD_FAB2_LIB.BASEBOARD_FAB2(SCH_1):PVDDQ_GHJ   I169 @BASEBOARD_FAB2_LIB.BASEBOARD_FAB2(SCH_1):PAGE81
    80 PVDDQ_GHJ @BASEBOARD_FAB2_LIB.BASEBOARD_FAB2(SCH_1):PVDDQ_GHJ   I169 @BASEBOARD_FAB2_LIB.BASEBOARD_FAB2(SCH_1):PAGE81
    83 PVDDQ_GHJ @BASEBOARD_FAB2_LIB.BASEBOARD_FAB2(SCH_1):PVDDQ_GHJ   I169 @BASEBOARD_FAB2_LIB.BASEBOARD_FAB2(SCH_1):PAGE81
    85 PVDDQ_GHJ @BASEBOARD_FAB2_LIB.BASEBOARD_FAB2(SCH_1):PVDDQ_GHJ   I169 @BASEBOARD_FAB2_LIB.BASEBOARD_FAB2(SCH_1):PAGE81
    88 PVDDQ_GHJ @BASEBOARD_FAB2_LIB.BASEBOARD_FAB2(SCH_1):PVDDQ_GHJ   I169 @BASEBOARD_FAB2_LIB.BASEBOARD_FAB2(SCH_1):PAGE81
    90 PVDDQ_GHJ @BASEBOARD_FAB2_LIB.BASEBOARD_FAB2(SCH_1):PVDDQ_GHJ   I169 @BASEBOARD_FAB2_LIB.BASEBOARD_FAB2(SCH_1):PAGE81
    92 PVDDQ_GHJ @BASEBOARD_FAB2_LIB.BASEBOARD_FAB2(SCH_1):PVDDQ_GHJ   I169 @BASEBOARD_FAB2_LIB.BASEBOARD_FAB2(SCH_1):PAGE81
   204 PVDDQ_GHJ @BASEBOARD_FAB2_LIB.BASEBOARD_FAB2(SCH_1):PVDDQ_GHJ   I169 @BASEBOARD_FAB2_LIB.BASEBOARD_FAB2(SCH_1):PAGE81
   206 PVDDQ_GHJ @BASEBOARD_FAB2_LIB.BASEBOARD_FAB2(SCH_1):PVDDQ_GHJ   I169 @BASEBOARD_FAB2_LIB.BASEBOARD_FAB2(SCH_1):PAGE81
   209 PVDDQ_GHJ @BASEBOARD_FAB2_LIB.BASEBOARD_FAB2(SCH_1):PVDDQ_GHJ   I169 @BASEBOARD_FAB2_LIB.BASEBOARD_FAB2(SCH_1):PAGE81
   212 PVDDQ_GHJ @BASEBOARD_FAB2_LIB.BASEBOARD_FAB2(SCH_1):PVDDQ_GHJ   I169 @BASEBOARD_FAB2_LIB.BASEBOARD_FAB2(SCH_1):PAGE81
   215 PVDDQ_GHJ @BASEBOARD_FAB2_LIB.BASEBOARD_FAB2(SCH_1):PVDDQ_GHJ   I169 @BASEBOARD_FAB2_LIB.BASEBOARD_FAB2(SCH_1):PAGE81
   217 PVDDQ_GHJ @BASEBOARD_FAB2_LIB.BASEBOARD_FAB2(SCH_1):PVDDQ_GHJ   I169 @BASEBOARD_FAB2_LIB.BASEBOARD_FAB2(SCH_1):PAGE81
   220 PVDDQ_GHJ @BASEBOARD_FAB2_LIB.BASEBOARD_FAB2(SCH_1):PVDDQ_GHJ   I169 @BASEBOARD_FAB2_LIB.BASEBOARD_FAB2(SCH_1):PAGE81
   223 PVDDQ_GHJ @BASEBOARD_FAB2_LIB.BASEBOARD_FAB2(SCH_1):PVDDQ_GHJ   I169 @BASEBOARD_FAB2_LIB.BASEBOARD_FAB2(SCH_1):PAGE81
   226 PVDDQ_GHJ @BASEBOARD_FAB2_LIB.BASEBOARD_FAB2(SCH_1):PVDDQ_GHJ   I169 @BASEBOARD_FAB2_LIB.BASEBOARD_FAB2(SCH_1):PAGE81
   229 PVDDQ_GHJ @BASEBOARD_FAB2_LIB.BASEBOARD_FAB2(SCH_1):PVDDQ_GHJ   I169 @BASEBOARD_FAB2_LIB.BASEBOARD_FAB2(SCH_1):PAGE81
   231 PVDDQ_GHJ @BASEBOARD_FAB2_LIB.BASEBOARD_FAB2(SCH_1):PVDDQ_GHJ   I169 @BASEBOARD_FAB2_LIB.BASEBOARD_FAB2(SCH_1):PAGE81
   233 PVDDQ_GHJ @BASEBOARD_FAB2_LIB.BASEBOARD_FAB2(SCH_1):PVDDQ_GHJ   I169 @BASEBOARD_FAB2_LIB.BASEBOARD_FAB2(SCH_1):PAGE81
   236 PVDDQ_GHJ @BASEBOARD_FAB2_LIB.BASEBOARD_FAB2(SCH_1):PVDDQ_GHJ   I169 @BASEBOARD_FAB2_LIB.BASEBOARD_FAB2(SCH_1):PAGE81
   142 PVPP_GHJ @BASEBOARD_FAB2_LIB.BASEBOARD_FAB2(SCH_1):PVPP_GHJ   I169 @BASEBOARD_FAB2_LIB.BASEBOARD_FAB2(SCH_1):PAGE81
   143 PVPP_GHJ @BASEBOARD_FAB2_LIB.BASEBOARD_FAB2(SCH_1):PVPP_GHJ   I169 @BASEBOARD_FAB2_LIB.BASEBOARD_FAB2(SCH_1):PAGE81
   288 PVPP_GHJ @BASEBOARD_FAB2_LIB.BASEBOARD_FAB2(SCH_1):PVPP_GHJ   I169 @BASEBOARD_FAB2_LIB.BASEBOARD_FAB2(SCH_1):PAGE81
   286 PVPP_GHJ @BASEBOARD_FAB2_LIB.BASEBOARD_FAB2(SCH_1):PVPP_GHJ   I169 @BASEBOARD_FAB2_LIB.BASEBOARD_FAB2(SCH_1):PAGE81
   287 PVPP_GHJ @BASEBOARD_FAB2_LIB.BASEBOARD_FAB2(SCH_1):PVPP_GHJ   I169 @BASEBOARD_FAB2_LIB.BASEBOARD_FAB2(SCH_1):PAGE81
    77 PVTT_GHJ @BASEBOARD_FAB2_LIB.BASEBOARD_FAB2(SCH_1):PVTT_GHJ   I169 @BASEBOARD_FAB2_LIB.BASEBOARD_FAB2(SCH_1):PAGE81
   221 PVTT_GHJ @BASEBOARD_FAB2_LIB.BASEBOARD_FAB2(SCH_1):PVTT_GHJ   I169 @BASEBOARD_FAB2_LIB.BASEBOARD_FAB2(SCH_1):PAGE81

J2W1 SKT-SATA7P-6P-165-GP-U1_SOCKETA
    S1    GND @BASEBOARD_FAB2_LIB.BASEBOARD_FAB2(SCH_1):GND    I67 @BASEBOARD_FAB2_LIB.BASEBOARD_FAB2(SCH_1):PAGE172
    S2 SATA6G_S1_TX_C_DP @BASEBOARD_FAB2_LIB.BASEBOARD_FAB2(SCH_1):SATA6G_S1_TX_C_DP    I67 @BASEBOARD_FAB2_LIB.BASEBOARD_FAB2(SCH_1):PAGE172
    S3 SATA6G_S1_TX_C_DN @BASEBOARD_FAB2_LIB.BASEBOARD_FAB2(SCH_1):SATA6G_S1_TX_C_DN    I67 @BASEBOARD_FAB2_LIB.BASEBOARD_FAB2(SCH_1):PAGE172
    S4    GND @BASEBOARD_FAB2_LIB.BASEBOARD_FAB2(SCH_1):GND    I67 @BASEBOARD_FAB2_LIB.BASEBOARD_FAB2(SCH_1):PAGE172
    S5 SATA6G_S1_RX_C_DN @BASEBOARD_FAB2_LIB.BASEBOARD_FAB2(SCH_1):SATA6G_S1_RX_C_DN    I67 @BASEBOARD_FAB2_LIB.BASEBOARD_FAB2(SCH_1):PAGE172
    S6 SATA6G_S1_RX_C_DP @BASEBOARD_FAB2_LIB.BASEBOARD_FAB2(SCH_1):SATA6G_S1_RX_C_DP    I67 @BASEBOARD_FAB2_LIB.BASEBOARD_FAB2(SCH_1):PAGE172
    S7    GND @BASEBOARD_FAB2_LIB.BASEBOARD_FAB2(SCH_1):GND    I67 @BASEBOARD_FAB2_LIB.BASEBOARD_FAB2(SCH_1):PAGE172
    P1 P5V_HDD_SATA @BASEBOARD_FAB2_LIB.BASEBOARD_FAB2(SCH_1):P5V_HDD_SATA    I67 @BASEBOARD_FAB2_LIB.BASEBOARD_FAB2(SCH_1):PAGE172
    P2 P5V_HDD_SATA @BASEBOARD_FAB2_LIB.BASEBOARD_FAB2(SCH_1):P5V_HDD_SATA    I67 @BASEBOARD_FAB2_LIB.BASEBOARD_FAB2(SCH_1):PAGE172
    P3    GND @BASEBOARD_FAB2_LIB.BASEBOARD_FAB2(SCH_1):GND    I67 @BASEBOARD_FAB2_LIB.BASEBOARD_FAB2(SCH_1):PAGE172
    P4    GND @BASEBOARD_FAB2_LIB.BASEBOARD_FAB2(SCH_1):GND    I67 @BASEBOARD_FAB2_LIB.BASEBOARD_FAB2(SCH_1):PAGE172
    P5 P12V_HDD_SATA @BASEBOARD_FAB2_LIB.BASEBOARD_FAB2(SCH_1):P12V_HDD_SATA    I67 @BASEBOARD_FAB2_LIB.BASEBOARD_FAB2(SCH_1):PAGE172
    P6 P12V_HDD_SATA @BASEBOARD_FAB2_LIB.BASEBOARD_FAB2(SCH_1):P12V_HDD_SATA    I67 @BASEBOARD_FAB2_LIB.BASEBOARD_FAB2(SCH_1):PAGE172
   NP1     NC     NC    I67 @BASEBOARD_FAB2_LIB.BASEBOARD_FAB2(SCH_1):PAGE172
   NP2     NC     NC    I67 @BASEBOARD_FAB2_LIB.BASEBOARD_FAB2(SCH_1):PAGE172
    H1    GND @BASEBOARD_FAB2_LIB.BASEBOARD_FAB2(SCH_1):GND    I67 @BASEBOARD_FAB2_LIB.BASEBOARD_FAB2(SCH_1):PAGE172
    H2    GND @BASEBOARD_FAB2_LIB.BASEBOARD_FAB2(SCH_1):GND    I67 @BASEBOARD_FAB2_LIB.BASEBOARD_FAB2(SCH_1):PAGE172

J2W2 SKT-SATA7P-6P-165-GP-U1_SOCKETA
    S1    GND @BASEBOARD_FAB2_LIB.BASEBOARD_FAB2(SCH_1):GND    I68 @BASEBOARD_FAB2_LIB.BASEBOARD_FAB2(SCH_1):PAGE172
    S2 SATA6G_S1_TX_C_DP @BASEBOARD_FAB2_LIB.BASEBOARD_FAB2(SCH_1):SATA6G_S1_TX_C_DP    I68 @BASEBOARD_FAB2_LIB.BASEBOARD_FAB2(SCH_1):PAGE172
    S3 SATA6G_S1_TX_C_DN @BASEBOARD_FAB2_LIB.BASEBOARD_FAB2(SCH_1):SATA6G_S1_TX_C_DN    I68 @BASEBOARD_FAB2_LIB.BASEBOARD_FAB2(SCH_1):PAGE172
    S4    GND @BASEBOARD_FAB2_LIB.BASEBOARD_FAB2(SCH_1):GND    I68 @BASEBOARD_FAB2_LIB.BASEBOARD_FAB2(SCH_1):PAGE172
    S5 SATA6G_S1_RX_C_DN @BASEBOARD_FAB2_LIB.BASEBOARD_FAB2(SCH_1):SATA6G_S1_RX_C_DN    I68 @BASEBOARD_FAB2_LIB.BASEBOARD_FAB2(SCH_1):PAGE172
    S6 SATA6G_S1_RX_C_DP @BASEBOARD_FAB2_LIB.BASEBOARD_FAB2(SCH_1):SATA6G_S1_RX_C_DP    I68 @BASEBOARD_FAB2_LIB.BASEBOARD_FAB2(SCH_1):PAGE172
    S7    GND @BASEBOARD_FAB2_LIB.BASEBOARD_FAB2(SCH_1):GND    I68 @BASEBOARD_FAB2_LIB.BASEBOARD_FAB2(SCH_1):PAGE172
    P1 P5V_HDD_SATA @BASEBOARD_FAB2_LIB.BASEBOARD_FAB2(SCH_1):P5V_HDD_SATA    I68 @BASEBOARD_FAB2_LIB.BASEBOARD_FAB2(SCH_1):PAGE172
    P2 P5V_HDD_SATA @BASEBOARD_FAB2_LIB.BASEBOARD_FAB2(SCH_1):P5V_HDD_SATA    I68 @BASEBOARD_FAB2_LIB.BASEBOARD_FAB2(SCH_1):PAGE172
    P3    GND @BASEBOARD_FAB2_LIB.BASEBOARD_FAB2(SCH_1):GND    I68 @BASEBOARD_FAB2_LIB.BASEBOARD_FAB2(SCH_1):PAGE172
    P4    GND @BASEBOARD_FAB2_LIB.BASEBOARD_FAB2(SCH_1):GND    I68 @BASEBOARD_FAB2_LIB.BASEBOARD_FAB2(SCH_1):PAGE172
    P5 P12V_HDD_SATA @BASEBOARD_FAB2_LIB.BASEBOARD_FAB2(SCH_1):P12V_HDD_SATA    I68 @BASEBOARD_FAB2_LIB.BASEBOARD_FAB2(SCH_1):PAGE172
    P6 P12V_HDD_SATA @BASEBOARD_FAB2_LIB.BASEBOARD_FAB2(SCH_1):P12V_HDD_SATA    I68 @BASEBOARD_FAB2_LIB.BASEBOARD_FAB2(SCH_1):PAGE172
   NP1     NC     NC    I68 @BASEBOARD_FAB2_LIB.BASEBOARD_FAB2(SCH_1):PAGE172
   NP2     NC     NC    I68 @BASEBOARD_FAB2_LIB.BASEBOARD_FAB2(SCH_1):PAGE172
    H1    GND @BASEBOARD_FAB2_LIB.BASEBOARD_FAB2(SCH_1):GND    I68 @BASEBOARD_FAB2_LIB.BASEBOARD_FAB2(SCH_1):PAGE172
    H2    GND @BASEBOARD_FAB2_LIB.BASEBOARD_FAB2(SCH_1):GND    I68 @BASEBOARD_FAB2_LIB.BASEBOARD_FAB2(SCH_1):PAGE172

J4A1 SCONN288_H44441004_PIP-SCONN,HA
    79 M_F_MA<0> @BASEBOARD_FAB2_LIB.BASEBOARD_FAB2(SCH_1):M_F_MA(0)   I111 @BASEBOARD_FAB2_LIB.BASEBOARD_FAB2(SCH_1):PAGE53
    72 M_F_MA<1> @BASEBOARD_FAB2_LIB.BASEBOARD_FAB2(SCH_1):M_F_MA(1)   I111 @BASEBOARD_FAB2_LIB.BASEBOARD_FAB2(SCH_1):PAGE53
   225 M_F_MA<10> @BASEBOARD_FAB2_LIB.BASEBOARD_FAB2(SCH_1):M_F_MA(10)   I111 @BASEBOARD_FAB2_LIB.BASEBOARD_FAB2(SCH_1):PAGE53
   210 M_F_MA<11> @BASEBOARD_FAB2_LIB.BASEBOARD_FAB2(SCH_1):M_F_MA(11)   I111 @BASEBOARD_FAB2_LIB.BASEBOARD_FAB2(SCH_1):PAGE53
    65 M_F_MA<12> @BASEBOARD_FAB2_LIB.BASEBOARD_FAB2(SCH_1):M_F_MA(12)   I111 @BASEBOARD_FAB2_LIB.BASEBOARD_FAB2(SCH_1):PAGE53
   232 M_F_MA<13> @BASEBOARD_FAB2_LIB.BASEBOARD_FAB2(SCH_1):M_F_MA(13)   I111 @BASEBOARD_FAB2_LIB.BASEBOARD_FAB2(SCH_1):PAGE53
   228 M_F_MA<14> @BASEBOARD_FAB2_LIB.BASEBOARD_FAB2(SCH_1):M_F_MA(14)   I111 @BASEBOARD_FAB2_LIB.BASEBOARD_FAB2(SCH_1):PAGE53
    86 M_F_MA<15> @BASEBOARD_FAB2_LIB.BASEBOARD_FAB2(SCH_1):M_F_MA(15)   I111 @BASEBOARD_FAB2_LIB.BASEBOARD_FAB2(SCH_1):PAGE53
    82 M_F_MA<16> @BASEBOARD_FAB2_LIB.BASEBOARD_FAB2(SCH_1):M_F_MA(16)   I111 @BASEBOARD_FAB2_LIB.BASEBOARD_FAB2(SCH_1):PAGE53
   234 M_F_MA<17> @BASEBOARD_FAB2_LIB.BASEBOARD_FAB2(SCH_1):M_F_MA(17)   I111 @BASEBOARD_FAB2_LIB.BASEBOARD_FAB2(SCH_1):PAGE53
   216 M_F_MA<2> @BASEBOARD_FAB2_LIB.BASEBOARD_FAB2(SCH_1):M_F_MA(2)   I111 @BASEBOARD_FAB2_LIB.BASEBOARD_FAB2(SCH_1):PAGE53
    71 M_F_MA<3> @BASEBOARD_FAB2_LIB.BASEBOARD_FAB2(SCH_1):M_F_MA(3)   I111 @BASEBOARD_FAB2_LIB.BASEBOARD_FAB2(SCH_1):PAGE53
   214 M_F_MA<4> @BASEBOARD_FAB2_LIB.BASEBOARD_FAB2(SCH_1):M_F_MA(4)   I111 @BASEBOARD_FAB2_LIB.BASEBOARD_FAB2(SCH_1):PAGE53
   213 M_F_MA<5> @BASEBOARD_FAB2_LIB.BASEBOARD_FAB2(SCH_1):M_F_MA(5)   I111 @BASEBOARD_FAB2_LIB.BASEBOARD_FAB2(SCH_1):PAGE53
    69 M_F_MA<6> @BASEBOARD_FAB2_LIB.BASEBOARD_FAB2(SCH_1):M_F_MA(6)   I111 @BASEBOARD_FAB2_LIB.BASEBOARD_FAB2(SCH_1):PAGE53
   211 M_F_MA<7> @BASEBOARD_FAB2_LIB.BASEBOARD_FAB2(SCH_1):M_F_MA(7)   I111 @BASEBOARD_FAB2_LIB.BASEBOARD_FAB2(SCH_1):PAGE53
    68 M_F_MA<8> @BASEBOARD_FAB2_LIB.BASEBOARD_FAB2(SCH_1):M_F_MA(8)   I111 @BASEBOARD_FAB2_LIB.BASEBOARD_FAB2(SCH_1):PAGE53
    66 M_F_MA<9> @BASEBOARD_FAB2_LIB.BASEBOARD_FAB2(SCH_1):M_F_MA(9)   I111 @BASEBOARD_FAB2_LIB.BASEBOARD_FAB2(SCH_1):PAGE53
    62 M_F_ACT_N @BASEBOARD_FAB2_LIB.BASEBOARD_FAB2(SCH_1):M_F_ACT_N   I111 @BASEBOARD_FAB2_LIB.BASEBOARD_FAB2(SCH_1):PAGE53
   208 M_F_ALERT_N @BASEBOARD_FAB2_LIB.BASEBOARD_FAB2(SCH_1):M_F_ALERT_N   I111 @BASEBOARD_FAB2_LIB.BASEBOARD_FAB2(SCH_1):PAGE53
   224 M_F_BA<1> @BASEBOARD_FAB2_LIB.BASEBOARD_FAB2(SCH_1):M_F_BA(1)   I111 @BASEBOARD_FAB2_LIB.BASEBOARD_FAB2(SCH_1):PAGE53
    81 M_F_BA<0> @BASEBOARD_FAB2_LIB.BASEBOARD_FAB2(SCH_1):M_F_BA(0)   I111 @BASEBOARD_FAB2_LIB.BASEBOARD_FAB2(SCH_1):PAGE53
   207 M_F_BG<1> @BASEBOARD_FAB2_LIB.BASEBOARD_FAB2(SCH_1):M_F_BG(1)   I111 @BASEBOARD_FAB2_LIB.BASEBOARD_FAB2(SCH_1):PAGE53
    63 M_F_BG<0> @BASEBOARD_FAB2_LIB.BASEBOARD_FAB2(SCH_1):M_F_BG(0)   I111 @BASEBOARD_FAB2_LIB.BASEBOARD_FAB2(SCH_1):PAGE53
   235 M_F_C<2> @BASEBOARD_FAB2_LIB.BASEBOARD_FAB2(SCH_1):M_F_C(2)   I111 @BASEBOARD_FAB2_LIB.BASEBOARD_FAB2(SCH_1):PAGE53
   199 M_F_ECC<6> @BASEBOARD_FAB2_LIB.BASEBOARD_FAB2(SCH_1):M_F_ECC(6)   I111 @BASEBOARD_FAB2_LIB.BASEBOARD_FAB2(SCH_1):PAGE53
    54 M_F_ECC<7> @BASEBOARD_FAB2_LIB.BASEBOARD_FAB2(SCH_1):M_F_ECC(7)   I111 @BASEBOARD_FAB2_LIB.BASEBOARD_FAB2(SCH_1):PAGE53
   192 M_F_ECC<4> @BASEBOARD_FAB2_LIB.BASEBOARD_FAB2(SCH_1):M_F_ECC(4)   I111 @BASEBOARD_FAB2_LIB.BASEBOARD_FAB2(SCH_1):PAGE53
    47 M_F_ECC<5> @BASEBOARD_FAB2_LIB.BASEBOARD_FAB2(SCH_1):M_F_ECC(5)   I111 @BASEBOARD_FAB2_LIB.BASEBOARD_FAB2(SCH_1):PAGE53
   201 M_F_ECC<2> @BASEBOARD_FAB2_LIB.BASEBOARD_FAB2(SCH_1):M_F_ECC(2)   I111 @BASEBOARD_FAB2_LIB.BASEBOARD_FAB2(SCH_1):PAGE53
    56 M_F_ECC<3> @BASEBOARD_FAB2_LIB.BASEBOARD_FAB2(SCH_1):M_F_ECC(3)   I111 @BASEBOARD_FAB2_LIB.BASEBOARD_FAB2(SCH_1):PAGE53
   194 M_F_ECC<0> @BASEBOARD_FAB2_LIB.BASEBOARD_FAB2(SCH_1):M_F_ECC(0)   I111 @BASEBOARD_FAB2_LIB.BASEBOARD_FAB2(SCH_1):PAGE53
    49 M_F_ECC<1> @BASEBOARD_FAB2_LIB.BASEBOARD_FAB2(SCH_1):M_F_ECC(1)   I111 @BASEBOARD_FAB2_LIB.BASEBOARD_FAB2(SCH_1):PAGE53
    75 M_F_CLK_DN<0> @BASEBOARD_FAB2_LIB.BASEBOARD_FAB2(SCH_1):M_F_CLK_DN(0)   I111 @BASEBOARD_FAB2_LIB.BASEBOARD_FAB2(SCH_1):PAGE53
    74 M_F_CLK_DP<0> @BASEBOARD_FAB2_LIB.BASEBOARD_FAB2(SCH_1):M_F_CLK_DP(0)   I111 @BASEBOARD_FAB2_LIB.BASEBOARD_FAB2(SCH_1):PAGE53
   219 M_F_CLK_DN<1> @BASEBOARD_FAB2_LIB.BASEBOARD_FAB2(SCH_1):M_F_CLK_DN(1)   I111 @BASEBOARD_FAB2_LIB.BASEBOARD_FAB2(SCH_1):PAGE53
   218 M_F_CLK_DP<1> @BASEBOARD_FAB2_LIB.BASEBOARD_FAB2(SCH_1):M_F_CLK_DP(1)   I111 @BASEBOARD_FAB2_LIB.BASEBOARD_FAB2(SCH_1):PAGE53
   203 M_F_CKE<1> @BASEBOARD_FAB2_LIB.BASEBOARD_FAB2(SCH_1):M_F_CKE(1)   I111 @BASEBOARD_FAB2_LIB.BASEBOARD_FAB2(SCH_1):PAGE53
    60 M_F_CKE<0> @BASEBOARD_FAB2_LIB.BASEBOARD_FAB2(SCH_1):M_F_CKE(0)   I111 @BASEBOARD_FAB2_LIB.BASEBOARD_FAB2(SCH_1):PAGE53
   280 M_F_DQ<62> @BASEBOARD_FAB2_LIB.BASEBOARD_FAB2(SCH_1):M_F_DQ(62)   I111 @BASEBOARD_FAB2_LIB.BASEBOARD_FAB2(SCH_1):PAGE53
   135 M_F_DQ<63> @BASEBOARD_FAB2_LIB.BASEBOARD_FAB2(SCH_1):M_F_DQ(63)   I111 @BASEBOARD_FAB2_LIB.BASEBOARD_FAB2(SCH_1):PAGE53
   273 M_F_DQ<60> @BASEBOARD_FAB2_LIB.BASEBOARD_FAB2(SCH_1):M_F_DQ(60)   I111 @BASEBOARD_FAB2_LIB.BASEBOARD_FAB2(SCH_1):PAGE53
   128 M_F_DQ<61> @BASEBOARD_FAB2_LIB.BASEBOARD_FAB2(SCH_1):M_F_DQ(61)   I111 @BASEBOARD_FAB2_LIB.BASEBOARD_FAB2(SCH_1):PAGE53
   282 M_F_DQ<58> @BASEBOARD_FAB2_LIB.BASEBOARD_FAB2(SCH_1):M_F_DQ(58)   I111 @BASEBOARD_FAB2_LIB.BASEBOARD_FAB2(SCH_1):PAGE53
   137 M_F_DQ<59> @BASEBOARD_FAB2_LIB.BASEBOARD_FAB2(SCH_1):M_F_DQ(59)   I111 @BASEBOARD_FAB2_LIB.BASEBOARD_FAB2(SCH_1):PAGE53
   275 M_F_DQ<56> @BASEBOARD_FAB2_LIB.BASEBOARD_FAB2(SCH_1):M_F_DQ(56)   I111 @BASEBOARD_FAB2_LIB.BASEBOARD_FAB2(SCH_1):PAGE53
   130 M_F_DQ<57> @BASEBOARD_FAB2_LIB.BASEBOARD_FAB2(SCH_1):M_F_DQ(57)   I111 @BASEBOARD_FAB2_LIB.BASEBOARD_FAB2(SCH_1):PAGE53
   269 M_F_DQ<54> @BASEBOARD_FAB2_LIB.BASEBOARD_FAB2(SCH_1):M_F_DQ(54)   I111 @BASEBOARD_FAB2_LIB.BASEBOARD_FAB2(SCH_1):PAGE53
   124 M_F_DQ<55> @BASEBOARD_FAB2_LIB.BASEBOARD_FAB2(SCH_1):M_F_DQ(55)   I111 @BASEBOARD_FAB2_LIB.BASEBOARD_FAB2(SCH_1):PAGE53
   262 M_F_DQ<52> @BASEBOARD_FAB2_LIB.BASEBOARD_FAB2(SCH_1):M_F_DQ(52)   I111 @BASEBOARD_FAB2_LIB.BASEBOARD_FAB2(SCH_1):PAGE53
   117 M_F_DQ<53> @BASEBOARD_FAB2_LIB.BASEBOARD_FAB2(SCH_1):M_F_DQ(53)   I111 @BASEBOARD_FAB2_LIB.BASEBOARD_FAB2(SCH_1):PAGE53
   271 M_F_DQ<50> @BASEBOARD_FAB2_LIB.BASEBOARD_FAB2(SCH_1):M_F_DQ(50)   I111 @BASEBOARD_FAB2_LIB.BASEBOARD_FAB2(SCH_1):PAGE53
   126 M_F_DQ<51> @BASEBOARD_FAB2_LIB.BASEBOARD_FAB2(SCH_1):M_F_DQ(51)   I111 @BASEBOARD_FAB2_LIB.BASEBOARD_FAB2(SCH_1):PAGE53
   264 M_F_DQ<48> @BASEBOARD_FAB2_LIB.BASEBOARD_FAB2(SCH_1):M_F_DQ(48)   I111 @BASEBOARD_FAB2_LIB.BASEBOARD_FAB2(SCH_1):PAGE53
   119 M_F_DQ<49> @BASEBOARD_FAB2_LIB.BASEBOARD_FAB2(SCH_1):M_F_DQ(49)   I111 @BASEBOARD_FAB2_LIB.BASEBOARD_FAB2(SCH_1):PAGE53
   258 M_F_DQ<46> @BASEBOARD_FAB2_LIB.BASEBOARD_FAB2(SCH_1):M_F_DQ(46)   I111 @BASEBOARD_FAB2_LIB.BASEBOARD_FAB2(SCH_1):PAGE53
   113 M_F_DQ<47> @BASEBOARD_FAB2_LIB.BASEBOARD_FAB2(SCH_1):M_F_DQ(47)   I111 @BASEBOARD_FAB2_LIB.BASEBOARD_FAB2(SCH_1):PAGE53
   251 M_F_DQ<44> @BASEBOARD_FAB2_LIB.BASEBOARD_FAB2(SCH_1):M_F_DQ(44)   I111 @BASEBOARD_FAB2_LIB.BASEBOARD_FAB2(SCH_1):PAGE53
   106 M_F_DQ<45> @BASEBOARD_FAB2_LIB.BASEBOARD_FAB2(SCH_1):M_F_DQ(45)   I111 @BASEBOARD_FAB2_LIB.BASEBOARD_FAB2(SCH_1):PAGE53
   260 M_F_DQ<42> @BASEBOARD_FAB2_LIB.BASEBOARD_FAB2(SCH_1):M_F_DQ(42)   I111 @BASEBOARD_FAB2_LIB.BASEBOARD_FAB2(SCH_1):PAGE53
   115 M_F_DQ<43> @BASEBOARD_FAB2_LIB.BASEBOARD_FAB2(SCH_1):M_F_DQ(43)   I111 @BASEBOARD_FAB2_LIB.BASEBOARD_FAB2(SCH_1):PAGE53
   253 M_F_DQ<40> @BASEBOARD_FAB2_LIB.BASEBOARD_FAB2(SCH_1):M_F_DQ(40)   I111 @BASEBOARD_FAB2_LIB.BASEBOARD_FAB2(SCH_1):PAGE53
   108 M_F_DQ<41> @BASEBOARD_FAB2_LIB.BASEBOARD_FAB2(SCH_1):M_F_DQ(41)   I111 @BASEBOARD_FAB2_LIB.BASEBOARD_FAB2(SCH_1):PAGE53
   247 M_F_DQ<38> @BASEBOARD_FAB2_LIB.BASEBOARD_FAB2(SCH_1):M_F_DQ(38)   I111 @BASEBOARD_FAB2_LIB.BASEBOARD_FAB2(SCH_1):PAGE53
   102 M_F_DQ<39> @BASEBOARD_FAB2_LIB.BASEBOARD_FAB2(SCH_1):M_F_DQ(39)   I111 @BASEBOARD_FAB2_LIB.BASEBOARD_FAB2(SCH_1):PAGE53
   240 M_F_DQ<36> @BASEBOARD_FAB2_LIB.BASEBOARD_FAB2(SCH_1):M_F_DQ(36)   I111 @BASEBOARD_FAB2_LIB.BASEBOARD_FAB2(SCH_1):PAGE53
    95 M_F_DQ<37> @BASEBOARD_FAB2_LIB.BASEBOARD_FAB2(SCH_1):M_F_DQ(37)   I111 @BASEBOARD_FAB2_LIB.BASEBOARD_FAB2(SCH_1):PAGE53
   249 M_F_DQ<34> @BASEBOARD_FAB2_LIB.BASEBOARD_FAB2(SCH_1):M_F_DQ(34)   I111 @BASEBOARD_FAB2_LIB.BASEBOARD_FAB2(SCH_1):PAGE53
   104 M_F_DQ<35> @BASEBOARD_FAB2_LIB.BASEBOARD_FAB2(SCH_1):M_F_DQ(35)   I111 @BASEBOARD_FAB2_LIB.BASEBOARD_FAB2(SCH_1):PAGE53
   242 M_F_DQ<32> @BASEBOARD_FAB2_LIB.BASEBOARD_FAB2(SCH_1):M_F_DQ(32)   I111 @BASEBOARD_FAB2_LIB.BASEBOARD_FAB2(SCH_1):PAGE53
    97 M_F_DQ<33> @BASEBOARD_FAB2_LIB.BASEBOARD_FAB2(SCH_1):M_F_DQ(33)   I111 @BASEBOARD_FAB2_LIB.BASEBOARD_FAB2(SCH_1):PAGE53
   188 M_F_DQ<30> @BASEBOARD_FAB2_LIB.BASEBOARD_FAB2(SCH_1):M_F_DQ(30)   I111 @BASEBOARD_FAB2_LIB.BASEBOARD_FAB2(SCH_1):PAGE53
    43 M_F_DQ<31> @BASEBOARD_FAB2_LIB.BASEBOARD_FAB2(SCH_1):M_F_DQ(31)   I111 @BASEBOARD_FAB2_LIB.BASEBOARD_FAB2(SCH_1):PAGE53
   181 M_F_DQ<28> @BASEBOARD_FAB2_LIB.BASEBOARD_FAB2(SCH_1):M_F_DQ(28)   I111 @BASEBOARD_FAB2_LIB.BASEBOARD_FAB2(SCH_1):PAGE53
    36 M_F_DQ<29> @BASEBOARD_FAB2_LIB.BASEBOARD_FAB2(SCH_1):M_F_DQ(29)   I111 @BASEBOARD_FAB2_LIB.BASEBOARD_FAB2(SCH_1):PAGE53
   190 M_F_DQ<26> @BASEBOARD_FAB2_LIB.BASEBOARD_FAB2(SCH_1):M_F_DQ(26)   I111 @BASEBOARD_FAB2_LIB.BASEBOARD_FAB2(SCH_1):PAGE53
    45 M_F_DQ<27> @BASEBOARD_FAB2_LIB.BASEBOARD_FAB2(SCH_1):M_F_DQ(27)   I111 @BASEBOARD_FAB2_LIB.BASEBOARD_FAB2(SCH_1):PAGE53
   183 M_F_DQ<24> @BASEBOARD_FAB2_LIB.BASEBOARD_FAB2(SCH_1):M_F_DQ(24)   I111 @BASEBOARD_FAB2_LIB.BASEBOARD_FAB2(SCH_1):PAGE53
    38 M_F_DQ<25> @BASEBOARD_FAB2_LIB.BASEBOARD_FAB2(SCH_1):M_F_DQ(25)   I111 @BASEBOARD_FAB2_LIB.BASEBOARD_FAB2(SCH_1):PAGE53
   177 M_F_DQ<22> @BASEBOARD_FAB2_LIB.BASEBOARD_FAB2(SCH_1):M_F_DQ(22)   I111 @BASEBOARD_FAB2_LIB.BASEBOARD_FAB2(SCH_1):PAGE53
    32 M_F_DQ<23> @BASEBOARD_FAB2_LIB.BASEBOARD_FAB2(SCH_1):M_F_DQ(23)   I111 @BASEBOARD_FAB2_LIB.BASEBOARD_FAB2(SCH_1):PAGE53
   170 M_F_DQ<20> @BASEBOARD_FAB2_LIB.BASEBOARD_FAB2(SCH_1):M_F_DQ(20)   I111 @BASEBOARD_FAB2_LIB.BASEBOARD_FAB2(SCH_1):PAGE53
    25 M_F_DQ<21> @BASEBOARD_FAB2_LIB.BASEBOARD_FAB2(SCH_1):M_F_DQ(21)   I111 @BASEBOARD_FAB2_LIB.BASEBOARD_FAB2(SCH_1):PAGE53
   179 M_F_DQ<18> @BASEBOARD_FAB2_LIB.BASEBOARD_FAB2(SCH_1):M_F_DQ(18)   I111 @BASEBOARD_FAB2_LIB.BASEBOARD_FAB2(SCH_1):PAGE53
    34 M_F_DQ<19> @BASEBOARD_FAB2_LIB.BASEBOARD_FAB2(SCH_1):M_F_DQ(19)   I111 @BASEBOARD_FAB2_LIB.BASEBOARD_FAB2(SCH_1):PAGE53
   172 M_F_DQ<16> @BASEBOARD_FAB2_LIB.BASEBOARD_FAB2(SCH_1):M_F_DQ(16)   I111 @BASEBOARD_FAB2_LIB.BASEBOARD_FAB2(SCH_1):PAGE53
    27 M_F_DQ<17> @BASEBOARD_FAB2_LIB.BASEBOARD_FAB2(SCH_1):M_F_DQ(17)   I111 @BASEBOARD_FAB2_LIB.BASEBOARD_FAB2(SCH_1):PAGE53
   166 M_F_DQ<14> @BASEBOARD_FAB2_LIB.BASEBOARD_FAB2(SCH_1):M_F_DQ(14)   I111 @BASEBOARD_FAB2_LIB.BASEBOARD_FAB2(SCH_1):PAGE53
    21 M_F_DQ<15> @BASEBOARD_FAB2_LIB.BASEBOARD_FAB2(SCH_1):M_F_DQ(15)   I111 @BASEBOARD_FAB2_LIB.BASEBOARD_FAB2(SCH_1):PAGE53
   159 M_F_DQ<12> @BASEBOARD_FAB2_LIB.BASEBOARD_FAB2(SCH_1):M_F_DQ(12)   I111 @BASEBOARD_FAB2_LIB.BASEBOARD_FAB2(SCH_1):PAGE53
    14 M_F_DQ<13> @BASEBOARD_FAB2_LIB.BASEBOARD_FAB2(SCH_1):M_F_DQ(13)   I111 @BASEBOARD_FAB2_LIB.BASEBOARD_FAB2(SCH_1):PAGE53
   168 M_F_DQ<10> @BASEBOARD_FAB2_LIB.BASEBOARD_FAB2(SCH_1):M_F_DQ(10)   I111 @BASEBOARD_FAB2_LIB.BASEBOARD_FAB2(SCH_1):PAGE53
    23 M_F_DQ<11> @BASEBOARD_FAB2_LIB.BASEBOARD_FAB2(SCH_1):M_F_DQ(11)   I111 @BASEBOARD_FAB2_LIB.BASEBOARD_FAB2(SCH_1):PAGE53
   161 M_F_DQ<8> @BASEBOARD_FAB2_LIB.BASEBOARD_FAB2(SCH_1):M_F_DQ(8)   I111 @BASEBOARD_FAB2_LIB.BASEBOARD_FAB2(SCH_1):PAGE53
    16 M_F_DQ<9> @BASEBOARD_FAB2_LIB.BASEBOARD_FAB2(SCH_1):M_F_DQ(9)   I111 @BASEBOARD_FAB2_LIB.BASEBOARD_FAB2(SCH_1):PAGE53
   155 M_F_DQ<6> @BASEBOARD_FAB2_LIB.BASEBOARD_FAB2(SCH_1):M_F_DQ(6)   I111 @BASEBOARD_FAB2_LIB.BASEBOARD_FAB2(SCH_1):PAGE53
    10 M_F_DQ<7> @BASEBOARD_FAB2_LIB.BASEBOARD_FAB2(SCH_1):M_F_DQ(7)   I111 @BASEBOARD_FAB2_LIB.BASEBOARD_FAB2(SCH_1):PAGE53
   148 M_F_DQ<4> @BASEBOARD_FAB2_LIB.BASEBOARD_FAB2(SCH_1):M_F_DQ(4)   I111 @BASEBOARD_FAB2_LIB.BASEBOARD_FAB2(SCH_1):PAGE53
     3 M_F_DQ<5> @BASEBOARD_FAB2_LIB.BASEBOARD_FAB2(SCH_1):M_F_DQ(5)   I111 @BASEBOARD_FAB2_LIB.BASEBOARD_FAB2(SCH_1):PAGE53
   157 M_F_DQ<2> @BASEBOARD_FAB2_LIB.BASEBOARD_FAB2(SCH_1):M_F_DQ(2)   I111 @BASEBOARD_FAB2_LIB.BASEBOARD_FAB2(SCH_1):PAGE53
    12 M_F_DQ<3> @BASEBOARD_FAB2_LIB.BASEBOARD_FAB2(SCH_1):M_F_DQ(3)   I111 @BASEBOARD_FAB2_LIB.BASEBOARD_FAB2(SCH_1):PAGE53
   150 M_F_DQ<0> @BASEBOARD_FAB2_LIB.BASEBOARD_FAB2(SCH_1):M_F_DQ(0)   I111 @BASEBOARD_FAB2_LIB.BASEBOARD_FAB2(SCH_1):PAGE53
     5 M_F_DQ<1> @BASEBOARD_FAB2_LIB.BASEBOARD_FAB2(SCH_1):M_F_DQ(1)   I111 @BASEBOARD_FAB2_LIB.BASEBOARD_FAB2(SCH_1):PAGE53
    78 FM_DIMM_EVENT_COD_N @BASEBOARD_FAB2_LIB.BASEBOARD_FAB2(SCH_1):FM_DIMM_EVENT_COD_N   I111 @BASEBOARD_FAB2_LIB.BASEBOARD_FAB2(SCH_1):PAGE53
    91 M_F_ODT<1> @BASEBOARD_FAB2_LIB.BASEBOARD_FAB2(SCH_1):M_F_ODT(1)   I111 @BASEBOARD_FAB2_LIB.BASEBOARD_FAB2(SCH_1):PAGE53
    87 M_F_ODT<0> @BASEBOARD_FAB2_LIB.BASEBOARD_FAB2(SCH_1):M_F_ODT(0)   I111 @BASEBOARD_FAB2_LIB.BASEBOARD_FAB2(SCH_1):PAGE53
   222 M_F_PAR @BASEBOARD_FAB2_LIB.BASEBOARD_FAB2(SCH_1):M_F_PAR   I111 @BASEBOARD_FAB2_LIB.BASEBOARD_FAB2(SCH_1):PAGE53
    58 M_DEF_RST_N @BASEBOARD_FAB2_LIB.BASEBOARD_FAB2(SCH_1):M_DEF_RST_N   I111 @BASEBOARD_FAB2_LIB.BASEBOARD_FAB2(SCH_1):PAGE53
   144 TP_CH_F_DIMM_F0_RFU_2 @BASEBOARD_FAB2_LIB.BASEBOARD_FAB2(SCH_1):TP_CH_F_DIMM_F0_RFU_2   I111 @BASEBOARD_FAB2_LIB.BASEBOARD_FAB2(SCH_1):PAGE53
   227 TP_CH_F_DIMM_F0_RFU_1 @BASEBOARD_FAB2_LIB.BASEBOARD_FAB2(SCH_1):TP_CH_F_DIMM_F0_RFU_1   I111 @BASEBOARD_FAB2_LIB.BASEBOARD_FAB2(SCH_1):PAGE53
   205 TP_CH_F_DIMM_F0_RFU_0 @BASEBOARD_FAB2_LIB.BASEBOARD_FAB2(SCH_1):TP_CH_F_DIMM_F0_RFU_0   I111 @BASEBOARD_FAB2_LIB.BASEBOARD_FAB2(SCH_1):PAGE53
    84 M_F_CS_N<0> @BASEBOARD_FAB2_LIB.BASEBOARD_FAB2(SCH_1):M_F_CS_N(0)   I111 @BASEBOARD_FAB2_LIB.BASEBOARD_FAB2(SCH_1):PAGE53
    89 M_F_CS_N<1> @BASEBOARD_FAB2_LIB.BASEBOARD_FAB2(SCH_1):M_F_CS_N(1)   I111 @BASEBOARD_FAB2_LIB.BASEBOARD_FAB2(SCH_1):PAGE53
    93 M_F_CS_N<2> @BASEBOARD_FAB2_LIB.BASEBOARD_FAB2(SCH_1):M_F_CS_N(2)   I111 @BASEBOARD_FAB2_LIB.BASEBOARD_FAB2(SCH_1):PAGE53
   237 M_F_CS_N<3> @BASEBOARD_FAB2_LIB.BASEBOARD_FAB2(SCH_1):M_F_CS_N(3)   I111 @BASEBOARD_FAB2_LIB.BASEBOARD_FAB2(SCH_1):PAGE53
   238 PVPP_DEF @BASEBOARD_FAB2_LIB.BASEBOARD_FAB2(SCH_1):PVPP_DEF   I111 @BASEBOARD_FAB2_LIB.BASEBOARD_FAB2(SCH_1):PAGE53
   140    GND @BASEBOARD_FAB2_LIB.BASEBOARD_FAB2(SCH_1):GND   I111 @BASEBOARD_FAB2_LIB.BASEBOARD_FAB2(SCH_1):PAGE53
   139    GND @BASEBOARD_FAB2_LIB.BASEBOARD_FAB2(SCH_1):GND   I111 @BASEBOARD_FAB2_LIB.BASEBOARD_FAB2(SCH_1):PAGE53
   230 FM_ADR_COMPLETE_DEF_N @BASEBOARD_FAB2_LIB.BASEBOARD_FAB2(SCH_1):FM_ADR_COMPLETE_DEF_N   I111 @BASEBOARD_FAB2_LIB.BASEBOARD_FAB2(SCH_1):PAGE53
   141 SMB_DDR_DEF_VPP_SCL @BASEBOARD_FAB2_LIB.BASEBOARD_FAB2(SCH_1):SMB_DDR_DEF_VPP_SCL   I111 @BASEBOARD_FAB2_LIB.BASEBOARD_FAB2(SCH_1):PAGE53
   285 SMB_DDR_DEF_VPP_SDA @BASEBOARD_FAB2_LIB.BASEBOARD_FAB2(SCH_1):SMB_DDR_DEF_VPP_SDA   I111 @BASEBOARD_FAB2_LIB.BASEBOARD_FAB2(SCH_1):PAGE53
   284 PVPP_DEF @BASEBOARD_FAB2_LIB.BASEBOARD_FAB2(SCH_1):PVPP_DEF   I111 @BASEBOARD_FAB2_LIB.BASEBOARD_FAB2(SCH_1):PAGE53
   146 M_F_VREF @BASEBOARD_FAB2_LIB.BASEBOARD_FAB2(SCH_1):M_F_VREF   I111 @BASEBOARD_FAB2_LIB.BASEBOARD_FAB2(SCH_1):PAGE53
   152 M_F_DQS_DN<0> @BASEBOARD_FAB2_LIB.BASEBOARD_FAB2(SCH_1):M_F_DQS_DN(0)    I66 @BASEBOARD_FAB2_LIB.BASEBOARD_FAB2(SCH_1):PAGE53
   153 M_F_DQS_DP<0> @BASEBOARD_FAB2_LIB.BASEBOARD_FAB2(SCH_1):M_F_DQS_DP(0)    I66 @BASEBOARD_FAB2_LIB.BASEBOARD_FAB2(SCH_1):PAGE53
    19 M_F_DQS_DN<10> @BASEBOARD_FAB2_LIB.BASEBOARD_FAB2(SCH_1):M_F_DQS_DN(10)    I66 @BASEBOARD_FAB2_LIB.BASEBOARD_FAB2(SCH_1):PAGE53
    18 M_F_DQS_DP<10> @BASEBOARD_FAB2_LIB.BASEBOARD_FAB2(SCH_1):M_F_DQS_DP(10)    I66 @BASEBOARD_FAB2_LIB.BASEBOARD_FAB2(SCH_1):PAGE53
    30 M_F_DQS_DN<11> @BASEBOARD_FAB2_LIB.BASEBOARD_FAB2(SCH_1):M_F_DQS_DN(11)    I66 @BASEBOARD_FAB2_LIB.BASEBOARD_FAB2(SCH_1):PAGE53
    29 M_F_DQS_DP<11> @BASEBOARD_FAB2_LIB.BASEBOARD_FAB2(SCH_1):M_F_DQS_DP(11)    I66 @BASEBOARD_FAB2_LIB.BASEBOARD_FAB2(SCH_1):PAGE53
    41 M_F_DQS_DN<12> @BASEBOARD_FAB2_LIB.BASEBOARD_FAB2(SCH_1):M_F_DQS_DN(12)    I66 @BASEBOARD_FAB2_LIB.BASEBOARD_FAB2(SCH_1):PAGE53
    40 M_F_DQS_DP<12> @BASEBOARD_FAB2_LIB.BASEBOARD_FAB2(SCH_1):M_F_DQS_DP(12)    I66 @BASEBOARD_FAB2_LIB.BASEBOARD_FAB2(SCH_1):PAGE53
   100 M_F_DQS_DN<13> @BASEBOARD_FAB2_LIB.BASEBOARD_FAB2(SCH_1):M_F_DQS_DN(13)    I66 @BASEBOARD_FAB2_LIB.BASEBOARD_FAB2(SCH_1):PAGE53
    99 M_F_DQS_DP<13> @BASEBOARD_FAB2_LIB.BASEBOARD_FAB2(SCH_1):M_F_DQS_DP(13)    I66 @BASEBOARD_FAB2_LIB.BASEBOARD_FAB2(SCH_1):PAGE53
   111 M_F_DQS_DN<14> @BASEBOARD_FAB2_LIB.BASEBOARD_FAB2(SCH_1):M_F_DQS_DN(14)    I66 @BASEBOARD_FAB2_LIB.BASEBOARD_FAB2(SCH_1):PAGE53
   110 M_F_DQS_DP<14> @BASEBOARD_FAB2_LIB.BASEBOARD_FAB2(SCH_1):M_F_DQS_DP(14)    I66 @BASEBOARD_FAB2_LIB.BASEBOARD_FAB2(SCH_1):PAGE53
   122 M_F_DQS_DN<15> @BASEBOARD_FAB2_LIB.BASEBOARD_FAB2(SCH_1):M_F_DQS_DN(15)    I66 @BASEBOARD_FAB2_LIB.BASEBOARD_FAB2(SCH_1):PAGE53
   121 M_F_DQS_DP<15> @BASEBOARD_FAB2_LIB.BASEBOARD_FAB2(SCH_1):M_F_DQS_DP(15)    I66 @BASEBOARD_FAB2_LIB.BASEBOARD_FAB2(SCH_1):PAGE53
   133 M_F_DQS_DN<16> @BASEBOARD_FAB2_LIB.BASEBOARD_FAB2(SCH_1):M_F_DQS_DN(16)    I66 @BASEBOARD_FAB2_LIB.BASEBOARD_FAB2(SCH_1):PAGE53
   132 M_F_DQS_DP<16> @BASEBOARD_FAB2_LIB.BASEBOARD_FAB2(SCH_1):M_F_DQS_DP(16)    I66 @BASEBOARD_FAB2_LIB.BASEBOARD_FAB2(SCH_1):PAGE53
    52 M_F_DQS_DN<17> @BASEBOARD_FAB2_LIB.BASEBOARD_FAB2(SCH_1):M_F_DQS_DN(17)    I66 @BASEBOARD_FAB2_LIB.BASEBOARD_FAB2(SCH_1):PAGE53
    51 M_F_DQS_DP<17> @BASEBOARD_FAB2_LIB.BASEBOARD_FAB2(SCH_1):M_F_DQS_DP(17)    I66 @BASEBOARD_FAB2_LIB.BASEBOARD_FAB2(SCH_1):PAGE53
   163 M_F_DQS_DN<1> @BASEBOARD_FAB2_LIB.BASEBOARD_FAB2(SCH_1):M_F_DQS_DN(1)    I66 @BASEBOARD_FAB2_LIB.BASEBOARD_FAB2(SCH_1):PAGE53
   164 M_F_DQS_DP<1> @BASEBOARD_FAB2_LIB.BASEBOARD_FAB2(SCH_1):M_F_DQS_DP(1)    I66 @BASEBOARD_FAB2_LIB.BASEBOARD_FAB2(SCH_1):PAGE53
   174 M_F_DQS_DN<2> @BASEBOARD_FAB2_LIB.BASEBOARD_FAB2(SCH_1):M_F_DQS_DN(2)    I66 @BASEBOARD_FAB2_LIB.BASEBOARD_FAB2(SCH_1):PAGE53
   175 M_F_DQS_DP<2> @BASEBOARD_FAB2_LIB.BASEBOARD_FAB2(SCH_1):M_F_DQS_DP(2)    I66 @BASEBOARD_FAB2_LIB.BASEBOARD_FAB2(SCH_1):PAGE53
   185 M_F_DQS_DN<3> @BASEBOARD_FAB2_LIB.BASEBOARD_FAB2(SCH_1):M_F_DQS_DN(3)    I66 @BASEBOARD_FAB2_LIB.BASEBOARD_FAB2(SCH_1):PAGE53
   186 M_F_DQS_DP<3> @BASEBOARD_FAB2_LIB.BASEBOARD_FAB2(SCH_1):M_F_DQS_DP(3)    I66 @BASEBOARD_FAB2_LIB.BASEBOARD_FAB2(SCH_1):PAGE53
   244 M_F_DQS_DN<4> @BASEBOARD_FAB2_LIB.BASEBOARD_FAB2(SCH_1):M_F_DQS_DN(4)    I66 @BASEBOARD_FAB2_LIB.BASEBOARD_FAB2(SCH_1):PAGE53
   245 M_F_DQS_DP<4> @BASEBOARD_FAB2_LIB.BASEBOARD_FAB2(SCH_1):M_F_DQS_DP(4)    I66 @BASEBOARD_FAB2_LIB.BASEBOARD_FAB2(SCH_1):PAGE53
   255 M_F_DQS_DN<5> @BASEBOARD_FAB2_LIB.BASEBOARD_FAB2(SCH_1):M_F_DQS_DN(5)    I66 @BASEBOARD_FAB2_LIB.BASEBOARD_FAB2(SCH_1):PAGE53
   256 M_F_DQS_DP<5> @BASEBOARD_FAB2_LIB.BASEBOARD_FAB2(SCH_1):M_F_DQS_DP(5)    I66 @BASEBOARD_FAB2_LIB.BASEBOARD_FAB2(SCH_1):PAGE53
   266 M_F_DQS_DN<6> @BASEBOARD_FAB2_LIB.BASEBOARD_FAB2(SCH_1):M_F_DQS_DN(6)    I66 @BASEBOARD_FAB2_LIB.BASEBOARD_FAB2(SCH_1):PAGE53
   267 M_F_DQS_DP<6> @BASEBOARD_FAB2_LIB.BASEBOARD_FAB2(SCH_1):M_F_DQS_DP(6)    I66 @BASEBOARD_FAB2_LIB.BASEBOARD_FAB2(SCH_1):PAGE53
   277 M_F_DQS_DN<7> @BASEBOARD_FAB2_LIB.BASEBOARD_FAB2(SCH_1):M_F_DQS_DN(7)    I66 @BASEBOARD_FAB2_LIB.BASEBOARD_FAB2(SCH_1):PAGE53
   278 M_F_DQS_DP<7> @BASEBOARD_FAB2_LIB.BASEBOARD_FAB2(SCH_1):M_F_DQS_DP(7)    I66 @BASEBOARD_FAB2_LIB.BASEBOARD_FAB2(SCH_1):PAGE53
   196 M_F_DQS_DN<8> @BASEBOARD_FAB2_LIB.BASEBOARD_FAB2(SCH_1):M_F_DQS_DN(8)    I66 @BASEBOARD_FAB2_LIB.BASEBOARD_FAB2(SCH_1):PAGE53
   197 M_F_DQS_DP<8> @BASEBOARD_FAB2_LIB.BASEBOARD_FAB2(SCH_1):M_F_DQS_DP(8)    I66 @BASEBOARD_FAB2_LIB.BASEBOARD_FAB2(SCH_1):PAGE53
     8 M_F_DQS_DN<9> @BASEBOARD_FAB2_LIB.BASEBOARD_FAB2(SCH_1):M_F_DQS_DN(9)    I66 @BASEBOARD_FAB2_LIB.BASEBOARD_FAB2(SCH_1):PAGE53
     7 M_F_DQS_DP<9> @BASEBOARD_FAB2_LIB.BASEBOARD_FAB2(SCH_1):M_F_DQS_DP(9)    I66 @BASEBOARD_FAB2_LIB.BASEBOARD_FAB2(SCH_1):PAGE53
     2    GND @BASEBOARD_FAB2_LIB.BASEBOARD_FAB2(SCH_1):GND    I43 @BASEBOARD_FAB2_LIB.BASEBOARD_FAB2(SCH_1):PAGE53
     4    GND @BASEBOARD_FAB2_LIB.BASEBOARD_FAB2(SCH_1):GND    I43 @BASEBOARD_FAB2_LIB.BASEBOARD_FAB2(SCH_1):PAGE53
     6    GND @BASEBOARD_FAB2_LIB.BASEBOARD_FAB2(SCH_1):GND    I43 @BASEBOARD_FAB2_LIB.BASEBOARD_FAB2(SCH_1):PAGE53
     9    GND @BASEBOARD_FAB2_LIB.BASEBOARD_FAB2(SCH_1):GND    I43 @BASEBOARD_FAB2_LIB.BASEBOARD_FAB2(SCH_1):PAGE53
    11    GND @BASEBOARD_FAB2_LIB.BASEBOARD_FAB2(SCH_1):GND    I43 @BASEBOARD_FAB2_LIB.BASEBOARD_FAB2(SCH_1):PAGE53
    13    GND @BASEBOARD_FAB2_LIB.BASEBOARD_FAB2(SCH_1):GND    I43 @BASEBOARD_FAB2_LIB.BASEBOARD_FAB2(SCH_1):PAGE53
    15    GND @BASEBOARD_FAB2_LIB.BASEBOARD_FAB2(SCH_1):GND    I43 @BASEBOARD_FAB2_LIB.BASEBOARD_FAB2(SCH_1):PAGE53
    17    GND @BASEBOARD_FAB2_LIB.BASEBOARD_FAB2(SCH_1):GND    I43 @BASEBOARD_FAB2_LIB.BASEBOARD_FAB2(SCH_1):PAGE53
    20    GND @BASEBOARD_FAB2_LIB.BASEBOARD_FAB2(SCH_1):GND    I43 @BASEBOARD_FAB2_LIB.BASEBOARD_FAB2(SCH_1):PAGE53
    22    GND @BASEBOARD_FAB2_LIB.BASEBOARD_FAB2(SCH_1):GND    I43 @BASEBOARD_FAB2_LIB.BASEBOARD_FAB2(SCH_1):PAGE53
    24    GND @BASEBOARD_FAB2_LIB.BASEBOARD_FAB2(SCH_1):GND    I43 @BASEBOARD_FAB2_LIB.BASEBOARD_FAB2(SCH_1):PAGE53
    26    GND @BASEBOARD_FAB2_LIB.BASEBOARD_FAB2(SCH_1):GND    I43 @BASEBOARD_FAB2_LIB.BASEBOARD_FAB2(SCH_1):PAGE53
    28    GND @BASEBOARD_FAB2_LIB.BASEBOARD_FAB2(SCH_1):GND    I43 @BASEBOARD_FAB2_LIB.BASEBOARD_FAB2(SCH_1):PAGE53
    31    GND @BASEBOARD_FAB2_LIB.BASEBOARD_FAB2(SCH_1):GND    I43 @BASEBOARD_FAB2_LIB.BASEBOARD_FAB2(SCH_1):PAGE53
    33    GND @BASEBOARD_FAB2_LIB.BASEBOARD_FAB2(SCH_1):GND    I43 @BASEBOARD_FAB2_LIB.BASEBOARD_FAB2(SCH_1):PAGE53
    35    GND @BASEBOARD_FAB2_LIB.BASEBOARD_FAB2(SCH_1):GND    I43 @BASEBOARD_FAB2_LIB.BASEBOARD_FAB2(SCH_1):PAGE53
    37    GND @BASEBOARD_FAB2_LIB.BASEBOARD_FAB2(SCH_1):GND    I43 @BASEBOARD_FAB2_LIB.BASEBOARD_FAB2(SCH_1):PAGE53
    39    GND @BASEBOARD_FAB2_LIB.BASEBOARD_FAB2(SCH_1):GND    I43 @BASEBOARD_FAB2_LIB.BASEBOARD_FAB2(SCH_1):PAGE53
    42    GND @BASEBOARD_FAB2_LIB.BASEBOARD_FAB2(SCH_1):GND    I43 @BASEBOARD_FAB2_LIB.BASEBOARD_FAB2(SCH_1):PAGE53
    44    GND @BASEBOARD_FAB2_LIB.BASEBOARD_FAB2(SCH_1):GND    I43 @BASEBOARD_FAB2_LIB.BASEBOARD_FAB2(SCH_1):PAGE53
    46    GND @BASEBOARD_FAB2_LIB.BASEBOARD_FAB2(SCH_1):GND    I43 @BASEBOARD_FAB2_LIB.BASEBOARD_FAB2(SCH_1):PAGE53
    48    GND @BASEBOARD_FAB2_LIB.BASEBOARD_FAB2(SCH_1):GND    I43 @BASEBOARD_FAB2_LIB.BASEBOARD_FAB2(SCH_1):PAGE53
    50    GND @BASEBOARD_FAB2_LIB.BASEBOARD_FAB2(SCH_1):GND    I43 @BASEBOARD_FAB2_LIB.BASEBOARD_FAB2(SCH_1):PAGE53
    53    GND @BASEBOARD_FAB2_LIB.BASEBOARD_FAB2(SCH_1):GND    I43 @BASEBOARD_FAB2_LIB.BASEBOARD_FAB2(SCH_1):PAGE53
    55    GND @BASEBOARD_FAB2_LIB.BASEBOARD_FAB2(SCH_1):GND    I43 @BASEBOARD_FAB2_LIB.BASEBOARD_FAB2(SCH_1):PAGE53
    57    GND @BASEBOARD_FAB2_LIB.BASEBOARD_FAB2(SCH_1):GND    I43 @BASEBOARD_FAB2_LIB.BASEBOARD_FAB2(SCH_1):PAGE53
    94    GND @BASEBOARD_FAB2_LIB.BASEBOARD_FAB2(SCH_1):GND    I43 @BASEBOARD_FAB2_LIB.BASEBOARD_FAB2(SCH_1):PAGE53
    96    GND @BASEBOARD_FAB2_LIB.BASEBOARD_FAB2(SCH_1):GND    I43 @BASEBOARD_FAB2_LIB.BASEBOARD_FAB2(SCH_1):PAGE53
    98    GND @BASEBOARD_FAB2_LIB.BASEBOARD_FAB2(SCH_1):GND    I43 @BASEBOARD_FAB2_LIB.BASEBOARD_FAB2(SCH_1):PAGE53
   101    GND @BASEBOARD_FAB2_LIB.BASEBOARD_FAB2(SCH_1):GND    I43 @BASEBOARD_FAB2_LIB.BASEBOARD_FAB2(SCH_1):PAGE53
   103    GND @BASEBOARD_FAB2_LIB.BASEBOARD_FAB2(SCH_1):GND    I43 @BASEBOARD_FAB2_LIB.BASEBOARD_FAB2(SCH_1):PAGE53
   105    GND @BASEBOARD_FAB2_LIB.BASEBOARD_FAB2(SCH_1):GND    I43 @BASEBOARD_FAB2_LIB.BASEBOARD_FAB2(SCH_1):PAGE53
   107    GND @BASEBOARD_FAB2_LIB.BASEBOARD_FAB2(SCH_1):GND    I43 @BASEBOARD_FAB2_LIB.BASEBOARD_FAB2(SCH_1):PAGE53
   109    GND @BASEBOARD_FAB2_LIB.BASEBOARD_FAB2(SCH_1):GND    I43 @BASEBOARD_FAB2_LIB.BASEBOARD_FAB2(SCH_1):PAGE53
   112    GND @BASEBOARD_FAB2_LIB.BASEBOARD_FAB2(SCH_1):GND    I43 @BASEBOARD_FAB2_LIB.BASEBOARD_FAB2(SCH_1):PAGE53
   114    GND @BASEBOARD_FAB2_LIB.BASEBOARD_FAB2(SCH_1):GND    I43 @BASEBOARD_FAB2_LIB.BASEBOARD_FAB2(SCH_1):PAGE53
   116    GND @BASEBOARD_FAB2_LIB.BASEBOARD_FAB2(SCH_1):GND    I43 @BASEBOARD_FAB2_LIB.BASEBOARD_FAB2(SCH_1):PAGE53
   118    GND @BASEBOARD_FAB2_LIB.BASEBOARD_FAB2(SCH_1):GND    I43 @BASEBOARD_FAB2_LIB.BASEBOARD_FAB2(SCH_1):PAGE53
   120    GND @BASEBOARD_FAB2_LIB.BASEBOARD_FAB2(SCH_1):GND    I43 @BASEBOARD_FAB2_LIB.BASEBOARD_FAB2(SCH_1):PAGE53
   123    GND @BASEBOARD_FAB2_LIB.BASEBOARD_FAB2(SCH_1):GND    I43 @BASEBOARD_FAB2_LIB.BASEBOARD_FAB2(SCH_1):PAGE53
   125    GND @BASEBOARD_FAB2_LIB.BASEBOARD_FAB2(SCH_1):GND    I43 @BASEBOARD_FAB2_LIB.BASEBOARD_FAB2(SCH_1):PAGE53
   127    GND @BASEBOARD_FAB2_LIB.BASEBOARD_FAB2(SCH_1):GND    I43 @BASEBOARD_FAB2_LIB.BASEBOARD_FAB2(SCH_1):PAGE53
   129    GND @BASEBOARD_FAB2_LIB.BASEBOARD_FAB2(SCH_1):GND    I43 @BASEBOARD_FAB2_LIB.BASEBOARD_FAB2(SCH_1):PAGE53
   131    GND @BASEBOARD_FAB2_LIB.BASEBOARD_FAB2(SCH_1):GND    I43 @BASEBOARD_FAB2_LIB.BASEBOARD_FAB2(SCH_1):PAGE53
   134    GND @BASEBOARD_FAB2_LIB.BASEBOARD_FAB2(SCH_1):GND    I43 @BASEBOARD_FAB2_LIB.BASEBOARD_FAB2(SCH_1):PAGE53
   136    GND @BASEBOARD_FAB2_LIB.BASEBOARD_FAB2(SCH_1):GND    I43 @BASEBOARD_FAB2_LIB.BASEBOARD_FAB2(SCH_1):PAGE53
   138    GND @BASEBOARD_FAB2_LIB.BASEBOARD_FAB2(SCH_1):GND    I43 @BASEBOARD_FAB2_LIB.BASEBOARD_FAB2(SCH_1):PAGE53
   147    GND @BASEBOARD_FAB2_LIB.BASEBOARD_FAB2(SCH_1):GND    I43 @BASEBOARD_FAB2_LIB.BASEBOARD_FAB2(SCH_1):PAGE53
   149    GND @BASEBOARD_FAB2_LIB.BASEBOARD_FAB2(SCH_1):GND    I43 @BASEBOARD_FAB2_LIB.BASEBOARD_FAB2(SCH_1):PAGE53
   151    GND @BASEBOARD_FAB2_LIB.BASEBOARD_FAB2(SCH_1):GND    I43 @BASEBOARD_FAB2_LIB.BASEBOARD_FAB2(SCH_1):PAGE53
   154    GND @BASEBOARD_FAB2_LIB.BASEBOARD_FAB2(SCH_1):GND    I43 @BASEBOARD_FAB2_LIB.BASEBOARD_FAB2(SCH_1):PAGE53
   156    GND @BASEBOARD_FAB2_LIB.BASEBOARD_FAB2(SCH_1):GND    I43 @BASEBOARD_FAB2_LIB.BASEBOARD_FAB2(SCH_1):PAGE53
   158    GND @BASEBOARD_FAB2_LIB.BASEBOARD_FAB2(SCH_1):GND    I43 @BASEBOARD_FAB2_LIB.BASEBOARD_FAB2(SCH_1):PAGE53
   160    GND @BASEBOARD_FAB2_LIB.BASEBOARD_FAB2(SCH_1):GND    I43 @BASEBOARD_FAB2_LIB.BASEBOARD_FAB2(SCH_1):PAGE53
   162    GND @BASEBOARD_FAB2_LIB.BASEBOARD_FAB2(SCH_1):GND    I43 @BASEBOARD_FAB2_LIB.BASEBOARD_FAB2(SCH_1):PAGE53
   165    GND @BASEBOARD_FAB2_LIB.BASEBOARD_FAB2(SCH_1):GND    I43 @BASEBOARD_FAB2_LIB.BASEBOARD_FAB2(SCH_1):PAGE53
   167    GND @BASEBOARD_FAB2_LIB.BASEBOARD_FAB2(SCH_1):GND    I43 @BASEBOARD_FAB2_LIB.BASEBOARD_FAB2(SCH_1):PAGE53
   169    GND @BASEBOARD_FAB2_LIB.BASEBOARD_FAB2(SCH_1):GND    I43 @BASEBOARD_FAB2_LIB.BASEBOARD_FAB2(SCH_1):PAGE53
   171    GND @BASEBOARD_FAB2_LIB.BASEBOARD_FAB2(SCH_1):GND    I43 @BASEBOARD_FAB2_LIB.BASEBOARD_FAB2(SCH_1):PAGE53
   173    GND @BASEBOARD_FAB2_LIB.BASEBOARD_FAB2(SCH_1):GND    I43 @BASEBOARD_FAB2_LIB.BASEBOARD_FAB2(SCH_1):PAGE53
   176    GND @BASEBOARD_FAB2_LIB.BASEBOARD_FAB2(SCH_1):GND    I43 @BASEBOARD_FAB2_LIB.BASEBOARD_FAB2(SCH_1):PAGE53
   178    GND @BASEBOARD_FAB2_LIB.BASEBOARD_FAB2(SCH_1):GND    I43 @BASEBOARD_FAB2_LIB.BASEBOARD_FAB2(SCH_1):PAGE53
   180    GND @BASEBOARD_FAB2_LIB.BASEBOARD_FAB2(SCH_1):GND    I43 @BASEBOARD_FAB2_LIB.BASEBOARD_FAB2(SCH_1):PAGE53
   182    GND @BASEBOARD_FAB2_LIB.BASEBOARD_FAB2(SCH_1):GND    I43 @BASEBOARD_FAB2_LIB.BASEBOARD_FAB2(SCH_1):PAGE53
   184    GND @BASEBOARD_FAB2_LIB.BASEBOARD_FAB2(SCH_1):GND    I43 @BASEBOARD_FAB2_LIB.BASEBOARD_FAB2(SCH_1):PAGE53
   187    GND @BASEBOARD_FAB2_LIB.BASEBOARD_FAB2(SCH_1):GND    I43 @BASEBOARD_FAB2_LIB.BASEBOARD_FAB2(SCH_1):PAGE53
   189    GND @BASEBOARD_FAB2_LIB.BASEBOARD_FAB2(SCH_1):GND    I43 @BASEBOARD_FAB2_LIB.BASEBOARD_FAB2(SCH_1):PAGE53
   191    GND @BASEBOARD_FAB2_LIB.BASEBOARD_FAB2(SCH_1):GND    I43 @BASEBOARD_FAB2_LIB.BASEBOARD_FAB2(SCH_1):PAGE53
   193    GND @BASEBOARD_FAB2_LIB.BASEBOARD_FAB2(SCH_1):GND    I43 @BASEBOARD_FAB2_LIB.BASEBOARD_FAB2(SCH_1):PAGE53
   195    GND @BASEBOARD_FAB2_LIB.BASEBOARD_FAB2(SCH_1):GND    I43 @BASEBOARD_FAB2_LIB.BASEBOARD_FAB2(SCH_1):PAGE53
   198    GND @BASEBOARD_FAB2_LIB.BASEBOARD_FAB2(SCH_1):GND    I43 @BASEBOARD_FAB2_LIB.BASEBOARD_FAB2(SCH_1):PAGE53
   200    GND @BASEBOARD_FAB2_LIB.BASEBOARD_FAB2(SCH_1):GND    I43 @BASEBOARD_FAB2_LIB.BASEBOARD_FAB2(SCH_1):PAGE53
   202    GND @BASEBOARD_FAB2_LIB.BASEBOARD_FAB2(SCH_1):GND    I43 @BASEBOARD_FAB2_LIB.BASEBOARD_FAB2(SCH_1):PAGE53
   239    GND @BASEBOARD_FAB2_LIB.BASEBOARD_FAB2(SCH_1):GND    I43 @BASEBOARD_FAB2_LIB.BASEBOARD_FAB2(SCH_1):PAGE53
   241    GND @BASEBOARD_FAB2_LIB.BASEBOARD_FAB2(SCH_1):GND    I43 @BASEBOARD_FAB2_LIB.BASEBOARD_FAB2(SCH_1):PAGE53
   243    GND @BASEBOARD_FAB2_LIB.BASEBOARD_FAB2(SCH_1):GND    I43 @BASEBOARD_FAB2_LIB.BASEBOARD_FAB2(SCH_1):PAGE53
   246    GND @BASEBOARD_FAB2_LIB.BASEBOARD_FAB2(SCH_1):GND    I43 @BASEBOARD_FAB2_LIB.BASEBOARD_FAB2(SCH_1):PAGE53
   248    GND @BASEBOARD_FAB2_LIB.BASEBOARD_FAB2(SCH_1):GND    I43 @BASEBOARD_FAB2_LIB.BASEBOARD_FAB2(SCH_1):PAGE53
   250    GND @BASEBOARD_FAB2_LIB.BASEBOARD_FAB2(SCH_1):GND    I43 @BASEBOARD_FAB2_LIB.BASEBOARD_FAB2(SCH_1):PAGE53
   252    GND @BASEBOARD_FAB2_LIB.BASEBOARD_FAB2(SCH_1):GND    I43 @BASEBOARD_FAB2_LIB.BASEBOARD_FAB2(SCH_1):PAGE53
   254    GND @BASEBOARD_FAB2_LIB.BASEBOARD_FAB2(SCH_1):GND    I43 @BASEBOARD_FAB2_LIB.BASEBOARD_FAB2(SCH_1):PAGE53
   257    GND @BASEBOARD_FAB2_LIB.BASEBOARD_FAB2(SCH_1):GND    I43 @BASEBOARD_FAB2_LIB.BASEBOARD_FAB2(SCH_1):PAGE53
   259    GND @BASEBOARD_FAB2_LIB.BASEBOARD_FAB2(SCH_1):GND    I43 @BASEBOARD_FAB2_LIB.BASEBOARD_FAB2(SCH_1):PAGE53
   261    GND @BASEBOARD_FAB2_LIB.BASEBOARD_FAB2(SCH_1):GND    I43 @BASEBOARD_FAB2_LIB.BASEBOARD_FAB2(SCH_1):PAGE53
   263    GND @BASEBOARD_FAB2_LIB.BASEBOARD_FAB2(SCH_1):GND    I43 @BASEBOARD_FAB2_LIB.BASEBOARD_FAB2(SCH_1):PAGE53
   265    GND @BASEBOARD_FAB2_LIB.BASEBOARD_FAB2(SCH_1):GND    I43 @BASEBOARD_FAB2_LIB.BASEBOARD_FAB2(SCH_1):PAGE53
   268    GND @BASEBOARD_FAB2_LIB.BASEBOARD_FAB2(SCH_1):GND    I43 @BASEBOARD_FAB2_LIB.BASEBOARD_FAB2(SCH_1):PAGE53
   270    GND @BASEBOARD_FAB2_LIB.BASEBOARD_FAB2(SCH_1):GND    I43 @BASEBOARD_FAB2_LIB.BASEBOARD_FAB2(SCH_1):PAGE53
   272    GND @BASEBOARD_FAB2_LIB.BASEBOARD_FAB2(SCH_1):GND    I43 @BASEBOARD_FAB2_LIB.BASEBOARD_FAB2(SCH_1):PAGE53
   274    GND @BASEBOARD_FAB2_LIB.BASEBOARD_FAB2(SCH_1):GND    I43 @BASEBOARD_FAB2_LIB.BASEBOARD_FAB2(SCH_1):PAGE53
   276    GND @BASEBOARD_FAB2_LIB.BASEBOARD_FAB2(SCH_1):GND    I43 @BASEBOARD_FAB2_LIB.BASEBOARD_FAB2(SCH_1):PAGE53
   279    GND @BASEBOARD_FAB2_LIB.BASEBOARD_FAB2(SCH_1):GND    I43 @BASEBOARD_FAB2_LIB.BASEBOARD_FAB2(SCH_1):PAGE53
   281    GND @BASEBOARD_FAB2_LIB.BASEBOARD_FAB2(SCH_1):GND    I43 @BASEBOARD_FAB2_LIB.BASEBOARD_FAB2(SCH_1):PAGE53
   283    GND @BASEBOARD_FAB2_LIB.BASEBOARD_FAB2(SCH_1):GND    I43 @BASEBOARD_FAB2_LIB.BASEBOARD_FAB2(SCH_1):PAGE53
     1 P12V_NVDIMM_DEF @BASEBOARD_FAB2_LIB.BASEBOARD_FAB2(SCH_1):P12V_NVDIMM_DEF   I171 @BASEBOARD_FAB2_LIB.BASEBOARD_FAB2(SCH_1):PAGE53
   145 P12V_NVDIMM_DEF @BASEBOARD_FAB2_LIB.BASEBOARD_FAB2(SCH_1):P12V_NVDIMM_DEF   I171 @BASEBOARD_FAB2_LIB.BASEBOARD_FAB2(SCH_1):PAGE53
    59 PVDDQ_DEF @BASEBOARD_FAB2_LIB.BASEBOARD_FAB2(SCH_1):PVDDQ_DEF   I171 @BASEBOARD_FAB2_LIB.BASEBOARD_FAB2(SCH_1):PAGE53
    61 PVDDQ_DEF @BASEBOARD_FAB2_LIB.BASEBOARD_FAB2(SCH_1):PVDDQ_DEF   I171 @BASEBOARD_FAB2_LIB.BASEBOARD_FAB2(SCH_1):PAGE53
    64 PVDDQ_DEF @BASEBOARD_FAB2_LIB.BASEBOARD_FAB2(SCH_1):PVDDQ_DEF   I171 @BASEBOARD_FAB2_LIB.BASEBOARD_FAB2(SCH_1):PAGE53
    67 PVDDQ_DEF @BASEBOARD_FAB2_LIB.BASEBOARD_FAB2(SCH_1):PVDDQ_DEF   I171 @BASEBOARD_FAB2_LIB.BASEBOARD_FAB2(SCH_1):PAGE53
    70 PVDDQ_DEF @BASEBOARD_FAB2_LIB.BASEBOARD_FAB2(SCH_1):PVDDQ_DEF   I171 @BASEBOARD_FAB2_LIB.BASEBOARD_FAB2(SCH_1):PAGE53
    73 PVDDQ_DEF @BASEBOARD_FAB2_LIB.BASEBOARD_FAB2(SCH_1):PVDDQ_DEF   I171 @BASEBOARD_FAB2_LIB.BASEBOARD_FAB2(SCH_1):PAGE53
    76 PVDDQ_DEF @BASEBOARD_FAB2_LIB.BASEBOARD_FAB2(SCH_1):PVDDQ_DEF   I171 @BASEBOARD_FAB2_LIB.BASEBOARD_FAB2(SCH_1):PAGE53
    80 PVDDQ_DEF @BASEBOARD_FAB2_LIB.BASEBOARD_FAB2(SCH_1):PVDDQ_DEF   I171 @BASEBOARD_FAB2_LIB.BASEBOARD_FAB2(SCH_1):PAGE53
    83 PVDDQ_DEF @BASEBOARD_FAB2_LIB.BASEBOARD_FAB2(SCH_1):PVDDQ_DEF   I171 @BASEBOARD_FAB2_LIB.BASEBOARD_FAB2(SCH_1):PAGE53
    85 PVDDQ_DEF @BASEBOARD_FAB2_LIB.BASEBOARD_FAB2(SCH_1):PVDDQ_DEF   I171 @BASEBOARD_FAB2_LIB.BASEBOARD_FAB2(SCH_1):PAGE53
    88 PVDDQ_DEF @BASEBOARD_FAB2_LIB.BASEBOARD_FAB2(SCH_1):PVDDQ_DEF   I171 @BASEBOARD_FAB2_LIB.BASEBOARD_FAB2(SCH_1):PAGE53
    90 PVDDQ_DEF @BASEBOARD_FAB2_LIB.BASEBOARD_FAB2(SCH_1):PVDDQ_DEF   I171 @BASEBOARD_FAB2_LIB.BASEBOARD_FAB2(SCH_1):PAGE53
    92 PVDDQ_DEF @BASEBOARD_FAB2_LIB.BASEBOARD_FAB2(SCH_1):PVDDQ_DEF   I171 @BASEBOARD_FAB2_LIB.BASEBOARD_FAB2(SCH_1):PAGE53
   204 PVDDQ_DEF @BASEBOARD_FAB2_LIB.BASEBOARD_FAB2(SCH_1):PVDDQ_DEF   I171 @BASEBOARD_FAB2_LIB.BASEBOARD_FAB2(SCH_1):PAGE53
   206 PVDDQ_DEF @BASEBOARD_FAB2_LIB.BASEBOARD_FAB2(SCH_1):PVDDQ_DEF   I171 @BASEBOARD_FAB2_LIB.BASEBOARD_FAB2(SCH_1):PAGE53
   209 PVDDQ_DEF @BASEBOARD_FAB2_LIB.BASEBOARD_FAB2(SCH_1):PVDDQ_DEF   I171 @BASEBOARD_FAB2_LIB.BASEBOARD_FAB2(SCH_1):PAGE53
   212 PVDDQ_DEF @BASEBOARD_FAB2_LIB.BASEBOARD_FAB2(SCH_1):PVDDQ_DEF   I171 @BASEBOARD_FAB2_LIB.BASEBOARD_FAB2(SCH_1):PAGE53
   215 PVDDQ_DEF @BASEBOARD_FAB2_LIB.BASEBOARD_FAB2(SCH_1):PVDDQ_DEF   I171 @BASEBOARD_FAB2_LIB.BASEBOARD_FAB2(SCH_1):PAGE53
   217 PVDDQ_DEF @BASEBOARD_FAB2_LIB.BASEBOARD_FAB2(SCH_1):PVDDQ_DEF   I171 @BASEBOARD_FAB2_LIB.BASEBOARD_FAB2(SCH_1):PAGE53
   220 PVDDQ_DEF @BASEBOARD_FAB2_LIB.BASEBOARD_FAB2(SCH_1):PVDDQ_DEF   I171 @BASEBOARD_FAB2_LIB.BASEBOARD_FAB2(SCH_1):PAGE53
   223 PVDDQ_DEF @BASEBOARD_FAB2_LIB.BASEBOARD_FAB2(SCH_1):PVDDQ_DEF   I171 @BASEBOARD_FAB2_LIB.BASEBOARD_FAB2(SCH_1):PAGE53
   226 PVDDQ_DEF @BASEBOARD_FAB2_LIB.BASEBOARD_FAB2(SCH_1):PVDDQ_DEF   I171 @BASEBOARD_FAB2_LIB.BASEBOARD_FAB2(SCH_1):PAGE53
   229 PVDDQ_DEF @BASEBOARD_FAB2_LIB.BASEBOARD_FAB2(SCH_1):PVDDQ_DEF   I171 @BASEBOARD_FAB2_LIB.BASEBOARD_FAB2(SCH_1):PAGE53
   231 PVDDQ_DEF @BASEBOARD_FAB2_LIB.BASEBOARD_FAB2(SCH_1):PVDDQ_DEF   I171 @BASEBOARD_FAB2_LIB.BASEBOARD_FAB2(SCH_1):PAGE53
   233 PVDDQ_DEF @BASEBOARD_FAB2_LIB.BASEBOARD_FAB2(SCH_1):PVDDQ_DEF   I171 @BASEBOARD_FAB2_LIB.BASEBOARD_FAB2(SCH_1):PAGE53
   236 PVDDQ_DEF @BASEBOARD_FAB2_LIB.BASEBOARD_FAB2(SCH_1):PVDDQ_DEF   I171 @BASEBOARD_FAB2_LIB.BASEBOARD_FAB2(SCH_1):PAGE53
   142 PVPP_DEF @BASEBOARD_FAB2_LIB.BASEBOARD_FAB2(SCH_1):PVPP_DEF   I171 @BASEBOARD_FAB2_LIB.BASEBOARD_FAB2(SCH_1):PAGE53
   143 PVPP_DEF @BASEBOARD_FAB2_LIB.BASEBOARD_FAB2(SCH_1):PVPP_DEF   I171 @BASEBOARD_FAB2_LIB.BASEBOARD_FAB2(SCH_1):PAGE53
   288 PVPP_DEF @BASEBOARD_FAB2_LIB.BASEBOARD_FAB2(SCH_1):PVPP_DEF   I171 @BASEBOARD_FAB2_LIB.BASEBOARD_FAB2(SCH_1):PAGE53
   286 PVPP_DEF @BASEBOARD_FAB2_LIB.BASEBOARD_FAB2(SCH_1):PVPP_DEF   I171 @BASEBOARD_FAB2_LIB.BASEBOARD_FAB2(SCH_1):PAGE53
   287 PVPP_DEF @BASEBOARD_FAB2_LIB.BASEBOARD_FAB2(SCH_1):PVPP_DEF   I171 @BASEBOARD_FAB2_LIB.BASEBOARD_FAB2(SCH_1):PAGE53
    77 PVTT_DEF @BASEBOARD_FAB2_LIB.BASEBOARD_FAB2(SCH_1):PVTT_DEF   I171 @BASEBOARD_FAB2_LIB.BASEBOARD_FAB2(SCH_1):PAGE53
   221 PVTT_DEF @BASEBOARD_FAB2_LIB.BASEBOARD_FAB2(SCH_1):PVTT_DEF   I171 @BASEBOARD_FAB2_LIB.BASEBOARD_FAB2(SCH_1):PAGE53

J4A2 SCONN288_H44441004_PIP-SCONN,HA
    79 M_E_MA<0> @BASEBOARD_FAB2_LIB.BASEBOARD_FAB2(SCH_1):M_E_MA(0)   I111 @BASEBOARD_FAB2_LIB.BASEBOARD_FAB2(SCH_1):PAGE51
    72 M_E_MA<1> @BASEBOARD_FAB2_LIB.BASEBOARD_FAB2(SCH_1):M_E_MA(1)   I111 @BASEBOARD_FAB2_LIB.BASEBOARD_FAB2(SCH_1):PAGE51
   225 M_E_MA<10> @BASEBOARD_FAB2_LIB.BASEBOARD_FAB2(SCH_1):M_E_MA(10)   I111 @BASEBOARD_FAB2_LIB.BASEBOARD_FAB2(SCH_1):PAGE51
   210 M_E_MA<11> @BASEBOARD_FAB2_LIB.BASEBOARD_FAB2(SCH_1):M_E_MA(11)   I111 @BASEBOARD_FAB2_LIB.BASEBOARD_FAB2(SCH_1):PAGE51
    65 M_E_MA<12> @BASEBOARD_FAB2_LIB.BASEBOARD_FAB2(SCH_1):M_E_MA(12)   I111 @BASEBOARD_FAB2_LIB.BASEBOARD_FAB2(SCH_1):PAGE51
   232 M_E_MA<13> @BASEBOARD_FAB2_LIB.BASEBOARD_FAB2(SCH_1):M_E_MA(13)   I111 @BASEBOARD_FAB2_LIB.BASEBOARD_FAB2(SCH_1):PAGE51
   228 M_E_MA<14> @BASEBOARD_FAB2_LIB.BASEBOARD_FAB2(SCH_1):M_E_MA(14)   I111 @BASEBOARD_FAB2_LIB.BASEBOARD_FAB2(SCH_1):PAGE51
    86 M_E_MA<15> @BASEBOARD_FAB2_LIB.BASEBOARD_FAB2(SCH_1):M_E_MA(15)   I111 @BASEBOARD_FAB2_LIB.BASEBOARD_FAB2(SCH_1):PAGE51
    82 M_E_MA<16> @BASEBOARD_FAB2_LIB.BASEBOARD_FAB2(SCH_1):M_E_MA(16)   I111 @BASEBOARD_FAB2_LIB.BASEBOARD_FAB2(SCH_1):PAGE51
   234 M_E_MA<17> @BASEBOARD_FAB2_LIB.BASEBOARD_FAB2(SCH_1):M_E_MA(17)   I111 @BASEBOARD_FAB2_LIB.BASEBOARD_FAB2(SCH_1):PAGE51
   216 M_E_MA<2> @BASEBOARD_FAB2_LIB.BASEBOARD_FAB2(SCH_1):M_E_MA(2)   I111 @BASEBOARD_FAB2_LIB.BASEBOARD_FAB2(SCH_1):PAGE51
    71 M_E_MA<3> @BASEBOARD_FAB2_LIB.BASEBOARD_FAB2(SCH_1):M_E_MA(3)   I111 @BASEBOARD_FAB2_LIB.BASEBOARD_FAB2(SCH_1):PAGE51
   214 M_E_MA<4> @BASEBOARD_FAB2_LIB.BASEBOARD_FAB2(SCH_1):M_E_MA(4)   I111 @BASEBOARD_FAB2_LIB.BASEBOARD_FAB2(SCH_1):PAGE51
   213 M_E_MA<5> @BASEBOARD_FAB2_LIB.BASEBOARD_FAB2(SCH_1):M_E_MA(5)   I111 @BASEBOARD_FAB2_LIB.BASEBOARD_FAB2(SCH_1):PAGE51
    69 M_E_MA<6> @BASEBOARD_FAB2_LIB.BASEBOARD_FAB2(SCH_1):M_E_MA(6)   I111 @BASEBOARD_FAB2_LIB.BASEBOARD_FAB2(SCH_1):PAGE51
   211 M_E_MA<7> @BASEBOARD_FAB2_LIB.BASEBOARD_FAB2(SCH_1):M_E_MA(7)   I111 @BASEBOARD_FAB2_LIB.BASEBOARD_FAB2(SCH_1):PAGE51
    68 M_E_MA<8> @BASEBOARD_FAB2_LIB.BASEBOARD_FAB2(SCH_1):M_E_MA(8)   I111 @BASEBOARD_FAB2_LIB.BASEBOARD_FAB2(SCH_1):PAGE51
    66 M_E_MA<9> @BASEBOARD_FAB2_LIB.BASEBOARD_FAB2(SCH_1):M_E_MA(9)   I111 @BASEBOARD_FAB2_LIB.BASEBOARD_FAB2(SCH_1):PAGE51
    62 M_E_ACT_N @BASEBOARD_FAB2_LIB.BASEBOARD_FAB2(SCH_1):M_E_ACT_N   I111 @BASEBOARD_FAB2_LIB.BASEBOARD_FAB2(SCH_1):PAGE51
   208 M_E_ALERT_N @BASEBOARD_FAB2_LIB.BASEBOARD_FAB2(SCH_1):M_E_ALERT_N   I111 @BASEBOARD_FAB2_LIB.BASEBOARD_FAB2(SCH_1):PAGE51
   224 M_E_BA<1> @BASEBOARD_FAB2_LIB.BASEBOARD_FAB2(SCH_1):M_E_BA(1)   I111 @BASEBOARD_FAB2_LIB.BASEBOARD_FAB2(SCH_1):PAGE51
    81 M_E_BA<0> @BASEBOARD_FAB2_LIB.BASEBOARD_FAB2(SCH_1):M_E_BA(0)   I111 @BASEBOARD_FAB2_LIB.BASEBOARD_FAB2(SCH_1):PAGE51
   207 M_E_BG<1> @BASEBOARD_FAB2_LIB.BASEBOARD_FAB2(SCH_1):M_E_BG(1)   I111 @BASEBOARD_FAB2_LIB.BASEBOARD_FAB2(SCH_1):PAGE51
    63 M_E_BG<0> @BASEBOARD_FAB2_LIB.BASEBOARD_FAB2(SCH_1):M_E_BG(0)   I111 @BASEBOARD_FAB2_LIB.BASEBOARD_FAB2(SCH_1):PAGE51
   235 M_E_C<2> @BASEBOARD_FAB2_LIB.BASEBOARD_FAB2(SCH_1):M_E_C(2)   I111 @BASEBOARD_FAB2_LIB.BASEBOARD_FAB2(SCH_1):PAGE51
   199 M_E_ECC<6> @BASEBOARD_FAB2_LIB.BASEBOARD_FAB2(SCH_1):M_E_ECC(6)   I111 @BASEBOARD_FAB2_LIB.BASEBOARD_FAB2(SCH_1):PAGE51
    54 M_E_ECC<7> @BASEBOARD_FAB2_LIB.BASEBOARD_FAB2(SCH_1):M_E_ECC(7)   I111 @BASEBOARD_FAB2_LIB.BASEBOARD_FAB2(SCH_1):PAGE51
   192 M_E_ECC<4> @BASEBOARD_FAB2_LIB.BASEBOARD_FAB2(SCH_1):M_E_ECC(4)   I111 @BASEBOARD_FAB2_LIB.BASEBOARD_FAB2(SCH_1):PAGE51
    47 M_E_ECC<5> @BASEBOARD_FAB2_LIB.BASEBOARD_FAB2(SCH_1):M_E_ECC(5)   I111 @BASEBOARD_FAB2_LIB.BASEBOARD_FAB2(SCH_1):PAGE51
   201 M_E_ECC<2> @BASEBOARD_FAB2_LIB.BASEBOARD_FAB2(SCH_1):M_E_ECC(2)   I111 @BASEBOARD_FAB2_LIB.BASEBOARD_FAB2(SCH_1):PAGE51
    56 M_E_ECC<3> @BASEBOARD_FAB2_LIB.BASEBOARD_FAB2(SCH_1):M_E_ECC(3)   I111 @BASEBOARD_FAB2_LIB.BASEBOARD_FAB2(SCH_1):PAGE51
   194 M_E_ECC<0> @BASEBOARD_FAB2_LIB.BASEBOARD_FAB2(SCH_1):M_E_ECC(0)   I111 @BASEBOARD_FAB2_LIB.BASEBOARD_FAB2(SCH_1):PAGE51
    49 M_E_ECC<1> @BASEBOARD_FAB2_LIB.BASEBOARD_FAB2(SCH_1):M_E_ECC(1)   I111 @BASEBOARD_FAB2_LIB.BASEBOARD_FAB2(SCH_1):PAGE51
    75 M_E_CLK_DN<0> @BASEBOARD_FAB2_LIB.BASEBOARD_FAB2(SCH_1):M_E_CLK_DN(0)   I111 @BASEBOARD_FAB2_LIB.BASEBOARD_FAB2(SCH_1):PAGE51
    74 M_E_CLK_DP<0> @BASEBOARD_FAB2_LIB.BASEBOARD_FAB2(SCH_1):M_E_CLK_DP(0)   I111 @BASEBOARD_FAB2_LIB.BASEBOARD_FAB2(SCH_1):PAGE51
   219 M_E_CLK_DN<1> @BASEBOARD_FAB2_LIB.BASEBOARD_FAB2(SCH_1):M_E_CLK_DN(1)   I111 @BASEBOARD_FAB2_LIB.BASEBOARD_FAB2(SCH_1):PAGE51
   218 M_E_CLK_DP<1> @BASEBOARD_FAB2_LIB.BASEBOARD_FAB2(SCH_1):M_E_CLK_DP(1)   I111 @BASEBOARD_FAB2_LIB.BASEBOARD_FAB2(SCH_1):PAGE51
   203 M_E_CKE<1> @BASEBOARD_FAB2_LIB.BASEBOARD_FAB2(SCH_1):M_E_CKE(1)   I111 @BASEBOARD_FAB2_LIB.BASEBOARD_FAB2(SCH_1):PAGE51
    60 M_E_CKE<0> @BASEBOARD_FAB2_LIB.BASEBOARD_FAB2(SCH_1):M_E_CKE(0)   I111 @BASEBOARD_FAB2_LIB.BASEBOARD_FAB2(SCH_1):PAGE51
   280 M_E_DQ<62> @BASEBOARD_FAB2_LIB.BASEBOARD_FAB2(SCH_1):M_E_DQ(62)   I111 @BASEBOARD_FAB2_LIB.BASEBOARD_FAB2(SCH_1):PAGE51
   135 M_E_DQ<63> @BASEBOARD_FAB2_LIB.BASEBOARD_FAB2(SCH_1):M_E_DQ(63)   I111 @BASEBOARD_FAB2_LIB.BASEBOARD_FAB2(SCH_1):PAGE51
   273 M_E_DQ<60> @BASEBOARD_FAB2_LIB.BASEBOARD_FAB2(SCH_1):M_E_DQ(60)   I111 @BASEBOARD_FAB2_LIB.BASEBOARD_FAB2(SCH_1):PAGE51
   128 M_E_DQ<61> @BASEBOARD_FAB2_LIB.BASEBOARD_FAB2(SCH_1):M_E_DQ(61)   I111 @BASEBOARD_FAB2_LIB.BASEBOARD_FAB2(SCH_1):PAGE51
   282 M_E_DQ<58> @BASEBOARD_FAB2_LIB.BASEBOARD_FAB2(SCH_1):M_E_DQ(58)   I111 @BASEBOARD_FAB2_LIB.BASEBOARD_FAB2(SCH_1):PAGE51
   137 M_E_DQ<59> @BASEBOARD_FAB2_LIB.BASEBOARD_FAB2(SCH_1):M_E_DQ(59)   I111 @BASEBOARD_FAB2_LIB.BASEBOARD_FAB2(SCH_1):PAGE51
   275 M_E_DQ<56> @BASEBOARD_FAB2_LIB.BASEBOARD_FAB2(SCH_1):M_E_DQ(56)   I111 @BASEBOARD_FAB2_LIB.BASEBOARD_FAB2(SCH_1):PAGE51
   130 M_E_DQ<57> @BASEBOARD_FAB2_LIB.BASEBOARD_FAB2(SCH_1):M_E_DQ(57)   I111 @BASEBOARD_FAB2_LIB.BASEBOARD_FAB2(SCH_1):PAGE51
   269 M_E_DQ<54> @BASEBOARD_FAB2_LIB.BASEBOARD_FAB2(SCH_1):M_E_DQ(54)   I111 @BASEBOARD_FAB2_LIB.BASEBOARD_FAB2(SCH_1):PAGE51
   124 M_E_DQ<55> @BASEBOARD_FAB2_LIB.BASEBOARD_FAB2(SCH_1):M_E_DQ(55)   I111 @BASEBOARD_FAB2_LIB.BASEBOARD_FAB2(SCH_1):PAGE51
   262 M_E_DQ<52> @BASEBOARD_FAB2_LIB.BASEBOARD_FAB2(SCH_1):M_E_DQ(52)   I111 @BASEBOARD_FAB2_LIB.BASEBOARD_FAB2(SCH_1):PAGE51
   117 M_E_DQ<53> @BASEBOARD_FAB2_LIB.BASEBOARD_FAB2(SCH_1):M_E_DQ(53)   I111 @BASEBOARD_FAB2_LIB.BASEBOARD_FAB2(SCH_1):PAGE51
   271 M_E_DQ<50> @BASEBOARD_FAB2_LIB.BASEBOARD_FAB2(SCH_1):M_E_DQ(50)   I111 @BASEBOARD_FAB2_LIB.BASEBOARD_FAB2(SCH_1):PAGE51
   126 M_E_DQ<51> @BASEBOARD_FAB2_LIB.BASEBOARD_FAB2(SCH_1):M_E_DQ(51)   I111 @BASEBOARD_FAB2_LIB.BASEBOARD_FAB2(SCH_1):PAGE51
   264 M_E_DQ<48> @BASEBOARD_FAB2_LIB.BASEBOARD_FAB2(SCH_1):M_E_DQ(48)   I111 @BASEBOARD_FAB2_LIB.BASEBOARD_FAB2(SCH_1):PAGE51
   119 M_E_DQ<49> @BASEBOARD_FAB2_LIB.BASEBOARD_FAB2(SCH_1):M_E_DQ(49)   I111 @BASEBOARD_FAB2_LIB.BASEBOARD_FAB2(SCH_1):PAGE51
   258 M_E_DQ<46> @BASEBOARD_FAB2_LIB.BASEBOARD_FAB2(SCH_1):M_E_DQ(46)   I111 @BASEBOARD_FAB2_LIB.BASEBOARD_FAB2(SCH_1):PAGE51
   113 M_E_DQ<47> @BASEBOARD_FAB2_LIB.BASEBOARD_FAB2(SCH_1):M_E_DQ(47)   I111 @BASEBOARD_FAB2_LIB.BASEBOARD_FAB2(SCH_1):PAGE51
   251 M_E_DQ<44> @BASEBOARD_FAB2_LIB.BASEBOARD_FAB2(SCH_1):M_E_DQ(44)   I111 @BASEBOARD_FAB2_LIB.BASEBOARD_FAB2(SCH_1):PAGE51
   106 M_E_DQ<45> @BASEBOARD_FAB2_LIB.BASEBOARD_FAB2(SCH_1):M_E_DQ(45)   I111 @BASEBOARD_FAB2_LIB.BASEBOARD_FAB2(SCH_1):PAGE51
   260 M_E_DQ<42> @BASEBOARD_FAB2_LIB.BASEBOARD_FAB2(SCH_1):M_E_DQ(42)   I111 @BASEBOARD_FAB2_LIB.BASEBOARD_FAB2(SCH_1):PAGE51
   115 M_E_DQ<43> @BASEBOARD_FAB2_LIB.BASEBOARD_FAB2(SCH_1):M_E_DQ(43)   I111 @BASEBOARD_FAB2_LIB.BASEBOARD_FAB2(SCH_1):PAGE51
   253 M_E_DQ<40> @BASEBOARD_FAB2_LIB.BASEBOARD_FAB2(SCH_1):M_E_DQ(40)   I111 @BASEBOARD_FAB2_LIB.BASEBOARD_FAB2(SCH_1):PAGE51
   108 M_E_DQ<41> @BASEBOARD_FAB2_LIB.BASEBOARD_FAB2(SCH_1):M_E_DQ(41)   I111 @BASEBOARD_FAB2_LIB.BASEBOARD_FAB2(SCH_1):PAGE51
   247 M_E_DQ<38> @BASEBOARD_FAB2_LIB.BASEBOARD_FAB2(SCH_1):M_E_DQ(38)   I111 @BASEBOARD_FAB2_LIB.BASEBOARD_FAB2(SCH_1):PAGE51
   102 M_E_DQ<39> @BASEBOARD_FAB2_LIB.BASEBOARD_FAB2(SCH_1):M_E_DQ(39)   I111 @BASEBOARD_FAB2_LIB.BASEBOARD_FAB2(SCH_1):PAGE51
   240 M_E_DQ<36> @BASEBOARD_FAB2_LIB.BASEBOARD_FAB2(SCH_1):M_E_DQ(36)   I111 @BASEBOARD_FAB2_LIB.BASEBOARD_FAB2(SCH_1):PAGE51
    95 M_E_DQ<37> @BASEBOARD_FAB2_LIB.BASEBOARD_FAB2(SCH_1):M_E_DQ(37)   I111 @BASEBOARD_FAB2_LIB.BASEBOARD_FAB2(SCH_1):PAGE51
   249 M_E_DQ<34> @BASEBOARD_FAB2_LIB.BASEBOARD_FAB2(SCH_1):M_E_DQ(34)   I111 @BASEBOARD_FAB2_LIB.BASEBOARD_FAB2(SCH_1):PAGE51
   104 M_E_DQ<35> @BASEBOARD_FAB2_LIB.BASEBOARD_FAB2(SCH_1):M_E_DQ(35)   I111 @BASEBOARD_FAB2_LIB.BASEBOARD_FAB2(SCH_1):PAGE51
   242 M_E_DQ<32> @BASEBOARD_FAB2_LIB.BASEBOARD_FAB2(SCH_1):M_E_DQ(32)   I111 @BASEBOARD_FAB2_LIB.BASEBOARD_FAB2(SCH_1):PAGE51
    97 M_E_DQ<33> @BASEBOARD_FAB2_LIB.BASEBOARD_FAB2(SCH_1):M_E_DQ(33)   I111 @BASEBOARD_FAB2_LIB.BASEBOARD_FAB2(SCH_1):PAGE51
   188 M_E_DQ<30> @BASEBOARD_FAB2_LIB.BASEBOARD_FAB2(SCH_1):M_E_DQ(30)   I111 @BASEBOARD_FAB2_LIB.BASEBOARD_FAB2(SCH_1):PAGE51
    43 M_E_DQ<31> @BASEBOARD_FAB2_LIB.BASEBOARD_FAB2(SCH_1):M_E_DQ(31)   I111 @BASEBOARD_FAB2_LIB.BASEBOARD_FAB2(SCH_1):PAGE51
   181 M_E_DQ<28> @BASEBOARD_FAB2_LIB.BASEBOARD_FAB2(SCH_1):M_E_DQ(28)   I111 @BASEBOARD_FAB2_LIB.BASEBOARD_FAB2(SCH_1):PAGE51
    36 M_E_DQ<29> @BASEBOARD_FAB2_LIB.BASEBOARD_FAB2(SCH_1):M_E_DQ(29)   I111 @BASEBOARD_FAB2_LIB.BASEBOARD_FAB2(SCH_1):PAGE51
   190 M_E_DQ<26> @BASEBOARD_FAB2_LIB.BASEBOARD_FAB2(SCH_1):M_E_DQ(26)   I111 @BASEBOARD_FAB2_LIB.BASEBOARD_FAB2(SCH_1):PAGE51
    45 M_E_DQ<27> @BASEBOARD_FAB2_LIB.BASEBOARD_FAB2(SCH_1):M_E_DQ(27)   I111 @BASEBOARD_FAB2_LIB.BASEBOARD_FAB2(SCH_1):PAGE51
   183 M_E_DQ<24> @BASEBOARD_FAB2_LIB.BASEBOARD_FAB2(SCH_1):M_E_DQ(24)   I111 @BASEBOARD_FAB2_LIB.BASEBOARD_FAB2(SCH_1):PAGE51
    38 M_E_DQ<25> @BASEBOARD_FAB2_LIB.BASEBOARD_FAB2(SCH_1):M_E_DQ(25)   I111 @BASEBOARD_FAB2_LIB.BASEBOARD_FAB2(SCH_1):PAGE51
   177 M_E_DQ<22> @BASEBOARD_FAB2_LIB.BASEBOARD_FAB2(SCH_1):M_E_DQ(22)   I111 @BASEBOARD_FAB2_LIB.BASEBOARD_FAB2(SCH_1):PAGE51
    32 M_E_DQ<23> @BASEBOARD_FAB2_LIB.BASEBOARD_FAB2(SCH_1):M_E_DQ(23)   I111 @BASEBOARD_FAB2_LIB.BASEBOARD_FAB2(SCH_1):PAGE51
   170 M_E_DQ<20> @BASEBOARD_FAB2_LIB.BASEBOARD_FAB2(SCH_1):M_E_DQ(20)   I111 @BASEBOARD_FAB2_LIB.BASEBOARD_FAB2(SCH_1):PAGE51
    25 M_E_DQ<21> @BASEBOARD_FAB2_LIB.BASEBOARD_FAB2(SCH_1):M_E_DQ(21)   I111 @BASEBOARD_FAB2_LIB.BASEBOARD_FAB2(SCH_1):PAGE51
   179 M_E_DQ<18> @BASEBOARD_FAB2_LIB.BASEBOARD_FAB2(SCH_1):M_E_DQ(18)   I111 @BASEBOARD_FAB2_LIB.BASEBOARD_FAB2(SCH_1):PAGE51
    34 M_E_DQ<19> @BASEBOARD_FAB2_LIB.BASEBOARD_FAB2(SCH_1):M_E_DQ(19)   I111 @BASEBOARD_FAB2_LIB.BASEBOARD_FAB2(SCH_1):PAGE51
   172 M_E_DQ<16> @BASEBOARD_FAB2_LIB.BASEBOARD_FAB2(SCH_1):M_E_DQ(16)   I111 @BASEBOARD_FAB2_LIB.BASEBOARD_FAB2(SCH_1):PAGE51
    27 M_E_DQ<17> @BASEBOARD_FAB2_LIB.BASEBOARD_FAB2(SCH_1):M_E_DQ(17)   I111 @BASEBOARD_FAB2_LIB.BASEBOARD_FAB2(SCH_1):PAGE51
   166 M_E_DQ<14> @BASEBOARD_FAB2_LIB.BASEBOARD_FAB2(SCH_1):M_E_DQ(14)   I111 @BASEBOARD_FAB2_LIB.BASEBOARD_FAB2(SCH_1):PAGE51
    21 M_E_DQ<15> @BASEBOARD_FAB2_LIB.BASEBOARD_FAB2(SCH_1):M_E_DQ(15)   I111 @BASEBOARD_FAB2_LIB.BASEBOARD_FAB2(SCH_1):PAGE51
   159 M_E_DQ<12> @BASEBOARD_FAB2_LIB.BASEBOARD_FAB2(SCH_1):M_E_DQ(12)   I111 @BASEBOARD_FAB2_LIB.BASEBOARD_FAB2(SCH_1):PAGE51
    14 M_E_DQ<13> @BASEBOARD_FAB2_LIB.BASEBOARD_FAB2(SCH_1):M_E_DQ(13)   I111 @BASEBOARD_FAB2_LIB.BASEBOARD_FAB2(SCH_1):PAGE51
   168 M_E_DQ<10> @BASEBOARD_FAB2_LIB.BASEBOARD_FAB2(SCH_1):M_E_DQ(10)   I111 @BASEBOARD_FAB2_LIB.BASEBOARD_FAB2(SCH_1):PAGE51
    23 M_E_DQ<11> @BASEBOARD_FAB2_LIB.BASEBOARD_FAB2(SCH_1):M_E_DQ(11)   I111 @BASEBOARD_FAB2_LIB.BASEBOARD_FAB2(SCH_1):PAGE51
   161 M_E_DQ<8> @BASEBOARD_FAB2_LIB.BASEBOARD_FAB2(SCH_1):M_E_DQ(8)   I111 @BASEBOARD_FAB2_LIB.BASEBOARD_FAB2(SCH_1):PAGE51
    16 M_E_DQ<9> @BASEBOARD_FAB2_LIB.BASEBOARD_FAB2(SCH_1):M_E_DQ(9)   I111 @BASEBOARD_FAB2_LIB.BASEBOARD_FAB2(SCH_1):PAGE51
   155 M_E_DQ<6> @BASEBOARD_FAB2_LIB.BASEBOARD_FAB2(SCH_1):M_E_DQ(6)   I111 @BASEBOARD_FAB2_LIB.BASEBOARD_FAB2(SCH_1):PAGE51
    10 M_E_DQ<7> @BASEBOARD_FAB2_LIB.BASEBOARD_FAB2(SCH_1):M_E_DQ(7)   I111 @BASEBOARD_FAB2_LIB.BASEBOARD_FAB2(SCH_1):PAGE51
   148 M_E_DQ<4> @BASEBOARD_FAB2_LIB.BASEBOARD_FAB2(SCH_1):M_E_DQ(4)   I111 @BASEBOARD_FAB2_LIB.BASEBOARD_FAB2(SCH_1):PAGE51
     3 M_E_DQ<5> @BASEBOARD_FAB2_LIB.BASEBOARD_FAB2(SCH_1):M_E_DQ(5)   I111 @BASEBOARD_FAB2_LIB.BASEBOARD_FAB2(SCH_1):PAGE51
   157 M_E_DQ<2> @BASEBOARD_FAB2_LIB.BASEBOARD_FAB2(SCH_1):M_E_DQ(2)   I111 @BASEBOARD_FAB2_LIB.BASEBOARD_FAB2(SCH_1):PAGE51
    12 M_E_DQ<3> @BASEBOARD_FAB2_LIB.BASEBOARD_FAB2(SCH_1):M_E_DQ(3)   I111 @BASEBOARD_FAB2_LIB.BASEBOARD_FAB2(SCH_1):PAGE51
   150 M_E_DQ<0> @BASEBOARD_FAB2_LIB.BASEBOARD_FAB2(SCH_1):M_E_DQ(0)   I111 @BASEBOARD_FAB2_LIB.BASEBOARD_FAB2(SCH_1):PAGE51
     5 M_E_DQ<1> @BASEBOARD_FAB2_LIB.BASEBOARD_FAB2(SCH_1):M_E_DQ(1)   I111 @BASEBOARD_FAB2_LIB.BASEBOARD_FAB2(SCH_1):PAGE51
    78 FM_DIMM_EVENT_COD_N @BASEBOARD_FAB2_LIB.BASEBOARD_FAB2(SCH_1):FM_DIMM_EVENT_COD_N   I111 @BASEBOARD_FAB2_LIB.BASEBOARD_FAB2(SCH_1):PAGE51
    91 M_E_ODT<1> @BASEBOARD_FAB2_LIB.BASEBOARD_FAB2(SCH_1):M_E_ODT(1)   I111 @BASEBOARD_FAB2_LIB.BASEBOARD_FAB2(SCH_1):PAGE51
    87 M_E_ODT<0> @BASEBOARD_FAB2_LIB.BASEBOARD_FAB2(SCH_1):M_E_ODT(0)   I111 @BASEBOARD_FAB2_LIB.BASEBOARD_FAB2(SCH_1):PAGE51
   222 M_E_PAR @BASEBOARD_FAB2_LIB.BASEBOARD_FAB2(SCH_1):M_E_PAR   I111 @BASEBOARD_FAB2_LIB.BASEBOARD_FAB2(SCH_1):PAGE51
    58 M_DEF_RST_N @BASEBOARD_FAB2_LIB.BASEBOARD_FAB2(SCH_1):M_DEF_RST_N   I111 @BASEBOARD_FAB2_LIB.BASEBOARD_FAB2(SCH_1):PAGE51
   144 TP_CH_E_DIMM_E0_RFU_2 @BASEBOARD_FAB2_LIB.BASEBOARD_FAB2(SCH_1):TP_CH_E_DIMM_E0_RFU_2   I111 @BASEBOARD_FAB2_LIB.BASEBOARD_FAB2(SCH_1):PAGE51
   227 TP_CH_E_DIMM_E0_RFU_1 @BASEBOARD_FAB2_LIB.BASEBOARD_FAB2(SCH_1):TP_CH_E_DIMM_E0_RFU_1   I111 @BASEBOARD_FAB2_LIB.BASEBOARD_FAB2(SCH_1):PAGE51
   205 TP_CH_E_DIMM_E0_RFU_0 @BASEBOARD_FAB2_LIB.BASEBOARD_FAB2(SCH_1):TP_CH_E_DIMM_E0_RFU_0   I111 @BASEBOARD_FAB2_LIB.BASEBOARD_FAB2(SCH_1):PAGE51
    84 M_E_CS_N<0> @BASEBOARD_FAB2_LIB.BASEBOARD_FAB2(SCH_1):M_E_CS_N(0)   I111 @BASEBOARD_FAB2_LIB.BASEBOARD_FAB2(SCH_1):PAGE51
    89 M_E_CS_N<1> @BASEBOARD_FAB2_LIB.BASEBOARD_FAB2(SCH_1):M_E_CS_N(1)   I111 @BASEBOARD_FAB2_LIB.BASEBOARD_FAB2(SCH_1):PAGE51
    93 M_E_CS_N<2> @BASEBOARD_FAB2_LIB.BASEBOARD_FAB2(SCH_1):M_E_CS_N(2)   I111 @BASEBOARD_FAB2_LIB.BASEBOARD_FAB2(SCH_1):PAGE51
   237 M_E_CS_N<3> @BASEBOARD_FAB2_LIB.BASEBOARD_FAB2(SCH_1):M_E_CS_N(3)   I111 @BASEBOARD_FAB2_LIB.BASEBOARD_FAB2(SCH_1):PAGE51
   238    GND @BASEBOARD_FAB2_LIB.BASEBOARD_FAB2(SCH_1):GND   I111 @BASEBOARD_FAB2_LIB.BASEBOARD_FAB2(SCH_1):PAGE51
   140 PVPP_DEF @BASEBOARD_FAB2_LIB.BASEBOARD_FAB2(SCH_1):PVPP_DEF   I111 @BASEBOARD_FAB2_LIB.BASEBOARD_FAB2(SCH_1):PAGE51
   139    GND @BASEBOARD_FAB2_LIB.BASEBOARD_FAB2(SCH_1):GND   I111 @BASEBOARD_FAB2_LIB.BASEBOARD_FAB2(SCH_1):PAGE51
   230 FM_ADR_COMPLETE_DEF_N @BASEBOARD_FAB2_LIB.BASEBOARD_FAB2(SCH_1):FM_ADR_COMPLETE_DEF_N   I111 @BASEBOARD_FAB2_LIB.BASEBOARD_FAB2(SCH_1):PAGE51
   141 SMB_DDR_DEF_VPP_SCL @BASEBOARD_FAB2_LIB.BASEBOARD_FAB2(SCH_1):SMB_DDR_DEF_VPP_SCL   I111 @BASEBOARD_FAB2_LIB.BASEBOARD_FAB2(SCH_1):PAGE51
   285 SMB_DDR_DEF_VPP_SDA @BASEBOARD_FAB2_LIB.BASEBOARD_FAB2(SCH_1):SMB_DDR_DEF_VPP_SDA   I111 @BASEBOARD_FAB2_LIB.BASEBOARD_FAB2(SCH_1):PAGE51
   284 PVPP_DEF @BASEBOARD_FAB2_LIB.BASEBOARD_FAB2(SCH_1):PVPP_DEF   I111 @BASEBOARD_FAB2_LIB.BASEBOARD_FAB2(SCH_1):PAGE51
   146 M_E_VREF @BASEBOARD_FAB2_LIB.BASEBOARD_FAB2(SCH_1):M_E_VREF   I111 @BASEBOARD_FAB2_LIB.BASEBOARD_FAB2(SCH_1):PAGE51
   152 M_E_DQS_DN<0> @BASEBOARD_FAB2_LIB.BASEBOARD_FAB2(SCH_1):M_E_DQS_DN(0)    I66 @BASEBOARD_FAB2_LIB.BASEBOARD_FAB2(SCH_1):PAGE51
   153 M_E_DQS_DP<0> @BASEBOARD_FAB2_LIB.BASEBOARD_FAB2(SCH_1):M_E_DQS_DP(0)    I66 @BASEBOARD_FAB2_LIB.BASEBOARD_FAB2(SCH_1):PAGE51
    19 M_E_DQS_DN<10> @BASEBOARD_FAB2_LIB.BASEBOARD_FAB2(SCH_1):M_E_DQS_DN(10)    I66 @BASEBOARD_FAB2_LIB.BASEBOARD_FAB2(SCH_1):PAGE51
    18 M_E_DQS_DP<10> @BASEBOARD_FAB2_LIB.BASEBOARD_FAB2(SCH_1):M_E_DQS_DP(10)    I66 @BASEBOARD_FAB2_LIB.BASEBOARD_FAB2(SCH_1):PAGE51
    30 M_E_DQS_DN<11> @BASEBOARD_FAB2_LIB.BASEBOARD_FAB2(SCH_1):M_E_DQS_DN(11)    I66 @BASEBOARD_FAB2_LIB.BASEBOARD_FAB2(SCH_1):PAGE51
    29 M_E_DQS_DP<11> @BASEBOARD_FAB2_LIB.BASEBOARD_FAB2(SCH_1):M_E_DQS_DP(11)    I66 @BASEBOARD_FAB2_LIB.BASEBOARD_FAB2(SCH_1):PAGE51
    41 M_E_DQS_DN<12> @BASEBOARD_FAB2_LIB.BASEBOARD_FAB2(SCH_1):M_E_DQS_DN(12)    I66 @BASEBOARD_FAB2_LIB.BASEBOARD_FAB2(SCH_1):PAGE51
    40 M_E_DQS_DP<12> @BASEBOARD_FAB2_LIB.BASEBOARD_FAB2(SCH_1):M_E_DQS_DP(12)    I66 @BASEBOARD_FAB2_LIB.BASEBOARD_FAB2(SCH_1):PAGE51
   100 M_E_DQS_DN<13> @BASEBOARD_FAB2_LIB.BASEBOARD_FAB2(SCH_1):M_E_DQS_DN(13)    I66 @BASEBOARD_FAB2_LIB.BASEBOARD_FAB2(SCH_1):PAGE51
    99 M_E_DQS_DP<13> @BASEBOARD_FAB2_LIB.BASEBOARD_FAB2(SCH_1):M_E_DQS_DP(13)    I66 @BASEBOARD_FAB2_LIB.BASEBOARD_FAB2(SCH_1):PAGE51
   111 M_E_DQS_DN<14> @BASEBOARD_FAB2_LIB.BASEBOARD_FAB2(SCH_1):M_E_DQS_DN(14)    I66 @BASEBOARD_FAB2_LIB.BASEBOARD_FAB2(SCH_1):PAGE51
   110 M_E_DQS_DP<14> @BASEBOARD_FAB2_LIB.BASEBOARD_FAB2(SCH_1):M_E_DQS_DP(14)    I66 @BASEBOARD_FAB2_LIB.BASEBOARD_FAB2(SCH_1):PAGE51
   122 M_E_DQS_DN<15> @BASEBOARD_FAB2_LIB.BASEBOARD_FAB2(SCH_1):M_E_DQS_DN(15)    I66 @BASEBOARD_FAB2_LIB.BASEBOARD_FAB2(SCH_1):PAGE51
   121 M_E_DQS_DP<15> @BASEBOARD_FAB2_LIB.BASEBOARD_FAB2(SCH_1):M_E_DQS_DP(15)    I66 @BASEBOARD_FAB2_LIB.BASEBOARD_FAB2(SCH_1):PAGE51
   133 M_E_DQS_DN<16> @BASEBOARD_FAB2_LIB.BASEBOARD_FAB2(SCH_1):M_E_DQS_DN(16)    I66 @BASEBOARD_FAB2_LIB.BASEBOARD_FAB2(SCH_1):PAGE51
   132 M_E_DQS_DP<16> @BASEBOARD_FAB2_LIB.BASEBOARD_FAB2(SCH_1):M_E_DQS_DP(16)    I66 @BASEBOARD_FAB2_LIB.BASEBOARD_FAB2(SCH_1):PAGE51
    52 M_E_DQS_DN<17> @BASEBOARD_FAB2_LIB.BASEBOARD_FAB2(SCH_1):M_E_DQS_DN(17)    I66 @BASEBOARD_FAB2_LIB.BASEBOARD_FAB2(SCH_1):PAGE51
    51 M_E_DQS_DP<17> @BASEBOARD_FAB2_LIB.BASEBOARD_FAB2(SCH_1):M_E_DQS_DP(17)    I66 @BASEBOARD_FAB2_LIB.BASEBOARD_FAB2(SCH_1):PAGE51
   163 M_E_DQS_DN<1> @BASEBOARD_FAB2_LIB.BASEBOARD_FAB2(SCH_1):M_E_DQS_DN(1)    I66 @BASEBOARD_FAB2_LIB.BASEBOARD_FAB2(SCH_1):PAGE51
   164 M_E_DQS_DP<1> @BASEBOARD_FAB2_LIB.BASEBOARD_FAB2(SCH_1):M_E_DQS_DP(1)    I66 @BASEBOARD_FAB2_LIB.BASEBOARD_FAB2(SCH_1):PAGE51
   174 M_E_DQS_DN<2> @BASEBOARD_FAB2_LIB.BASEBOARD_FAB2(SCH_1):M_E_DQS_DN(2)    I66 @BASEBOARD_FAB2_LIB.BASEBOARD_FAB2(SCH_1):PAGE51
   175 M_E_DQS_DP<2> @BASEBOARD_FAB2_LIB.BASEBOARD_FAB2(SCH_1):M_E_DQS_DP(2)    I66 @BASEBOARD_FAB2_LIB.BASEBOARD_FAB2(SCH_1):PAGE51
   185 M_E_DQS_DN<3> @BASEBOARD_FAB2_LIB.BASEBOARD_FAB2(SCH_1):M_E_DQS_DN(3)    I66 @BASEBOARD_FAB2_LIB.BASEBOARD_FAB2(SCH_1):PAGE51
   186 M_E_DQS_DP<3> @BASEBOARD_FAB2_LIB.BASEBOARD_FAB2(SCH_1):M_E_DQS_DP(3)    I66 @BASEBOARD_FAB2_LIB.BASEBOARD_FAB2(SCH_1):PAGE51
   244 M_E_DQS_DN<4> @BASEBOARD_FAB2_LIB.BASEBOARD_FAB2(SCH_1):M_E_DQS_DN(4)    I66 @BASEBOARD_FAB2_LIB.BASEBOARD_FAB2(SCH_1):PAGE51
   245 M_E_DQS_DP<4> @BASEBOARD_FAB2_LIB.BASEBOARD_FAB2(SCH_1):M_E_DQS_DP(4)    I66 @BASEBOARD_FAB2_LIB.BASEBOARD_FAB2(SCH_1):PAGE51
   255 M_E_DQS_DN<5> @BASEBOARD_FAB2_LIB.BASEBOARD_FAB2(SCH_1):M_E_DQS_DN(5)    I66 @BASEBOARD_FAB2_LIB.BASEBOARD_FAB2(SCH_1):PAGE51
   256 M_E_DQS_DP<5> @BASEBOARD_FAB2_LIB.BASEBOARD_FAB2(SCH_1):M_E_DQS_DP(5)    I66 @BASEBOARD_FAB2_LIB.BASEBOARD_FAB2(SCH_1):PAGE51
   266 M_E_DQS_DN<6> @BASEBOARD_FAB2_LIB.BASEBOARD_FAB2(SCH_1):M_E_DQS_DN(6)    I66 @BASEBOARD_FAB2_LIB.BASEBOARD_FAB2(SCH_1):PAGE51
   267 M_E_DQS_DP<6> @BASEBOARD_FAB2_LIB.BASEBOARD_FAB2(SCH_1):M_E_DQS_DP(6)    I66 @BASEBOARD_FAB2_LIB.BASEBOARD_FAB2(SCH_1):PAGE51
   277 M_E_DQS_DN<7> @BASEBOARD_FAB2_LIB.BASEBOARD_FAB2(SCH_1):M_E_DQS_DN(7)    I66 @BASEBOARD_FAB2_LIB.BASEBOARD_FAB2(SCH_1):PAGE51
   278 M_E_DQS_DP<7> @BASEBOARD_FAB2_LIB.BASEBOARD_FAB2(SCH_1):M_E_DQS_DP(7)    I66 @BASEBOARD_FAB2_LIB.BASEBOARD_FAB2(SCH_1):PAGE51
   196 M_E_DQS_DN<8> @BASEBOARD_FAB2_LIB.BASEBOARD_FAB2(SCH_1):M_E_DQS_DN(8)    I66 @BASEBOARD_FAB2_LIB.BASEBOARD_FAB2(SCH_1):PAGE51
   197 M_E_DQS_DP<8> @BASEBOARD_FAB2_LIB.BASEBOARD_FAB2(SCH_1):M_E_DQS_DP(8)    I66 @BASEBOARD_FAB2_LIB.BASEBOARD_FAB2(SCH_1):PAGE51
     8 M_E_DQS_DN<9> @BASEBOARD_FAB2_LIB.BASEBOARD_FAB2(SCH_1):M_E_DQS_DN(9)    I66 @BASEBOARD_FAB2_LIB.BASEBOARD_FAB2(SCH_1):PAGE51
     7 M_E_DQS_DP<9> @BASEBOARD_FAB2_LIB.BASEBOARD_FAB2(SCH_1):M_E_DQS_DP(9)    I66 @BASEBOARD_FAB2_LIB.BASEBOARD_FAB2(SCH_1):PAGE51
     2    GND @BASEBOARD_FAB2_LIB.BASEBOARD_FAB2(SCH_1):GND    I43 @BASEBOARD_FAB2_LIB.BASEBOARD_FAB2(SCH_1):PAGE51
     4    GND @BASEBOARD_FAB2_LIB.BASEBOARD_FAB2(SCH_1):GND    I43 @BASEBOARD_FAB2_LIB.BASEBOARD_FAB2(SCH_1):PAGE51
     6    GND @BASEBOARD_FAB2_LIB.BASEBOARD_FAB2(SCH_1):GND    I43 @BASEBOARD_FAB2_LIB.BASEBOARD_FAB2(SCH_1):PAGE51
     9    GND @BASEBOARD_FAB2_LIB.BASEBOARD_FAB2(SCH_1):GND    I43 @BASEBOARD_FAB2_LIB.BASEBOARD_FAB2(SCH_1):PAGE51
    11    GND @BASEBOARD_FAB2_LIB.BASEBOARD_FAB2(SCH_1):GND    I43 @BASEBOARD_FAB2_LIB.BASEBOARD_FAB2(SCH_1):PAGE51
    13    GND @BASEBOARD_FAB2_LIB.BASEBOARD_FAB2(SCH_1):GND    I43 @BASEBOARD_FAB2_LIB.BASEBOARD_FAB2(SCH_1):PAGE51
    15    GND @BASEBOARD_FAB2_LIB.BASEBOARD_FAB2(SCH_1):GND    I43 @BASEBOARD_FAB2_LIB.BASEBOARD_FAB2(SCH_1):PAGE51
    17    GND @BASEBOARD_FAB2_LIB.BASEBOARD_FAB2(SCH_1):GND    I43 @BASEBOARD_FAB2_LIB.BASEBOARD_FAB2(SCH_1):PAGE51
    20    GND @BASEBOARD_FAB2_LIB.BASEBOARD_FAB2(SCH_1):GND    I43 @BASEBOARD_FAB2_LIB.BASEBOARD_FAB2(SCH_1):PAGE51
    22    GND @BASEBOARD_FAB2_LIB.BASEBOARD_FAB2(SCH_1):GND    I43 @BASEBOARD_FAB2_LIB.BASEBOARD_FAB2(SCH_1):PAGE51
    24    GND @BASEBOARD_FAB2_LIB.BASEBOARD_FAB2(SCH_1):GND    I43 @BASEBOARD_FAB2_LIB.BASEBOARD_FAB2(SCH_1):PAGE51
    26    GND @BASEBOARD_FAB2_LIB.BASEBOARD_FAB2(SCH_1):GND    I43 @BASEBOARD_FAB2_LIB.BASEBOARD_FAB2(SCH_1):PAGE51
    28    GND @BASEBOARD_FAB2_LIB.BASEBOARD_FAB2(SCH_1):GND    I43 @BASEBOARD_FAB2_LIB.BASEBOARD_FAB2(SCH_1):PAGE51
    31    GND @BASEBOARD_FAB2_LIB.BASEBOARD_FAB2(SCH_1):GND    I43 @BASEBOARD_FAB2_LIB.BASEBOARD_FAB2(SCH_1):PAGE51
    33    GND @BASEBOARD_FAB2_LIB.BASEBOARD_FAB2(SCH_1):GND    I43 @BASEBOARD_FAB2_LIB.BASEBOARD_FAB2(SCH_1):PAGE51
    35    GND @BASEBOARD_FAB2_LIB.BASEBOARD_FAB2(SCH_1):GND    I43 @BASEBOARD_FAB2_LIB.BASEBOARD_FAB2(SCH_1):PAGE51
    37    GND @BASEBOARD_FAB2_LIB.BASEBOARD_FAB2(SCH_1):GND    I43 @BASEBOARD_FAB2_LIB.BASEBOARD_FAB2(SCH_1):PAGE51
    39    GND @BASEBOARD_FAB2_LIB.BASEBOARD_FAB2(SCH_1):GND    I43 @BASEBOARD_FAB2_LIB.BASEBOARD_FAB2(SCH_1):PAGE51
    42    GND @BASEBOARD_FAB2_LIB.BASEBOARD_FAB2(SCH_1):GND    I43 @BASEBOARD_FAB2_LIB.BASEBOARD_FAB2(SCH_1):PAGE51
    44    GND @BASEBOARD_FAB2_LIB.BASEBOARD_FAB2(SCH_1):GND    I43 @BASEBOARD_FAB2_LIB.BASEBOARD_FAB2(SCH_1):PAGE51
    46    GND @BASEBOARD_FAB2_LIB.BASEBOARD_FAB2(SCH_1):GND    I43 @BASEBOARD_FAB2_LIB.BASEBOARD_FAB2(SCH_1):PAGE51
    48    GND @BASEBOARD_FAB2_LIB.BASEBOARD_FAB2(SCH_1):GND    I43 @BASEBOARD_FAB2_LIB.BASEBOARD_FAB2(SCH_1):PAGE51
    50    GND @BASEBOARD_FAB2_LIB.BASEBOARD_FAB2(SCH_1):GND    I43 @BASEBOARD_FAB2_LIB.BASEBOARD_FAB2(SCH_1):PAGE51
    53    GND @BASEBOARD_FAB2_LIB.BASEBOARD_FAB2(SCH_1):GND    I43 @BASEBOARD_FAB2_LIB.BASEBOARD_FAB2(SCH_1):PAGE51
    55    GND @BASEBOARD_FAB2_LIB.BASEBOARD_FAB2(SCH_1):GND    I43 @BASEBOARD_FAB2_LIB.BASEBOARD_FAB2(SCH_1):PAGE51
    57    GND @BASEBOARD_FAB2_LIB.BASEBOARD_FAB2(SCH_1):GND    I43 @BASEBOARD_FAB2_LIB.BASEBOARD_FAB2(SCH_1):PAGE51
    94    GND @BASEBOARD_FAB2_LIB.BASEBOARD_FAB2(SCH_1):GND    I43 @BASEBOARD_FAB2_LIB.BASEBOARD_FAB2(SCH_1):PAGE51
    96    GND @BASEBOARD_FAB2_LIB.BASEBOARD_FAB2(SCH_1):GND    I43 @BASEBOARD_FAB2_LIB.BASEBOARD_FAB2(SCH_1):PAGE51
    98    GND @BASEBOARD_FAB2_LIB.BASEBOARD_FAB2(SCH_1):GND    I43 @BASEBOARD_FAB2_LIB.BASEBOARD_FAB2(SCH_1):PAGE51
   101    GND @BASEBOARD_FAB2_LIB.BASEBOARD_FAB2(SCH_1):GND    I43 @BASEBOARD_FAB2_LIB.BASEBOARD_FAB2(SCH_1):PAGE51
   103    GND @BASEBOARD_FAB2_LIB.BASEBOARD_FAB2(SCH_1):GND    I43 @BASEBOARD_FAB2_LIB.BASEBOARD_FAB2(SCH_1):PAGE51
   105    GND @BASEBOARD_FAB2_LIB.BASEBOARD_FAB2(SCH_1):GND    I43 @BASEBOARD_FAB2_LIB.BASEBOARD_FAB2(SCH_1):PAGE51
   107    GND @BASEBOARD_FAB2_LIB.BASEBOARD_FAB2(SCH_1):GND    I43 @BASEBOARD_FAB2_LIB.BASEBOARD_FAB2(SCH_1):PAGE51
   109    GND @BASEBOARD_FAB2_LIB.BASEBOARD_FAB2(SCH_1):GND    I43 @BASEBOARD_FAB2_LIB.BASEBOARD_FAB2(SCH_1):PAGE51
   112    GND @BASEBOARD_FAB2_LIB.BASEBOARD_FAB2(SCH_1):GND    I43 @BASEBOARD_FAB2_LIB.BASEBOARD_FAB2(SCH_1):PAGE51
   114    GND @BASEBOARD_FAB2_LIB.BASEBOARD_FAB2(SCH_1):GND    I43 @BASEBOARD_FAB2_LIB.BASEBOARD_FAB2(SCH_1):PAGE51
   116    GND @BASEBOARD_FAB2_LIB.BASEBOARD_FAB2(SCH_1):GND    I43 @BASEBOARD_FAB2_LIB.BASEBOARD_FAB2(SCH_1):PAGE51
   118    GND @BASEBOARD_FAB2_LIB.BASEBOARD_FAB2(SCH_1):GND    I43 @BASEBOARD_FAB2_LIB.BASEBOARD_FAB2(SCH_1):PAGE51
   120    GND @BASEBOARD_FAB2_LIB.BASEBOARD_FAB2(SCH_1):GND    I43 @BASEBOARD_FAB2_LIB.BASEBOARD_FAB2(SCH_1):PAGE51
   123    GND @BASEBOARD_FAB2_LIB.BASEBOARD_FAB2(SCH_1):GND    I43 @BASEBOARD_FAB2_LIB.BASEBOARD_FAB2(SCH_1):PAGE51
   125    GND @BASEBOARD_FAB2_LIB.BASEBOARD_FAB2(SCH_1):GND    I43 @BASEBOARD_FAB2_LIB.BASEBOARD_FAB2(SCH_1):PAGE51
   127    GND @BASEBOARD_FAB2_LIB.BASEBOARD_FAB2(SCH_1):GND    I43 @BASEBOARD_FAB2_LIB.BASEBOARD_FAB2(SCH_1):PAGE51
   129    GND @BASEBOARD_FAB2_LIB.BASEBOARD_FAB2(SCH_1):GND    I43 @BASEBOARD_FAB2_LIB.BASEBOARD_FAB2(SCH_1):PAGE51
   131    GND @BASEBOARD_FAB2_LIB.BASEBOARD_FAB2(SCH_1):GND    I43 @BASEBOARD_FAB2_LIB.BASEBOARD_FAB2(SCH_1):PAGE51
   134    GND @BASEBOARD_FAB2_LIB.BASEBOARD_FAB2(SCH_1):GND    I43 @BASEBOARD_FAB2_LIB.BASEBOARD_FAB2(SCH_1):PAGE51
   136    GND @BASEBOARD_FAB2_LIB.BASEBOARD_FAB2(SCH_1):GND    I43 @BASEBOARD_FAB2_LIB.BASEBOARD_FAB2(SCH_1):PAGE51
   138    GND @BASEBOARD_FAB2_LIB.BASEBOARD_FAB2(SCH_1):GND    I43 @BASEBOARD_FAB2_LIB.BASEBOARD_FAB2(SCH_1):PAGE51
   147    GND @BASEBOARD_FAB2_LIB.BASEBOARD_FAB2(SCH_1):GND    I43 @BASEBOARD_FAB2_LIB.BASEBOARD_FAB2(SCH_1):PAGE51
   149    GND @BASEBOARD_FAB2_LIB.BASEBOARD_FAB2(SCH_1):GND    I43 @BASEBOARD_FAB2_LIB.BASEBOARD_FAB2(SCH_1):PAGE51
   151    GND @BASEBOARD_FAB2_LIB.BASEBOARD_FAB2(SCH_1):GND    I43 @BASEBOARD_FAB2_LIB.BASEBOARD_FAB2(SCH_1):PAGE51
   154    GND @BASEBOARD_FAB2_LIB.BASEBOARD_FAB2(SCH_1):GND    I43 @BASEBOARD_FAB2_LIB.BASEBOARD_FAB2(SCH_1):PAGE51
   156    GND @BASEBOARD_FAB2_LIB.BASEBOARD_FAB2(SCH_1):GND    I43 @BASEBOARD_FAB2_LIB.BASEBOARD_FAB2(SCH_1):PAGE51
   158    GND @BASEBOARD_FAB2_LIB.BASEBOARD_FAB2(SCH_1):GND    I43 @BASEBOARD_FAB2_LIB.BASEBOARD_FAB2(SCH_1):PAGE51
   160    GND @BASEBOARD_FAB2_LIB.BASEBOARD_FAB2(SCH_1):GND    I43 @BASEBOARD_FAB2_LIB.BASEBOARD_FAB2(SCH_1):PAGE51
   162    GND @BASEBOARD_FAB2_LIB.BASEBOARD_FAB2(SCH_1):GND    I43 @BASEBOARD_FAB2_LIB.BASEBOARD_FAB2(SCH_1):PAGE51
   165    GND @BASEBOARD_FAB2_LIB.BASEBOARD_FAB2(SCH_1):GND    I43 @BASEBOARD_FAB2_LIB.BASEBOARD_FAB2(SCH_1):PAGE51
   167    GND @BASEBOARD_FAB2_LIB.BASEBOARD_FAB2(SCH_1):GND    I43 @BASEBOARD_FAB2_LIB.BASEBOARD_FAB2(SCH_1):PAGE51
   169    GND @BASEBOARD_FAB2_LIB.BASEBOARD_FAB2(SCH_1):GND    I43 @BASEBOARD_FAB2_LIB.BASEBOARD_FAB2(SCH_1):PAGE51
   171    GND @BASEBOARD_FAB2_LIB.BASEBOARD_FAB2(SCH_1):GND    I43 @BASEBOARD_FAB2_LIB.BASEBOARD_FAB2(SCH_1):PAGE51
   173    GND @BASEBOARD_FAB2_LIB.BASEBOARD_FAB2(SCH_1):GND    I43 @BASEBOARD_FAB2_LIB.BASEBOARD_FAB2(SCH_1):PAGE51
   176    GND @BASEBOARD_FAB2_LIB.BASEBOARD_FAB2(SCH_1):GND    I43 @BASEBOARD_FAB2_LIB.BASEBOARD_FAB2(SCH_1):PAGE51
   178    GND @BASEBOARD_FAB2_LIB.BASEBOARD_FAB2(SCH_1):GND    I43 @BASEBOARD_FAB2_LIB.BASEBOARD_FAB2(SCH_1):PAGE51
   180    GND @BASEBOARD_FAB2_LIB.BASEBOARD_FAB2(SCH_1):GND    I43 @BASEBOARD_FAB2_LIB.BASEBOARD_FAB2(SCH_1):PAGE51
   182    GND @BASEBOARD_FAB2_LIB.BASEBOARD_FAB2(SCH_1):GND    I43 @BASEBOARD_FAB2_LIB.BASEBOARD_FAB2(SCH_1):PAGE51
   184    GND @BASEBOARD_FAB2_LIB.BASEBOARD_FAB2(SCH_1):GND    I43 @BASEBOARD_FAB2_LIB.BASEBOARD_FAB2(SCH_1):PAGE51
   187    GND @BASEBOARD_FAB2_LIB.BASEBOARD_FAB2(SCH_1):GND    I43 @BASEBOARD_FAB2_LIB.BASEBOARD_FAB2(SCH_1):PAGE51
   189    GND @BASEBOARD_FAB2_LIB.BASEBOARD_FAB2(SCH_1):GND    I43 @BASEBOARD_FAB2_LIB.BASEBOARD_FAB2(SCH_1):PAGE51
   191    GND @BASEBOARD_FAB2_LIB.BASEBOARD_FAB2(SCH_1):GND    I43 @BASEBOARD_FAB2_LIB.BASEBOARD_FAB2(SCH_1):PAGE51
   193    GND @BASEBOARD_FAB2_LIB.BASEBOARD_FAB2(SCH_1):GND    I43 @BASEBOARD_FAB2_LIB.BASEBOARD_FAB2(SCH_1):PAGE51
   195    GND @BASEBOARD_FAB2_LIB.BASEBOARD_FAB2(SCH_1):GND    I43 @BASEBOARD_FAB2_LIB.BASEBOARD_FAB2(SCH_1):PAGE51
   198    GND @BASEBOARD_FAB2_LIB.BASEBOARD_FAB2(SCH_1):GND    I43 @BASEBOARD_FAB2_LIB.BASEBOARD_FAB2(SCH_1):PAGE51
   200    GND @BASEBOARD_FAB2_LIB.BASEBOARD_FAB2(SCH_1):GND    I43 @BASEBOARD_FAB2_LIB.BASEBOARD_FAB2(SCH_1):PAGE51
   202    GND @BASEBOARD_FAB2_LIB.BASEBOARD_FAB2(SCH_1):GND    I43 @BASEBOARD_FAB2_LIB.BASEBOARD_FAB2(SCH_1):PAGE51
   239    GND @BASEBOARD_FAB2_LIB.BASEBOARD_FAB2(SCH_1):GND    I43 @BASEBOARD_FAB2_LIB.BASEBOARD_FAB2(SCH_1):PAGE51
   241    GND @BASEBOARD_FAB2_LIB.BASEBOARD_FAB2(SCH_1):GND    I43 @BASEBOARD_FAB2_LIB.BASEBOARD_FAB2(SCH_1):PAGE51
   243    GND @BASEBOARD_FAB2_LIB.BASEBOARD_FAB2(SCH_1):GND    I43 @BASEBOARD_FAB2_LIB.BASEBOARD_FAB2(SCH_1):PAGE51
   246    GND @BASEBOARD_FAB2_LIB.BASEBOARD_FAB2(SCH_1):GND    I43 @BASEBOARD_FAB2_LIB.BASEBOARD_FAB2(SCH_1):PAGE51
   248    GND @BASEBOARD_FAB2_LIB.BASEBOARD_FAB2(SCH_1):GND    I43 @BASEBOARD_FAB2_LIB.BASEBOARD_FAB2(SCH_1):PAGE51
   250    GND @BASEBOARD_FAB2_LIB.BASEBOARD_FAB2(SCH_1):GND    I43 @BASEBOARD_FAB2_LIB.BASEBOARD_FAB2(SCH_1):PAGE51
   252    GND @BASEBOARD_FAB2_LIB.BASEBOARD_FAB2(SCH_1):GND    I43 @BASEBOARD_FAB2_LIB.BASEBOARD_FAB2(SCH_1):PAGE51
   254    GND @BASEBOARD_FAB2_LIB.BASEBOARD_FAB2(SCH_1):GND    I43 @BASEBOARD_FAB2_LIB.BASEBOARD_FAB2(SCH_1):PAGE51
   257    GND @BASEBOARD_FAB2_LIB.BASEBOARD_FAB2(SCH_1):GND    I43 @BASEBOARD_FAB2_LIB.BASEBOARD_FAB2(SCH_1):PAGE51
   259    GND @BASEBOARD_FAB2_LIB.BASEBOARD_FAB2(SCH_1):GND    I43 @BASEBOARD_FAB2_LIB.BASEBOARD_FAB2(SCH_1):PAGE51
   261    GND @BASEBOARD_FAB2_LIB.BASEBOARD_FAB2(SCH_1):GND    I43 @BASEBOARD_FAB2_LIB.BASEBOARD_FAB2(SCH_1):PAGE51
   263    GND @BASEBOARD_FAB2_LIB.BASEBOARD_FAB2(SCH_1):GND    I43 @BASEBOARD_FAB2_LIB.BASEBOARD_FAB2(SCH_1):PAGE51
   265    GND @BASEBOARD_FAB2_LIB.BASEBOARD_FAB2(SCH_1):GND    I43 @BASEBOARD_FAB2_LIB.BASEBOARD_FAB2(SCH_1):PAGE51
   268    GND @BASEBOARD_FAB2_LIB.BASEBOARD_FAB2(SCH_1):GND    I43 @BASEBOARD_FAB2_LIB.BASEBOARD_FAB2(SCH_1):PAGE51
   270    GND @BASEBOARD_FAB2_LIB.BASEBOARD_FAB2(SCH_1):GND    I43 @BASEBOARD_FAB2_LIB.BASEBOARD_FAB2(SCH_1):PAGE51
   272    GND @BASEBOARD_FAB2_LIB.BASEBOARD_FAB2(SCH_1):GND    I43 @BASEBOARD_FAB2_LIB.BASEBOARD_FAB2(SCH_1):PAGE51
   274    GND @BASEBOARD_FAB2_LIB.BASEBOARD_FAB2(SCH_1):GND    I43 @BASEBOARD_FAB2_LIB.BASEBOARD_FAB2(SCH_1):PAGE51
   276    GND @BASEBOARD_FAB2_LIB.BASEBOARD_FAB2(SCH_1):GND    I43 @BASEBOARD_FAB2_LIB.BASEBOARD_FAB2(SCH_1):PAGE51
   279    GND @BASEBOARD_FAB2_LIB.BASEBOARD_FAB2(SCH_1):GND    I43 @BASEBOARD_FAB2_LIB.BASEBOARD_FAB2(SCH_1):PAGE51
   281    GND @BASEBOARD_FAB2_LIB.BASEBOARD_FAB2(SCH_1):GND    I43 @BASEBOARD_FAB2_LIB.BASEBOARD_FAB2(SCH_1):PAGE51
   283    GND @BASEBOARD_FAB2_LIB.BASEBOARD_FAB2(SCH_1):GND    I43 @BASEBOARD_FAB2_LIB.BASEBOARD_FAB2(SCH_1):PAGE51
     1 P12V_NVDIMM_DEF @BASEBOARD_FAB2_LIB.BASEBOARD_FAB2(SCH_1):P12V_NVDIMM_DEF   I167 @BASEBOARD_FAB2_LIB.BASEBOARD_FAB2(SCH_1):PAGE51
   145 P12V_NVDIMM_DEF @BASEBOARD_FAB2_LIB.BASEBOARD_FAB2(SCH_1):P12V_NVDIMM_DEF   I167 @BASEBOARD_FAB2_LIB.BASEBOARD_FAB2(SCH_1):PAGE51
    59 PVDDQ_DEF @BASEBOARD_FAB2_LIB.BASEBOARD_FAB2(SCH_1):PVDDQ_DEF   I167 @BASEBOARD_FAB2_LIB.BASEBOARD_FAB2(SCH_1):PAGE51
    61 PVDDQ_DEF @BASEBOARD_FAB2_LIB.BASEBOARD_FAB2(SCH_1):PVDDQ_DEF   I167 @BASEBOARD_FAB2_LIB.BASEBOARD_FAB2(SCH_1):PAGE51
    64 PVDDQ_DEF @BASEBOARD_FAB2_LIB.BASEBOARD_FAB2(SCH_1):PVDDQ_DEF   I167 @BASEBOARD_FAB2_LIB.BASEBOARD_FAB2(SCH_1):PAGE51
    67 PVDDQ_DEF @BASEBOARD_FAB2_LIB.BASEBOARD_FAB2(SCH_1):PVDDQ_DEF   I167 @BASEBOARD_FAB2_LIB.BASEBOARD_FAB2(SCH_1):PAGE51
    70 PVDDQ_DEF @BASEBOARD_FAB2_LIB.BASEBOARD_FAB2(SCH_1):PVDDQ_DEF   I167 @BASEBOARD_FAB2_LIB.BASEBOARD_FAB2(SCH_1):PAGE51
    73 PVDDQ_DEF @BASEBOARD_FAB2_LIB.BASEBOARD_FAB2(SCH_1):PVDDQ_DEF   I167 @BASEBOARD_FAB2_LIB.BASEBOARD_FAB2(SCH_1):PAGE51
    76 PVDDQ_DEF @BASEBOARD_FAB2_LIB.BASEBOARD_FAB2(SCH_1):PVDDQ_DEF   I167 @BASEBOARD_FAB2_LIB.BASEBOARD_FAB2(SCH_1):PAGE51
    80 PVDDQ_DEF @BASEBOARD_FAB2_LIB.BASEBOARD_FAB2(SCH_1):PVDDQ_DEF   I167 @BASEBOARD_FAB2_LIB.BASEBOARD_FAB2(SCH_1):PAGE51
    83 PVDDQ_DEF @BASEBOARD_FAB2_LIB.BASEBOARD_FAB2(SCH_1):PVDDQ_DEF   I167 @BASEBOARD_FAB2_LIB.BASEBOARD_FAB2(SCH_1):PAGE51
    85 PVDDQ_DEF @BASEBOARD_FAB2_LIB.BASEBOARD_FAB2(SCH_1):PVDDQ_DEF   I167 @BASEBOARD_FAB2_LIB.BASEBOARD_FAB2(SCH_1):PAGE51
    88 PVDDQ_DEF @BASEBOARD_FAB2_LIB.BASEBOARD_FAB2(SCH_1):PVDDQ_DEF   I167 @BASEBOARD_FAB2_LIB.BASEBOARD_FAB2(SCH_1):PAGE51
    90 PVDDQ_DEF @BASEBOARD_FAB2_LIB.BASEBOARD_FAB2(SCH_1):PVDDQ_DEF   I167 @BASEBOARD_FAB2_LIB.BASEBOARD_FAB2(SCH_1):PAGE51
    92 PVDDQ_DEF @BASEBOARD_FAB2_LIB.BASEBOARD_FAB2(SCH_1):PVDDQ_DEF   I167 @BASEBOARD_FAB2_LIB.BASEBOARD_FAB2(SCH_1):PAGE51
   204 PVDDQ_DEF @BASEBOARD_FAB2_LIB.BASEBOARD_FAB2(SCH_1):PVDDQ_DEF   I167 @BASEBOARD_FAB2_LIB.BASEBOARD_FAB2(SCH_1):PAGE51
   206 PVDDQ_DEF @BASEBOARD_FAB2_LIB.BASEBOARD_FAB2(SCH_1):PVDDQ_DEF   I167 @BASEBOARD_FAB2_LIB.BASEBOARD_FAB2(SCH_1):PAGE51
   209 PVDDQ_DEF @BASEBOARD_FAB2_LIB.BASEBOARD_FAB2(SCH_1):PVDDQ_DEF   I167 @BASEBOARD_FAB2_LIB.BASEBOARD_FAB2(SCH_1):PAGE51
   212 PVDDQ_DEF @BASEBOARD_FAB2_LIB.BASEBOARD_FAB2(SCH_1):PVDDQ_DEF   I167 @BASEBOARD_FAB2_LIB.BASEBOARD_FAB2(SCH_1):PAGE51
   215 PVDDQ_DEF @BASEBOARD_FAB2_LIB.BASEBOARD_FAB2(SCH_1):PVDDQ_DEF   I167 @BASEBOARD_FAB2_LIB.BASEBOARD_FAB2(SCH_1):PAGE51
   217 PVDDQ_DEF @BASEBOARD_FAB2_LIB.BASEBOARD_FAB2(SCH_1):PVDDQ_DEF   I167 @BASEBOARD_FAB2_LIB.BASEBOARD_FAB2(SCH_1):PAGE51
   220 PVDDQ_DEF @BASEBOARD_FAB2_LIB.BASEBOARD_FAB2(SCH_1):PVDDQ_DEF   I167 @BASEBOARD_FAB2_LIB.BASEBOARD_FAB2(SCH_1):PAGE51
   223 PVDDQ_DEF @BASEBOARD_FAB2_LIB.BASEBOARD_FAB2(SCH_1):PVDDQ_DEF   I167 @BASEBOARD_FAB2_LIB.BASEBOARD_FAB2(SCH_1):PAGE51
   226 PVDDQ_DEF @BASEBOARD_FAB2_LIB.BASEBOARD_FAB2(SCH_1):PVDDQ_DEF   I167 @BASEBOARD_FAB2_LIB.BASEBOARD_FAB2(SCH_1):PAGE51
   229 PVDDQ_DEF @BASEBOARD_FAB2_LIB.BASEBOARD_FAB2(SCH_1):PVDDQ_DEF   I167 @BASEBOARD_FAB2_LIB.BASEBOARD_FAB2(SCH_1):PAGE51
   231 PVDDQ_DEF @BASEBOARD_FAB2_LIB.BASEBOARD_FAB2(SCH_1):PVDDQ_DEF   I167 @BASEBOARD_FAB2_LIB.BASEBOARD_FAB2(SCH_1):PAGE51
   233 PVDDQ_DEF @BASEBOARD_FAB2_LIB.BASEBOARD_FAB2(SCH_1):PVDDQ_DEF   I167 @BASEBOARD_FAB2_LIB.BASEBOARD_FAB2(SCH_1):PAGE51
   236 PVDDQ_DEF @BASEBOARD_FAB2_LIB.BASEBOARD_FAB2(SCH_1):PVDDQ_DEF   I167 @BASEBOARD_FAB2_LIB.BASEBOARD_FAB2(SCH_1):PAGE51
   142 PVPP_DEF @BASEBOARD_FAB2_LIB.BASEBOARD_FAB2(SCH_1):PVPP_DEF   I167 @BASEBOARD_FAB2_LIB.BASEBOARD_FAB2(SCH_1):PAGE51
   143 PVPP_DEF @BASEBOARD_FAB2_LIB.BASEBOARD_FAB2(SCH_1):PVPP_DEF   I167 @BASEBOARD_FAB2_LIB.BASEBOARD_FAB2(SCH_1):PAGE51
   288 PVPP_DEF @BASEBOARD_FAB2_LIB.BASEBOARD_FAB2(SCH_1):PVPP_DEF   I167 @BASEBOARD_FAB2_LIB.BASEBOARD_FAB2(SCH_1):PAGE51
   286 PVPP_DEF @BASEBOARD_FAB2_LIB.BASEBOARD_FAB2(SCH_1):PVPP_DEF   I167 @BASEBOARD_FAB2_LIB.BASEBOARD_FAB2(SCH_1):PAGE51
   287 PVPP_DEF @BASEBOARD_FAB2_LIB.BASEBOARD_FAB2(SCH_1):PVPP_DEF   I167 @BASEBOARD_FAB2_LIB.BASEBOARD_FAB2(SCH_1):PAGE51
    77 PVTT_DEF @BASEBOARD_FAB2_LIB.BASEBOARD_FAB2(SCH_1):PVTT_DEF   I167 @BASEBOARD_FAB2_LIB.BASEBOARD_FAB2(SCH_1):PAGE51
   221 PVTT_DEF @BASEBOARD_FAB2_LIB.BASEBOARD_FAB2(SCH_1):PVTT_DEF   I167 @BASEBOARD_FAB2_LIB.BASEBOARD_FAB2(SCH_1):PAGE51

J4B1 SCONN288_H44441004_PIP-SCONN,HA
    79 M_D_MA<0> @BASEBOARD_FAB2_LIB.BASEBOARD_FAB2(SCH_1):M_D_MA(0)   I111 @BASEBOARD_FAB2_LIB.BASEBOARD_FAB2(SCH_1):PAGE49
    72 M_D_MA<1> @BASEBOARD_FAB2_LIB.BASEBOARD_FAB2(SCH_1):M_D_MA(1)   I111 @BASEBOARD_FAB2_LIB.BASEBOARD_FAB2(SCH_1):PAGE49
   225 M_D_MA<10> @BASEBOARD_FAB2_LIB.BASEBOARD_FAB2(SCH_1):M_D_MA(10)   I111 @BASEBOARD_FAB2_LIB.BASEBOARD_FAB2(SCH_1):PAGE49
   210 M_D_MA<11> @BASEBOARD_FAB2_LIB.BASEBOARD_FAB2(SCH_1):M_D_MA(11)   I111 @BASEBOARD_FAB2_LIB.BASEBOARD_FAB2(SCH_1):PAGE49
    65 M_D_MA<12> @BASEBOARD_FAB2_LIB.BASEBOARD_FAB2(SCH_1):M_D_MA(12)   I111 @BASEBOARD_FAB2_LIB.BASEBOARD_FAB2(SCH_1):PAGE49
   232 M_D_MA<13> @BASEBOARD_FAB2_LIB.BASEBOARD_FAB2(SCH_1):M_D_MA(13)   I111 @BASEBOARD_FAB2_LIB.BASEBOARD_FAB2(SCH_1):PAGE49
   228 M_D_MA<14> @BASEBOARD_FAB2_LIB.BASEBOARD_FAB2(SCH_1):M_D_MA(14)   I111 @BASEBOARD_FAB2_LIB.BASEBOARD_FAB2(SCH_1):PAGE49
    86 M_D_MA<15> @BASEBOARD_FAB2_LIB.BASEBOARD_FAB2(SCH_1):M_D_MA(15)   I111 @BASEBOARD_FAB2_LIB.BASEBOARD_FAB2(SCH_1):PAGE49
    82 M_D_MA<16> @BASEBOARD_FAB2_LIB.BASEBOARD_FAB2(SCH_1):M_D_MA(16)   I111 @BASEBOARD_FAB2_LIB.BASEBOARD_FAB2(SCH_1):PAGE49
   234 M_D_MA<17> @BASEBOARD_FAB2_LIB.BASEBOARD_FAB2(SCH_1):M_D_MA(17)   I111 @BASEBOARD_FAB2_LIB.BASEBOARD_FAB2(SCH_1):PAGE49
   216 M_D_MA<2> @BASEBOARD_FAB2_LIB.BASEBOARD_FAB2(SCH_1):M_D_MA(2)   I111 @BASEBOARD_FAB2_LIB.BASEBOARD_FAB2(SCH_1):PAGE49
    71 M_D_MA<3> @BASEBOARD_FAB2_LIB.BASEBOARD_FAB2(SCH_1):M_D_MA(3)   I111 @BASEBOARD_FAB2_LIB.BASEBOARD_FAB2(SCH_1):PAGE49
   214 M_D_MA<4> @BASEBOARD_FAB2_LIB.BASEBOARD_FAB2(SCH_1):M_D_MA(4)   I111 @BASEBOARD_FAB2_LIB.BASEBOARD_FAB2(SCH_1):PAGE49
   213 M_D_MA<5> @BASEBOARD_FAB2_LIB.BASEBOARD_FAB2(SCH_1):M_D_MA(5)   I111 @BASEBOARD_FAB2_LIB.BASEBOARD_FAB2(SCH_1):PAGE49
    69 M_D_MA<6> @BASEBOARD_FAB2_LIB.BASEBOARD_FAB2(SCH_1):M_D_MA(6)   I111 @BASEBOARD_FAB2_LIB.BASEBOARD_FAB2(SCH_1):PAGE49
   211 M_D_MA<7> @BASEBOARD_FAB2_LIB.BASEBOARD_FAB2(SCH_1):M_D_MA(7)   I111 @BASEBOARD_FAB2_LIB.BASEBOARD_FAB2(SCH_1):PAGE49
    68 M_D_MA<8> @BASEBOARD_FAB2_LIB.BASEBOARD_FAB2(SCH_1):M_D_MA(8)   I111 @BASEBOARD_FAB2_LIB.BASEBOARD_FAB2(SCH_1):PAGE49
    66 M_D_MA<9> @BASEBOARD_FAB2_LIB.BASEBOARD_FAB2(SCH_1):M_D_MA(9)   I111 @BASEBOARD_FAB2_LIB.BASEBOARD_FAB2(SCH_1):PAGE49
    62 M_D_ACT_N @BASEBOARD_FAB2_LIB.BASEBOARD_FAB2(SCH_1):M_D_ACT_N   I111 @BASEBOARD_FAB2_LIB.BASEBOARD_FAB2(SCH_1):PAGE49
   208 M_D_ALERT_N @BASEBOARD_FAB2_LIB.BASEBOARD_FAB2(SCH_1):M_D_ALERT_N   I111 @BASEBOARD_FAB2_LIB.BASEBOARD_FAB2(SCH_1):PAGE49
   224 M_D_BA<1> @BASEBOARD_FAB2_LIB.BASEBOARD_FAB2(SCH_1):M_D_BA(1)   I111 @BASEBOARD_FAB2_LIB.BASEBOARD_FAB2(SCH_1):PAGE49
    81 M_D_BA<0> @BASEBOARD_FAB2_LIB.BASEBOARD_FAB2(SCH_1):M_D_BA(0)   I111 @BASEBOARD_FAB2_LIB.BASEBOARD_FAB2(SCH_1):PAGE49
   207 M_D_BG<1> @BASEBOARD_FAB2_LIB.BASEBOARD_FAB2(SCH_1):M_D_BG(1)   I111 @BASEBOARD_FAB2_LIB.BASEBOARD_FAB2(SCH_1):PAGE49
    63 M_D_BG<0> @BASEBOARD_FAB2_LIB.BASEBOARD_FAB2(SCH_1):M_D_BG(0)   I111 @BASEBOARD_FAB2_LIB.BASEBOARD_FAB2(SCH_1):PAGE49
   235 M_D_C<2> @BASEBOARD_FAB2_LIB.BASEBOARD_FAB2(SCH_1):M_D_C(2)   I111 @BASEBOARD_FAB2_LIB.BASEBOARD_FAB2(SCH_1):PAGE49
   199 M_D_ECC<6> @BASEBOARD_FAB2_LIB.BASEBOARD_FAB2(SCH_1):M_D_ECC(6)   I111 @BASEBOARD_FAB2_LIB.BASEBOARD_FAB2(SCH_1):PAGE49
    54 M_D_ECC<7> @BASEBOARD_FAB2_LIB.BASEBOARD_FAB2(SCH_1):M_D_ECC(7)   I111 @BASEBOARD_FAB2_LIB.BASEBOARD_FAB2(SCH_1):PAGE49
   192 M_D_ECC<4> @BASEBOARD_FAB2_LIB.BASEBOARD_FAB2(SCH_1):M_D_ECC(4)   I111 @BASEBOARD_FAB2_LIB.BASEBOARD_FAB2(SCH_1):PAGE49
    47 M_D_ECC<5> @BASEBOARD_FAB2_LIB.BASEBOARD_FAB2(SCH_1):M_D_ECC(5)   I111 @BASEBOARD_FAB2_LIB.BASEBOARD_FAB2(SCH_1):PAGE49
   201 M_D_ECC<2> @BASEBOARD_FAB2_LIB.BASEBOARD_FAB2(SCH_1):M_D_ECC(2)   I111 @BASEBOARD_FAB2_LIB.BASEBOARD_FAB2(SCH_1):PAGE49
    56 M_D_ECC<3> @BASEBOARD_FAB2_LIB.BASEBOARD_FAB2(SCH_1):M_D_ECC(3)   I111 @BASEBOARD_FAB2_LIB.BASEBOARD_FAB2(SCH_1):PAGE49
   194 M_D_ECC<0> @BASEBOARD_FAB2_LIB.BASEBOARD_FAB2(SCH_1):M_D_ECC(0)   I111 @BASEBOARD_FAB2_LIB.BASEBOARD_FAB2(SCH_1):PAGE49
    49 M_D_ECC<1> @BASEBOARD_FAB2_LIB.BASEBOARD_FAB2(SCH_1):M_D_ECC(1)   I111 @BASEBOARD_FAB2_LIB.BASEBOARD_FAB2(SCH_1):PAGE49
    75 M_D_CLK_DN<0> @BASEBOARD_FAB2_LIB.BASEBOARD_FAB2(SCH_1):M_D_CLK_DN(0)   I111 @BASEBOARD_FAB2_LIB.BASEBOARD_FAB2(SCH_1):PAGE49
    74 M_D_CLK_DP<0> @BASEBOARD_FAB2_LIB.BASEBOARD_FAB2(SCH_1):M_D_CLK_DP(0)   I111 @BASEBOARD_FAB2_LIB.BASEBOARD_FAB2(SCH_1):PAGE49
   219 M_D_CLK_DN<1> @BASEBOARD_FAB2_LIB.BASEBOARD_FAB2(SCH_1):M_D_CLK_DN(1)   I111 @BASEBOARD_FAB2_LIB.BASEBOARD_FAB2(SCH_1):PAGE49
   218 M_D_CLK_DP<1> @BASEBOARD_FAB2_LIB.BASEBOARD_FAB2(SCH_1):M_D_CLK_DP(1)   I111 @BASEBOARD_FAB2_LIB.BASEBOARD_FAB2(SCH_1):PAGE49
   203 M_D_CKE<1> @BASEBOARD_FAB2_LIB.BASEBOARD_FAB2(SCH_1):M_D_CKE(1)   I111 @BASEBOARD_FAB2_LIB.BASEBOARD_FAB2(SCH_1):PAGE49
    60 M_D_CKE<0> @BASEBOARD_FAB2_LIB.BASEBOARD_FAB2(SCH_1):M_D_CKE(0)   I111 @BASEBOARD_FAB2_LIB.BASEBOARD_FAB2(SCH_1):PAGE49
   280 M_D_DQ<62> @BASEBOARD_FAB2_LIB.BASEBOARD_FAB2(SCH_1):M_D_DQ(62)   I111 @BASEBOARD_FAB2_LIB.BASEBOARD_FAB2(SCH_1):PAGE49
   135 M_D_DQ<63> @BASEBOARD_FAB2_LIB.BASEBOARD_FAB2(SCH_1):M_D_DQ(63)   I111 @BASEBOARD_FAB2_LIB.BASEBOARD_FAB2(SCH_1):PAGE49
   273 M_D_DQ<60> @BASEBOARD_FAB2_LIB.BASEBOARD_FAB2(SCH_1):M_D_DQ(60)   I111 @BASEBOARD_FAB2_LIB.BASEBOARD_FAB2(SCH_1):PAGE49
   128 M_D_DQ<61> @BASEBOARD_FAB2_LIB.BASEBOARD_FAB2(SCH_1):M_D_DQ(61)   I111 @BASEBOARD_FAB2_LIB.BASEBOARD_FAB2(SCH_1):PAGE49
   282 M_D_DQ<58> @BASEBOARD_FAB2_LIB.BASEBOARD_FAB2(SCH_1):M_D_DQ(58)   I111 @BASEBOARD_FAB2_LIB.BASEBOARD_FAB2(SCH_1):PAGE49
   137 M_D_DQ<59> @BASEBOARD_FAB2_LIB.BASEBOARD_FAB2(SCH_1):M_D_DQ(59)   I111 @BASEBOARD_FAB2_LIB.BASEBOARD_FAB2(SCH_1):PAGE49
   275 M_D_DQ<56> @BASEBOARD_FAB2_LIB.BASEBOARD_FAB2(SCH_1):M_D_DQ(56)   I111 @BASEBOARD_FAB2_LIB.BASEBOARD_FAB2(SCH_1):PAGE49
   130 M_D_DQ<57> @BASEBOARD_FAB2_LIB.BASEBOARD_FAB2(SCH_1):M_D_DQ(57)   I111 @BASEBOARD_FAB2_LIB.BASEBOARD_FAB2(SCH_1):PAGE49
   269 M_D_DQ<54> @BASEBOARD_FAB2_LIB.BASEBOARD_FAB2(SCH_1):M_D_DQ(54)   I111 @BASEBOARD_FAB2_LIB.BASEBOARD_FAB2(SCH_1):PAGE49
   124 M_D_DQ<55> @BASEBOARD_FAB2_LIB.BASEBOARD_FAB2(SCH_1):M_D_DQ(55)   I111 @BASEBOARD_FAB2_LIB.BASEBOARD_FAB2(SCH_1):PAGE49
   262 M_D_DQ<52> @BASEBOARD_FAB2_LIB.BASEBOARD_FAB2(SCH_1):M_D_DQ(52)   I111 @BASEBOARD_FAB2_LIB.BASEBOARD_FAB2(SCH_1):PAGE49
   117 M_D_DQ<53> @BASEBOARD_FAB2_LIB.BASEBOARD_FAB2(SCH_1):M_D_DQ(53)   I111 @BASEBOARD_FAB2_LIB.BASEBOARD_FAB2(SCH_1):PAGE49
   271 M_D_DQ<50> @BASEBOARD_FAB2_LIB.BASEBOARD_FAB2(SCH_1):M_D_DQ(50)   I111 @BASEBOARD_FAB2_LIB.BASEBOARD_FAB2(SCH_1):PAGE49
   126 M_D_DQ<51> @BASEBOARD_FAB2_LIB.BASEBOARD_FAB2(SCH_1):M_D_DQ(51)   I111 @BASEBOARD_FAB2_LIB.BASEBOARD_FAB2(SCH_1):PAGE49
   264 M_D_DQ<48> @BASEBOARD_FAB2_LIB.BASEBOARD_FAB2(SCH_1):M_D_DQ(48)   I111 @BASEBOARD_FAB2_LIB.BASEBOARD_FAB2(SCH_1):PAGE49
   119 M_D_DQ<49> @BASEBOARD_FAB2_LIB.BASEBOARD_FAB2(SCH_1):M_D_DQ(49)   I111 @BASEBOARD_FAB2_LIB.BASEBOARD_FAB2(SCH_1):PAGE49
   258 M_D_DQ<46> @BASEBOARD_FAB2_LIB.BASEBOARD_FAB2(SCH_1):M_D_DQ(46)   I111 @BASEBOARD_FAB2_LIB.BASEBOARD_FAB2(SCH_1):PAGE49
   113 M_D_DQ<47> @BASEBOARD_FAB2_LIB.BASEBOARD_FAB2(SCH_1):M_D_DQ(47)   I111 @BASEBOARD_FAB2_LIB.BASEBOARD_FAB2(SCH_1):PAGE49
   251 M_D_DQ<44> @BASEBOARD_FAB2_LIB.BASEBOARD_FAB2(SCH_1):M_D_DQ(44)   I111 @BASEBOARD_FAB2_LIB.BASEBOARD_FAB2(SCH_1):PAGE49
   106 M_D_DQ<45> @BASEBOARD_FAB2_LIB.BASEBOARD_FAB2(SCH_1):M_D_DQ(45)   I111 @BASEBOARD_FAB2_LIB.BASEBOARD_FAB2(SCH_1):PAGE49
   260 M_D_DQ<42> @BASEBOARD_FAB2_LIB.BASEBOARD_FAB2(SCH_1):M_D_DQ(42)   I111 @BASEBOARD_FAB2_LIB.BASEBOARD_FAB2(SCH_1):PAGE49
   115 M_D_DQ<43> @BASEBOARD_FAB2_LIB.BASEBOARD_FAB2(SCH_1):M_D_DQ(43)   I111 @BASEBOARD_FAB2_LIB.BASEBOARD_FAB2(SCH_1):PAGE49
   253 M_D_DQ<40> @BASEBOARD_FAB2_LIB.BASEBOARD_FAB2(SCH_1):M_D_DQ(40)   I111 @BASEBOARD_FAB2_LIB.BASEBOARD_FAB2(SCH_1):PAGE49
   108 M_D_DQ<41> @BASEBOARD_FAB2_LIB.BASEBOARD_FAB2(SCH_1):M_D_DQ(41)   I111 @BASEBOARD_FAB2_LIB.BASEBOARD_FAB2(SCH_1):PAGE49
   247 M_D_DQ<38> @BASEBOARD_FAB2_LIB.BASEBOARD_FAB2(SCH_1):M_D_DQ(38)   I111 @BASEBOARD_FAB2_LIB.BASEBOARD_FAB2(SCH_1):PAGE49
   102 M_D_DQ<39> @BASEBOARD_FAB2_LIB.BASEBOARD_FAB2(SCH_1):M_D_DQ(39)   I111 @BASEBOARD_FAB2_LIB.BASEBOARD_FAB2(SCH_1):PAGE49
   240 M_D_DQ<36> @BASEBOARD_FAB2_LIB.BASEBOARD_FAB2(SCH_1):M_D_DQ(36)   I111 @BASEBOARD_FAB2_LIB.BASEBOARD_FAB2(SCH_1):PAGE49
    95 M_D_DQ<37> @BASEBOARD_FAB2_LIB.BASEBOARD_FAB2(SCH_1):M_D_DQ(37)   I111 @BASEBOARD_FAB2_LIB.BASEBOARD_FAB2(SCH_1):PAGE49
   249 M_D_DQ<34> @BASEBOARD_FAB2_LIB.BASEBOARD_FAB2(SCH_1):M_D_DQ(34)   I111 @BASEBOARD_FAB2_LIB.BASEBOARD_FAB2(SCH_1):PAGE49
   104 M_D_DQ<35> @BASEBOARD_FAB2_LIB.BASEBOARD_FAB2(SCH_1):M_D_DQ(35)   I111 @BASEBOARD_FAB2_LIB.BASEBOARD_FAB2(SCH_1):PAGE49
   242 M_D_DQ<32> @BASEBOARD_FAB2_LIB.BASEBOARD_FAB2(SCH_1):M_D_DQ(32)   I111 @BASEBOARD_FAB2_LIB.BASEBOARD_FAB2(SCH_1):PAGE49
    97 M_D_DQ<33> @BASEBOARD_FAB2_LIB.BASEBOARD_FAB2(SCH_1):M_D_DQ(33)   I111 @BASEBOARD_FAB2_LIB.BASEBOARD_FAB2(SCH_1):PAGE49
   188 M_D_DQ<30> @BASEBOARD_FAB2_LIB.BASEBOARD_FAB2(SCH_1):M_D_DQ(30)   I111 @BASEBOARD_FAB2_LIB.BASEBOARD_FAB2(SCH_1):PAGE49
    43 M_D_DQ<31> @BASEBOARD_FAB2_LIB.BASEBOARD_FAB2(SCH_1):M_D_DQ(31)   I111 @BASEBOARD_FAB2_LIB.BASEBOARD_FAB2(SCH_1):PAGE49
   181 M_D_DQ<28> @BASEBOARD_FAB2_LIB.BASEBOARD_FAB2(SCH_1):M_D_DQ(28)   I111 @BASEBOARD_FAB2_LIB.BASEBOARD_FAB2(SCH_1):PAGE49
    36 M_D_DQ<29> @BASEBOARD_FAB2_LIB.BASEBOARD_FAB2(SCH_1):M_D_DQ(29)   I111 @BASEBOARD_FAB2_LIB.BASEBOARD_FAB2(SCH_1):PAGE49
   190 M_D_DQ<26> @BASEBOARD_FAB2_LIB.BASEBOARD_FAB2(SCH_1):M_D_DQ(26)   I111 @BASEBOARD_FAB2_LIB.BASEBOARD_FAB2(SCH_1):PAGE49
    45 M_D_DQ<27> @BASEBOARD_FAB2_LIB.BASEBOARD_FAB2(SCH_1):M_D_DQ(27)   I111 @BASEBOARD_FAB2_LIB.BASEBOARD_FAB2(SCH_1):PAGE49
   183 M_D_DQ<24> @BASEBOARD_FAB2_LIB.BASEBOARD_FAB2(SCH_1):M_D_DQ(24)   I111 @BASEBOARD_FAB2_LIB.BASEBOARD_FAB2(SCH_1):PAGE49
    38 M_D_DQ<25> @BASEBOARD_FAB2_LIB.BASEBOARD_FAB2(SCH_1):M_D_DQ(25)   I111 @BASEBOARD_FAB2_LIB.BASEBOARD_FAB2(SCH_1):PAGE49
   177 M_D_DQ<22> @BASEBOARD_FAB2_LIB.BASEBOARD_FAB2(SCH_1):M_D_DQ(22)   I111 @BASEBOARD_FAB2_LIB.BASEBOARD_FAB2(SCH_1):PAGE49
    32 M_D_DQ<23> @BASEBOARD_FAB2_LIB.BASEBOARD_FAB2(SCH_1):M_D_DQ(23)   I111 @BASEBOARD_FAB2_LIB.BASEBOARD_FAB2(SCH_1):PAGE49
   170 M_D_DQ<20> @BASEBOARD_FAB2_LIB.BASEBOARD_FAB2(SCH_1):M_D_DQ(20)   I111 @BASEBOARD_FAB2_LIB.BASEBOARD_FAB2(SCH_1):PAGE49
    25 M_D_DQ<21> @BASEBOARD_FAB2_LIB.BASEBOARD_FAB2(SCH_1):M_D_DQ(21)   I111 @BASEBOARD_FAB2_LIB.BASEBOARD_FAB2(SCH_1):PAGE49
   179 M_D_DQ<18> @BASEBOARD_FAB2_LIB.BASEBOARD_FAB2(SCH_1):M_D_DQ(18)   I111 @BASEBOARD_FAB2_LIB.BASEBOARD_FAB2(SCH_1):PAGE49
    34 M_D_DQ<19> @BASEBOARD_FAB2_LIB.BASEBOARD_FAB2(SCH_1):M_D_DQ(19)   I111 @BASEBOARD_FAB2_LIB.BASEBOARD_FAB2(SCH_1):PAGE49
   172 M_D_DQ<16> @BASEBOARD_FAB2_LIB.BASEBOARD_FAB2(SCH_1):M_D_DQ(16)   I111 @BASEBOARD_FAB2_LIB.BASEBOARD_FAB2(SCH_1):PAGE49
    27 M_D_DQ<17> @BASEBOARD_FAB2_LIB.BASEBOARD_FAB2(SCH_1):M_D_DQ(17)   I111 @BASEBOARD_FAB2_LIB.BASEBOARD_FAB2(SCH_1):PAGE49
   166 M_D_DQ<14> @BASEBOARD_FAB2_LIB.BASEBOARD_FAB2(SCH_1):M_D_DQ(14)   I111 @BASEBOARD_FAB2_LIB.BASEBOARD_FAB2(SCH_1):PAGE49
    21 M_D_DQ<15> @BASEBOARD_FAB2_LIB.BASEBOARD_FAB2(SCH_1):M_D_DQ(15)   I111 @BASEBOARD_FAB2_LIB.BASEBOARD_FAB2(SCH_1):PAGE49
   159 M_D_DQ<12> @BASEBOARD_FAB2_LIB.BASEBOARD_FAB2(SCH_1):M_D_DQ(12)   I111 @BASEBOARD_FAB2_LIB.BASEBOARD_FAB2(SCH_1):PAGE49
    14 M_D_DQ<13> @BASEBOARD_FAB2_LIB.BASEBOARD_FAB2(SCH_1):M_D_DQ(13)   I111 @BASEBOARD_FAB2_LIB.BASEBOARD_FAB2(SCH_1):PAGE49
   168 M_D_DQ<10> @BASEBOARD_FAB2_LIB.BASEBOARD_FAB2(SCH_1):M_D_DQ(10)   I111 @BASEBOARD_FAB2_LIB.BASEBOARD_FAB2(SCH_1):PAGE49
    23 M_D_DQ<11> @BASEBOARD_FAB2_LIB.BASEBOARD_FAB2(SCH_1):M_D_DQ(11)   I111 @BASEBOARD_FAB2_LIB.BASEBOARD_FAB2(SCH_1):PAGE49
   161 M_D_DQ<8> @BASEBOARD_FAB2_LIB.BASEBOARD_FAB2(SCH_1):M_D_DQ(8)   I111 @BASEBOARD_FAB2_LIB.BASEBOARD_FAB2(SCH_1):PAGE49
    16 M_D_DQ<9> @BASEBOARD_FAB2_LIB.BASEBOARD_FAB2(SCH_1):M_D_DQ(9)   I111 @BASEBOARD_FAB2_LIB.BASEBOARD_FAB2(SCH_1):PAGE49
   155 M_D_DQ<6> @BASEBOARD_FAB2_LIB.BASEBOARD_FAB2(SCH_1):M_D_DQ(6)   I111 @BASEBOARD_FAB2_LIB.BASEBOARD_FAB2(SCH_1):PAGE49
    10 M_D_DQ<7> @BASEBOARD_FAB2_LIB.BASEBOARD_FAB2(SCH_1):M_D_DQ(7)   I111 @BASEBOARD_FAB2_LIB.BASEBOARD_FAB2(SCH_1):PAGE49
   148 M_D_DQ<4> @BASEBOARD_FAB2_LIB.BASEBOARD_FAB2(SCH_1):M_D_DQ(4)   I111 @BASEBOARD_FAB2_LIB.BASEBOARD_FAB2(SCH_1):PAGE49
     3 M_D_DQ<5> @BASEBOARD_FAB2_LIB.BASEBOARD_FAB2(SCH_1):M_D_DQ(5)   I111 @BASEBOARD_FAB2_LIB.BASEBOARD_FAB2(SCH_1):PAGE49
   157 M_D_DQ<2> @BASEBOARD_FAB2_LIB.BASEBOARD_FAB2(SCH_1):M_D_DQ(2)   I111 @BASEBOARD_FAB2_LIB.BASEBOARD_FAB2(SCH_1):PAGE49
    12 M_D_DQ<3> @BASEBOARD_FAB2_LIB.BASEBOARD_FAB2(SCH_1):M_D_DQ(3)   I111 @BASEBOARD_FAB2_LIB.BASEBOARD_FAB2(SCH_1):PAGE49
   150 M_D_DQ<0> @BASEBOARD_FAB2_LIB.BASEBOARD_FAB2(SCH_1):M_D_DQ(0)   I111 @BASEBOARD_FAB2_LIB.BASEBOARD_FAB2(SCH_1):PAGE49
     5 M_D_DQ<1> @BASEBOARD_FAB2_LIB.BASEBOARD_FAB2(SCH_1):M_D_DQ(1)   I111 @BASEBOARD_FAB2_LIB.BASEBOARD_FAB2(SCH_1):PAGE49
    78 FM_DIMM_EVENT_COD_N @BASEBOARD_FAB2_LIB.BASEBOARD_FAB2(SCH_1):FM_DIMM_EVENT_COD_N   I111 @BASEBOARD_FAB2_LIB.BASEBOARD_FAB2(SCH_1):PAGE49
    91 M_D_ODT<1> @BASEBOARD_FAB2_LIB.BASEBOARD_FAB2(SCH_1):M_D_ODT(1)   I111 @BASEBOARD_FAB2_LIB.BASEBOARD_FAB2(SCH_1):PAGE49
    87 M_D_ODT<0> @BASEBOARD_FAB2_LIB.BASEBOARD_FAB2(SCH_1):M_D_ODT(0)   I111 @BASEBOARD_FAB2_LIB.BASEBOARD_FAB2(SCH_1):PAGE49
   222 M_D_PAR @BASEBOARD_FAB2_LIB.BASEBOARD_FAB2(SCH_1):M_D_PAR   I111 @BASEBOARD_FAB2_LIB.BASEBOARD_FAB2(SCH_1):PAGE49
    58 M_DEF_RST_N @BASEBOARD_FAB2_LIB.BASEBOARD_FAB2(SCH_1):M_DEF_RST_N   I111 @BASEBOARD_FAB2_LIB.BASEBOARD_FAB2(SCH_1):PAGE49
   144 TP_CH_D_DIMM_D0_RFU_2 @BASEBOARD_FAB2_LIB.BASEBOARD_FAB2(SCH_1):TP_CH_D_DIMM_D0_RFU_2   I111 @BASEBOARD_FAB2_LIB.BASEBOARD_FAB2(SCH_1):PAGE49
   227 TP_CH_D_DIMM_D0_RFU_1 @BASEBOARD_FAB2_LIB.BASEBOARD_FAB2(SCH_1):TP_CH_D_DIMM_D0_RFU_1   I111 @BASEBOARD_FAB2_LIB.BASEBOARD_FAB2(SCH_1):PAGE49
   205 TP_CH_D_DIMM_D0_RFU_0 @BASEBOARD_FAB2_LIB.BASEBOARD_FAB2(SCH_1):TP_CH_D_DIMM_D0_RFU_0   I111 @BASEBOARD_FAB2_LIB.BASEBOARD_FAB2(SCH_1):PAGE49
    84 M_D_CS_N<0> @BASEBOARD_FAB2_LIB.BASEBOARD_FAB2(SCH_1):M_D_CS_N(0)   I111 @BASEBOARD_FAB2_LIB.BASEBOARD_FAB2(SCH_1):PAGE49
    89 M_D_CS_N<1> @BASEBOARD_FAB2_LIB.BASEBOARD_FAB2(SCH_1):M_D_CS_N(1)   I111 @BASEBOARD_FAB2_LIB.BASEBOARD_FAB2(SCH_1):PAGE49
    93 M_D_CS_N<2> @BASEBOARD_FAB2_LIB.BASEBOARD_FAB2(SCH_1):M_D_CS_N(2)   I111 @BASEBOARD_FAB2_LIB.BASEBOARD_FAB2(SCH_1):PAGE49
   237 M_D_CS_N<3> @BASEBOARD_FAB2_LIB.BASEBOARD_FAB2(SCH_1):M_D_CS_N(3)   I111 @BASEBOARD_FAB2_LIB.BASEBOARD_FAB2(SCH_1):PAGE49
   238    GND @BASEBOARD_FAB2_LIB.BASEBOARD_FAB2(SCH_1):GND   I111 @BASEBOARD_FAB2_LIB.BASEBOARD_FAB2(SCH_1):PAGE49
   140    GND @BASEBOARD_FAB2_LIB.BASEBOARD_FAB2(SCH_1):GND   I111 @BASEBOARD_FAB2_LIB.BASEBOARD_FAB2(SCH_1):PAGE49
   139    GND @BASEBOARD_FAB2_LIB.BASEBOARD_FAB2(SCH_1):GND   I111 @BASEBOARD_FAB2_LIB.BASEBOARD_FAB2(SCH_1):PAGE49
   230 FM_ADR_COMPLETE_DEF_N @BASEBOARD_FAB2_LIB.BASEBOARD_FAB2(SCH_1):FM_ADR_COMPLETE_DEF_N   I111 @BASEBOARD_FAB2_LIB.BASEBOARD_FAB2(SCH_1):PAGE49
   141 SMB_DDR_DEF_VPP_SCL @BASEBOARD_FAB2_LIB.BASEBOARD_FAB2(SCH_1):SMB_DDR_DEF_VPP_SCL   I111 @BASEBOARD_FAB2_LIB.BASEBOARD_FAB2(SCH_1):PAGE49
   285 SMB_DDR_DEF_VPP_SDA @BASEBOARD_FAB2_LIB.BASEBOARD_FAB2(SCH_1):SMB_DDR_DEF_VPP_SDA   I111 @BASEBOARD_FAB2_LIB.BASEBOARD_FAB2(SCH_1):PAGE49
   284 PVPP_DEF @BASEBOARD_FAB2_LIB.BASEBOARD_FAB2(SCH_1):PVPP_DEF   I111 @BASEBOARD_FAB2_LIB.BASEBOARD_FAB2(SCH_1):PAGE49
   146 M_D_VREF @BASEBOARD_FAB2_LIB.BASEBOARD_FAB2(SCH_1):M_D_VREF   I111 @BASEBOARD_FAB2_LIB.BASEBOARD_FAB2(SCH_1):PAGE49
   152 M_D_DQS_DN<0> @BASEBOARD_FAB2_LIB.BASEBOARD_FAB2(SCH_1):M_D_DQS_DN(0)    I66 @BASEBOARD_FAB2_LIB.BASEBOARD_FAB2(SCH_1):PAGE49
   153 M_D_DQS_DP<0> @BASEBOARD_FAB2_LIB.BASEBOARD_FAB2(SCH_1):M_D_DQS_DP(0)    I66 @BASEBOARD_FAB2_LIB.BASEBOARD_FAB2(SCH_1):PAGE49
    19 M_D_DQS_DN<10> @BASEBOARD_FAB2_LIB.BASEBOARD_FAB2(SCH_1):M_D_DQS_DN(10)    I66 @BASEBOARD_FAB2_LIB.BASEBOARD_FAB2(SCH_1):PAGE49
    18 M_D_DQS_DP<10> @BASEBOARD_FAB2_LIB.BASEBOARD_FAB2(SCH_1):M_D_DQS_DP(10)    I66 @BASEBOARD_FAB2_LIB.BASEBOARD_FAB2(SCH_1):PAGE49
    30 M_D_DQS_DN<11> @BASEBOARD_FAB2_LIB.BASEBOARD_FAB2(SCH_1):M_D_DQS_DN(11)    I66 @BASEBOARD_FAB2_LIB.BASEBOARD_FAB2(SCH_1):PAGE49
    29 M_D_DQS_DP<11> @BASEBOARD_FAB2_LIB.BASEBOARD_FAB2(SCH_1):M_D_DQS_DP(11)    I66 @BASEBOARD_FAB2_LIB.BASEBOARD_FAB2(SCH_1):PAGE49
    41 M_D_DQS_DN<12> @BASEBOARD_FAB2_LIB.BASEBOARD_FAB2(SCH_1):M_D_DQS_DN(12)    I66 @BASEBOARD_FAB2_LIB.BASEBOARD_FAB2(SCH_1):PAGE49
    40 M_D_DQS_DP<12> @BASEBOARD_FAB2_LIB.BASEBOARD_FAB2(SCH_1):M_D_DQS_DP(12)    I66 @BASEBOARD_FAB2_LIB.BASEBOARD_FAB2(SCH_1):PAGE49
   100 M_D_DQS_DN<13> @BASEBOARD_FAB2_LIB.BASEBOARD_FAB2(SCH_1):M_D_DQS_DN(13)    I66 @BASEBOARD_FAB2_LIB.BASEBOARD_FAB2(SCH_1):PAGE49
    99 M_D_DQS_DP<13> @BASEBOARD_FAB2_LIB.BASEBOARD_FAB2(SCH_1):M_D_DQS_DP(13)    I66 @BASEBOARD_FAB2_LIB.BASEBOARD_FAB2(SCH_1):PAGE49
   111 M_D_DQS_DN<14> @BASEBOARD_FAB2_LIB.BASEBOARD_FAB2(SCH_1):M_D_DQS_DN(14)    I66 @BASEBOARD_FAB2_LIB.BASEBOARD_FAB2(SCH_1):PAGE49
   110 M_D_DQS_DP<14> @BASEBOARD_FAB2_LIB.BASEBOARD_FAB2(SCH_1):M_D_DQS_DP(14)    I66 @BASEBOARD_FAB2_LIB.BASEBOARD_FAB2(SCH_1):PAGE49
   122 M_D_DQS_DN<15> @BASEBOARD_FAB2_LIB.BASEBOARD_FAB2(SCH_1):M_D_DQS_DN(15)    I66 @BASEBOARD_FAB2_LIB.BASEBOARD_FAB2(SCH_1):PAGE49
   121 M_D_DQS_DP<15> @BASEBOARD_FAB2_LIB.BASEBOARD_FAB2(SCH_1):M_D_DQS_DP(15)    I66 @BASEBOARD_FAB2_LIB.BASEBOARD_FAB2(SCH_1):PAGE49
   133 M_D_DQS_DN<16> @BASEBOARD_FAB2_LIB.BASEBOARD_FAB2(SCH_1):M_D_DQS_DN(16)    I66 @BASEBOARD_FAB2_LIB.BASEBOARD_FAB2(SCH_1):PAGE49
   132 M_D_DQS_DP<16> @BASEBOARD_FAB2_LIB.BASEBOARD_FAB2(SCH_1):M_D_DQS_DP(16)    I66 @BASEBOARD_FAB2_LIB.BASEBOARD_FAB2(SCH_1):PAGE49
    52 M_D_DQS_DN<17> @BASEBOARD_FAB2_LIB.BASEBOARD_FAB2(SCH_1):M_D_DQS_DN(17)    I66 @BASEBOARD_FAB2_LIB.BASEBOARD_FAB2(SCH_1):PAGE49
    51 M_D_DQS_DP<17> @BASEBOARD_FAB2_LIB.BASEBOARD_FAB2(SCH_1):M_D_DQS_DP(17)    I66 @BASEBOARD_FAB2_LIB.BASEBOARD_FAB2(SCH_1):PAGE49
   163 M_D_DQS_DN<1> @BASEBOARD_FAB2_LIB.BASEBOARD_FAB2(SCH_1):M_D_DQS_DN(1)    I66 @BASEBOARD_FAB2_LIB.BASEBOARD_FAB2(SCH_1):PAGE49
   164 M_D_DQS_DP<1> @BASEBOARD_FAB2_LIB.BASEBOARD_FAB2(SCH_1):M_D_DQS_DP(1)    I66 @BASEBOARD_FAB2_LIB.BASEBOARD_FAB2(SCH_1):PAGE49
   174 M_D_DQS_DN<2> @BASEBOARD_FAB2_LIB.BASEBOARD_FAB2(SCH_1):M_D_DQS_DN(2)    I66 @BASEBOARD_FAB2_LIB.BASEBOARD_FAB2(SCH_1):PAGE49
   175 M_D_DQS_DP<2> @BASEBOARD_FAB2_LIB.BASEBOARD_FAB2(SCH_1):M_D_DQS_DP(2)    I66 @BASEBOARD_FAB2_LIB.BASEBOARD_FAB2(SCH_1):PAGE49
   185 M_D_DQS_DN<3> @BASEBOARD_FAB2_LIB.BASEBOARD_FAB2(SCH_1):M_D_DQS_DN(3)    I66 @BASEBOARD_FAB2_LIB.BASEBOARD_FAB2(SCH_1):PAGE49
   186 M_D_DQS_DP<3> @BASEBOARD_FAB2_LIB.BASEBOARD_FAB2(SCH_1):M_D_DQS_DP(3)    I66 @BASEBOARD_FAB2_LIB.BASEBOARD_FAB2(SCH_1):PAGE49
   244 M_D_DQS_DN<4> @BASEBOARD_FAB2_LIB.BASEBOARD_FAB2(SCH_1):M_D_DQS_DN(4)    I66 @BASEBOARD_FAB2_LIB.BASEBOARD_FAB2(SCH_1):PAGE49
   245 M_D_DQS_DP<4> @BASEBOARD_FAB2_LIB.BASEBOARD_FAB2(SCH_1):M_D_DQS_DP(4)    I66 @BASEBOARD_FAB2_LIB.BASEBOARD_FAB2(SCH_1):PAGE49
   255 M_D_DQS_DN<5> @BASEBOARD_FAB2_LIB.BASEBOARD_FAB2(SCH_1):M_D_DQS_DN(5)    I66 @BASEBOARD_FAB2_LIB.BASEBOARD_FAB2(SCH_1):PAGE49
   256 M_D_DQS_DP<5> @BASEBOARD_FAB2_LIB.BASEBOARD_FAB2(SCH_1):M_D_DQS_DP(5)    I66 @BASEBOARD_FAB2_LIB.BASEBOARD_FAB2(SCH_1):PAGE49
   266 M_D_DQS_DN<6> @BASEBOARD_FAB2_LIB.BASEBOARD_FAB2(SCH_1):M_D_DQS_DN(6)    I66 @BASEBOARD_FAB2_LIB.BASEBOARD_FAB2(SCH_1):PAGE49
   267 M_D_DQS_DP<6> @BASEBOARD_FAB2_LIB.BASEBOARD_FAB2(SCH_1):M_D_DQS_DP(6)    I66 @BASEBOARD_FAB2_LIB.BASEBOARD_FAB2(SCH_1):PAGE49
   277 M_D_DQS_DN<7> @BASEBOARD_FAB2_LIB.BASEBOARD_FAB2(SCH_1):M_D_DQS_DN(7)    I66 @BASEBOARD_FAB2_LIB.BASEBOARD_FAB2(SCH_1):PAGE49
   278 M_D_DQS_DP<7> @BASEBOARD_FAB2_LIB.BASEBOARD_FAB2(SCH_1):M_D_DQS_DP(7)    I66 @BASEBOARD_FAB2_LIB.BASEBOARD_FAB2(SCH_1):PAGE49
   196 M_D_DQS_DN<8> @BASEBOARD_FAB2_LIB.BASEBOARD_FAB2(SCH_1):M_D_DQS_DN(8)    I66 @BASEBOARD_FAB2_LIB.BASEBOARD_FAB2(SCH_1):PAGE49
   197 M_D_DQS_DP<8> @BASEBOARD_FAB2_LIB.BASEBOARD_FAB2(SCH_1):M_D_DQS_DP(8)    I66 @BASEBOARD_FAB2_LIB.BASEBOARD_FAB2(SCH_1):PAGE49
     8 M_D_DQS_DN<9> @BASEBOARD_FAB2_LIB.BASEBOARD_FAB2(SCH_1):M_D_DQS_DN(9)    I66 @BASEBOARD_FAB2_LIB.BASEBOARD_FAB2(SCH_1):PAGE49
     7 M_D_DQS_DP<9> @BASEBOARD_FAB2_LIB.BASEBOARD_FAB2(SCH_1):M_D_DQS_DP(9)    I66 @BASEBOARD_FAB2_LIB.BASEBOARD_FAB2(SCH_1):PAGE49
     2    GND @BASEBOARD_FAB2_LIB.BASEBOARD_FAB2(SCH_1):GND    I43 @BASEBOARD_FAB2_LIB.BASEBOARD_FAB2(SCH_1):PAGE49
     4    GND @BASEBOARD_FAB2_LIB.BASEBOARD_FAB2(SCH_1):GND    I43 @BASEBOARD_FAB2_LIB.BASEBOARD_FAB2(SCH_1):PAGE49
     6    GND @BASEBOARD_FAB2_LIB.BASEBOARD_FAB2(SCH_1):GND    I43 @BASEBOARD_FAB2_LIB.BASEBOARD_FAB2(SCH_1):PAGE49
     9    GND @BASEBOARD_FAB2_LIB.BASEBOARD_FAB2(SCH_1):GND    I43 @BASEBOARD_FAB2_LIB.BASEBOARD_FAB2(SCH_1):PAGE49
    11    GND @BASEBOARD_FAB2_LIB.BASEBOARD_FAB2(SCH_1):GND    I43 @BASEBOARD_FAB2_LIB.BASEBOARD_FAB2(SCH_1):PAGE49
    13    GND @BASEBOARD_FAB2_LIB.BASEBOARD_FAB2(SCH_1):GND    I43 @BASEBOARD_FAB2_LIB.BASEBOARD_FAB2(SCH_1):PAGE49
    15    GND @BASEBOARD_FAB2_LIB.BASEBOARD_FAB2(SCH_1):GND    I43 @BASEBOARD_FAB2_LIB.BASEBOARD_FAB2(SCH_1):PAGE49
    17    GND @BASEBOARD_FAB2_LIB.BASEBOARD_FAB2(SCH_1):GND    I43 @BASEBOARD_FAB2_LIB.BASEBOARD_FAB2(SCH_1):PAGE49
    20    GND @BASEBOARD_FAB2_LIB.BASEBOARD_FAB2(SCH_1):GND    I43 @BASEBOARD_FAB2_LIB.BASEBOARD_FAB2(SCH_1):PAGE49
    22    GND @BASEBOARD_FAB2_LIB.BASEBOARD_FAB2(SCH_1):GND    I43 @BASEBOARD_FAB2_LIB.BASEBOARD_FAB2(SCH_1):PAGE49
    24    GND @BASEBOARD_FAB2_LIB.BASEBOARD_FAB2(SCH_1):GND    I43 @BASEBOARD_FAB2_LIB.BASEBOARD_FAB2(SCH_1):PAGE49
    26    GND @BASEBOARD_FAB2_LIB.BASEBOARD_FAB2(SCH_1):GND    I43 @BASEBOARD_FAB2_LIB.BASEBOARD_FAB2(SCH_1):PAGE49
    28    GND @BASEBOARD_FAB2_LIB.BASEBOARD_FAB2(SCH_1):GND    I43 @BASEBOARD_FAB2_LIB.BASEBOARD_FAB2(SCH_1):PAGE49
    31    GND @BASEBOARD_FAB2_LIB.BASEBOARD_FAB2(SCH_1):GND    I43 @BASEBOARD_FAB2_LIB.BASEBOARD_FAB2(SCH_1):PAGE49
    33    GND @BASEBOARD_FAB2_LIB.BASEBOARD_FAB2(SCH_1):GND    I43 @BASEBOARD_FAB2_LIB.BASEBOARD_FAB2(SCH_1):PAGE49
    35    GND @BASEBOARD_FAB2_LIB.BASEBOARD_FAB2(SCH_1):GND    I43 @BASEBOARD_FAB2_LIB.BASEBOARD_FAB2(SCH_1):PAGE49
    37    GND @BASEBOARD_FAB2_LIB.BASEBOARD_FAB2(SCH_1):GND    I43 @BASEBOARD_FAB2_LIB.BASEBOARD_FAB2(SCH_1):PAGE49
    39    GND @BASEBOARD_FAB2_LIB.BASEBOARD_FAB2(SCH_1):GND    I43 @BASEBOARD_FAB2_LIB.BASEBOARD_FAB2(SCH_1):PAGE49
    42    GND @BASEBOARD_FAB2_LIB.BASEBOARD_FAB2(SCH_1):GND    I43 @BASEBOARD_FAB2_LIB.BASEBOARD_FAB2(SCH_1):PAGE49
    44    GND @BASEBOARD_FAB2_LIB.BASEBOARD_FAB2(SCH_1):GND    I43 @BASEBOARD_FAB2_LIB.BASEBOARD_FAB2(SCH_1):PAGE49
    46    GND @BASEBOARD_FAB2_LIB.BASEBOARD_FAB2(SCH_1):GND    I43 @BASEBOARD_FAB2_LIB.BASEBOARD_FAB2(SCH_1):PAGE49
    48    GND @BASEBOARD_FAB2_LIB.BASEBOARD_FAB2(SCH_1):GND    I43 @BASEBOARD_FAB2_LIB.BASEBOARD_FAB2(SCH_1):PAGE49
    50    GND @BASEBOARD_FAB2_LIB.BASEBOARD_FAB2(SCH_1):GND    I43 @BASEBOARD_FAB2_LIB.BASEBOARD_FAB2(SCH_1):PAGE49
    53    GND @BASEBOARD_FAB2_LIB.BASEBOARD_FAB2(SCH_1):GND    I43 @BASEBOARD_FAB2_LIB.BASEBOARD_FAB2(SCH_1):PAGE49
    55    GND @BASEBOARD_FAB2_LIB.BASEBOARD_FAB2(SCH_1):GND    I43 @BASEBOARD_FAB2_LIB.BASEBOARD_FAB2(SCH_1):PAGE49
    57    GND @BASEBOARD_FAB2_LIB.BASEBOARD_FAB2(SCH_1):GND    I43 @BASEBOARD_FAB2_LIB.BASEBOARD_FAB2(SCH_1):PAGE49
    94    GND @BASEBOARD_FAB2_LIB.BASEBOARD_FAB2(SCH_1):GND    I43 @BASEBOARD_FAB2_LIB.BASEBOARD_FAB2(SCH_1):PAGE49
    96    GND @BASEBOARD_FAB2_LIB.BASEBOARD_FAB2(SCH_1):GND    I43 @BASEBOARD_FAB2_LIB.BASEBOARD_FAB2(SCH_1):PAGE49
    98    GND @BASEBOARD_FAB2_LIB.BASEBOARD_FAB2(SCH_1):GND    I43 @BASEBOARD_FAB2_LIB.BASEBOARD_FAB2(SCH_1):PAGE49
   101    GND @BASEBOARD_FAB2_LIB.BASEBOARD_FAB2(SCH_1):GND    I43 @BASEBOARD_FAB2_LIB.BASEBOARD_FAB2(SCH_1):PAGE49
   103    GND @BASEBOARD_FAB2_LIB.BASEBOARD_FAB2(SCH_1):GND    I43 @BASEBOARD_FAB2_LIB.BASEBOARD_FAB2(SCH_1):PAGE49
   105    GND @BASEBOARD_FAB2_LIB.BASEBOARD_FAB2(SCH_1):GND    I43 @BASEBOARD_FAB2_LIB.BASEBOARD_FAB2(SCH_1):PAGE49
   107    GND @BASEBOARD_FAB2_LIB.BASEBOARD_FAB2(SCH_1):GND    I43 @BASEBOARD_FAB2_LIB.BASEBOARD_FAB2(SCH_1):PAGE49
   109    GND @BASEBOARD_FAB2_LIB.BASEBOARD_FAB2(SCH_1):GND    I43 @BASEBOARD_FAB2_LIB.BASEBOARD_FAB2(SCH_1):PAGE49
   112    GND @BASEBOARD_FAB2_LIB.BASEBOARD_FAB2(SCH_1):GND    I43 @BASEBOARD_FAB2_LIB.BASEBOARD_FAB2(SCH_1):PAGE49
   114    GND @BASEBOARD_FAB2_LIB.BASEBOARD_FAB2(SCH_1):GND    I43 @BASEBOARD_FAB2_LIB.BASEBOARD_FAB2(SCH_1):PAGE49
   116    GND @BASEBOARD_FAB2_LIB.BASEBOARD_FAB2(SCH_1):GND    I43 @BASEBOARD_FAB2_LIB.BASEBOARD_FAB2(SCH_1):PAGE49
   118    GND @BASEBOARD_FAB2_LIB.BASEBOARD_FAB2(SCH_1):GND    I43 @BASEBOARD_FAB2_LIB.BASEBOARD_FAB2(SCH_1):PAGE49
   120    GND @BASEBOARD_FAB2_LIB.BASEBOARD_FAB2(SCH_1):GND    I43 @BASEBOARD_FAB2_LIB.BASEBOARD_FAB2(SCH_1):PAGE49
   123    GND @BASEBOARD_FAB2_LIB.BASEBOARD_FAB2(SCH_1):GND    I43 @BASEBOARD_FAB2_LIB.BASEBOARD_FAB2(SCH_1):PAGE49
   125    GND @BASEBOARD_FAB2_LIB.BASEBOARD_FAB2(SCH_1):GND    I43 @BASEBOARD_FAB2_LIB.BASEBOARD_FAB2(SCH_1):PAGE49
   127    GND @BASEBOARD_FAB2_LIB.BASEBOARD_FAB2(SCH_1):GND    I43 @BASEBOARD_FAB2_LIB.BASEBOARD_FAB2(SCH_1):PAGE49
   129    GND @BASEBOARD_FAB2_LIB.BASEBOARD_FAB2(SCH_1):GND    I43 @BASEBOARD_FAB2_LIB.BASEBOARD_FAB2(SCH_1):PAGE49
   131    GND @BASEBOARD_FAB2_LIB.BASEBOARD_FAB2(SCH_1):GND    I43 @BASEBOARD_FAB2_LIB.BASEBOARD_FAB2(SCH_1):PAGE49
   134    GND @BASEBOARD_FAB2_LIB.BASEBOARD_FAB2(SCH_1):GND    I43 @BASEBOARD_FAB2_LIB.BASEBOARD_FAB2(SCH_1):PAGE49
   136    GND @BASEBOARD_FAB2_LIB.BASEBOARD_FAB2(SCH_1):GND    I43 @BASEBOARD_FAB2_LIB.BASEBOARD_FAB2(SCH_1):PAGE49
   138    GND @BASEBOARD_FAB2_LIB.BASEBOARD_FAB2(SCH_1):GND    I43 @BASEBOARD_FAB2_LIB.BASEBOARD_FAB2(SCH_1):PAGE49
   147    GND @BASEBOARD_FAB2_LIB.BASEBOARD_FAB2(SCH_1):GND    I43 @BASEBOARD_FAB2_LIB.BASEBOARD_FAB2(SCH_1):PAGE49
   149    GND @BASEBOARD_FAB2_LIB.BASEBOARD_FAB2(SCH_1):GND    I43 @BASEBOARD_FAB2_LIB.BASEBOARD_FAB2(SCH_1):PAGE49
   151    GND @BASEBOARD_FAB2_LIB.BASEBOARD_FAB2(SCH_1):GND    I43 @BASEBOARD_FAB2_LIB.BASEBOARD_FAB2(SCH_1):PAGE49
   154    GND @BASEBOARD_FAB2_LIB.BASEBOARD_FAB2(SCH_1):GND    I43 @BASEBOARD_FAB2_LIB.BASEBOARD_FAB2(SCH_1):PAGE49
   156    GND @BASEBOARD_FAB2_LIB.BASEBOARD_FAB2(SCH_1):GND    I43 @BASEBOARD_FAB2_LIB.BASEBOARD_FAB2(SCH_1):PAGE49
   158    GND @BASEBOARD_FAB2_LIB.BASEBOARD_FAB2(SCH_1):GND    I43 @BASEBOARD_FAB2_LIB.BASEBOARD_FAB2(SCH_1):PAGE49
   160    GND @BASEBOARD_FAB2_LIB.BASEBOARD_FAB2(SCH_1):GND    I43 @BASEBOARD_FAB2_LIB.BASEBOARD_FAB2(SCH_1):PAGE49
   162    GND @BASEBOARD_FAB2_LIB.BASEBOARD_FAB2(SCH_1):GND    I43 @BASEBOARD_FAB2_LIB.BASEBOARD_FAB2(SCH_1):PAGE49
   165    GND @BASEBOARD_FAB2_LIB.BASEBOARD_FAB2(SCH_1):GND    I43 @BASEBOARD_FAB2_LIB.BASEBOARD_FAB2(SCH_1):PAGE49
   167    GND @BASEBOARD_FAB2_LIB.BASEBOARD_FAB2(SCH_1):GND    I43 @BASEBOARD_FAB2_LIB.BASEBOARD_FAB2(SCH_1):PAGE49
   169    GND @BASEBOARD_FAB2_LIB.BASEBOARD_FAB2(SCH_1):GND    I43 @BASEBOARD_FAB2_LIB.BASEBOARD_FAB2(SCH_1):PAGE49
   171    GND @BASEBOARD_FAB2_LIB.BASEBOARD_FAB2(SCH_1):GND    I43 @BASEBOARD_FAB2_LIB.BASEBOARD_FAB2(SCH_1):PAGE49
   173    GND @BASEBOARD_FAB2_LIB.BASEBOARD_FAB2(SCH_1):GND    I43 @BASEBOARD_FAB2_LIB.BASEBOARD_FAB2(SCH_1):PAGE49
   176    GND @BASEBOARD_FAB2_LIB.BASEBOARD_FAB2(SCH_1):GND    I43 @BASEBOARD_FAB2_LIB.BASEBOARD_FAB2(SCH_1):PAGE49
   178    GND @BASEBOARD_FAB2_LIB.BASEBOARD_FAB2(SCH_1):GND    I43 @BASEBOARD_FAB2_LIB.BASEBOARD_FAB2(SCH_1):PAGE49
   180    GND @BASEBOARD_FAB2_LIB.BASEBOARD_FAB2(SCH_1):GND    I43 @BASEBOARD_FAB2_LIB.BASEBOARD_FAB2(SCH_1):PAGE49
   182    GND @BASEBOARD_FAB2_LIB.BASEBOARD_FAB2(SCH_1):GND    I43 @BASEBOARD_FAB2_LIB.BASEBOARD_FAB2(SCH_1):PAGE49
   184    GND @BASEBOARD_FAB2_LIB.BASEBOARD_FAB2(SCH_1):GND    I43 @BASEBOARD_FAB2_LIB.BASEBOARD_FAB2(SCH_1):PAGE49
   187    GND @BASEBOARD_FAB2_LIB.BASEBOARD_FAB2(SCH_1):GND    I43 @BASEBOARD_FAB2_LIB.BASEBOARD_FAB2(SCH_1):PAGE49
   189    GND @BASEBOARD_FAB2_LIB.BASEBOARD_FAB2(SCH_1):GND    I43 @BASEBOARD_FAB2_LIB.BASEBOARD_FAB2(SCH_1):PAGE49
   191    GND @BASEBOARD_FAB2_LIB.BASEBOARD_FAB2(SCH_1):GND    I43 @BASEBOARD_FAB2_LIB.BASEBOARD_FAB2(SCH_1):PAGE49
   193    GND @BASEBOARD_FAB2_LIB.BASEBOARD_FAB2(SCH_1):GND    I43 @BASEBOARD_FAB2_LIB.BASEBOARD_FAB2(SCH_1):PAGE49
   195    GND @BASEBOARD_FAB2_LIB.BASEBOARD_FAB2(SCH_1):GND    I43 @BASEBOARD_FAB2_LIB.BASEBOARD_FAB2(SCH_1):PAGE49
   198    GND @BASEBOARD_FAB2_LIB.BASEBOARD_FAB2(SCH_1):GND    I43 @BASEBOARD_FAB2_LIB.BASEBOARD_FAB2(SCH_1):PAGE49
   200    GND @BASEBOARD_FAB2_LIB.BASEBOARD_FAB2(SCH_1):GND    I43 @BASEBOARD_FAB2_LIB.BASEBOARD_FAB2(SCH_1):PAGE49
   202    GND @BASEBOARD_FAB2_LIB.BASEBOARD_FAB2(SCH_1):GND    I43 @BASEBOARD_FAB2_LIB.BASEBOARD_FAB2(SCH_1):PAGE49
   239    GND @BASEBOARD_FAB2_LIB.BASEBOARD_FAB2(SCH_1):GND    I43 @BASEBOARD_FAB2_LIB.BASEBOARD_FAB2(SCH_1):PAGE49
   241    GND @BASEBOARD_FAB2_LIB.BASEBOARD_FAB2(SCH_1):GND    I43 @BASEBOARD_FAB2_LIB.BASEBOARD_FAB2(SCH_1):PAGE49
   243    GND @BASEBOARD_FAB2_LIB.BASEBOARD_FAB2(SCH_1):GND    I43 @BASEBOARD_FAB2_LIB.BASEBOARD_FAB2(SCH_1):PAGE49
   246    GND @BASEBOARD_FAB2_LIB.BASEBOARD_FAB2(SCH_1):GND    I43 @BASEBOARD_FAB2_LIB.BASEBOARD_FAB2(SCH_1):PAGE49
   248    GND @BASEBOARD_FAB2_LIB.BASEBOARD_FAB2(SCH_1):GND    I43 @BASEBOARD_FAB2_LIB.BASEBOARD_FAB2(SCH_1):PAGE49
   250    GND @BASEBOARD_FAB2_LIB.BASEBOARD_FAB2(SCH_1):GND    I43 @BASEBOARD_FAB2_LIB.BASEBOARD_FAB2(SCH_1):PAGE49
   252    GND @BASEBOARD_FAB2_LIB.BASEBOARD_FAB2(SCH_1):GND    I43 @BASEBOARD_FAB2_LIB.BASEBOARD_FAB2(SCH_1):PAGE49
   254    GND @BASEBOARD_FAB2_LIB.BASEBOARD_FAB2(SCH_1):GND    I43 @BASEBOARD_FAB2_LIB.BASEBOARD_FAB2(SCH_1):PAGE49
   257    GND @BASEBOARD_FAB2_LIB.BASEBOARD_FAB2(SCH_1):GND    I43 @BASEBOARD_FAB2_LIB.BASEBOARD_FAB2(SCH_1):PAGE49
   259    GND @BASEBOARD_FAB2_LIB.BASEBOARD_FAB2(SCH_1):GND    I43 @BASEBOARD_FAB2_LIB.BASEBOARD_FAB2(SCH_1):PAGE49
   261    GND @BASEBOARD_FAB2_LIB.BASEBOARD_FAB2(SCH_1):GND    I43 @BASEBOARD_FAB2_LIB.BASEBOARD_FAB2(SCH_1):PAGE49
   263    GND @BASEBOARD_FAB2_LIB.BASEBOARD_FAB2(SCH_1):GND    I43 @BASEBOARD_FAB2_LIB.BASEBOARD_FAB2(SCH_1):PAGE49
   265    GND @BASEBOARD_FAB2_LIB.BASEBOARD_FAB2(SCH_1):GND    I43 @BASEBOARD_FAB2_LIB.BASEBOARD_FAB2(SCH_1):PAGE49
   268    GND @BASEBOARD_FAB2_LIB.BASEBOARD_FAB2(SCH_1):GND    I43 @BASEBOARD_FAB2_LIB.BASEBOARD_FAB2(SCH_1):PAGE49
   270    GND @BASEBOARD_FAB2_LIB.BASEBOARD_FAB2(SCH_1):GND    I43 @BASEBOARD_FAB2_LIB.BASEBOARD_FAB2(SCH_1):PAGE49
   272    GND @BASEBOARD_FAB2_LIB.BASEBOARD_FAB2(SCH_1):GND    I43 @BASEBOARD_FAB2_LIB.BASEBOARD_FAB2(SCH_1):PAGE49
   274    GND @BASEBOARD_FAB2_LIB.BASEBOARD_FAB2(SCH_1):GND    I43 @BASEBOARD_FAB2_LIB.BASEBOARD_FAB2(SCH_1):PAGE49
   276    GND @BASEBOARD_FAB2_LIB.BASEBOARD_FAB2(SCH_1):GND    I43 @BASEBOARD_FAB2_LIB.BASEBOARD_FAB2(SCH_1):PAGE49
   279    GND @BASEBOARD_FAB2_LIB.BASEBOARD_FAB2(SCH_1):GND    I43 @BASEBOARD_FAB2_LIB.BASEBOARD_FAB2(SCH_1):PAGE49
   281    GND @BASEBOARD_FAB2_LIB.BASEBOARD_FAB2(SCH_1):GND    I43 @BASEBOARD_FAB2_LIB.BASEBOARD_FAB2(SCH_1):PAGE49
   283    GND @BASEBOARD_FAB2_LIB.BASEBOARD_FAB2(SCH_1):GND    I43 @BASEBOARD_FAB2_LIB.BASEBOARD_FAB2(SCH_1):PAGE49
     1 P12V_NVDIMM_DEF @BASEBOARD_FAB2_LIB.BASEBOARD_FAB2(SCH_1):P12V_NVDIMM_DEF   I169 @BASEBOARD_FAB2_LIB.BASEBOARD_FAB2(SCH_1):PAGE49
   145 P12V_NVDIMM_DEF @BASEBOARD_FAB2_LIB.BASEBOARD_FAB2(SCH_1):P12V_NVDIMM_DEF   I169 @BASEBOARD_FAB2_LIB.BASEBOARD_FAB2(SCH_1):PAGE49
    59 PVDDQ_DEF @BASEBOARD_FAB2_LIB.BASEBOARD_FAB2(SCH_1):PVDDQ_DEF   I169 @BASEBOARD_FAB2_LIB.BASEBOARD_FAB2(SCH_1):PAGE49
    61 PVDDQ_DEF @BASEBOARD_FAB2_LIB.BASEBOARD_FAB2(SCH_1):PVDDQ_DEF   I169 @BASEBOARD_FAB2_LIB.BASEBOARD_FAB2(SCH_1):PAGE49
    64 PVDDQ_DEF @BASEBOARD_FAB2_LIB.BASEBOARD_FAB2(SCH_1):PVDDQ_DEF   I169 @BASEBOARD_FAB2_LIB.BASEBOARD_FAB2(SCH_1):PAGE49
    67 PVDDQ_DEF @BASEBOARD_FAB2_LIB.BASEBOARD_FAB2(SCH_1):PVDDQ_DEF   I169 @BASEBOARD_FAB2_LIB.BASEBOARD_FAB2(SCH_1):PAGE49
    70 PVDDQ_DEF @BASEBOARD_FAB2_LIB.BASEBOARD_FAB2(SCH_1):PVDDQ_DEF   I169 @BASEBOARD_FAB2_LIB.BASEBOARD_FAB2(SCH_1):PAGE49
    73 PVDDQ_DEF @BASEBOARD_FAB2_LIB.BASEBOARD_FAB2(SCH_1):PVDDQ_DEF   I169 @BASEBOARD_FAB2_LIB.BASEBOARD_FAB2(SCH_1):PAGE49
    76 PVDDQ_DEF @BASEBOARD_FAB2_LIB.BASEBOARD_FAB2(SCH_1):PVDDQ_DEF   I169 @BASEBOARD_FAB2_LIB.BASEBOARD_FAB2(SCH_1):PAGE49
    80 PVDDQ_DEF @BASEBOARD_FAB2_LIB.BASEBOARD_FAB2(SCH_1):PVDDQ_DEF   I169 @BASEBOARD_FAB2_LIB.BASEBOARD_FAB2(SCH_1):PAGE49
    83 PVDDQ_DEF @BASEBOARD_FAB2_LIB.BASEBOARD_FAB2(SCH_1):PVDDQ_DEF   I169 @BASEBOARD_FAB2_LIB.BASEBOARD_FAB2(SCH_1):PAGE49
    85 PVDDQ_DEF @BASEBOARD_FAB2_LIB.BASEBOARD_FAB2(SCH_1):PVDDQ_DEF   I169 @BASEBOARD_FAB2_LIB.BASEBOARD_FAB2(SCH_1):PAGE49
    88 PVDDQ_DEF @BASEBOARD_FAB2_LIB.BASEBOARD_FAB2(SCH_1):PVDDQ_DEF   I169 @BASEBOARD_FAB2_LIB.BASEBOARD_FAB2(SCH_1):PAGE49
    90 PVDDQ_DEF @BASEBOARD_FAB2_LIB.BASEBOARD_FAB2(SCH_1):PVDDQ_DEF   I169 @BASEBOARD_FAB2_LIB.BASEBOARD_FAB2(SCH_1):PAGE49
    92 PVDDQ_DEF @BASEBOARD_FAB2_LIB.BASEBOARD_FAB2(SCH_1):PVDDQ_DEF   I169 @BASEBOARD_FAB2_LIB.BASEBOARD_FAB2(SCH_1):PAGE49
   204 PVDDQ_DEF @BASEBOARD_FAB2_LIB.BASEBOARD_FAB2(SCH_1):PVDDQ_DEF   I169 @BASEBOARD_FAB2_LIB.BASEBOARD_FAB2(SCH_1):PAGE49
   206 PVDDQ_DEF @BASEBOARD_FAB2_LIB.BASEBOARD_FAB2(SCH_1):PVDDQ_DEF   I169 @BASEBOARD_FAB2_LIB.BASEBOARD_FAB2(SCH_1):PAGE49
   209 PVDDQ_DEF @BASEBOARD_FAB2_LIB.BASEBOARD_FAB2(SCH_1):PVDDQ_DEF   I169 @BASEBOARD_FAB2_LIB.BASEBOARD_FAB2(SCH_1):PAGE49
   212 PVDDQ_DEF @BASEBOARD_FAB2_LIB.BASEBOARD_FAB2(SCH_1):PVDDQ_DEF   I169 @BASEBOARD_FAB2_LIB.BASEBOARD_FAB2(SCH_1):PAGE49
   215 PVDDQ_DEF @BASEBOARD_FAB2_LIB.BASEBOARD_FAB2(SCH_1):PVDDQ_DEF   I169 @BASEBOARD_FAB2_LIB.BASEBOARD_FAB2(SCH_1):PAGE49
   217 PVDDQ_DEF @BASEBOARD_FAB2_LIB.BASEBOARD_FAB2(SCH_1):PVDDQ_DEF   I169 @BASEBOARD_FAB2_LIB.BASEBOARD_FAB2(SCH_1):PAGE49
   220 PVDDQ_DEF @BASEBOARD_FAB2_LIB.BASEBOARD_FAB2(SCH_1):PVDDQ_DEF   I169 @BASEBOARD_FAB2_LIB.BASEBOARD_FAB2(SCH_1):PAGE49
   223 PVDDQ_DEF @BASEBOARD_FAB2_LIB.BASEBOARD_FAB2(SCH_1):PVDDQ_DEF   I169 @BASEBOARD_FAB2_LIB.BASEBOARD_FAB2(SCH_1):PAGE49
   226 PVDDQ_DEF @BASEBOARD_FAB2_LIB.BASEBOARD_FAB2(SCH_1):PVDDQ_DEF   I169 @BASEBOARD_FAB2_LIB.BASEBOARD_FAB2(SCH_1):PAGE49
   229 PVDDQ_DEF @BASEBOARD_FAB2_LIB.BASEBOARD_FAB2(SCH_1):PVDDQ_DEF   I169 @BASEBOARD_FAB2_LIB.BASEBOARD_FAB2(SCH_1):PAGE49
   231 PVDDQ_DEF @BASEBOARD_FAB2_LIB.BASEBOARD_FAB2(SCH_1):PVDDQ_DEF   I169 @BASEBOARD_FAB2_LIB.BASEBOARD_FAB2(SCH_1):PAGE49
   233 PVDDQ_DEF @BASEBOARD_FAB2_LIB.BASEBOARD_FAB2(SCH_1):PVDDQ_DEF   I169 @BASEBOARD_FAB2_LIB.BASEBOARD_FAB2(SCH_1):PAGE49
   236 PVDDQ_DEF @BASEBOARD_FAB2_LIB.BASEBOARD_FAB2(SCH_1):PVDDQ_DEF   I169 @BASEBOARD_FAB2_LIB.BASEBOARD_FAB2(SCH_1):PAGE49
   142 PVPP_DEF @BASEBOARD_FAB2_LIB.BASEBOARD_FAB2(SCH_1):PVPP_DEF   I169 @BASEBOARD_FAB2_LIB.BASEBOARD_FAB2(SCH_1):PAGE49
   143 PVPP_DEF @BASEBOARD_FAB2_LIB.BASEBOARD_FAB2(SCH_1):PVPP_DEF   I169 @BASEBOARD_FAB2_LIB.BASEBOARD_FAB2(SCH_1):PAGE49
   288 PVPP_DEF @BASEBOARD_FAB2_LIB.BASEBOARD_FAB2(SCH_1):PVPP_DEF   I169 @BASEBOARD_FAB2_LIB.BASEBOARD_FAB2(SCH_1):PAGE49
   286 PVPP_DEF @BASEBOARD_FAB2_LIB.BASEBOARD_FAB2(SCH_1):PVPP_DEF   I169 @BASEBOARD_FAB2_LIB.BASEBOARD_FAB2(SCH_1):PAGE49
   287 PVPP_DEF @BASEBOARD_FAB2_LIB.BASEBOARD_FAB2(SCH_1):PVPP_DEF   I169 @BASEBOARD_FAB2_LIB.BASEBOARD_FAB2(SCH_1):PAGE49
    77 PVTT_DEF @BASEBOARD_FAB2_LIB.BASEBOARD_FAB2(SCH_1):PVTT_DEF   I169 @BASEBOARD_FAB2_LIB.BASEBOARD_FAB2(SCH_1):PAGE49
   221 PVTT_DEF @BASEBOARD_FAB2_LIB.BASEBOARD_FAB2(SCH_1):PVTT_DEF   I169 @BASEBOARD_FAB2_LIB.BASEBOARD_FAB2(SCH_1):PAGE49

J4B2 SCONN120_H61426002_SM-CONN,H61A
    A1 P12V_STBY @BASEBOARD_FAB2_LIB.BASEBOARD_FAB2(SCH_1):P12V_STBY    I46 @BASEBOARD_FAB2_LIB.BASEBOARD_FAB2(SCH_1):PAGE193
   A10    GND @BASEBOARD_FAB2_LIB.BASEBOARD_FAB2(SCH_1):GND    I46 @BASEBOARD_FAB2_LIB.BASEBOARD_FAB2(SCH_1):PAGE193
   A11 P3V3_STBY @BASEBOARD_FAB2_LIB.BASEBOARD_FAB2(SCH_1):P3V3_STBY    I46 @BASEBOARD_FAB2_LIB.BASEBOARD_FAB2(SCH_1):PAGE193
   A12    GND @BASEBOARD_FAB2_LIB.BASEBOARD_FAB2(SCH_1):GND    I46 @BASEBOARD_FAB2_LIB.BASEBOARD_FAB2(SCH_1):PAGE193
   A13 P5V_STBY @BASEBOARD_FAB2_LIB.BASEBOARD_FAB2(SCH_1):P5V_STBY    I46 @BASEBOARD_FAB2_LIB.BASEBOARD_FAB2(SCH_1):PAGE193
   A14    GND @BASEBOARD_FAB2_LIB.BASEBOARD_FAB2(SCH_1):GND    I46 @BASEBOARD_FAB2_LIB.BASEBOARD_FAB2(SCH_1):PAGE193
   A15 FM_P1V8MCP_CPU1_EN @BASEBOARD_FAB2_LIB.BASEBOARD_FAB2(SCH_1):FM_P1V8MCP_CPU1_EN    I46 @BASEBOARD_FAB2_LIB.BASEBOARD_FAB2(SCH_1):PAGE193
   A16 FM_PVCCIOMCP_CPU1_EN @BASEBOARD_FAB2_LIB.BASEBOARD_FAB2(SCH_1):FM_PVCCIOMCP_CPU1_EN    I46 @BASEBOARD_FAB2_LIB.BASEBOARD_FAB2(SCH_1):PAGE193
   A17    GND @BASEBOARD_FAB2_LIB.BASEBOARD_FAB2(SCH_1):GND    I46 @BASEBOARD_FAB2_LIB.BASEBOARD_FAB2(SCH_1):PAGE193
   A18 SMB_VR_STBY_LVC3_SCL @BASEBOARD_FAB2_LIB.BASEBOARD_FAB2(SCH_1):SMB_VR_STBY_LVC3_SCL    I46 @BASEBOARD_FAB2_LIB.BASEBOARD_FAB2(SCH_1):PAGE193
   A19 SVID_ALERT0_CPU1_R_N @BASEBOARD_FAB2_LIB.BASEBOARD_FAB2(SCH_1):SVID_ALERT0_CPU1_R_N    I46 @BASEBOARD_FAB2_LIB.BASEBOARD_FAB2(SCH_1):PAGE193
    A2 P12V_STBY @BASEBOARD_FAB2_LIB.BASEBOARD_FAB2(SCH_1):P12V_STBY    I46 @BASEBOARD_FAB2_LIB.BASEBOARD_FAB2(SCH_1):PAGE193
   A20 SVID_CLK0_CPU1_R @BASEBOARD_FAB2_LIB.BASEBOARD_FAB2(SCH_1):SVID_CLK0_CPU1_R    I46 @BASEBOARD_FAB2_LIB.BASEBOARD_FAB2(SCH_1):PAGE193
    A3 P12V_STBY @BASEBOARD_FAB2_LIB.BASEBOARD_FAB2(SCH_1):P12V_STBY    I46 @BASEBOARD_FAB2_LIB.BASEBOARD_FAB2(SCH_1):PAGE193
    A4 P12V_STBY @BASEBOARD_FAB2_LIB.BASEBOARD_FAB2(SCH_1):P12V_STBY    I46 @BASEBOARD_FAB2_LIB.BASEBOARD_FAB2(SCH_1):PAGE193
    A5 P12V_STBY @BASEBOARD_FAB2_LIB.BASEBOARD_FAB2(SCH_1):P12V_STBY    I46 @BASEBOARD_FAB2_LIB.BASEBOARD_FAB2(SCH_1):PAGE193
    A6 P12V_STBY @BASEBOARD_FAB2_LIB.BASEBOARD_FAB2(SCH_1):P12V_STBY    I46 @BASEBOARD_FAB2_LIB.BASEBOARD_FAB2(SCH_1):PAGE193
    A7 P12V_STBY @BASEBOARD_FAB2_LIB.BASEBOARD_FAB2(SCH_1):P12V_STBY    I46 @BASEBOARD_FAB2_LIB.BASEBOARD_FAB2(SCH_1):PAGE193
    A8 P12V_STBY @BASEBOARD_FAB2_LIB.BASEBOARD_FAB2(SCH_1):P12V_STBY    I46 @BASEBOARD_FAB2_LIB.BASEBOARD_FAB2(SCH_1):PAGE193
    A9    GND @BASEBOARD_FAB2_LIB.BASEBOARD_FAB2(SCH_1):GND    I46 @BASEBOARD_FAB2_LIB.BASEBOARD_FAB2(SCH_1):PAGE193
    B1 P12V_STBY @BASEBOARD_FAB2_LIB.BASEBOARD_FAB2(SCH_1):P12V_STBY    I46 @BASEBOARD_FAB2_LIB.BASEBOARD_FAB2(SCH_1):PAGE193
   B10    GND @BASEBOARD_FAB2_LIB.BASEBOARD_FAB2(SCH_1):GND    I46 @BASEBOARD_FAB2_LIB.BASEBOARD_FAB2(SCH_1):PAGE193
   B11 P3V3_STBY @BASEBOARD_FAB2_LIB.BASEBOARD_FAB2(SCH_1):P3V3_STBY    I46 @BASEBOARD_FAB2_LIB.BASEBOARD_FAB2(SCH_1):PAGE193
   B12    GND @BASEBOARD_FAB2_LIB.BASEBOARD_FAB2(SCH_1):GND    I46 @BASEBOARD_FAB2_LIB.BASEBOARD_FAB2(SCH_1):PAGE193
   B13 P5V_STBY @BASEBOARD_FAB2_LIB.BASEBOARD_FAB2(SCH_1):P5V_STBY    I46 @BASEBOARD_FAB2_LIB.BASEBOARD_FAB2(SCH_1):PAGE193
   B14    GND @BASEBOARD_FAB2_LIB.BASEBOARD_FAB2(SCH_1):GND    I46 @BASEBOARD_FAB2_LIB.BASEBOARD_FAB2(SCH_1):PAGE193
   B15 PWRGD_P1V8MCP_CPU1 @BASEBOARD_FAB2_LIB.BASEBOARD_FAB2(SCH_1):PWRGD_P1V8MCP_CPU1    I46 @BASEBOARD_FAB2_LIB.BASEBOARD_FAB2(SCH_1):PAGE193
   B16 PWRGD_PVCCIOMCP_CPU1 @BASEBOARD_FAB2_LIB.BASEBOARD_FAB2(SCH_1):PWRGD_PVCCIOMCP_CPU1    I46 @BASEBOARD_FAB2_LIB.BASEBOARD_FAB2(SCH_1):PAGE193
   B17    GND @BASEBOARD_FAB2_LIB.BASEBOARD_FAB2(SCH_1):GND    I46 @BASEBOARD_FAB2_LIB.BASEBOARD_FAB2(SCH_1):PAGE193
   B18 SMB_VR_STBY_LVC3_SDA @BASEBOARD_FAB2_LIB.BASEBOARD_FAB2(SCH_1):SMB_VR_STBY_LVC3_SDA    I46 @BASEBOARD_FAB2_LIB.BASEBOARD_FAB2(SCH_1):PAGE193
   B19 SVID_ALERT1_CPU1_R_N @BASEBOARD_FAB2_LIB.BASEBOARD_FAB2(SCH_1):SVID_ALERT1_CPU1_R_N    I46 @BASEBOARD_FAB2_LIB.BASEBOARD_FAB2(SCH_1):PAGE193
    B2 P12V_STBY @BASEBOARD_FAB2_LIB.BASEBOARD_FAB2(SCH_1):P12V_STBY    I46 @BASEBOARD_FAB2_LIB.BASEBOARD_FAB2(SCH_1):PAGE193
   B20 SVID_DIO0_CPU1_R @BASEBOARD_FAB2_LIB.BASEBOARD_FAB2(SCH_1):SVID_DIO0_CPU1_R    I46 @BASEBOARD_FAB2_LIB.BASEBOARD_FAB2(SCH_1):PAGE193
    B3 P12V_STBY @BASEBOARD_FAB2_LIB.BASEBOARD_FAB2(SCH_1):P12V_STBY    I46 @BASEBOARD_FAB2_LIB.BASEBOARD_FAB2(SCH_1):PAGE193
    B4 P12V_STBY @BASEBOARD_FAB2_LIB.BASEBOARD_FAB2(SCH_1):P12V_STBY    I46 @BASEBOARD_FAB2_LIB.BASEBOARD_FAB2(SCH_1):PAGE193
    B5 P12V_STBY @BASEBOARD_FAB2_LIB.BASEBOARD_FAB2(SCH_1):P12V_STBY    I46 @BASEBOARD_FAB2_LIB.BASEBOARD_FAB2(SCH_1):PAGE193
    B6 P12V_STBY @BASEBOARD_FAB2_LIB.BASEBOARD_FAB2(SCH_1):P12V_STBY    I46 @BASEBOARD_FAB2_LIB.BASEBOARD_FAB2(SCH_1):PAGE193
    B7 P12V_STBY @BASEBOARD_FAB2_LIB.BASEBOARD_FAB2(SCH_1):P12V_STBY    I46 @BASEBOARD_FAB2_LIB.BASEBOARD_FAB2(SCH_1):PAGE193
    B8 P12V_STBY @BASEBOARD_FAB2_LIB.BASEBOARD_FAB2(SCH_1):P12V_STBY    I46 @BASEBOARD_FAB2_LIB.BASEBOARD_FAB2(SCH_1):PAGE193
    B9    GND @BASEBOARD_FAB2_LIB.BASEBOARD_FAB2(SCH_1):GND    I46 @BASEBOARD_FAB2_LIB.BASEBOARD_FAB2(SCH_1):PAGE193
    C1    GND @BASEBOARD_FAB2_LIB.BASEBOARD_FAB2(SCH_1):GND    I46 @BASEBOARD_FAB2_LIB.BASEBOARD_FAB2(SCH_1):PAGE193
   C10    GND @BASEBOARD_FAB2_LIB.BASEBOARD_FAB2(SCH_1):GND    I46 @BASEBOARD_FAB2_LIB.BASEBOARD_FAB2(SCH_1):PAGE193
   C11 P3V3_STBY @BASEBOARD_FAB2_LIB.BASEBOARD_FAB2(SCH_1):P3V3_STBY    I46 @BASEBOARD_FAB2_LIB.BASEBOARD_FAB2(SCH_1):PAGE193
   C12    GND @BASEBOARD_FAB2_LIB.BASEBOARD_FAB2(SCH_1):GND    I46 @BASEBOARD_FAB2_LIB.BASEBOARD_FAB2(SCH_1):PAGE193
   C13 P5V_STBY @BASEBOARD_FAB2_LIB.BASEBOARD_FAB2(SCH_1):P5V_STBY    I46 @BASEBOARD_FAB2_LIB.BASEBOARD_FAB2(SCH_1):PAGE193
   C14    GND @BASEBOARD_FAB2_LIB.BASEBOARD_FAB2(SCH_1):GND    I46 @BASEBOARD_FAB2_LIB.BASEBOARD_FAB2(SCH_1):PAGE193
   C15    GND @BASEBOARD_FAB2_LIB.BASEBOARD_FAB2(SCH_1):GND    I46 @BASEBOARD_FAB2_LIB.BASEBOARD_FAB2(SCH_1):PAGE193
   C16    GND @BASEBOARD_FAB2_LIB.BASEBOARD_FAB2(SCH_1):GND    I46 @BASEBOARD_FAB2_LIB.BASEBOARD_FAB2(SCH_1):PAGE193
   C17 PVCCIOMCP_CPU1 @BASEBOARD_FAB2_LIB.BASEBOARD_FAB2(SCH_1):PVCCIOMCP_CPU1    I46 @BASEBOARD_FAB2_LIB.BASEBOARD_FAB2(SCH_1):PAGE193
   C18 PVCCIOMCP_CPU1 @BASEBOARD_FAB2_LIB.BASEBOARD_FAB2(SCH_1):PVCCIOMCP_CPU1    I46 @BASEBOARD_FAB2_LIB.BASEBOARD_FAB2(SCH_1):PAGE193
   C19 PVCCIOMCP_CPU1 @BASEBOARD_FAB2_LIB.BASEBOARD_FAB2(SCH_1):PVCCIOMCP_CPU1    I46 @BASEBOARD_FAB2_LIB.BASEBOARD_FAB2(SCH_1):PAGE193
    C2    GND @BASEBOARD_FAB2_LIB.BASEBOARD_FAB2(SCH_1):GND    I46 @BASEBOARD_FAB2_LIB.BASEBOARD_FAB2(SCH_1):PAGE193
   C20 FM_PVCCMCP_CPU1_EN @BASEBOARD_FAB2_LIB.BASEBOARD_FAB2(SCH_1):FM_PVCCMCP_CPU1_EN    I46 @BASEBOARD_FAB2_LIB.BASEBOARD_FAB2(SCH_1):PAGE193
    C3    GND @BASEBOARD_FAB2_LIB.BASEBOARD_FAB2(SCH_1):GND    I46 @BASEBOARD_FAB2_LIB.BASEBOARD_FAB2(SCH_1):PAGE193
    C4    GND @BASEBOARD_FAB2_LIB.BASEBOARD_FAB2(SCH_1):GND    I46 @BASEBOARD_FAB2_LIB.BASEBOARD_FAB2(SCH_1):PAGE193
    C5    GND @BASEBOARD_FAB2_LIB.BASEBOARD_FAB2(SCH_1):GND    I46 @BASEBOARD_FAB2_LIB.BASEBOARD_FAB2(SCH_1):PAGE193
    C6    GND @BASEBOARD_FAB2_LIB.BASEBOARD_FAB2(SCH_1):GND    I46 @BASEBOARD_FAB2_LIB.BASEBOARD_FAB2(SCH_1):PAGE193
    C7    GND @BASEBOARD_FAB2_LIB.BASEBOARD_FAB2(SCH_1):GND    I46 @BASEBOARD_FAB2_LIB.BASEBOARD_FAB2(SCH_1):PAGE193
    C8    GND @BASEBOARD_FAB2_LIB.BASEBOARD_FAB2(SCH_1):GND    I46 @BASEBOARD_FAB2_LIB.BASEBOARD_FAB2(SCH_1):PAGE193
    C9    GND @BASEBOARD_FAB2_LIB.BASEBOARD_FAB2(SCH_1):GND    I46 @BASEBOARD_FAB2_LIB.BASEBOARD_FAB2(SCH_1):PAGE193
    D1   P3V3 @BASEBOARD_FAB2_LIB.BASEBOARD_FAB2(SCH_1):P3V3    I46 @BASEBOARD_FAB2_LIB.BASEBOARD_FAB2(SCH_1):PAGE193
   D10    GND @BASEBOARD_FAB2_LIB.BASEBOARD_FAB2(SCH_1):GND    I46 @BASEBOARD_FAB2_LIB.BASEBOARD_FAB2(SCH_1):PAGE193
   D11    GND @BASEBOARD_FAB2_LIB.BASEBOARD_FAB2(SCH_1):GND    I46 @BASEBOARD_FAB2_LIB.BASEBOARD_FAB2(SCH_1):PAGE193
   D12    GND @BASEBOARD_FAB2_LIB.BASEBOARD_FAB2(SCH_1):GND    I46 @BASEBOARD_FAB2_LIB.BASEBOARD_FAB2(SCH_1):PAGE193
   D13    GND @BASEBOARD_FAB2_LIB.BASEBOARD_FAB2(SCH_1):GND    I46 @BASEBOARD_FAB2_LIB.BASEBOARD_FAB2(SCH_1):PAGE193
   D14    GND @BASEBOARD_FAB2_LIB.BASEBOARD_FAB2(SCH_1):GND    I46 @BASEBOARD_FAB2_LIB.BASEBOARD_FAB2(SCH_1):PAGE193
   D15    GND @BASEBOARD_FAB2_LIB.BASEBOARD_FAB2(SCH_1):GND    I46 @BASEBOARD_FAB2_LIB.BASEBOARD_FAB2(SCH_1):PAGE193
   D16    GND @BASEBOARD_FAB2_LIB.BASEBOARD_FAB2(SCH_1):GND    I46 @BASEBOARD_FAB2_LIB.BASEBOARD_FAB2(SCH_1):PAGE193
   D17 PVCCIOMCP_CPU1 @BASEBOARD_FAB2_LIB.BASEBOARD_FAB2(SCH_1):PVCCIOMCP_CPU1    I46 @BASEBOARD_FAB2_LIB.BASEBOARD_FAB2(SCH_1):PAGE193
   D18 PVCCIOMCP_CPU1 @BASEBOARD_FAB2_LIB.BASEBOARD_FAB2(SCH_1):PVCCIOMCP_CPU1    I46 @BASEBOARD_FAB2_LIB.BASEBOARD_FAB2(SCH_1):PAGE193
   D19 PVCCIOMCP_CPU1 @BASEBOARD_FAB2_LIB.BASEBOARD_FAB2(SCH_1):PVCCIOMCP_CPU1    I46 @BASEBOARD_FAB2_LIB.BASEBOARD_FAB2(SCH_1):PAGE193
    D2    GND @BASEBOARD_FAB2_LIB.BASEBOARD_FAB2(SCH_1):GND    I46 @BASEBOARD_FAB2_LIB.BASEBOARD_FAB2(SCH_1):PAGE193
   D20 PWRGD_PVCCMCP_CPU1 @BASEBOARD_FAB2_LIB.BASEBOARD_FAB2(SCH_1):PWRGD_PVCCMCP_CPU1    I46 @BASEBOARD_FAB2_LIB.BASEBOARD_FAB2(SCH_1):PAGE193
    D3    GND @BASEBOARD_FAB2_LIB.BASEBOARD_FAB2(SCH_1):GND    I46 @BASEBOARD_FAB2_LIB.BASEBOARD_FAB2(SCH_1):PAGE193
    D4    GND @BASEBOARD_FAB2_LIB.BASEBOARD_FAB2(SCH_1):GND    I46 @BASEBOARD_FAB2_LIB.BASEBOARD_FAB2(SCH_1):PAGE193
    D5    GND @BASEBOARD_FAB2_LIB.BASEBOARD_FAB2(SCH_1):GND    I46 @BASEBOARD_FAB2_LIB.BASEBOARD_FAB2(SCH_1):PAGE193
    D6    GND @BASEBOARD_FAB2_LIB.BASEBOARD_FAB2(SCH_1):GND    I46 @BASEBOARD_FAB2_LIB.BASEBOARD_FAB2(SCH_1):PAGE193
    D7    GND @BASEBOARD_FAB2_LIB.BASEBOARD_FAB2(SCH_1):GND    I46 @BASEBOARD_FAB2_LIB.BASEBOARD_FAB2(SCH_1):PAGE193
    D8    GND @BASEBOARD_FAB2_LIB.BASEBOARD_FAB2(SCH_1):GND    I46 @BASEBOARD_FAB2_LIB.BASEBOARD_FAB2(SCH_1):PAGE193
    D9    GND @BASEBOARD_FAB2_LIB.BASEBOARD_FAB2(SCH_1):GND    I46 @BASEBOARD_FAB2_LIB.BASEBOARD_FAB2(SCH_1):PAGE193
    E1 FM_CPU1_VRM_322M_156M_OSC_EN @BASEBOARD_FAB2_LIB.BASEBOARD_FAB2(SCH_1):FM_CPU1_VRM_322M_156M_OSC_EN    I46 @BASEBOARD_FAB2_LIB.BASEBOARD_FAB2(SCH_1):PAGE193
   E10 VR_PVCCIOMCP_CPU1_XADDR1 @BASEBOARD_FAB2_LIB.BASEBOARD_FAB2(SCH_1):VR_PVCCIOMCP_CPU1_XADDR1    I46 @BASEBOARD_FAB2_LIB.BASEBOARD_FAB2(SCH_1):PAGE193
   E11    GND @BASEBOARD_FAB2_LIB.BASEBOARD_FAB2(SCH_1):GND    I46 @BASEBOARD_FAB2_LIB.BASEBOARD_FAB2(SCH_1):PAGE193
   E12    GND @BASEBOARD_FAB2_LIB.BASEBOARD_FAB2(SCH_1):GND    I46 @BASEBOARD_FAB2_LIB.BASEBOARD_FAB2(SCH_1):PAGE193
   E13    GND @BASEBOARD_FAB2_LIB.BASEBOARD_FAB2(SCH_1):GND    I46 @BASEBOARD_FAB2_LIB.BASEBOARD_FAB2(SCH_1):PAGE193
   E14    GND @BASEBOARD_FAB2_LIB.BASEBOARD_FAB2(SCH_1):GND    I46 @BASEBOARD_FAB2_LIB.BASEBOARD_FAB2(SCH_1):PAGE193
   E15 PVCCIOMCP_CPU1 @BASEBOARD_FAB2_LIB.BASEBOARD_FAB2(SCH_1):PVCCIOMCP_CPU1    I46 @BASEBOARD_FAB2_LIB.BASEBOARD_FAB2(SCH_1):PAGE193
   E16 PVCCIOMCP_CPU1 @BASEBOARD_FAB2_LIB.BASEBOARD_FAB2(SCH_1):PVCCIOMCP_CPU1    I46 @BASEBOARD_FAB2_LIB.BASEBOARD_FAB2(SCH_1):PAGE193
   E17 PVCCIOMCP_CPU1 @BASEBOARD_FAB2_LIB.BASEBOARD_FAB2(SCH_1):PVCCIOMCP_CPU1    I46 @BASEBOARD_FAB2_LIB.BASEBOARD_FAB2(SCH_1):PAGE193
   E18 PVCCIOMCP_CPU1 @BASEBOARD_FAB2_LIB.BASEBOARD_FAB2(SCH_1):PVCCIOMCP_CPU1    I46 @BASEBOARD_FAB2_LIB.BASEBOARD_FAB2(SCH_1):PAGE193
   E19 PVCCIOMCP_CPU1 @BASEBOARD_FAB2_LIB.BASEBOARD_FAB2(SCH_1):PVCCIOMCP_CPU1    I46 @BASEBOARD_FAB2_LIB.BASEBOARD_FAB2(SCH_1):PAGE193
    E2    GND @BASEBOARD_FAB2_LIB.BASEBOARD_FAB2(SCH_1):GND    I46 @BASEBOARD_FAB2_LIB.BASEBOARD_FAB2(SCH_1):PAGE193
   E20 SVID_CLK1_CPU1_R @BASEBOARD_FAB2_LIB.BASEBOARD_FAB2(SCH_1):SVID_CLK1_CPU1_R    I46 @BASEBOARD_FAB2_LIB.BASEBOARD_FAB2(SCH_1):PAGE193
    E3    GND @BASEBOARD_FAB2_LIB.BASEBOARD_FAB2(SCH_1):GND    I46 @BASEBOARD_FAB2_LIB.BASEBOARD_FAB2(SCH_1):PAGE193
    E4    GND @BASEBOARD_FAB2_LIB.BASEBOARD_FAB2(SCH_1):GND    I46 @BASEBOARD_FAB2_LIB.BASEBOARD_FAB2(SCH_1):PAGE193
    E5    GND @BASEBOARD_FAB2_LIB.BASEBOARD_FAB2(SCH_1):GND    I46 @BASEBOARD_FAB2_LIB.BASEBOARD_FAB2(SCH_1):PAGE193
    E6    GND @BASEBOARD_FAB2_LIB.BASEBOARD_FAB2(SCH_1):GND    I46 @BASEBOARD_FAB2_LIB.BASEBOARD_FAB2(SCH_1):PAGE193
    E7    GND @BASEBOARD_FAB2_LIB.BASEBOARD_FAB2(SCH_1):GND    I46 @BASEBOARD_FAB2_LIB.BASEBOARD_FAB2(SCH_1):PAGE193
    E8 VSENSE_PVCCIOMCP_CPU1_SKT_VSEN @BASEBOARD_FAB2_LIB.BASEBOARD_FAB2(SCH_1):VSENSE_PVCCIOMCP_CPU1_SKT_VSEN    I46 @BASEBOARD_FAB2_LIB.BASEBOARD_FAB2(SCH_1):PAGE193
    E9    GND @BASEBOARD_FAB2_LIB.BASEBOARD_FAB2(SCH_1):GND    I46 @BASEBOARD_FAB2_LIB.BASEBOARD_FAB2(SCH_1):PAGE193
    F1 PVCCIO_CPU1 @BASEBOARD_FAB2_LIB.BASEBOARD_FAB2(SCH_1):PVCCIO_CPU1    I46 @BASEBOARD_FAB2_LIB.BASEBOARD_FAB2(SCH_1):PAGE193
   F10 VR_PVCCMCP_CPU1_XADDR2 @BASEBOARD_FAB2_LIB.BASEBOARD_FAB2(SCH_1):VR_PVCCMCP_CPU1_XADDR2    I46 @BASEBOARD_FAB2_LIB.BASEBOARD_FAB2(SCH_1):PAGE193
   F11    GND @BASEBOARD_FAB2_LIB.BASEBOARD_FAB2(SCH_1):GND    I46 @BASEBOARD_FAB2_LIB.BASEBOARD_FAB2(SCH_1):PAGE193
   F12    GND @BASEBOARD_FAB2_LIB.BASEBOARD_FAB2(SCH_1):GND    I46 @BASEBOARD_FAB2_LIB.BASEBOARD_FAB2(SCH_1):PAGE193
   F13    GND @BASEBOARD_FAB2_LIB.BASEBOARD_FAB2(SCH_1):GND    I46 @BASEBOARD_FAB2_LIB.BASEBOARD_FAB2(SCH_1):PAGE193
   F14    GND @BASEBOARD_FAB2_LIB.BASEBOARD_FAB2(SCH_1):GND    I46 @BASEBOARD_FAB2_LIB.BASEBOARD_FAB2(SCH_1):PAGE193
   F15 PVCCIOMCP_CPU1 @BASEBOARD_FAB2_LIB.BASEBOARD_FAB2(SCH_1):PVCCIOMCP_CPU1    I46 @BASEBOARD_FAB2_LIB.BASEBOARD_FAB2(SCH_1):PAGE193
   F16 PVCCIOMCP_CPU1 @BASEBOARD_FAB2_LIB.BASEBOARD_FAB2(SCH_1):PVCCIOMCP_CPU1    I46 @BASEBOARD_FAB2_LIB.BASEBOARD_FAB2(SCH_1):PAGE193
   F17 PVCCIOMCP_CPU1 @BASEBOARD_FAB2_LIB.BASEBOARD_FAB2(SCH_1):PVCCIOMCP_CPU1    I46 @BASEBOARD_FAB2_LIB.BASEBOARD_FAB2(SCH_1):PAGE193
   F18 PVCCIOMCP_CPU1 @BASEBOARD_FAB2_LIB.BASEBOARD_FAB2(SCH_1):PVCCIOMCP_CPU1    I46 @BASEBOARD_FAB2_LIB.BASEBOARD_FAB2(SCH_1):PAGE193
   F19 PVCCIOMCP_CPU1 @BASEBOARD_FAB2_LIB.BASEBOARD_FAB2(SCH_1):PVCCIOMCP_CPU1    I46 @BASEBOARD_FAB2_LIB.BASEBOARD_FAB2(SCH_1):PAGE193
    F2    GND @BASEBOARD_FAB2_LIB.BASEBOARD_FAB2(SCH_1):GND    I46 @BASEBOARD_FAB2_LIB.BASEBOARD_FAB2(SCH_1):PAGE193
   F20 SVID_DIO1_CPU1_R @BASEBOARD_FAB2_LIB.BASEBOARD_FAB2(SCH_1):SVID_DIO1_CPU1_R    I46 @BASEBOARD_FAB2_LIB.BASEBOARD_FAB2(SCH_1):PAGE193
    F3    GND @BASEBOARD_FAB2_LIB.BASEBOARD_FAB2(SCH_1):GND    I46 @BASEBOARD_FAB2_LIB.BASEBOARD_FAB2(SCH_1):PAGE193
    F4    GND @BASEBOARD_FAB2_LIB.BASEBOARD_FAB2(SCH_1):GND    I46 @BASEBOARD_FAB2_LIB.BASEBOARD_FAB2(SCH_1):PAGE193
    F5    GND @BASEBOARD_FAB2_LIB.BASEBOARD_FAB2(SCH_1):GND    I46 @BASEBOARD_FAB2_LIB.BASEBOARD_FAB2(SCH_1):PAGE193
    F6    GND @BASEBOARD_FAB2_LIB.BASEBOARD_FAB2(SCH_1):GND    I46 @BASEBOARD_FAB2_LIB.BASEBOARD_FAB2(SCH_1):PAGE193
    F7    GND @BASEBOARD_FAB2_LIB.BASEBOARD_FAB2(SCH_1):GND    I46 @BASEBOARD_FAB2_LIB.BASEBOARD_FAB2(SCH_1):PAGE193
    F8 VSENSE_PVCCIOMCP_CPU1_SKT_VRTN @BASEBOARD_FAB2_LIB.BASEBOARD_FAB2(SCH_1):VSENSE_PVCCIOMCP_CPU1_SKT_VRTN    I46 @BASEBOARD_FAB2_LIB.BASEBOARD_FAB2(SCH_1):PAGE193
    F9    GND @BASEBOARD_FAB2_LIB.BASEBOARD_FAB2(SCH_1):GND    I46 @BASEBOARD_FAB2_LIB.BASEBOARD_FAB2(SCH_1):PAGE193

J4E1 SCONN120_H61426002_SM-CONN,H61A
    A1 PVCCMCP_CPU1 @BASEBOARD_FAB2_LIB.BASEBOARD_FAB2(SCH_1):PVCCMCP_CPU1    I45 @BASEBOARD_FAB2_LIB.BASEBOARD_FAB2(SCH_1):PAGE193
   A10 PVCCMCP_CPU1 @BASEBOARD_FAB2_LIB.BASEBOARD_FAB2(SCH_1):PVCCMCP_CPU1    I45 @BASEBOARD_FAB2_LIB.BASEBOARD_FAB2(SCH_1):PAGE193
   A11 PVCCMCP_CPU1 @BASEBOARD_FAB2_LIB.BASEBOARD_FAB2(SCH_1):PVCCMCP_CPU1    I45 @BASEBOARD_FAB2_LIB.BASEBOARD_FAB2(SCH_1):PAGE193
   A12 PVCCMCP_CPU1 @BASEBOARD_FAB2_LIB.BASEBOARD_FAB2(SCH_1):PVCCMCP_CPU1    I45 @BASEBOARD_FAB2_LIB.BASEBOARD_FAB2(SCH_1):PAGE193
   A13 PVCCMCP_CPU1 @BASEBOARD_FAB2_LIB.BASEBOARD_FAB2(SCH_1):PVCCMCP_CPU1    I45 @BASEBOARD_FAB2_LIB.BASEBOARD_FAB2(SCH_1):PAGE193
   A14 PVCCMCP_CPU1 @BASEBOARD_FAB2_LIB.BASEBOARD_FAB2(SCH_1):PVCCMCP_CPU1    I45 @BASEBOARD_FAB2_LIB.BASEBOARD_FAB2(SCH_1):PAGE193
   A15 PVCCMCP_CPU1 @BASEBOARD_FAB2_LIB.BASEBOARD_FAB2(SCH_1):PVCCMCP_CPU1    I45 @BASEBOARD_FAB2_LIB.BASEBOARD_FAB2(SCH_1):PAGE193
   A16 PVCCMCP_CPU1 @BASEBOARD_FAB2_LIB.BASEBOARD_FAB2(SCH_1):PVCCMCP_CPU1    I45 @BASEBOARD_FAB2_LIB.BASEBOARD_FAB2(SCH_1):PAGE193
   A17 PVCCMCP_CPU1 @BASEBOARD_FAB2_LIB.BASEBOARD_FAB2(SCH_1):PVCCMCP_CPU1    I45 @BASEBOARD_FAB2_LIB.BASEBOARD_FAB2(SCH_1):PAGE193
   A18 PVCCMCP_CPU1 @BASEBOARD_FAB2_LIB.BASEBOARD_FAB2(SCH_1):PVCCMCP_CPU1    I45 @BASEBOARD_FAB2_LIB.BASEBOARD_FAB2(SCH_1):PAGE193
   A19    GND @BASEBOARD_FAB2_LIB.BASEBOARD_FAB2(SCH_1):GND    I45 @BASEBOARD_FAB2_LIB.BASEBOARD_FAB2(SCH_1):PAGE193
    A2 PVCCMCP_CPU1 @BASEBOARD_FAB2_LIB.BASEBOARD_FAB2(SCH_1):PVCCMCP_CPU1    I45 @BASEBOARD_FAB2_LIB.BASEBOARD_FAB2(SCH_1):PAGE193
   A20    GND @BASEBOARD_FAB2_LIB.BASEBOARD_FAB2(SCH_1):GND    I45 @BASEBOARD_FAB2_LIB.BASEBOARD_FAB2(SCH_1):PAGE193
    A3 PVCCMCP_CPU1 @BASEBOARD_FAB2_LIB.BASEBOARD_FAB2(SCH_1):PVCCMCP_CPU1    I45 @BASEBOARD_FAB2_LIB.BASEBOARD_FAB2(SCH_1):PAGE193
    A4 VSENSE_PVCCMCP_CPU1_SKT_VSEN @BASEBOARD_FAB2_LIB.BASEBOARD_FAB2(SCH_1):VSENSE_PVCCMCP_CPU1_SKT_VSEN    I45 @BASEBOARD_FAB2_LIB.BASEBOARD_FAB2(SCH_1):PAGE193
    A5 PVCCMCP_CPU1 @BASEBOARD_FAB2_LIB.BASEBOARD_FAB2(SCH_1):PVCCMCP_CPU1    I45 @BASEBOARD_FAB2_LIB.BASEBOARD_FAB2(SCH_1):PAGE193
    A6 PVCCMCP_CPU1 @BASEBOARD_FAB2_LIB.BASEBOARD_FAB2(SCH_1):PVCCMCP_CPU1    I45 @BASEBOARD_FAB2_LIB.BASEBOARD_FAB2(SCH_1):PAGE193
    A7 PVCCMCP_CPU1 @BASEBOARD_FAB2_LIB.BASEBOARD_FAB2(SCH_1):PVCCMCP_CPU1    I45 @BASEBOARD_FAB2_LIB.BASEBOARD_FAB2(SCH_1):PAGE193
    A8 PVCCMCP_CPU1 @BASEBOARD_FAB2_LIB.BASEBOARD_FAB2(SCH_1):PVCCMCP_CPU1    I45 @BASEBOARD_FAB2_LIB.BASEBOARD_FAB2(SCH_1):PAGE193
    A9 PVCCMCP_CPU1 @BASEBOARD_FAB2_LIB.BASEBOARD_FAB2(SCH_1):PVCCMCP_CPU1    I45 @BASEBOARD_FAB2_LIB.BASEBOARD_FAB2(SCH_1):PAGE193
    B1 PVCCMCP_CPU1 @BASEBOARD_FAB2_LIB.BASEBOARD_FAB2(SCH_1):PVCCMCP_CPU1    I45 @BASEBOARD_FAB2_LIB.BASEBOARD_FAB2(SCH_1):PAGE193
   B10 PVCCMCP_CPU1 @BASEBOARD_FAB2_LIB.BASEBOARD_FAB2(SCH_1):PVCCMCP_CPU1    I45 @BASEBOARD_FAB2_LIB.BASEBOARD_FAB2(SCH_1):PAGE193
   B11 PVCCMCP_CPU1 @BASEBOARD_FAB2_LIB.BASEBOARD_FAB2(SCH_1):PVCCMCP_CPU1    I45 @BASEBOARD_FAB2_LIB.BASEBOARD_FAB2(SCH_1):PAGE193
   B12 PVCCMCP_CPU1 @BASEBOARD_FAB2_LIB.BASEBOARD_FAB2(SCH_1):PVCCMCP_CPU1    I45 @BASEBOARD_FAB2_LIB.BASEBOARD_FAB2(SCH_1):PAGE193
   B13 PVCCMCP_CPU1 @BASEBOARD_FAB2_LIB.BASEBOARD_FAB2(SCH_1):PVCCMCP_CPU1    I45 @BASEBOARD_FAB2_LIB.BASEBOARD_FAB2(SCH_1):PAGE193
   B14 PVCCMCP_CPU1 @BASEBOARD_FAB2_LIB.BASEBOARD_FAB2(SCH_1):PVCCMCP_CPU1    I45 @BASEBOARD_FAB2_LIB.BASEBOARD_FAB2(SCH_1):PAGE193
   B15 PVCCMCP_CPU1 @BASEBOARD_FAB2_LIB.BASEBOARD_FAB2(SCH_1):PVCCMCP_CPU1    I45 @BASEBOARD_FAB2_LIB.BASEBOARD_FAB2(SCH_1):PAGE193
   B16 PVCCMCP_CPU1 @BASEBOARD_FAB2_LIB.BASEBOARD_FAB2(SCH_1):PVCCMCP_CPU1    I45 @BASEBOARD_FAB2_LIB.BASEBOARD_FAB2(SCH_1):PAGE193
   B17 PVCCMCP_CPU1 @BASEBOARD_FAB2_LIB.BASEBOARD_FAB2(SCH_1):PVCCMCP_CPU1    I45 @BASEBOARD_FAB2_LIB.BASEBOARD_FAB2(SCH_1):PAGE193
   B18 PVCCMCP_CPU1 @BASEBOARD_FAB2_LIB.BASEBOARD_FAB2(SCH_1):PVCCMCP_CPU1    I45 @BASEBOARD_FAB2_LIB.BASEBOARD_FAB2(SCH_1):PAGE193
   B19    GND @BASEBOARD_FAB2_LIB.BASEBOARD_FAB2(SCH_1):GND    I45 @BASEBOARD_FAB2_LIB.BASEBOARD_FAB2(SCH_1):PAGE193
    B2 PVCCMCP_CPU1 @BASEBOARD_FAB2_LIB.BASEBOARD_FAB2(SCH_1):PVCCMCP_CPU1    I45 @BASEBOARD_FAB2_LIB.BASEBOARD_FAB2(SCH_1):PAGE193
   B20    GND @BASEBOARD_FAB2_LIB.BASEBOARD_FAB2(SCH_1):GND    I45 @BASEBOARD_FAB2_LIB.BASEBOARD_FAB2(SCH_1):PAGE193
    B3 PVCCMCP_CPU1 @BASEBOARD_FAB2_LIB.BASEBOARD_FAB2(SCH_1):PVCCMCP_CPU1    I45 @BASEBOARD_FAB2_LIB.BASEBOARD_FAB2(SCH_1):PAGE193
    B4 VSENSE_PVCCMCP_CPU1_SKT_VRTN @BASEBOARD_FAB2_LIB.BASEBOARD_FAB2(SCH_1):VSENSE_PVCCMCP_CPU1_SKT_VRTN    I45 @BASEBOARD_FAB2_LIB.BASEBOARD_FAB2(SCH_1):PAGE193
    B5 PVCCMCP_CPU1 @BASEBOARD_FAB2_LIB.BASEBOARD_FAB2(SCH_1):PVCCMCP_CPU1    I45 @BASEBOARD_FAB2_LIB.BASEBOARD_FAB2(SCH_1):PAGE193
    B6 PVCCMCP_CPU1 @BASEBOARD_FAB2_LIB.BASEBOARD_FAB2(SCH_1):PVCCMCP_CPU1    I45 @BASEBOARD_FAB2_LIB.BASEBOARD_FAB2(SCH_1):PAGE193
    B7 PVCCMCP_CPU1 @BASEBOARD_FAB2_LIB.BASEBOARD_FAB2(SCH_1):PVCCMCP_CPU1    I45 @BASEBOARD_FAB2_LIB.BASEBOARD_FAB2(SCH_1):PAGE193
    B8 PVCCMCP_CPU1 @BASEBOARD_FAB2_LIB.BASEBOARD_FAB2(SCH_1):PVCCMCP_CPU1    I45 @BASEBOARD_FAB2_LIB.BASEBOARD_FAB2(SCH_1):PAGE193
    B9 PVCCMCP_CPU1 @BASEBOARD_FAB2_LIB.BASEBOARD_FAB2(SCH_1):PVCCMCP_CPU1    I45 @BASEBOARD_FAB2_LIB.BASEBOARD_FAB2(SCH_1):PAGE193
    C1 PVCCMCP_CPU1 @BASEBOARD_FAB2_LIB.BASEBOARD_FAB2(SCH_1):PVCCMCP_CPU1    I45 @BASEBOARD_FAB2_LIB.BASEBOARD_FAB2(SCH_1):PAGE193
   C10 PVCCMCP_CPU1 @BASEBOARD_FAB2_LIB.BASEBOARD_FAB2(SCH_1):PVCCMCP_CPU1    I45 @BASEBOARD_FAB2_LIB.BASEBOARD_FAB2(SCH_1):PAGE193
   C11 PVCCMCP_CPU1 @BASEBOARD_FAB2_LIB.BASEBOARD_FAB2(SCH_1):PVCCMCP_CPU1    I45 @BASEBOARD_FAB2_LIB.BASEBOARD_FAB2(SCH_1):PAGE193
   C12 PVCCMCP_CPU1 @BASEBOARD_FAB2_LIB.BASEBOARD_FAB2(SCH_1):PVCCMCP_CPU1    I45 @BASEBOARD_FAB2_LIB.BASEBOARD_FAB2(SCH_1):PAGE193
   C13 PVCCMCP_CPU1 @BASEBOARD_FAB2_LIB.BASEBOARD_FAB2(SCH_1):PVCCMCP_CPU1    I45 @BASEBOARD_FAB2_LIB.BASEBOARD_FAB2(SCH_1):PAGE193
   C14 PVCCMCP_CPU1 @BASEBOARD_FAB2_LIB.BASEBOARD_FAB2(SCH_1):PVCCMCP_CPU1    I45 @BASEBOARD_FAB2_LIB.BASEBOARD_FAB2(SCH_1):PAGE193
   C15 PVCCMCP_CPU1 @BASEBOARD_FAB2_LIB.BASEBOARD_FAB2(SCH_1):PVCCMCP_CPU1    I45 @BASEBOARD_FAB2_LIB.BASEBOARD_FAB2(SCH_1):PAGE193
   C16 PVCCMCP_CPU1 @BASEBOARD_FAB2_LIB.BASEBOARD_FAB2(SCH_1):PVCCMCP_CPU1    I45 @BASEBOARD_FAB2_LIB.BASEBOARD_FAB2(SCH_1):PAGE193
   C17 PVCCMCP_CPU1 @BASEBOARD_FAB2_LIB.BASEBOARD_FAB2(SCH_1):PVCCMCP_CPU1    I45 @BASEBOARD_FAB2_LIB.BASEBOARD_FAB2(SCH_1):PAGE193
   C18 PVCCMCP_CPU1 @BASEBOARD_FAB2_LIB.BASEBOARD_FAB2(SCH_1):PVCCMCP_CPU1    I45 @BASEBOARD_FAB2_LIB.BASEBOARD_FAB2(SCH_1):PAGE193
   C19    GND @BASEBOARD_FAB2_LIB.BASEBOARD_FAB2(SCH_1):GND    I45 @BASEBOARD_FAB2_LIB.BASEBOARD_FAB2(SCH_1):PAGE193
    C2 PVCCMCP_CPU1 @BASEBOARD_FAB2_LIB.BASEBOARD_FAB2(SCH_1):PVCCMCP_CPU1    I45 @BASEBOARD_FAB2_LIB.BASEBOARD_FAB2(SCH_1):PAGE193
   C20    GND @BASEBOARD_FAB2_LIB.BASEBOARD_FAB2(SCH_1):GND    I45 @BASEBOARD_FAB2_LIB.BASEBOARD_FAB2(SCH_1):PAGE193
    C3 PVCCMCP_CPU1 @BASEBOARD_FAB2_LIB.BASEBOARD_FAB2(SCH_1):PVCCMCP_CPU1    I45 @BASEBOARD_FAB2_LIB.BASEBOARD_FAB2(SCH_1):PAGE193
    C4 PVCCMCP_CPU1 @BASEBOARD_FAB2_LIB.BASEBOARD_FAB2(SCH_1):PVCCMCP_CPU1    I45 @BASEBOARD_FAB2_LIB.BASEBOARD_FAB2(SCH_1):PAGE193
    C5 PVCCMCP_CPU1 @BASEBOARD_FAB2_LIB.BASEBOARD_FAB2(SCH_1):PVCCMCP_CPU1    I45 @BASEBOARD_FAB2_LIB.BASEBOARD_FAB2(SCH_1):PAGE193
    C6 PVCCMCP_CPU1 @BASEBOARD_FAB2_LIB.BASEBOARD_FAB2(SCH_1):PVCCMCP_CPU1    I45 @BASEBOARD_FAB2_LIB.BASEBOARD_FAB2(SCH_1):PAGE193
    C7 PVCCMCP_CPU1 @BASEBOARD_FAB2_LIB.BASEBOARD_FAB2(SCH_1):PVCCMCP_CPU1    I45 @BASEBOARD_FAB2_LIB.BASEBOARD_FAB2(SCH_1):PAGE193
    C8 PVCCMCP_CPU1 @BASEBOARD_FAB2_LIB.BASEBOARD_FAB2(SCH_1):PVCCMCP_CPU1    I45 @BASEBOARD_FAB2_LIB.BASEBOARD_FAB2(SCH_1):PAGE193
    C9 PVCCMCP_CPU1 @BASEBOARD_FAB2_LIB.BASEBOARD_FAB2(SCH_1):PVCCMCP_CPU1    I45 @BASEBOARD_FAB2_LIB.BASEBOARD_FAB2(SCH_1):PAGE193
    D1 VSENSE_P1V8MCP_CPU1_SKT_VSEN @BASEBOARD_FAB2_LIB.BASEBOARD_FAB2(SCH_1):VSENSE_P1V8MCP_CPU1_SKT_VSEN    I45 @BASEBOARD_FAB2_LIB.BASEBOARD_FAB2(SCH_1):PAGE193
   D10    GND @BASEBOARD_FAB2_LIB.BASEBOARD_FAB2(SCH_1):GND    I45 @BASEBOARD_FAB2_LIB.BASEBOARD_FAB2(SCH_1):PAGE193
   D11    GND @BASEBOARD_FAB2_LIB.BASEBOARD_FAB2(SCH_1):GND    I45 @BASEBOARD_FAB2_LIB.BASEBOARD_FAB2(SCH_1):PAGE193
   D12    GND @BASEBOARD_FAB2_LIB.BASEBOARD_FAB2(SCH_1):GND    I45 @BASEBOARD_FAB2_LIB.BASEBOARD_FAB2(SCH_1):PAGE193
   D13    GND @BASEBOARD_FAB2_LIB.BASEBOARD_FAB2(SCH_1):GND    I45 @BASEBOARD_FAB2_LIB.BASEBOARD_FAB2(SCH_1):PAGE193
   D14    GND @BASEBOARD_FAB2_LIB.BASEBOARD_FAB2(SCH_1):GND    I45 @BASEBOARD_FAB2_LIB.BASEBOARD_FAB2(SCH_1):PAGE193
   D15    GND @BASEBOARD_FAB2_LIB.BASEBOARD_FAB2(SCH_1):GND    I45 @BASEBOARD_FAB2_LIB.BASEBOARD_FAB2(SCH_1):PAGE193
   D16    GND @BASEBOARD_FAB2_LIB.BASEBOARD_FAB2(SCH_1):GND    I45 @BASEBOARD_FAB2_LIB.BASEBOARD_FAB2(SCH_1):PAGE193
   D17    GND @BASEBOARD_FAB2_LIB.BASEBOARD_FAB2(SCH_1):GND    I45 @BASEBOARD_FAB2_LIB.BASEBOARD_FAB2(SCH_1):PAGE193
   D18    GND @BASEBOARD_FAB2_LIB.BASEBOARD_FAB2(SCH_1):GND    I45 @BASEBOARD_FAB2_LIB.BASEBOARD_FAB2(SCH_1):PAGE193
   D19    GND @BASEBOARD_FAB2_LIB.BASEBOARD_FAB2(SCH_1):GND    I45 @BASEBOARD_FAB2_LIB.BASEBOARD_FAB2(SCH_1):PAGE193
    D2 VSENSE_P1V8MCP_CPU1_SKT_VRTN @BASEBOARD_FAB2_LIB.BASEBOARD_FAB2(SCH_1):VSENSE_P1V8MCP_CPU1_SKT_VRTN    I45 @BASEBOARD_FAB2_LIB.BASEBOARD_FAB2(SCH_1):PAGE193
   D20    GND @BASEBOARD_FAB2_LIB.BASEBOARD_FAB2(SCH_1):GND    I45 @BASEBOARD_FAB2_LIB.BASEBOARD_FAB2(SCH_1):PAGE193
    D3 P1V8_MCP_CPU1 @BASEBOARD_FAB2_LIB.BASEBOARD_FAB2(SCH_1):P1V8_MCP_CPU1    I45 @BASEBOARD_FAB2_LIB.BASEBOARD_FAB2(SCH_1):PAGE193
    D4    GND @BASEBOARD_FAB2_LIB.BASEBOARD_FAB2(SCH_1):GND    I45 @BASEBOARD_FAB2_LIB.BASEBOARD_FAB2(SCH_1):PAGE193
    D5    GND @BASEBOARD_FAB2_LIB.BASEBOARD_FAB2(SCH_1):GND    I45 @BASEBOARD_FAB2_LIB.BASEBOARD_FAB2(SCH_1):PAGE193
    D6    GND @BASEBOARD_FAB2_LIB.BASEBOARD_FAB2(SCH_1):GND    I45 @BASEBOARD_FAB2_LIB.BASEBOARD_FAB2(SCH_1):PAGE193
    D7    GND @BASEBOARD_FAB2_LIB.BASEBOARD_FAB2(SCH_1):GND    I45 @BASEBOARD_FAB2_LIB.BASEBOARD_FAB2(SCH_1):PAGE193
    D8    GND @BASEBOARD_FAB2_LIB.BASEBOARD_FAB2(SCH_1):GND    I45 @BASEBOARD_FAB2_LIB.BASEBOARD_FAB2(SCH_1):PAGE193
    D9    GND @BASEBOARD_FAB2_LIB.BASEBOARD_FAB2(SCH_1):GND    I45 @BASEBOARD_FAB2_LIB.BASEBOARD_FAB2(SCH_1):PAGE193
    E1 P1V8_MCP_CPU1 @BASEBOARD_FAB2_LIB.BASEBOARD_FAB2(SCH_1):P1V8_MCP_CPU1    I45 @BASEBOARD_FAB2_LIB.BASEBOARD_FAB2(SCH_1):PAGE193
   E10    GND @BASEBOARD_FAB2_LIB.BASEBOARD_FAB2(SCH_1):GND    I45 @BASEBOARD_FAB2_LIB.BASEBOARD_FAB2(SCH_1):PAGE193
   E11    GND @BASEBOARD_FAB2_LIB.BASEBOARD_FAB2(SCH_1):GND    I45 @BASEBOARD_FAB2_LIB.BASEBOARD_FAB2(SCH_1):PAGE193
   E12    GND @BASEBOARD_FAB2_LIB.BASEBOARD_FAB2(SCH_1):GND    I45 @BASEBOARD_FAB2_LIB.BASEBOARD_FAB2(SCH_1):PAGE193
   E13    GND @BASEBOARD_FAB2_LIB.BASEBOARD_FAB2(SCH_1):GND    I45 @BASEBOARD_FAB2_LIB.BASEBOARD_FAB2(SCH_1):PAGE193
   E14    GND @BASEBOARD_FAB2_LIB.BASEBOARD_FAB2(SCH_1):GND    I45 @BASEBOARD_FAB2_LIB.BASEBOARD_FAB2(SCH_1):PAGE193
   E15    GND @BASEBOARD_FAB2_LIB.BASEBOARD_FAB2(SCH_1):GND    I45 @BASEBOARD_FAB2_LIB.BASEBOARD_FAB2(SCH_1):PAGE193
   E16    GND @BASEBOARD_FAB2_LIB.BASEBOARD_FAB2(SCH_1):GND    I45 @BASEBOARD_FAB2_LIB.BASEBOARD_FAB2(SCH_1):PAGE193
   E17    GND @BASEBOARD_FAB2_LIB.BASEBOARD_FAB2(SCH_1):GND    I45 @BASEBOARD_FAB2_LIB.BASEBOARD_FAB2(SCH_1):PAGE193
   E18    GND @BASEBOARD_FAB2_LIB.BASEBOARD_FAB2(SCH_1):GND    I45 @BASEBOARD_FAB2_LIB.BASEBOARD_FAB2(SCH_1):PAGE193
   E19    GND @BASEBOARD_FAB2_LIB.BASEBOARD_FAB2(SCH_1):GND    I45 @BASEBOARD_FAB2_LIB.BASEBOARD_FAB2(SCH_1):PAGE193
    E2 P1V8_MCP_CPU1 @BASEBOARD_FAB2_LIB.BASEBOARD_FAB2(SCH_1):P1V8_MCP_CPU1    I45 @BASEBOARD_FAB2_LIB.BASEBOARD_FAB2(SCH_1):PAGE193
   E20    GND @BASEBOARD_FAB2_LIB.BASEBOARD_FAB2(SCH_1):GND    I45 @BASEBOARD_FAB2_LIB.BASEBOARD_FAB2(SCH_1):PAGE193
    E3 P1V8_MCP_CPU1 @BASEBOARD_FAB2_LIB.BASEBOARD_FAB2(SCH_1):P1V8_MCP_CPU1    I45 @BASEBOARD_FAB2_LIB.BASEBOARD_FAB2(SCH_1):PAGE193
    E4    GND @BASEBOARD_FAB2_LIB.BASEBOARD_FAB2(SCH_1):GND    I45 @BASEBOARD_FAB2_LIB.BASEBOARD_FAB2(SCH_1):PAGE193
    E5 CLK_322M_156M_CPU1_OSC_VRM_DP @BASEBOARD_FAB2_LIB.BASEBOARD_FAB2(SCH_1):CLK_322M_156M_CPU1_OSC_VRM_DP    I45 @BASEBOARD_FAB2_LIB.BASEBOARD_FAB2(SCH_1):PAGE193
    E6    GND @BASEBOARD_FAB2_LIB.BASEBOARD_FAB2(SCH_1):GND    I45 @BASEBOARD_FAB2_LIB.BASEBOARD_FAB2(SCH_1):PAGE193
    E7    GND @BASEBOARD_FAB2_LIB.BASEBOARD_FAB2(SCH_1):GND    I45 @BASEBOARD_FAB2_LIB.BASEBOARD_FAB2(SCH_1):PAGE193
    E8    GND @BASEBOARD_FAB2_LIB.BASEBOARD_FAB2(SCH_1):GND    I45 @BASEBOARD_FAB2_LIB.BASEBOARD_FAB2(SCH_1):PAGE193
    E9    GND @BASEBOARD_FAB2_LIB.BASEBOARD_FAB2(SCH_1):GND    I45 @BASEBOARD_FAB2_LIB.BASEBOARD_FAB2(SCH_1):PAGE193
    F1 P1V8_MCP_CPU1 @BASEBOARD_FAB2_LIB.BASEBOARD_FAB2(SCH_1):P1V8_MCP_CPU1    I45 @BASEBOARD_FAB2_LIB.BASEBOARD_FAB2(SCH_1):PAGE193
   F10    GND @BASEBOARD_FAB2_LIB.BASEBOARD_FAB2(SCH_1):GND    I45 @BASEBOARD_FAB2_LIB.BASEBOARD_FAB2(SCH_1):PAGE193
   F11    GND @BASEBOARD_FAB2_LIB.BASEBOARD_FAB2(SCH_1):GND    I45 @BASEBOARD_FAB2_LIB.BASEBOARD_FAB2(SCH_1):PAGE193
   F12    GND @BASEBOARD_FAB2_LIB.BASEBOARD_FAB2(SCH_1):GND    I45 @BASEBOARD_FAB2_LIB.BASEBOARD_FAB2(SCH_1):PAGE193
   F13    GND @BASEBOARD_FAB2_LIB.BASEBOARD_FAB2(SCH_1):GND    I45 @BASEBOARD_FAB2_LIB.BASEBOARD_FAB2(SCH_1):PAGE193
   F14    GND @BASEBOARD_FAB2_LIB.BASEBOARD_FAB2(SCH_1):GND    I45 @BASEBOARD_FAB2_LIB.BASEBOARD_FAB2(SCH_1):PAGE193
   F15    GND @BASEBOARD_FAB2_LIB.BASEBOARD_FAB2(SCH_1):GND    I45 @BASEBOARD_FAB2_LIB.BASEBOARD_FAB2(SCH_1):PAGE193
   F16    GND @BASEBOARD_FAB2_LIB.BASEBOARD_FAB2(SCH_1):GND    I45 @BASEBOARD_FAB2_LIB.BASEBOARD_FAB2(SCH_1):PAGE193
   F17    GND @BASEBOARD_FAB2_LIB.BASEBOARD_FAB2(SCH_1):GND    I45 @BASEBOARD_FAB2_LIB.BASEBOARD_FAB2(SCH_1):PAGE193
   F18    GND @BASEBOARD_FAB2_LIB.BASEBOARD_FAB2(SCH_1):GND    I45 @BASEBOARD_FAB2_LIB.BASEBOARD_FAB2(SCH_1):PAGE193
   F19    GND @BASEBOARD_FAB2_LIB.BASEBOARD_FAB2(SCH_1):GND    I45 @BASEBOARD_FAB2_LIB.BASEBOARD_FAB2(SCH_1):PAGE193
    F2 P1V8_MCP_CPU1 @BASEBOARD_FAB2_LIB.BASEBOARD_FAB2(SCH_1):P1V8_MCP_CPU1    I45 @BASEBOARD_FAB2_LIB.BASEBOARD_FAB2(SCH_1):PAGE193
   F20    GND @BASEBOARD_FAB2_LIB.BASEBOARD_FAB2(SCH_1):GND    I45 @BASEBOARD_FAB2_LIB.BASEBOARD_FAB2(SCH_1):PAGE193
    F3 P1V8_MCP_CPU1 @BASEBOARD_FAB2_LIB.BASEBOARD_FAB2(SCH_1):P1V8_MCP_CPU1    I45 @BASEBOARD_FAB2_LIB.BASEBOARD_FAB2(SCH_1):PAGE193
    F4    GND @BASEBOARD_FAB2_LIB.BASEBOARD_FAB2(SCH_1):GND    I45 @BASEBOARD_FAB2_LIB.BASEBOARD_FAB2(SCH_1):PAGE193
    F5 CLK_322M_156M_CPU1_OSC_VRM_DN @BASEBOARD_FAB2_LIB.BASEBOARD_FAB2(SCH_1):CLK_322M_156M_CPU1_OSC_VRM_DN    I45 @BASEBOARD_FAB2_LIB.BASEBOARD_FAB2(SCH_1):PAGE193
    F6    GND @BASEBOARD_FAB2_LIB.BASEBOARD_FAB2(SCH_1):GND    I45 @BASEBOARD_FAB2_LIB.BASEBOARD_FAB2(SCH_1):PAGE193
    F7    GND @BASEBOARD_FAB2_LIB.BASEBOARD_FAB2(SCH_1):GND    I45 @BASEBOARD_FAB2_LIB.BASEBOARD_FAB2(SCH_1):PAGE193
    F8    GND @BASEBOARD_FAB2_LIB.BASEBOARD_FAB2(SCH_1):GND    I45 @BASEBOARD_FAB2_LIB.BASEBOARD_FAB2(SCH_1):PAGE193
    F9    GND @BASEBOARD_FAB2_LIB.BASEBOARD_FAB2(SCH_1):GND    I45 @BASEBOARD_FAB2_LIB.BASEBOARD_FAB2(SCH_1):PAGE193

J4G1 SCONN288_H44441004_PIP-SCONN,HA
    79 M_A_MA<0> @BASEBOARD_FAB2_LIB.BASEBOARD_FAB2(SCH_1):M_A_MA(0)     I1 @BASEBOARD_FAB2_LIB.BASEBOARD_FAB2(SCH_1):PAGE43
    72 M_A_MA<1> @BASEBOARD_FAB2_LIB.BASEBOARD_FAB2(SCH_1):M_A_MA(1)     I1 @BASEBOARD_FAB2_LIB.BASEBOARD_FAB2(SCH_1):PAGE43
   225 M_A_MA<10> @BASEBOARD_FAB2_LIB.BASEBOARD_FAB2(SCH_1):M_A_MA(10)     I1 @BASEBOARD_FAB2_LIB.BASEBOARD_FAB2(SCH_1):PAGE43
   210 M_A_MA<11> @BASEBOARD_FAB2_LIB.BASEBOARD_FAB2(SCH_1):M_A_MA(11)     I1 @BASEBOARD_FAB2_LIB.BASEBOARD_FAB2(SCH_1):PAGE43
    65 M_A_MA<12> @BASEBOARD_FAB2_LIB.BASEBOARD_FAB2(SCH_1):M_A_MA(12)     I1 @BASEBOARD_FAB2_LIB.BASEBOARD_FAB2(SCH_1):PAGE43
   232 M_A_MA<13> @BASEBOARD_FAB2_LIB.BASEBOARD_FAB2(SCH_1):M_A_MA(13)     I1 @BASEBOARD_FAB2_LIB.BASEBOARD_FAB2(SCH_1):PAGE43
   228 M_A_MA<14> @BASEBOARD_FAB2_LIB.BASEBOARD_FAB2(SCH_1):M_A_MA(14)     I1 @BASEBOARD_FAB2_LIB.BASEBOARD_FAB2(SCH_1):PAGE43
    86 M_A_MA<15> @BASEBOARD_FAB2_LIB.BASEBOARD_FAB2(SCH_1):M_A_MA(15)     I1 @BASEBOARD_FAB2_LIB.BASEBOARD_FAB2(SCH_1):PAGE43
    82 M_A_MA<16> @BASEBOARD_FAB2_LIB.BASEBOARD_FAB2(SCH_1):M_A_MA(16)     I1 @BASEBOARD_FAB2_LIB.BASEBOARD_FAB2(SCH_1):PAGE43
   234 M_A_MA<17> @BASEBOARD_FAB2_LIB.BASEBOARD_FAB2(SCH_1):M_A_MA(17)     I1 @BASEBOARD_FAB2_LIB.BASEBOARD_FAB2(SCH_1):PAGE43
   216 M_A_MA<2> @BASEBOARD_FAB2_LIB.BASEBOARD_FAB2(SCH_1):M_A_MA(2)     I1 @BASEBOARD_FAB2_LIB.BASEBOARD_FAB2(SCH_1):PAGE43
    71 M_A_MA<3> @BASEBOARD_FAB2_LIB.BASEBOARD_FAB2(SCH_1):M_A_MA(3)     I1 @BASEBOARD_FAB2_LIB.BASEBOARD_FAB2(SCH_1):PAGE43
   214 M_A_MA<4> @BASEBOARD_FAB2_LIB.BASEBOARD_FAB2(SCH_1):M_A_MA(4)     I1 @BASEBOARD_FAB2_LIB.BASEBOARD_FAB2(SCH_1):PAGE43
   213 M_A_MA<5> @BASEBOARD_FAB2_LIB.BASEBOARD_FAB2(SCH_1):M_A_MA(5)     I1 @BASEBOARD_FAB2_LIB.BASEBOARD_FAB2(SCH_1):PAGE43
    69 M_A_MA<6> @BASEBOARD_FAB2_LIB.BASEBOARD_FAB2(SCH_1):M_A_MA(6)     I1 @BASEBOARD_FAB2_LIB.BASEBOARD_FAB2(SCH_1):PAGE43
   211 M_A_MA<7> @BASEBOARD_FAB2_LIB.BASEBOARD_FAB2(SCH_1):M_A_MA(7)     I1 @BASEBOARD_FAB2_LIB.BASEBOARD_FAB2(SCH_1):PAGE43
    68 M_A_MA<8> @BASEBOARD_FAB2_LIB.BASEBOARD_FAB2(SCH_1):M_A_MA(8)     I1 @BASEBOARD_FAB2_LIB.BASEBOARD_FAB2(SCH_1):PAGE43
    66 M_A_MA<9> @BASEBOARD_FAB2_LIB.BASEBOARD_FAB2(SCH_1):M_A_MA(9)     I1 @BASEBOARD_FAB2_LIB.BASEBOARD_FAB2(SCH_1):PAGE43
    62 M_A_ACT_N @BASEBOARD_FAB2_LIB.BASEBOARD_FAB2(SCH_1):M_A_ACT_N     I1 @BASEBOARD_FAB2_LIB.BASEBOARD_FAB2(SCH_1):PAGE43
   208 M_A_ALERT_N @BASEBOARD_FAB2_LIB.BASEBOARD_FAB2(SCH_1):M_A_ALERT_N     I1 @BASEBOARD_FAB2_LIB.BASEBOARD_FAB2(SCH_1):PAGE43
   224 M_A_BA<1> @BASEBOARD_FAB2_LIB.BASEBOARD_FAB2(SCH_1):M_A_BA(1)     I1 @BASEBOARD_FAB2_LIB.BASEBOARD_FAB2(SCH_1):PAGE43
    81 M_A_BA<0> @BASEBOARD_FAB2_LIB.BASEBOARD_FAB2(SCH_1):M_A_BA(0)     I1 @BASEBOARD_FAB2_LIB.BASEBOARD_FAB2(SCH_1):PAGE43
   207 M_A_BG<1> @BASEBOARD_FAB2_LIB.BASEBOARD_FAB2(SCH_1):M_A_BG(1)     I1 @BASEBOARD_FAB2_LIB.BASEBOARD_FAB2(SCH_1):PAGE43
    63 M_A_BG<0> @BASEBOARD_FAB2_LIB.BASEBOARD_FAB2(SCH_1):M_A_BG(0)     I1 @BASEBOARD_FAB2_LIB.BASEBOARD_FAB2(SCH_1):PAGE43
   235 M_A_C<2> @BASEBOARD_FAB2_LIB.BASEBOARD_FAB2(SCH_1):M_A_C(2)     I1 @BASEBOARD_FAB2_LIB.BASEBOARD_FAB2(SCH_1):PAGE43
   199 M_A_ECC<6> @BASEBOARD_FAB2_LIB.BASEBOARD_FAB2(SCH_1):M_A_ECC(6)     I1 @BASEBOARD_FAB2_LIB.BASEBOARD_FAB2(SCH_1):PAGE43
    54 M_A_ECC<7> @BASEBOARD_FAB2_LIB.BASEBOARD_FAB2(SCH_1):M_A_ECC(7)     I1 @BASEBOARD_FAB2_LIB.BASEBOARD_FAB2(SCH_1):PAGE43
   192 M_A_ECC<4> @BASEBOARD_FAB2_LIB.BASEBOARD_FAB2(SCH_1):M_A_ECC(4)     I1 @BASEBOARD_FAB2_LIB.BASEBOARD_FAB2(SCH_1):PAGE43
    47 M_A_ECC<5> @BASEBOARD_FAB2_LIB.BASEBOARD_FAB2(SCH_1):M_A_ECC(5)     I1 @BASEBOARD_FAB2_LIB.BASEBOARD_FAB2(SCH_1):PAGE43
   201 M_A_ECC<2> @BASEBOARD_FAB2_LIB.BASEBOARD_FAB2(SCH_1):M_A_ECC(2)     I1 @BASEBOARD_FAB2_LIB.BASEBOARD_FAB2(SCH_1):PAGE43
    56 M_A_ECC<3> @BASEBOARD_FAB2_LIB.BASEBOARD_FAB2(SCH_1):M_A_ECC(3)     I1 @BASEBOARD_FAB2_LIB.BASEBOARD_FAB2(SCH_1):PAGE43
   194 M_A_ECC<0> @BASEBOARD_FAB2_LIB.BASEBOARD_FAB2(SCH_1):M_A_ECC(0)     I1 @BASEBOARD_FAB2_LIB.BASEBOARD_FAB2(SCH_1):PAGE43
    49 M_A_ECC<1> @BASEBOARD_FAB2_LIB.BASEBOARD_FAB2(SCH_1):M_A_ECC(1)     I1 @BASEBOARD_FAB2_LIB.BASEBOARD_FAB2(SCH_1):PAGE43
    75 M_A_CLK_DN<0> @BASEBOARD_FAB2_LIB.BASEBOARD_FAB2(SCH_1):M_A_CLK_DN(0)     I1 @BASEBOARD_FAB2_LIB.BASEBOARD_FAB2(SCH_1):PAGE43
    74 M_A_CLK_DP<0> @BASEBOARD_FAB2_LIB.BASEBOARD_FAB2(SCH_1):M_A_CLK_DP(0)     I1 @BASEBOARD_FAB2_LIB.BASEBOARD_FAB2(SCH_1):PAGE43
   219 M_A_CLK_DN<1> @BASEBOARD_FAB2_LIB.BASEBOARD_FAB2(SCH_1):M_A_CLK_DN(1)     I1 @BASEBOARD_FAB2_LIB.BASEBOARD_FAB2(SCH_1):PAGE43
   218 M_A_CLK_DP<1> @BASEBOARD_FAB2_LIB.BASEBOARD_FAB2(SCH_1):M_A_CLK_DP(1)     I1 @BASEBOARD_FAB2_LIB.BASEBOARD_FAB2(SCH_1):PAGE43
   203 M_A_CKE<1> @BASEBOARD_FAB2_LIB.BASEBOARD_FAB2(SCH_1):M_A_CKE(1)     I1 @BASEBOARD_FAB2_LIB.BASEBOARD_FAB2(SCH_1):PAGE43
    60 M_A_CKE<0> @BASEBOARD_FAB2_LIB.BASEBOARD_FAB2(SCH_1):M_A_CKE(0)     I1 @BASEBOARD_FAB2_LIB.BASEBOARD_FAB2(SCH_1):PAGE43
   280 M_A_DQ<62> @BASEBOARD_FAB2_LIB.BASEBOARD_FAB2(SCH_1):M_A_DQ(62)     I1 @BASEBOARD_FAB2_LIB.BASEBOARD_FAB2(SCH_1):PAGE43
   135 M_A_DQ<63> @BASEBOARD_FAB2_LIB.BASEBOARD_FAB2(SCH_1):M_A_DQ(63)     I1 @BASEBOARD_FAB2_LIB.BASEBOARD_FAB2(SCH_1):PAGE43
   273 M_A_DQ<60> @BASEBOARD_FAB2_LIB.BASEBOARD_FAB2(SCH_1):M_A_DQ(60)     I1 @BASEBOARD_FAB2_LIB.BASEBOARD_FAB2(SCH_1):PAGE43
   128 M_A_DQ<61> @BASEBOARD_FAB2_LIB.BASEBOARD_FAB2(SCH_1):M_A_DQ(61)     I1 @BASEBOARD_FAB2_LIB.BASEBOARD_FAB2(SCH_1):PAGE43
   282 M_A_DQ<58> @BASEBOARD_FAB2_LIB.BASEBOARD_FAB2(SCH_1):M_A_DQ(58)     I1 @BASEBOARD_FAB2_LIB.BASEBOARD_FAB2(SCH_1):PAGE43
   137 M_A_DQ<59> @BASEBOARD_FAB2_LIB.BASEBOARD_FAB2(SCH_1):M_A_DQ(59)     I1 @BASEBOARD_FAB2_LIB.BASEBOARD_FAB2(SCH_1):PAGE43
   275 M_A_DQ<56> @BASEBOARD_FAB2_LIB.BASEBOARD_FAB2(SCH_1):M_A_DQ(56)     I1 @BASEBOARD_FAB2_LIB.BASEBOARD_FAB2(SCH_1):PAGE43
   130 M_A_DQ<57> @BASEBOARD_FAB2_LIB.BASEBOARD_FAB2(SCH_1):M_A_DQ(57)     I1 @BASEBOARD_FAB2_LIB.BASEBOARD_FAB2(SCH_1):PAGE43
   269 M_A_DQ<54> @BASEBOARD_FAB2_LIB.BASEBOARD_FAB2(SCH_1):M_A_DQ(54)     I1 @BASEBOARD_FAB2_LIB.BASEBOARD_FAB2(SCH_1):PAGE43
   124 M_A_DQ<55> @BASEBOARD_FAB2_LIB.BASEBOARD_FAB2(SCH_1):M_A_DQ(55)     I1 @BASEBOARD_FAB2_LIB.BASEBOARD_FAB2(SCH_1):PAGE43
   262 M_A_DQ<52> @BASEBOARD_FAB2_LIB.BASEBOARD_FAB2(SCH_1):M_A_DQ(52)     I1 @BASEBOARD_FAB2_LIB.BASEBOARD_FAB2(SCH_1):PAGE43
   117 M_A_DQ<53> @BASEBOARD_FAB2_LIB.BASEBOARD_FAB2(SCH_1):M_A_DQ(53)     I1 @BASEBOARD_FAB2_LIB.BASEBOARD_FAB2(SCH_1):PAGE43
   271 M_A_DQ<50> @BASEBOARD_FAB2_LIB.BASEBOARD_FAB2(SCH_1):M_A_DQ(50)     I1 @BASEBOARD_FAB2_LIB.BASEBOARD_FAB2(SCH_1):PAGE43
   126 M_A_DQ<51> @BASEBOARD_FAB2_LIB.BASEBOARD_FAB2(SCH_1):M_A_DQ(51)     I1 @BASEBOARD_FAB2_LIB.BASEBOARD_FAB2(SCH_1):PAGE43
   264 M_A_DQ<48> @BASEBOARD_FAB2_LIB.BASEBOARD_FAB2(SCH_1):M_A_DQ(48)     I1 @BASEBOARD_FAB2_LIB.BASEBOARD_FAB2(SCH_1):PAGE43
   119 M_A_DQ<49> @BASEBOARD_FAB2_LIB.BASEBOARD_FAB2(SCH_1):M_A_DQ(49)     I1 @BASEBOARD_FAB2_LIB.BASEBOARD_FAB2(SCH_1):PAGE43
   258 M_A_DQ<46> @BASEBOARD_FAB2_LIB.BASEBOARD_FAB2(SCH_1):M_A_DQ(46)     I1 @BASEBOARD_FAB2_LIB.BASEBOARD_FAB2(SCH_1):PAGE43
   113 M_A_DQ<47> @BASEBOARD_FAB2_LIB.BASEBOARD_FAB2(SCH_1):M_A_DQ(47)     I1 @BASEBOARD_FAB2_LIB.BASEBOARD_FAB2(SCH_1):PAGE43
   251 M_A_DQ<44> @BASEBOARD_FAB2_LIB.BASEBOARD_FAB2(SCH_1):M_A_DQ(44)     I1 @BASEBOARD_FAB2_LIB.BASEBOARD_FAB2(SCH_1):PAGE43
   106 M_A_DQ<45> @BASEBOARD_FAB2_LIB.BASEBOARD_FAB2(SCH_1):M_A_DQ(45)     I1 @BASEBOARD_FAB2_LIB.BASEBOARD_FAB2(SCH_1):PAGE43
   260 M_A_DQ<42> @BASEBOARD_FAB2_LIB.BASEBOARD_FAB2(SCH_1):M_A_DQ(42)     I1 @BASEBOARD_FAB2_LIB.BASEBOARD_FAB2(SCH_1):PAGE43
   115 M_A_DQ<43> @BASEBOARD_FAB2_LIB.BASEBOARD_FAB2(SCH_1):M_A_DQ(43)     I1 @BASEBOARD_FAB2_LIB.BASEBOARD_FAB2(SCH_1):PAGE43
   253 M_A_DQ<40> @BASEBOARD_FAB2_LIB.BASEBOARD_FAB2(SCH_1):M_A_DQ(40)     I1 @BASEBOARD_FAB2_LIB.BASEBOARD_FAB2(SCH_1):PAGE43
   108 M_A_DQ<41> @BASEBOARD_FAB2_LIB.BASEBOARD_FAB2(SCH_1):M_A_DQ(41)     I1 @BASEBOARD_FAB2_LIB.BASEBOARD_FAB2(SCH_1):PAGE43
   247 M_A_DQ<38> @BASEBOARD_FAB2_LIB.BASEBOARD_FAB2(SCH_1):M_A_DQ(38)     I1 @BASEBOARD_FAB2_LIB.BASEBOARD_FAB2(SCH_1):PAGE43
   102 M_A_DQ<39> @BASEBOARD_FAB2_LIB.BASEBOARD_FAB2(SCH_1):M_A_DQ(39)     I1 @BASEBOARD_FAB2_LIB.BASEBOARD_FAB2(SCH_1):PAGE43
   240 M_A_DQ<36> @BASEBOARD_FAB2_LIB.BASEBOARD_FAB2(SCH_1):M_A_DQ(36)     I1 @BASEBOARD_FAB2_LIB.BASEBOARD_FAB2(SCH_1):PAGE43
    95 M_A_DQ<37> @BASEBOARD_FAB2_LIB.BASEBOARD_FAB2(SCH_1):M_A_DQ(37)     I1 @BASEBOARD_FAB2_LIB.BASEBOARD_FAB2(SCH_1):PAGE43
   249 M_A_DQ<34> @BASEBOARD_FAB2_LIB.BASEBOARD_FAB2(SCH_1):M_A_DQ(34)     I1 @BASEBOARD_FAB2_LIB.BASEBOARD_FAB2(SCH_1):PAGE43
   104 M_A_DQ<35> @BASEBOARD_FAB2_LIB.BASEBOARD_FAB2(SCH_1):M_A_DQ(35)     I1 @BASEBOARD_FAB2_LIB.BASEBOARD_FAB2(SCH_1):PAGE43
   242 M_A_DQ<32> @BASEBOARD_FAB2_LIB.BASEBOARD_FAB2(SCH_1):M_A_DQ(32)     I1 @BASEBOARD_FAB2_LIB.BASEBOARD_FAB2(SCH_1):PAGE43
    97 M_A_DQ<33> @BASEBOARD_FAB2_LIB.BASEBOARD_FAB2(SCH_1):M_A_DQ(33)     I1 @BASEBOARD_FAB2_LIB.BASEBOARD_FAB2(SCH_1):PAGE43
   188 M_A_DQ<30> @BASEBOARD_FAB2_LIB.BASEBOARD_FAB2(SCH_1):M_A_DQ(30)     I1 @BASEBOARD_FAB2_LIB.BASEBOARD_FAB2(SCH_1):PAGE43
    43 M_A_DQ<31> @BASEBOARD_FAB2_LIB.BASEBOARD_FAB2(SCH_1):M_A_DQ(31)     I1 @BASEBOARD_FAB2_LIB.BASEBOARD_FAB2(SCH_1):PAGE43
   181 M_A_DQ<28> @BASEBOARD_FAB2_LIB.BASEBOARD_FAB2(SCH_1):M_A_DQ(28)     I1 @BASEBOARD_FAB2_LIB.BASEBOARD_FAB2(SCH_1):PAGE43
    36 M_A_DQ<29> @BASEBOARD_FAB2_LIB.BASEBOARD_FAB2(SCH_1):M_A_DQ(29)     I1 @BASEBOARD_FAB2_LIB.BASEBOARD_FAB2(SCH_1):PAGE43
   190 M_A_DQ<26> @BASEBOARD_FAB2_LIB.BASEBOARD_FAB2(SCH_1):M_A_DQ(26)     I1 @BASEBOARD_FAB2_LIB.BASEBOARD_FAB2(SCH_1):PAGE43
    45 M_A_DQ<27> @BASEBOARD_FAB2_LIB.BASEBOARD_FAB2(SCH_1):M_A_DQ(27)     I1 @BASEBOARD_FAB2_LIB.BASEBOARD_FAB2(SCH_1):PAGE43
   183 M_A_DQ<24> @BASEBOARD_FAB2_LIB.BASEBOARD_FAB2(SCH_1):M_A_DQ(24)     I1 @BASEBOARD_FAB2_LIB.BASEBOARD_FAB2(SCH_1):PAGE43
    38 M_A_DQ<25> @BASEBOARD_FAB2_LIB.BASEBOARD_FAB2(SCH_1):M_A_DQ(25)     I1 @BASEBOARD_FAB2_LIB.BASEBOARD_FAB2(SCH_1):PAGE43
   177 M_A_DQ<22> @BASEBOARD_FAB2_LIB.BASEBOARD_FAB2(SCH_1):M_A_DQ(22)     I1 @BASEBOARD_FAB2_LIB.BASEBOARD_FAB2(SCH_1):PAGE43
    32 M_A_DQ<23> @BASEBOARD_FAB2_LIB.BASEBOARD_FAB2(SCH_1):M_A_DQ(23)     I1 @BASEBOARD_FAB2_LIB.BASEBOARD_FAB2(SCH_1):PAGE43
   170 M_A_DQ<20> @BASEBOARD_FAB2_LIB.BASEBOARD_FAB2(SCH_1):M_A_DQ(20)     I1 @BASEBOARD_FAB2_LIB.BASEBOARD_FAB2(SCH_1):PAGE43
    25 M_A_DQ<21> @BASEBOARD_FAB2_LIB.BASEBOARD_FAB2(SCH_1):M_A_DQ(21)     I1 @BASEBOARD_FAB2_LIB.BASEBOARD_FAB2(SCH_1):PAGE43
   179 M_A_DQ<18> @BASEBOARD_FAB2_LIB.BASEBOARD_FAB2(SCH_1):M_A_DQ(18)     I1 @BASEBOARD_FAB2_LIB.BASEBOARD_FAB2(SCH_1):PAGE43
    34 M_A_DQ<19> @BASEBOARD_FAB2_LIB.BASEBOARD_FAB2(SCH_1):M_A_DQ(19)     I1 @BASEBOARD_FAB2_LIB.BASEBOARD_FAB2(SCH_1):PAGE43
   172 M_A_DQ<16> @BASEBOARD_FAB2_LIB.BASEBOARD_FAB2(SCH_1):M_A_DQ(16)     I1 @BASEBOARD_FAB2_LIB.BASEBOARD_FAB2(SCH_1):PAGE43
    27 M_A_DQ<17> @BASEBOARD_FAB2_LIB.BASEBOARD_FAB2(SCH_1):M_A_DQ(17)     I1 @BASEBOARD_FAB2_LIB.BASEBOARD_FAB2(SCH_1):PAGE43
   166 M_A_DQ<14> @BASEBOARD_FAB2_LIB.BASEBOARD_FAB2(SCH_1):M_A_DQ(14)     I1 @BASEBOARD_FAB2_LIB.BASEBOARD_FAB2(SCH_1):PAGE43
    21 M_A_DQ<15> @BASEBOARD_FAB2_LIB.BASEBOARD_FAB2(SCH_1):M_A_DQ(15)     I1 @BASEBOARD_FAB2_LIB.BASEBOARD_FAB2(SCH_1):PAGE43
   159 M_A_DQ<12> @BASEBOARD_FAB2_LIB.BASEBOARD_FAB2(SCH_1):M_A_DQ(12)     I1 @BASEBOARD_FAB2_LIB.BASEBOARD_FAB2(SCH_1):PAGE43
    14 M_A_DQ<13> @BASEBOARD_FAB2_LIB.BASEBOARD_FAB2(SCH_1):M_A_DQ(13)     I1 @BASEBOARD_FAB2_LIB.BASEBOARD_FAB2(SCH_1):PAGE43
   168 M_A_DQ<10> @BASEBOARD_FAB2_LIB.BASEBOARD_FAB2(SCH_1):M_A_DQ(10)     I1 @BASEBOARD_FAB2_LIB.BASEBOARD_FAB2(SCH_1):PAGE43
    23 M_A_DQ<11> @BASEBOARD_FAB2_LIB.BASEBOARD_FAB2(SCH_1):M_A_DQ(11)     I1 @BASEBOARD_FAB2_LIB.BASEBOARD_FAB2(SCH_1):PAGE43
   161 M_A_DQ<8> @BASEBOARD_FAB2_LIB.BASEBOARD_FAB2(SCH_1):M_A_DQ(8)     I1 @BASEBOARD_FAB2_LIB.BASEBOARD_FAB2(SCH_1):PAGE43
    16 M_A_DQ<9> @BASEBOARD_FAB2_LIB.BASEBOARD_FAB2(SCH_1):M_A_DQ(9)     I1 @BASEBOARD_FAB2_LIB.BASEBOARD_FAB2(SCH_1):PAGE43
   155 M_A_DQ<6> @BASEBOARD_FAB2_LIB.BASEBOARD_FAB2(SCH_1):M_A_DQ(6)     I1 @BASEBOARD_FAB2_LIB.BASEBOARD_FAB2(SCH_1):PAGE43
    10 M_A_DQ<7> @BASEBOARD_FAB2_LIB.BASEBOARD_FAB2(SCH_1):M_A_DQ(7)     I1 @BASEBOARD_FAB2_LIB.BASEBOARD_FAB2(SCH_1):PAGE43
   148 M_A_DQ<4> @BASEBOARD_FAB2_LIB.BASEBOARD_FAB2(SCH_1):M_A_DQ(4)     I1 @BASEBOARD_FAB2_LIB.BASEBOARD_FAB2(SCH_1):PAGE43
     3 M_A_DQ<5> @BASEBOARD_FAB2_LIB.BASEBOARD_FAB2(SCH_1):M_A_DQ(5)     I1 @BASEBOARD_FAB2_LIB.BASEBOARD_FAB2(SCH_1):PAGE43
   157 M_A_DQ<2> @BASEBOARD_FAB2_LIB.BASEBOARD_FAB2(SCH_1):M_A_DQ(2)     I1 @BASEBOARD_FAB2_LIB.BASEBOARD_FAB2(SCH_1):PAGE43
    12 M_A_DQ<3> @BASEBOARD_FAB2_LIB.BASEBOARD_FAB2(SCH_1):M_A_DQ(3)     I1 @BASEBOARD_FAB2_LIB.BASEBOARD_FAB2(SCH_1):PAGE43
   150 M_A_DQ<0> @BASEBOARD_FAB2_LIB.BASEBOARD_FAB2(SCH_1):M_A_DQ(0)     I1 @BASEBOARD_FAB2_LIB.BASEBOARD_FAB2(SCH_1):PAGE43
     5 M_A_DQ<1> @BASEBOARD_FAB2_LIB.BASEBOARD_FAB2(SCH_1):M_A_DQ(1)     I1 @BASEBOARD_FAB2_LIB.BASEBOARD_FAB2(SCH_1):PAGE43
    78 FM_DIMM_EVENT_COD_N @BASEBOARD_FAB2_LIB.BASEBOARD_FAB2(SCH_1):FM_DIMM_EVENT_COD_N     I1 @BASEBOARD_FAB2_LIB.BASEBOARD_FAB2(SCH_1):PAGE43
    91 M_A_ODT<1> @BASEBOARD_FAB2_LIB.BASEBOARD_FAB2(SCH_1):M_A_ODT(1)     I1 @BASEBOARD_FAB2_LIB.BASEBOARD_FAB2(SCH_1):PAGE43
    87 M_A_ODT<0> @BASEBOARD_FAB2_LIB.BASEBOARD_FAB2(SCH_1):M_A_ODT(0)     I1 @BASEBOARD_FAB2_LIB.BASEBOARD_FAB2(SCH_1):PAGE43
   222 M_A_PAR @BASEBOARD_FAB2_LIB.BASEBOARD_FAB2(SCH_1):M_A_PAR     I1 @BASEBOARD_FAB2_LIB.BASEBOARD_FAB2(SCH_1):PAGE43
    58 M_ABC_RST_N @BASEBOARD_FAB2_LIB.BASEBOARD_FAB2(SCH_1):M_ABC_RST_N     I1 @BASEBOARD_FAB2_LIB.BASEBOARD_FAB2(SCH_1):PAGE43
   144 TP_CH_A_DIMM_A0_RFU_2 @BASEBOARD_FAB2_LIB.BASEBOARD_FAB2(SCH_1):TP_CH_A_DIMM_A0_RFU_2     I1 @BASEBOARD_FAB2_LIB.BASEBOARD_FAB2(SCH_1):PAGE43
   227 TP_CH_A_DIMM_A0_RFU_1 @BASEBOARD_FAB2_LIB.BASEBOARD_FAB2(SCH_1):TP_CH_A_DIMM_A0_RFU_1     I1 @BASEBOARD_FAB2_LIB.BASEBOARD_FAB2(SCH_1):PAGE43
   205 TP_CH_A_DIMM_A0_RFU_0 @BASEBOARD_FAB2_LIB.BASEBOARD_FAB2(SCH_1):TP_CH_A_DIMM_A0_RFU_0     I1 @BASEBOARD_FAB2_LIB.BASEBOARD_FAB2(SCH_1):PAGE43
    84 M_A_CS_N<0> @BASEBOARD_FAB2_LIB.BASEBOARD_FAB2(SCH_1):M_A_CS_N(0)     I1 @BASEBOARD_FAB2_LIB.BASEBOARD_FAB2(SCH_1):PAGE43
    89 M_A_CS_N<1> @BASEBOARD_FAB2_LIB.BASEBOARD_FAB2(SCH_1):M_A_CS_N(1)     I1 @BASEBOARD_FAB2_LIB.BASEBOARD_FAB2(SCH_1):PAGE43
    93 M_A_CS_N<2> @BASEBOARD_FAB2_LIB.BASEBOARD_FAB2(SCH_1):M_A_CS_N(2)     I1 @BASEBOARD_FAB2_LIB.BASEBOARD_FAB2(SCH_1):PAGE43
   237 M_A_CS_N<3> @BASEBOARD_FAB2_LIB.BASEBOARD_FAB2(SCH_1):M_A_CS_N(3)     I1 @BASEBOARD_FAB2_LIB.BASEBOARD_FAB2(SCH_1):PAGE43
   238    GND @BASEBOARD_FAB2_LIB.BASEBOARD_FAB2(SCH_1):GND     I1 @BASEBOARD_FAB2_LIB.BASEBOARD_FAB2(SCH_1):PAGE43
   140    GND @BASEBOARD_FAB2_LIB.BASEBOARD_FAB2(SCH_1):GND     I1 @BASEBOARD_FAB2_LIB.BASEBOARD_FAB2(SCH_1):PAGE43
   139    GND @BASEBOARD_FAB2_LIB.BASEBOARD_FAB2(SCH_1):GND     I1 @BASEBOARD_FAB2_LIB.BASEBOARD_FAB2(SCH_1):PAGE43
   230 FM_ADR_COMPLETE_ABC_N @BASEBOARD_FAB2_LIB.BASEBOARD_FAB2(SCH_1):FM_ADR_COMPLETE_ABC_N     I1 @BASEBOARD_FAB2_LIB.BASEBOARD_FAB2(SCH_1):PAGE43
   141 SMB_DDR_ABC_VPP_SCL @BASEBOARD_FAB2_LIB.BASEBOARD_FAB2(SCH_1):SMB_DDR_ABC_VPP_SCL     I1 @BASEBOARD_FAB2_LIB.BASEBOARD_FAB2(SCH_1):PAGE43
   285 SMB_DDR_ABC_VPP_SDA @BASEBOARD_FAB2_LIB.BASEBOARD_FAB2(SCH_1):SMB_DDR_ABC_VPP_SDA     I1 @BASEBOARD_FAB2_LIB.BASEBOARD_FAB2(SCH_1):PAGE43
   284 PVPP_ABC @BASEBOARD_FAB2_LIB.BASEBOARD_FAB2(SCH_1):PVPP_ABC     I1 @BASEBOARD_FAB2_LIB.BASEBOARD_FAB2(SCH_1):PAGE43
   146 M_A_VREF @BASEBOARD_FAB2_LIB.BASEBOARD_FAB2(SCH_1):M_A_VREF     I1 @BASEBOARD_FAB2_LIB.BASEBOARD_FAB2(SCH_1):PAGE43
   152 M_A_DQS_DN<0> @BASEBOARD_FAB2_LIB.BASEBOARD_FAB2(SCH_1):M_A_DQS_DN(0)     I2 @BASEBOARD_FAB2_LIB.BASEBOARD_FAB2(SCH_1):PAGE43
   153 M_A_DQS_DP<0> @BASEBOARD_FAB2_LIB.BASEBOARD_FAB2(SCH_1):M_A_DQS_DP(0)     I2 @BASEBOARD_FAB2_LIB.BASEBOARD_FAB2(SCH_1):PAGE43
    19 M_A_DQS_DN<10> @BASEBOARD_FAB2_LIB.BASEBOARD_FAB2(SCH_1):M_A_DQS_DN(10)     I2 @BASEBOARD_FAB2_LIB.BASEBOARD_FAB2(SCH_1):PAGE43
    18 M_A_DQS_DP<10> @BASEBOARD_FAB2_LIB.BASEBOARD_FAB2(SCH_1):M_A_DQS_DP(10)     I2 @BASEBOARD_FAB2_LIB.BASEBOARD_FAB2(SCH_1):PAGE43
    30 M_A_DQS_DN<11> @BASEBOARD_FAB2_LIB.BASEBOARD_FAB2(SCH_1):M_A_DQS_DN(11)     I2 @BASEBOARD_FAB2_LIB.BASEBOARD_FAB2(SCH_1):PAGE43
    29 M_A_DQS_DP<11> @BASEBOARD_FAB2_LIB.BASEBOARD_FAB2(SCH_1):M_A_DQS_DP(11)     I2 @BASEBOARD_FAB2_LIB.BASEBOARD_FAB2(SCH_1):PAGE43
    41 M_A_DQS_DN<12> @BASEBOARD_FAB2_LIB.BASEBOARD_FAB2(SCH_1):M_A_DQS_DN(12)     I2 @BASEBOARD_FAB2_LIB.BASEBOARD_FAB2(SCH_1):PAGE43
    40 M_A_DQS_DP<12> @BASEBOARD_FAB2_LIB.BASEBOARD_FAB2(SCH_1):M_A_DQS_DP(12)     I2 @BASEBOARD_FAB2_LIB.BASEBOARD_FAB2(SCH_1):PAGE43
   100 M_A_DQS_DN<13> @BASEBOARD_FAB2_LIB.BASEBOARD_FAB2(SCH_1):M_A_DQS_DN(13)     I2 @BASEBOARD_FAB2_LIB.BASEBOARD_FAB2(SCH_1):PAGE43
    99 M_A_DQS_DP<13> @BASEBOARD_FAB2_LIB.BASEBOARD_FAB2(SCH_1):M_A_DQS_DP(13)     I2 @BASEBOARD_FAB2_LIB.BASEBOARD_FAB2(SCH_1):PAGE43
   111 M_A_DQS_DN<14> @BASEBOARD_FAB2_LIB.BASEBOARD_FAB2(SCH_1):M_A_DQS_DN(14)     I2 @BASEBOARD_FAB2_LIB.BASEBOARD_FAB2(SCH_1):PAGE43
   110 M_A_DQS_DP<14> @BASEBOARD_FAB2_LIB.BASEBOARD_FAB2(SCH_1):M_A_DQS_DP(14)     I2 @BASEBOARD_FAB2_LIB.BASEBOARD_FAB2(SCH_1):PAGE43
   122 M_A_DQS_DN<15> @BASEBOARD_FAB2_LIB.BASEBOARD_FAB2(SCH_1):M_A_DQS_DN(15)     I2 @BASEBOARD_FAB2_LIB.BASEBOARD_FAB2(SCH_1):PAGE43
   121 M_A_DQS_DP<15> @BASEBOARD_FAB2_LIB.BASEBOARD_FAB2(SCH_1):M_A_DQS_DP(15)     I2 @BASEBOARD_FAB2_LIB.BASEBOARD_FAB2(SCH_1):PAGE43
   133 M_A_DQS_DN<16> @BASEBOARD_FAB2_LIB.BASEBOARD_FAB2(SCH_1):M_A_DQS_DN(16)     I2 @BASEBOARD_FAB2_LIB.BASEBOARD_FAB2(SCH_1):PAGE43
   132 M_A_DQS_DP<16> @BASEBOARD_FAB2_LIB.BASEBOARD_FAB2(SCH_1):M_A_DQS_DP(16)     I2 @BASEBOARD_FAB2_LIB.BASEBOARD_FAB2(SCH_1):PAGE43
    52 M_A_DQS_DN<17> @BASEBOARD_FAB2_LIB.BASEBOARD_FAB2(SCH_1):M_A_DQS_DN(17)     I2 @BASEBOARD_FAB2_LIB.BASEBOARD_FAB2(SCH_1):PAGE43
    51 M_A_DQS_DP<17> @BASEBOARD_FAB2_LIB.BASEBOARD_FAB2(SCH_1):M_A_DQS_DP(17)     I2 @BASEBOARD_FAB2_LIB.BASEBOARD_FAB2(SCH_1):PAGE43
   163 M_A_DQS_DN<1> @BASEBOARD_FAB2_LIB.BASEBOARD_FAB2(SCH_1):M_A_DQS_DN(1)     I2 @BASEBOARD_FAB2_LIB.BASEBOARD_FAB2(SCH_1):PAGE43
   164 M_A_DQS_DP<1> @BASEBOARD_FAB2_LIB.BASEBOARD_FAB2(SCH_1):M_A_DQS_DP(1)     I2 @BASEBOARD_FAB2_LIB.BASEBOARD_FAB2(SCH_1):PAGE43
   174 M_A_DQS_DN<2> @BASEBOARD_FAB2_LIB.BASEBOARD_FAB2(SCH_1):M_A_DQS_DN(2)     I2 @BASEBOARD_FAB2_LIB.BASEBOARD_FAB2(SCH_1):PAGE43
   175 M_A_DQS_DP<2> @BASEBOARD_FAB2_LIB.BASEBOARD_FAB2(SCH_1):M_A_DQS_DP(2)     I2 @BASEBOARD_FAB2_LIB.BASEBOARD_FAB2(SCH_1):PAGE43
   185 M_A_DQS_DN<3> @BASEBOARD_FAB2_LIB.BASEBOARD_FAB2(SCH_1):M_A_DQS_DN(3)     I2 @BASEBOARD_FAB2_LIB.BASEBOARD_FAB2(SCH_1):PAGE43
   186 M_A_DQS_DP<3> @BASEBOARD_FAB2_LIB.BASEBOARD_FAB2(SCH_1):M_A_DQS_DP(3)     I2 @BASEBOARD_FAB2_LIB.BASEBOARD_FAB2(SCH_1):PAGE43
   244 M_A_DQS_DN<4> @BASEBOARD_FAB2_LIB.BASEBOARD_FAB2(SCH_1):M_A_DQS_DN(4)     I2 @BASEBOARD_FAB2_LIB.BASEBOARD_FAB2(SCH_1):PAGE43
   245 M_A_DQS_DP<4> @BASEBOARD_FAB2_LIB.BASEBOARD_FAB2(SCH_1):M_A_DQS_DP(4)     I2 @BASEBOARD_FAB2_LIB.BASEBOARD_FAB2(SCH_1):PAGE43
   255 M_A_DQS_DN<5> @BASEBOARD_FAB2_LIB.BASEBOARD_FAB2(SCH_1):M_A_DQS_DN(5)     I2 @BASEBOARD_FAB2_LIB.BASEBOARD_FAB2(SCH_1):PAGE43
   256 M_A_DQS_DP<5> @BASEBOARD_FAB2_LIB.BASEBOARD_FAB2(SCH_1):M_A_DQS_DP(5)     I2 @BASEBOARD_FAB2_LIB.BASEBOARD_FAB2(SCH_1):PAGE43
   266 M_A_DQS_DN<6> @BASEBOARD_FAB2_LIB.BASEBOARD_FAB2(SCH_1):M_A_DQS_DN(6)     I2 @BASEBOARD_FAB2_LIB.BASEBOARD_FAB2(SCH_1):PAGE43
   267 M_A_DQS_DP<6> @BASEBOARD_FAB2_LIB.BASEBOARD_FAB2(SCH_1):M_A_DQS_DP(6)     I2 @BASEBOARD_FAB2_LIB.BASEBOARD_FAB2(SCH_1):PAGE43
   277 M_A_DQS_DN<7> @BASEBOARD_FAB2_LIB.BASEBOARD_FAB2(SCH_1):M_A_DQS_DN(7)     I2 @BASEBOARD_FAB2_LIB.BASEBOARD_FAB2(SCH_1):PAGE43
   278 M_A_DQS_DP<7> @BASEBOARD_FAB2_LIB.BASEBOARD_FAB2(SCH_1):M_A_DQS_DP(7)     I2 @BASEBOARD_FAB2_LIB.BASEBOARD_FAB2(SCH_1):PAGE43
   196 M_A_DQS_DN<8> @BASEBOARD_FAB2_LIB.BASEBOARD_FAB2(SCH_1):M_A_DQS_DN(8)     I2 @BASEBOARD_FAB2_LIB.BASEBOARD_FAB2(SCH_1):PAGE43
   197 M_A_DQS_DP<8> @BASEBOARD_FAB2_LIB.BASEBOARD_FAB2(SCH_1):M_A_DQS_DP(8)     I2 @BASEBOARD_FAB2_LIB.BASEBOARD_FAB2(SCH_1):PAGE43
     8 M_A_DQS_DN<9> @BASEBOARD_FAB2_LIB.BASEBOARD_FAB2(SCH_1):M_A_DQS_DN(9)     I2 @BASEBOARD_FAB2_LIB.BASEBOARD_FAB2(SCH_1):PAGE43
     7 M_A_DQS_DP<9> @BASEBOARD_FAB2_LIB.BASEBOARD_FAB2(SCH_1):M_A_DQS_DP(9)     I2 @BASEBOARD_FAB2_LIB.BASEBOARD_FAB2(SCH_1):PAGE43
     2    GND @BASEBOARD_FAB2_LIB.BASEBOARD_FAB2(SCH_1):GND   I259 @BASEBOARD_FAB2_LIB.BASEBOARD_FAB2(SCH_1):PAGE43
     4    GND @BASEBOARD_FAB2_LIB.BASEBOARD_FAB2(SCH_1):GND   I259 @BASEBOARD_FAB2_LIB.BASEBOARD_FAB2(SCH_1):PAGE43
     6    GND @BASEBOARD_FAB2_LIB.BASEBOARD_FAB2(SCH_1):GND   I259 @BASEBOARD_FAB2_LIB.BASEBOARD_FAB2(SCH_1):PAGE43
     9    GND @BASEBOARD_FAB2_LIB.BASEBOARD_FAB2(SCH_1):GND   I259 @BASEBOARD_FAB2_LIB.BASEBOARD_FAB2(SCH_1):PAGE43
    11    GND @BASEBOARD_FAB2_LIB.BASEBOARD_FAB2(SCH_1):GND   I259 @BASEBOARD_FAB2_LIB.BASEBOARD_FAB2(SCH_1):PAGE43
    13    GND @BASEBOARD_FAB2_LIB.BASEBOARD_FAB2(SCH_1):GND   I259 @BASEBOARD_FAB2_LIB.BASEBOARD_FAB2(SCH_1):PAGE43
    15    GND @BASEBOARD_FAB2_LIB.BASEBOARD_FAB2(SCH_1):GND   I259 @BASEBOARD_FAB2_LIB.BASEBOARD_FAB2(SCH_1):PAGE43
    17    GND @BASEBOARD_FAB2_LIB.BASEBOARD_FAB2(SCH_1):GND   I259 @BASEBOARD_FAB2_LIB.BASEBOARD_FAB2(SCH_1):PAGE43
    20    GND @BASEBOARD_FAB2_LIB.BASEBOARD_FAB2(SCH_1):GND   I259 @BASEBOARD_FAB2_LIB.BASEBOARD_FAB2(SCH_1):PAGE43
    22    GND @BASEBOARD_FAB2_LIB.BASEBOARD_FAB2(SCH_1):GND   I259 @BASEBOARD_FAB2_LIB.BASEBOARD_FAB2(SCH_1):PAGE43
    24    GND @BASEBOARD_FAB2_LIB.BASEBOARD_FAB2(SCH_1):GND   I259 @BASEBOARD_FAB2_LIB.BASEBOARD_FAB2(SCH_1):PAGE43
    26    GND @BASEBOARD_FAB2_LIB.BASEBOARD_FAB2(SCH_1):GND   I259 @BASEBOARD_FAB2_LIB.BASEBOARD_FAB2(SCH_1):PAGE43
    28    GND @BASEBOARD_FAB2_LIB.BASEBOARD_FAB2(SCH_1):GND   I259 @BASEBOARD_FAB2_LIB.BASEBOARD_FAB2(SCH_1):PAGE43
    31    GND @BASEBOARD_FAB2_LIB.BASEBOARD_FAB2(SCH_1):GND   I259 @BASEBOARD_FAB2_LIB.BASEBOARD_FAB2(SCH_1):PAGE43
    33    GND @BASEBOARD_FAB2_LIB.BASEBOARD_FAB2(SCH_1):GND   I259 @BASEBOARD_FAB2_LIB.BASEBOARD_FAB2(SCH_1):PAGE43
    35    GND @BASEBOARD_FAB2_LIB.BASEBOARD_FAB2(SCH_1):GND   I259 @BASEBOARD_FAB2_LIB.BASEBOARD_FAB2(SCH_1):PAGE43
    37    GND @BASEBOARD_FAB2_LIB.BASEBOARD_FAB2(SCH_1):GND   I259 @BASEBOARD_FAB2_LIB.BASEBOARD_FAB2(SCH_1):PAGE43
    39    GND @BASEBOARD_FAB2_LIB.BASEBOARD_FAB2(SCH_1):GND   I259 @BASEBOARD_FAB2_LIB.BASEBOARD_FAB2(SCH_1):PAGE43
    42    GND @BASEBOARD_FAB2_LIB.BASEBOARD_FAB2(SCH_1):GND   I259 @BASEBOARD_FAB2_LIB.BASEBOARD_FAB2(SCH_1):PAGE43
    44    GND @BASEBOARD_FAB2_LIB.BASEBOARD_FAB2(SCH_1):GND   I259 @BASEBOARD_FAB2_LIB.BASEBOARD_FAB2(SCH_1):PAGE43
    46    GND @BASEBOARD_FAB2_LIB.BASEBOARD_FAB2(SCH_1):GND   I259 @BASEBOARD_FAB2_LIB.BASEBOARD_FAB2(SCH_1):PAGE43
    48    GND @BASEBOARD_FAB2_LIB.BASEBOARD_FAB2(SCH_1):GND   I259 @BASEBOARD_FAB2_LIB.BASEBOARD_FAB2(SCH_1):PAGE43
    50    GND @BASEBOARD_FAB2_LIB.BASEBOARD_FAB2(SCH_1):GND   I259 @BASEBOARD_FAB2_LIB.BASEBOARD_FAB2(SCH_1):PAGE43
    53    GND @BASEBOARD_FAB2_LIB.BASEBOARD_FAB2(SCH_1):GND   I259 @BASEBOARD_FAB2_LIB.BASEBOARD_FAB2(SCH_1):PAGE43
    55    GND @BASEBOARD_FAB2_LIB.BASEBOARD_FAB2(SCH_1):GND   I259 @BASEBOARD_FAB2_LIB.BASEBOARD_FAB2(SCH_1):PAGE43
    57    GND @BASEBOARD_FAB2_LIB.BASEBOARD_FAB2(SCH_1):GND   I259 @BASEBOARD_FAB2_LIB.BASEBOARD_FAB2(SCH_1):PAGE43
    94    GND @BASEBOARD_FAB2_LIB.BASEBOARD_FAB2(SCH_1):GND   I259 @BASEBOARD_FAB2_LIB.BASEBOARD_FAB2(SCH_1):PAGE43
    96    GND @BASEBOARD_FAB2_LIB.BASEBOARD_FAB2(SCH_1):GND   I259 @BASEBOARD_FAB2_LIB.BASEBOARD_FAB2(SCH_1):PAGE43
    98    GND @BASEBOARD_FAB2_LIB.BASEBOARD_FAB2(SCH_1):GND   I259 @BASEBOARD_FAB2_LIB.BASEBOARD_FAB2(SCH_1):PAGE43
   101    GND @BASEBOARD_FAB2_LIB.BASEBOARD_FAB2(SCH_1):GND   I259 @BASEBOARD_FAB2_LIB.BASEBOARD_FAB2(SCH_1):PAGE43
   103    GND @BASEBOARD_FAB2_LIB.BASEBOARD_FAB2(SCH_1):GND   I259 @BASEBOARD_FAB2_LIB.BASEBOARD_FAB2(SCH_1):PAGE43
   105    GND @BASEBOARD_FAB2_LIB.BASEBOARD_FAB2(SCH_1):GND   I259 @BASEBOARD_FAB2_LIB.BASEBOARD_FAB2(SCH_1):PAGE43
   107    GND @BASEBOARD_FAB2_LIB.BASEBOARD_FAB2(SCH_1):GND   I259 @BASEBOARD_FAB2_LIB.BASEBOARD_FAB2(SCH_1):PAGE43
   109    GND @BASEBOARD_FAB2_LIB.BASEBOARD_FAB2(SCH_1):GND   I259 @BASEBOARD_FAB2_LIB.BASEBOARD_FAB2(SCH_1):PAGE43
   112    GND @BASEBOARD_FAB2_LIB.BASEBOARD_FAB2(SCH_1):GND   I259 @BASEBOARD_FAB2_LIB.BASEBOARD_FAB2(SCH_1):PAGE43
   114    GND @BASEBOARD_FAB2_LIB.BASEBOARD_FAB2(SCH_1):GND   I259 @BASEBOARD_FAB2_LIB.BASEBOARD_FAB2(SCH_1):PAGE43
   116    GND @BASEBOARD_FAB2_LIB.BASEBOARD_FAB2(SCH_1):GND   I259 @BASEBOARD_FAB2_LIB.BASEBOARD_FAB2(SCH_1):PAGE43
   118    GND @BASEBOARD_FAB2_LIB.BASEBOARD_FAB2(SCH_1):GND   I259 @BASEBOARD_FAB2_LIB.BASEBOARD_FAB2(SCH_1):PAGE43
   120    GND @BASEBOARD_FAB2_LIB.BASEBOARD_FAB2(SCH_1):GND   I259 @BASEBOARD_FAB2_LIB.BASEBOARD_FAB2(SCH_1):PAGE43
   123    GND @BASEBOARD_FAB2_LIB.BASEBOARD_FAB2(SCH_1):GND   I259 @BASEBOARD_FAB2_LIB.BASEBOARD_FAB2(SCH_1):PAGE43
   125    GND @BASEBOARD_FAB2_LIB.BASEBOARD_FAB2(SCH_1):GND   I259 @BASEBOARD_FAB2_LIB.BASEBOARD_FAB2(SCH_1):PAGE43
   127    GND @BASEBOARD_FAB2_LIB.BASEBOARD_FAB2(SCH_1):GND   I259 @BASEBOARD_FAB2_LIB.BASEBOARD_FAB2(SCH_1):PAGE43
   129    GND @BASEBOARD_FAB2_LIB.BASEBOARD_FAB2(SCH_1):GND   I259 @BASEBOARD_FAB2_LIB.BASEBOARD_FAB2(SCH_1):PAGE43
   131    GND @BASEBOARD_FAB2_LIB.BASEBOARD_FAB2(SCH_1):GND   I259 @BASEBOARD_FAB2_LIB.BASEBOARD_FAB2(SCH_1):PAGE43
   134    GND @BASEBOARD_FAB2_LIB.BASEBOARD_FAB2(SCH_1):GND   I259 @BASEBOARD_FAB2_LIB.BASEBOARD_FAB2(SCH_1):PAGE43
   136    GND @BASEBOARD_FAB2_LIB.BASEBOARD_FAB2(SCH_1):GND   I259 @BASEBOARD_FAB2_LIB.BASEBOARD_FAB2(SCH_1):PAGE43
   138    GND @BASEBOARD_FAB2_LIB.BASEBOARD_FAB2(SCH_1):GND   I259 @BASEBOARD_FAB2_LIB.BASEBOARD_FAB2(SCH_1):PAGE43
   147    GND @BASEBOARD_FAB2_LIB.BASEBOARD_FAB2(SCH_1):GND   I259 @BASEBOARD_FAB2_LIB.BASEBOARD_FAB2(SCH_1):PAGE43
   149    GND @BASEBOARD_FAB2_LIB.BASEBOARD_FAB2(SCH_1):GND   I259 @BASEBOARD_FAB2_LIB.BASEBOARD_FAB2(SCH_1):PAGE43
   151    GND @BASEBOARD_FAB2_LIB.BASEBOARD_FAB2(SCH_1):GND   I259 @BASEBOARD_FAB2_LIB.BASEBOARD_FAB2(SCH_1):PAGE43
   154    GND @BASEBOARD_FAB2_LIB.BASEBOARD_FAB2(SCH_1):GND   I259 @BASEBOARD_FAB2_LIB.BASEBOARD_FAB2(SCH_1):PAGE43
   156    GND @BASEBOARD_FAB2_LIB.BASEBOARD_FAB2(SCH_1):GND   I259 @BASEBOARD_FAB2_LIB.BASEBOARD_FAB2(SCH_1):PAGE43
   158    GND @BASEBOARD_FAB2_LIB.BASEBOARD_FAB2(SCH_1):GND   I259 @BASEBOARD_FAB2_LIB.BASEBOARD_FAB2(SCH_1):PAGE43
   160    GND @BASEBOARD_FAB2_LIB.BASEBOARD_FAB2(SCH_1):GND   I259 @BASEBOARD_FAB2_LIB.BASEBOARD_FAB2(SCH_1):PAGE43
   162    GND @BASEBOARD_FAB2_LIB.BASEBOARD_FAB2(SCH_1):GND   I259 @BASEBOARD_FAB2_LIB.BASEBOARD_FAB2(SCH_1):PAGE43
   165    GND @BASEBOARD_FAB2_LIB.BASEBOARD_FAB2(SCH_1):GND   I259 @BASEBOARD_FAB2_LIB.BASEBOARD_FAB2(SCH_1):PAGE43
   167    GND @BASEBOARD_FAB2_LIB.BASEBOARD_FAB2(SCH_1):GND   I259 @BASEBOARD_FAB2_LIB.BASEBOARD_FAB2(SCH_1):PAGE43
   169    GND @BASEBOARD_FAB2_LIB.BASEBOARD_FAB2(SCH_1):GND   I259 @BASEBOARD_FAB2_LIB.BASEBOARD_FAB2(SCH_1):PAGE43
   171    GND @BASEBOARD_FAB2_LIB.BASEBOARD_FAB2(SCH_1):GND   I259 @BASEBOARD_FAB2_LIB.BASEBOARD_FAB2(SCH_1):PAGE43
   173    GND @BASEBOARD_FAB2_LIB.BASEBOARD_FAB2(SCH_1):GND   I259 @BASEBOARD_FAB2_LIB.BASEBOARD_FAB2(SCH_1):PAGE43
   176    GND @BASEBOARD_FAB2_LIB.BASEBOARD_FAB2(SCH_1):GND   I259 @BASEBOARD_FAB2_LIB.BASEBOARD_FAB2(SCH_1):PAGE43
   178    GND @BASEBOARD_FAB2_LIB.BASEBOARD_FAB2(SCH_1):GND   I259 @BASEBOARD_FAB2_LIB.BASEBOARD_FAB2(SCH_1):PAGE43
   180    GND @BASEBOARD_FAB2_LIB.BASEBOARD_FAB2(SCH_1):GND   I259 @BASEBOARD_FAB2_LIB.BASEBOARD_FAB2(SCH_1):PAGE43
   182    GND @BASEBOARD_FAB2_LIB.BASEBOARD_FAB2(SCH_1):GND   I259 @BASEBOARD_FAB2_LIB.BASEBOARD_FAB2(SCH_1):PAGE43
   184    GND @BASEBOARD_FAB2_LIB.BASEBOARD_FAB2(SCH_1):GND   I259 @BASEBOARD_FAB2_LIB.BASEBOARD_FAB2(SCH_1):PAGE43
   187    GND @BASEBOARD_FAB2_LIB.BASEBOARD_FAB2(SCH_1):GND   I259 @BASEBOARD_FAB2_LIB.BASEBOARD_FAB2(SCH_1):PAGE43
   189    GND @BASEBOARD_FAB2_LIB.BASEBOARD_FAB2(SCH_1):GND   I259 @BASEBOARD_FAB2_LIB.BASEBOARD_FAB2(SCH_1):PAGE43
   191    GND @BASEBOARD_FAB2_LIB.BASEBOARD_FAB2(SCH_1):GND   I259 @BASEBOARD_FAB2_LIB.BASEBOARD_FAB2(SCH_1):PAGE43
   193    GND @BASEBOARD_FAB2_LIB.BASEBOARD_FAB2(SCH_1):GND   I259 @BASEBOARD_FAB2_LIB.BASEBOARD_FAB2(SCH_1):PAGE43
   195    GND @BASEBOARD_FAB2_LIB.BASEBOARD_FAB2(SCH_1):GND   I259 @BASEBOARD_FAB2_LIB.BASEBOARD_FAB2(SCH_1):PAGE43
   198    GND @BASEBOARD_FAB2_LIB.BASEBOARD_FAB2(SCH_1):GND   I259 @BASEBOARD_FAB2_LIB.BASEBOARD_FAB2(SCH_1):PAGE43
   200    GND @BASEBOARD_FAB2_LIB.BASEBOARD_FAB2(SCH_1):GND   I259 @BASEBOARD_FAB2_LIB.BASEBOARD_FAB2(SCH_1):PAGE43
   202    GND @BASEBOARD_FAB2_LIB.BASEBOARD_FAB2(SCH_1):GND   I259 @BASEBOARD_FAB2_LIB.BASEBOARD_FAB2(SCH_1):PAGE43
   239    GND @BASEBOARD_FAB2_LIB.BASEBOARD_FAB2(SCH_1):GND   I259 @BASEBOARD_FAB2_LIB.BASEBOARD_FAB2(SCH_1):PAGE43
   241    GND @BASEBOARD_FAB2_LIB.BASEBOARD_FAB2(SCH_1):GND   I259 @BASEBOARD_FAB2_LIB.BASEBOARD_FAB2(SCH_1):PAGE43
   243    GND @BASEBOARD_FAB2_LIB.BASEBOARD_FAB2(SCH_1):GND   I259 @BASEBOARD_FAB2_LIB.BASEBOARD_FAB2(SCH_1):PAGE43
   246    GND @BASEBOARD_FAB2_LIB.BASEBOARD_FAB2(SCH_1):GND   I259 @BASEBOARD_FAB2_LIB.BASEBOARD_FAB2(SCH_1):PAGE43
   248    GND @BASEBOARD_FAB2_LIB.BASEBOARD_FAB2(SCH_1):GND   I259 @BASEBOARD_FAB2_LIB.BASEBOARD_FAB2(SCH_1):PAGE43
   250    GND @BASEBOARD_FAB2_LIB.BASEBOARD_FAB2(SCH_1):GND   I259 @BASEBOARD_FAB2_LIB.BASEBOARD_FAB2(SCH_1):PAGE43
   252    GND @BASEBOARD_FAB2_LIB.BASEBOARD_FAB2(SCH_1):GND   I259 @BASEBOARD_FAB2_LIB.BASEBOARD_FAB2(SCH_1):PAGE43
   254    GND @BASEBOARD_FAB2_LIB.BASEBOARD_FAB2(SCH_1):GND   I259 @BASEBOARD_FAB2_LIB.BASEBOARD_FAB2(SCH_1):PAGE43
   257    GND @BASEBOARD_FAB2_LIB.BASEBOARD_FAB2(SCH_1):GND   I259 @BASEBOARD_FAB2_LIB.BASEBOARD_FAB2(SCH_1):PAGE43
   259    GND @BASEBOARD_FAB2_LIB.BASEBOARD_FAB2(SCH_1):GND   I259 @BASEBOARD_FAB2_LIB.BASEBOARD_FAB2(SCH_1):PAGE43
   261    GND @BASEBOARD_FAB2_LIB.BASEBOARD_FAB2(SCH_1):GND   I259 @BASEBOARD_FAB2_LIB.BASEBOARD_FAB2(SCH_1):PAGE43
   263    GND @BASEBOARD_FAB2_LIB.BASEBOARD_FAB2(SCH_1):GND   I259 @BASEBOARD_FAB2_LIB.BASEBOARD_FAB2(SCH_1):PAGE43
   265    GND @BASEBOARD_FAB2_LIB.BASEBOARD_FAB2(SCH_1):GND   I259 @BASEBOARD_FAB2_LIB.BASEBOARD_FAB2(SCH_1):PAGE43
   268    GND @BASEBOARD_FAB2_LIB.BASEBOARD_FAB2(SCH_1):GND   I259 @BASEBOARD_FAB2_LIB.BASEBOARD_FAB2(SCH_1):PAGE43
   270    GND @BASEBOARD_FAB2_LIB.BASEBOARD_FAB2(SCH_1):GND   I259 @BASEBOARD_FAB2_LIB.BASEBOARD_FAB2(SCH_1):PAGE43
   272    GND @BASEBOARD_FAB2_LIB.BASEBOARD_FAB2(SCH_1):GND   I259 @BASEBOARD_FAB2_LIB.BASEBOARD_FAB2(SCH_1):PAGE43
   274    GND @BASEBOARD_FAB2_LIB.BASEBOARD_FAB2(SCH_1):GND   I259 @BASEBOARD_FAB2_LIB.BASEBOARD_FAB2(SCH_1):PAGE43
   276    GND @BASEBOARD_FAB2_LIB.BASEBOARD_FAB2(SCH_1):GND   I259 @BASEBOARD_FAB2_LIB.BASEBOARD_FAB2(SCH_1):PAGE43
   279    GND @BASEBOARD_FAB2_LIB.BASEBOARD_FAB2(SCH_1):GND   I259 @BASEBOARD_FAB2_LIB.BASEBOARD_FAB2(SCH_1):PAGE43
   281    GND @BASEBOARD_FAB2_LIB.BASEBOARD_FAB2(SCH_1):GND   I259 @BASEBOARD_FAB2_LIB.BASEBOARD_FAB2(SCH_1):PAGE43
   283    GND @BASEBOARD_FAB2_LIB.BASEBOARD_FAB2(SCH_1):GND   I259 @BASEBOARD_FAB2_LIB.BASEBOARD_FAB2(SCH_1):PAGE43
     1 P12V_NVDIMM_ABC @BASEBOARD_FAB2_LIB.BASEBOARD_FAB2(SCH_1):P12V_NVDIMM_ABC   I260 @BASEBOARD_FAB2_LIB.BASEBOARD_FAB2(SCH_1):PAGE43
   145 P12V_NVDIMM_ABC @BASEBOARD_FAB2_LIB.BASEBOARD_FAB2(SCH_1):P12V_NVDIMM_ABC   I260 @BASEBOARD_FAB2_LIB.BASEBOARD_FAB2(SCH_1):PAGE43
    59 PVDDQ_ABC @BASEBOARD_FAB2_LIB.BASEBOARD_FAB2(SCH_1):PVDDQ_ABC   I260 @BASEBOARD_FAB2_LIB.BASEBOARD_FAB2(SCH_1):PAGE43
    61 PVDDQ_ABC @BASEBOARD_FAB2_LIB.BASEBOARD_FAB2(SCH_1):PVDDQ_ABC   I260 @BASEBOARD_FAB2_LIB.BASEBOARD_FAB2(SCH_1):PAGE43
    64 PVDDQ_ABC @BASEBOARD_FAB2_LIB.BASEBOARD_FAB2(SCH_1):PVDDQ_ABC   I260 @BASEBOARD_FAB2_LIB.BASEBOARD_FAB2(SCH_1):PAGE43
    67 PVDDQ_ABC @BASEBOARD_FAB2_LIB.BASEBOARD_FAB2(SCH_1):PVDDQ_ABC   I260 @BASEBOARD_FAB2_LIB.BASEBOARD_FAB2(SCH_1):PAGE43
    70 PVDDQ_ABC @BASEBOARD_FAB2_LIB.BASEBOARD_FAB2(SCH_1):PVDDQ_ABC   I260 @BASEBOARD_FAB2_LIB.BASEBOARD_FAB2(SCH_1):PAGE43
    73 PVDDQ_ABC @BASEBOARD_FAB2_LIB.BASEBOARD_FAB2(SCH_1):PVDDQ_ABC   I260 @BASEBOARD_FAB2_LIB.BASEBOARD_FAB2(SCH_1):PAGE43
    76 PVDDQ_ABC @BASEBOARD_FAB2_LIB.BASEBOARD_FAB2(SCH_1):PVDDQ_ABC   I260 @BASEBOARD_FAB2_LIB.BASEBOARD_FAB2(SCH_1):PAGE43
    80 PVDDQ_ABC @BASEBOARD_FAB2_LIB.BASEBOARD_FAB2(SCH_1):PVDDQ_ABC   I260 @BASEBOARD_FAB2_LIB.BASEBOARD_FAB2(SCH_1):PAGE43
    83 PVDDQ_ABC @BASEBOARD_FAB2_LIB.BASEBOARD_FAB2(SCH_1):PVDDQ_ABC   I260 @BASEBOARD_FAB2_LIB.BASEBOARD_FAB2(SCH_1):PAGE43
    85 PVDDQ_ABC @BASEBOARD_FAB2_LIB.BASEBOARD_FAB2(SCH_1):PVDDQ_ABC   I260 @BASEBOARD_FAB2_LIB.BASEBOARD_FAB2(SCH_1):PAGE43
    88 PVDDQ_ABC @BASEBOARD_FAB2_LIB.BASEBOARD_FAB2(SCH_1):PVDDQ_ABC   I260 @BASEBOARD_FAB2_LIB.BASEBOARD_FAB2(SCH_1):PAGE43
    90 PVDDQ_ABC @BASEBOARD_FAB2_LIB.BASEBOARD_FAB2(SCH_1):PVDDQ_ABC   I260 @BASEBOARD_FAB2_LIB.BASEBOARD_FAB2(SCH_1):PAGE43
    92 PVDDQ_ABC @BASEBOARD_FAB2_LIB.BASEBOARD_FAB2(SCH_1):PVDDQ_ABC   I260 @BASEBOARD_FAB2_LIB.BASEBOARD_FAB2(SCH_1):PAGE43
   204 PVDDQ_ABC @BASEBOARD_FAB2_LIB.BASEBOARD_FAB2(SCH_1):PVDDQ_ABC   I260 @BASEBOARD_FAB2_LIB.BASEBOARD_FAB2(SCH_1):PAGE43
   206 PVDDQ_ABC @BASEBOARD_FAB2_LIB.BASEBOARD_FAB2(SCH_1):PVDDQ_ABC   I260 @BASEBOARD_FAB2_LIB.BASEBOARD_FAB2(SCH_1):PAGE43
   209 PVDDQ_ABC @BASEBOARD_FAB2_LIB.BASEBOARD_FAB2(SCH_1):PVDDQ_ABC   I260 @BASEBOARD_FAB2_LIB.BASEBOARD_FAB2(SCH_1):PAGE43
   212 PVDDQ_ABC @BASEBOARD_FAB2_LIB.BASEBOARD_FAB2(SCH_1):PVDDQ_ABC   I260 @BASEBOARD_FAB2_LIB.BASEBOARD_FAB2(SCH_1):PAGE43
   215 PVDDQ_ABC @BASEBOARD_FAB2_LIB.BASEBOARD_FAB2(SCH_1):PVDDQ_ABC   I260 @BASEBOARD_FAB2_LIB.BASEBOARD_FAB2(SCH_1):PAGE43
   217 PVDDQ_ABC @BASEBOARD_FAB2_LIB.BASEBOARD_FAB2(SCH_1):PVDDQ_ABC   I260 @BASEBOARD_FAB2_LIB.BASEBOARD_FAB2(SCH_1):PAGE43
   220 PVDDQ_ABC @BASEBOARD_FAB2_LIB.BASEBOARD_FAB2(SCH_1):PVDDQ_ABC   I260 @BASEBOARD_FAB2_LIB.BASEBOARD_FAB2(SCH_1):PAGE43
   223 PVDDQ_ABC @BASEBOARD_FAB2_LIB.BASEBOARD_FAB2(SCH_1):PVDDQ_ABC   I260 @BASEBOARD_FAB2_LIB.BASEBOARD_FAB2(SCH_1):PAGE43
   226 PVDDQ_ABC @BASEBOARD_FAB2_LIB.BASEBOARD_FAB2(SCH_1):PVDDQ_ABC   I260 @BASEBOARD_FAB2_LIB.BASEBOARD_FAB2(SCH_1):PAGE43
   229 PVDDQ_ABC @BASEBOARD_FAB2_LIB.BASEBOARD_FAB2(SCH_1):PVDDQ_ABC   I260 @BASEBOARD_FAB2_LIB.BASEBOARD_FAB2(SCH_1):PAGE43
   231 PVDDQ_ABC @BASEBOARD_FAB2_LIB.BASEBOARD_FAB2(SCH_1):PVDDQ_ABC   I260 @BASEBOARD_FAB2_LIB.BASEBOARD_FAB2(SCH_1):PAGE43
   233 PVDDQ_ABC @BASEBOARD_FAB2_LIB.BASEBOARD_FAB2(SCH_1):PVDDQ_ABC   I260 @BASEBOARD_FAB2_LIB.BASEBOARD_FAB2(SCH_1):PAGE43
   236 PVDDQ_ABC @BASEBOARD_FAB2_LIB.BASEBOARD_FAB2(SCH_1):PVDDQ_ABC   I260 @BASEBOARD_FAB2_LIB.BASEBOARD_FAB2(SCH_1):PAGE43
   142 PVPP_ABC @BASEBOARD_FAB2_LIB.BASEBOARD_FAB2(SCH_1):PVPP_ABC   I260 @BASEBOARD_FAB2_LIB.BASEBOARD_FAB2(SCH_1):PAGE43
   143 PVPP_ABC @BASEBOARD_FAB2_LIB.BASEBOARD_FAB2(SCH_1):PVPP_ABC   I260 @BASEBOARD_FAB2_LIB.BASEBOARD_FAB2(SCH_1):PAGE43
   288 PVPP_ABC @BASEBOARD_FAB2_LIB.BASEBOARD_FAB2(SCH_1):PVPP_ABC   I260 @BASEBOARD_FAB2_LIB.BASEBOARD_FAB2(SCH_1):PAGE43
   286 PVPP_ABC @BASEBOARD_FAB2_LIB.BASEBOARD_FAB2(SCH_1):PVPP_ABC   I260 @BASEBOARD_FAB2_LIB.BASEBOARD_FAB2(SCH_1):PAGE43
   287 PVPP_ABC @BASEBOARD_FAB2_LIB.BASEBOARD_FAB2(SCH_1):PVPP_ABC   I260 @BASEBOARD_FAB2_LIB.BASEBOARD_FAB2(SCH_1):PAGE43
    77 PVTT_ABC @BASEBOARD_FAB2_LIB.BASEBOARD_FAB2(SCH_1):PVTT_ABC   I260 @BASEBOARD_FAB2_LIB.BASEBOARD_FAB2(SCH_1):PAGE43
   221 PVTT_ABC @BASEBOARD_FAB2_LIB.BASEBOARD_FAB2(SCH_1):PVTT_ABC   I260 @BASEBOARD_FAB2_LIB.BASEBOARD_FAB2(SCH_1):PAGE43

J4G2 SCONN288_H44441004_PIP-SCONN,HA
    79 M_B_MA<0> @BASEBOARD_FAB2_LIB.BASEBOARD_FAB2(SCH_1):M_B_MA(0)   I111 @BASEBOARD_FAB2_LIB.BASEBOARD_FAB2(SCH_1):PAGE45
    72 M_B_MA<1> @BASEBOARD_FAB2_LIB.BASEBOARD_FAB2(SCH_1):M_B_MA(1)   I111 @BASEBOARD_FAB2_LIB.BASEBOARD_FAB2(SCH_1):PAGE45
   225 M_B_MA<10> @BASEBOARD_FAB2_LIB.BASEBOARD_FAB2(SCH_1):M_B_MA(10)   I111 @BASEBOARD_FAB2_LIB.BASEBOARD_FAB2(SCH_1):PAGE45
   210 M_B_MA<11> @BASEBOARD_FAB2_LIB.BASEBOARD_FAB2(SCH_1):M_B_MA(11)   I111 @BASEBOARD_FAB2_LIB.BASEBOARD_FAB2(SCH_1):PAGE45
    65 M_B_MA<12> @BASEBOARD_FAB2_LIB.BASEBOARD_FAB2(SCH_1):M_B_MA(12)   I111 @BASEBOARD_FAB2_LIB.BASEBOARD_FAB2(SCH_1):PAGE45
   232 M_B_MA<13> @BASEBOARD_FAB2_LIB.BASEBOARD_FAB2(SCH_1):M_B_MA(13)   I111 @BASEBOARD_FAB2_LIB.BASEBOARD_FAB2(SCH_1):PAGE45
   228 M_B_MA<14> @BASEBOARD_FAB2_LIB.BASEBOARD_FAB2(SCH_1):M_B_MA(14)   I111 @BASEBOARD_FAB2_LIB.BASEBOARD_FAB2(SCH_1):PAGE45
    86 M_B_MA<15> @BASEBOARD_FAB2_LIB.BASEBOARD_FAB2(SCH_1):M_B_MA(15)   I111 @BASEBOARD_FAB2_LIB.BASEBOARD_FAB2(SCH_1):PAGE45
    82 M_B_MA<16> @BASEBOARD_FAB2_LIB.BASEBOARD_FAB2(SCH_1):M_B_MA(16)   I111 @BASEBOARD_FAB2_LIB.BASEBOARD_FAB2(SCH_1):PAGE45
   234 M_B_MA<17> @BASEBOARD_FAB2_LIB.BASEBOARD_FAB2(SCH_1):M_B_MA(17)   I111 @BASEBOARD_FAB2_LIB.BASEBOARD_FAB2(SCH_1):PAGE45
   216 M_B_MA<2> @BASEBOARD_FAB2_LIB.BASEBOARD_FAB2(SCH_1):M_B_MA(2)   I111 @BASEBOARD_FAB2_LIB.BASEBOARD_FAB2(SCH_1):PAGE45
    71 M_B_MA<3> @BASEBOARD_FAB2_LIB.BASEBOARD_FAB2(SCH_1):M_B_MA(3)   I111 @BASEBOARD_FAB2_LIB.BASEBOARD_FAB2(SCH_1):PAGE45
   214 M_B_MA<4> @BASEBOARD_FAB2_LIB.BASEBOARD_FAB2(SCH_1):M_B_MA(4)   I111 @BASEBOARD_FAB2_LIB.BASEBOARD_FAB2(SCH_1):PAGE45
   213 M_B_MA<5> @BASEBOARD_FAB2_LIB.BASEBOARD_FAB2(SCH_1):M_B_MA(5)   I111 @BASEBOARD_FAB2_LIB.BASEBOARD_FAB2(SCH_1):PAGE45
    69 M_B_MA<6> @BASEBOARD_FAB2_LIB.BASEBOARD_FAB2(SCH_1):M_B_MA(6)   I111 @BASEBOARD_FAB2_LIB.BASEBOARD_FAB2(SCH_1):PAGE45
   211 M_B_MA<7> @BASEBOARD_FAB2_LIB.BASEBOARD_FAB2(SCH_1):M_B_MA(7)   I111 @BASEBOARD_FAB2_LIB.BASEBOARD_FAB2(SCH_1):PAGE45
    68 M_B_MA<8> @BASEBOARD_FAB2_LIB.BASEBOARD_FAB2(SCH_1):M_B_MA(8)   I111 @BASEBOARD_FAB2_LIB.BASEBOARD_FAB2(SCH_1):PAGE45
    66 M_B_MA<9> @BASEBOARD_FAB2_LIB.BASEBOARD_FAB2(SCH_1):M_B_MA(9)   I111 @BASEBOARD_FAB2_LIB.BASEBOARD_FAB2(SCH_1):PAGE45
    62 M_B_ACT_N @BASEBOARD_FAB2_LIB.BASEBOARD_FAB2(SCH_1):M_B_ACT_N   I111 @BASEBOARD_FAB2_LIB.BASEBOARD_FAB2(SCH_1):PAGE45
   208 M_B_ALERT_N @BASEBOARD_FAB2_LIB.BASEBOARD_FAB2(SCH_1):M_B_ALERT_N   I111 @BASEBOARD_FAB2_LIB.BASEBOARD_FAB2(SCH_1):PAGE45
   224 M_B_BA<1> @BASEBOARD_FAB2_LIB.BASEBOARD_FAB2(SCH_1):M_B_BA(1)   I111 @BASEBOARD_FAB2_LIB.BASEBOARD_FAB2(SCH_1):PAGE45
    81 M_B_BA<0> @BASEBOARD_FAB2_LIB.BASEBOARD_FAB2(SCH_1):M_B_BA(0)   I111 @BASEBOARD_FAB2_LIB.BASEBOARD_FAB2(SCH_1):PAGE45
   207 M_B_BG<1> @BASEBOARD_FAB2_LIB.BASEBOARD_FAB2(SCH_1):M_B_BG(1)   I111 @BASEBOARD_FAB2_LIB.BASEBOARD_FAB2(SCH_1):PAGE45
    63 M_B_BG<0> @BASEBOARD_FAB2_LIB.BASEBOARD_FAB2(SCH_1):M_B_BG(0)   I111 @BASEBOARD_FAB2_LIB.BASEBOARD_FAB2(SCH_1):PAGE45
   235 M_B_C<2> @BASEBOARD_FAB2_LIB.BASEBOARD_FAB2(SCH_1):M_B_C(2)   I111 @BASEBOARD_FAB2_LIB.BASEBOARD_FAB2(SCH_1):PAGE45
   199 M_B_ECC<6> @BASEBOARD_FAB2_LIB.BASEBOARD_FAB2(SCH_1):M_B_ECC(6)   I111 @BASEBOARD_FAB2_LIB.BASEBOARD_FAB2(SCH_1):PAGE45
    54 M_B_ECC<7> @BASEBOARD_FAB2_LIB.BASEBOARD_FAB2(SCH_1):M_B_ECC(7)   I111 @BASEBOARD_FAB2_LIB.BASEBOARD_FAB2(SCH_1):PAGE45
   192 M_B_ECC<4> @BASEBOARD_FAB2_LIB.BASEBOARD_FAB2(SCH_1):M_B_ECC(4)   I111 @BASEBOARD_FAB2_LIB.BASEBOARD_FAB2(SCH_1):PAGE45
    47 M_B_ECC<5> @BASEBOARD_FAB2_LIB.BASEBOARD_FAB2(SCH_1):M_B_ECC(5)   I111 @BASEBOARD_FAB2_LIB.BASEBOARD_FAB2(SCH_1):PAGE45
   201 M_B_ECC<2> @BASEBOARD_FAB2_LIB.BASEBOARD_FAB2(SCH_1):M_B_ECC(2)   I111 @BASEBOARD_FAB2_LIB.BASEBOARD_FAB2(SCH_1):PAGE45
    56 M_B_ECC<3> @BASEBOARD_FAB2_LIB.BASEBOARD_FAB2(SCH_1):M_B_ECC(3)   I111 @BASEBOARD_FAB2_LIB.BASEBOARD_FAB2(SCH_1):PAGE45
   194 M_B_ECC<0> @BASEBOARD_FAB2_LIB.BASEBOARD_FAB2(SCH_1):M_B_ECC(0)   I111 @BASEBOARD_FAB2_LIB.BASEBOARD_FAB2(SCH_1):PAGE45
    49 M_B_ECC<1> @BASEBOARD_FAB2_LIB.BASEBOARD_FAB2(SCH_1):M_B_ECC(1)   I111 @BASEBOARD_FAB2_LIB.BASEBOARD_FAB2(SCH_1):PAGE45
    75 M_B_CLK_DN<0> @BASEBOARD_FAB2_LIB.BASEBOARD_FAB2(SCH_1):M_B_CLK_DN(0)   I111 @BASEBOARD_FAB2_LIB.BASEBOARD_FAB2(SCH_1):PAGE45
    74 M_B_CLK_DP<0> @BASEBOARD_FAB2_LIB.BASEBOARD_FAB2(SCH_1):M_B_CLK_DP(0)   I111 @BASEBOARD_FAB2_LIB.BASEBOARD_FAB2(SCH_1):PAGE45
   219 M_B_CLK_DN<1> @BASEBOARD_FAB2_LIB.BASEBOARD_FAB2(SCH_1):M_B_CLK_DN(1)   I111 @BASEBOARD_FAB2_LIB.BASEBOARD_FAB2(SCH_1):PAGE45
   218 M_B_CLK_DP<1> @BASEBOARD_FAB2_LIB.BASEBOARD_FAB2(SCH_1):M_B_CLK_DP(1)   I111 @BASEBOARD_FAB2_LIB.BASEBOARD_FAB2(SCH_1):PAGE45
   203 M_B_CKE<1> @BASEBOARD_FAB2_LIB.BASEBOARD_FAB2(SCH_1):M_B_CKE(1)   I111 @BASEBOARD_FAB2_LIB.BASEBOARD_FAB2(SCH_1):PAGE45
    60 M_B_CKE<0> @BASEBOARD_FAB2_LIB.BASEBOARD_FAB2(SCH_1):M_B_CKE(0)   I111 @BASEBOARD_FAB2_LIB.BASEBOARD_FAB2(SCH_1):PAGE45
   280 M_B_DQ<62> @BASEBOARD_FAB2_LIB.BASEBOARD_FAB2(SCH_1):M_B_DQ(62)   I111 @BASEBOARD_FAB2_LIB.BASEBOARD_FAB2(SCH_1):PAGE45
   135 M_B_DQ<63> @BASEBOARD_FAB2_LIB.BASEBOARD_FAB2(SCH_1):M_B_DQ(63)   I111 @BASEBOARD_FAB2_LIB.BASEBOARD_FAB2(SCH_1):PAGE45
   273 M_B_DQ<60> @BASEBOARD_FAB2_LIB.BASEBOARD_FAB2(SCH_1):M_B_DQ(60)   I111 @BASEBOARD_FAB2_LIB.BASEBOARD_FAB2(SCH_1):PAGE45
   128 M_B_DQ<61> @BASEBOARD_FAB2_LIB.BASEBOARD_FAB2(SCH_1):M_B_DQ(61)   I111 @BASEBOARD_FAB2_LIB.BASEBOARD_FAB2(SCH_1):PAGE45
   282 M_B_DQ<58> @BASEBOARD_FAB2_LIB.BASEBOARD_FAB2(SCH_1):M_B_DQ(58)   I111 @BASEBOARD_FAB2_LIB.BASEBOARD_FAB2(SCH_1):PAGE45
   137 M_B_DQ<59> @BASEBOARD_FAB2_LIB.BASEBOARD_FAB2(SCH_1):M_B_DQ(59)   I111 @BASEBOARD_FAB2_LIB.BASEBOARD_FAB2(SCH_1):PAGE45
   275 M_B_DQ<56> @BASEBOARD_FAB2_LIB.BASEBOARD_FAB2(SCH_1):M_B_DQ(56)   I111 @BASEBOARD_FAB2_LIB.BASEBOARD_FAB2(SCH_1):PAGE45
   130 M_B_DQ<57> @BASEBOARD_FAB2_LIB.BASEBOARD_FAB2(SCH_1):M_B_DQ(57)   I111 @BASEBOARD_FAB2_LIB.BASEBOARD_FAB2(SCH_1):PAGE45
   269 M_B_DQ<54> @BASEBOARD_FAB2_LIB.BASEBOARD_FAB2(SCH_1):M_B_DQ(54)   I111 @BASEBOARD_FAB2_LIB.BASEBOARD_FAB2(SCH_1):PAGE45
   124 M_B_DQ<55> @BASEBOARD_FAB2_LIB.BASEBOARD_FAB2(SCH_1):M_B_DQ(55)   I111 @BASEBOARD_FAB2_LIB.BASEBOARD_FAB2(SCH_1):PAGE45
   262 M_B_DQ<52> @BASEBOARD_FAB2_LIB.BASEBOARD_FAB2(SCH_1):M_B_DQ(52)   I111 @BASEBOARD_FAB2_LIB.BASEBOARD_FAB2(SCH_1):PAGE45
   117 M_B_DQ<53> @BASEBOARD_FAB2_LIB.BASEBOARD_FAB2(SCH_1):M_B_DQ(53)   I111 @BASEBOARD_FAB2_LIB.BASEBOARD_FAB2(SCH_1):PAGE45
   271 M_B_DQ<50> @BASEBOARD_FAB2_LIB.BASEBOARD_FAB2(SCH_1):M_B_DQ(50)   I111 @BASEBOARD_FAB2_LIB.BASEBOARD_FAB2(SCH_1):PAGE45
   126 M_B_DQ<51> @BASEBOARD_FAB2_LIB.BASEBOARD_FAB2(SCH_1):M_B_DQ(51)   I111 @BASEBOARD_FAB2_LIB.BASEBOARD_FAB2(SCH_1):PAGE45
   264 M_B_DQ<48> @BASEBOARD_FAB2_LIB.BASEBOARD_FAB2(SCH_1):M_B_DQ(48)   I111 @BASEBOARD_FAB2_LIB.BASEBOARD_FAB2(SCH_1):PAGE45
   119 M_B_DQ<49> @BASEBOARD_FAB2_LIB.BASEBOARD_FAB2(SCH_1):M_B_DQ(49)   I111 @BASEBOARD_FAB2_LIB.BASEBOARD_FAB2(SCH_1):PAGE45
   258 M_B_DQ<46> @BASEBOARD_FAB2_LIB.BASEBOARD_FAB2(SCH_1):M_B_DQ(46)   I111 @BASEBOARD_FAB2_LIB.BASEBOARD_FAB2(SCH_1):PAGE45
   113 M_B_DQ<47> @BASEBOARD_FAB2_LIB.BASEBOARD_FAB2(SCH_1):M_B_DQ(47)   I111 @BASEBOARD_FAB2_LIB.BASEBOARD_FAB2(SCH_1):PAGE45
   251 M_B_DQ<44> @BASEBOARD_FAB2_LIB.BASEBOARD_FAB2(SCH_1):M_B_DQ(44)   I111 @BASEBOARD_FAB2_LIB.BASEBOARD_FAB2(SCH_1):PAGE45
   106 M_B_DQ<45> @BASEBOARD_FAB2_LIB.BASEBOARD_FAB2(SCH_1):M_B_DQ(45)   I111 @BASEBOARD_FAB2_LIB.BASEBOARD_FAB2(SCH_1):PAGE45
   260 M_B_DQ<42> @BASEBOARD_FAB2_LIB.BASEBOARD_FAB2(SCH_1):M_B_DQ(42)   I111 @BASEBOARD_FAB2_LIB.BASEBOARD_FAB2(SCH_1):PAGE45
   115 M_B_DQ<43> @BASEBOARD_FAB2_LIB.BASEBOARD_FAB2(SCH_1):M_B_DQ(43)   I111 @BASEBOARD_FAB2_LIB.BASEBOARD_FAB2(SCH_1):PAGE45
   253 M_B_DQ<40> @BASEBOARD_FAB2_LIB.BASEBOARD_FAB2(SCH_1):M_B_DQ(40)   I111 @BASEBOARD_FAB2_LIB.BASEBOARD_FAB2(SCH_1):PAGE45
   108 M_B_DQ<41> @BASEBOARD_FAB2_LIB.BASEBOARD_FAB2(SCH_1):M_B_DQ(41)   I111 @BASEBOARD_FAB2_LIB.BASEBOARD_FAB2(SCH_1):PAGE45
   247 M_B_DQ<38> @BASEBOARD_FAB2_LIB.BASEBOARD_FAB2(SCH_1):M_B_DQ(38)   I111 @BASEBOARD_FAB2_LIB.BASEBOARD_FAB2(SCH_1):PAGE45
   102 M_B_DQ<39> @BASEBOARD_FAB2_LIB.BASEBOARD_FAB2(SCH_1):M_B_DQ(39)   I111 @BASEBOARD_FAB2_LIB.BASEBOARD_FAB2(SCH_1):PAGE45
   240 M_B_DQ<36> @BASEBOARD_FAB2_LIB.BASEBOARD_FAB2(SCH_1):M_B_DQ(36)   I111 @BASEBOARD_FAB2_LIB.BASEBOARD_FAB2(SCH_1):PAGE45
    95 M_B_DQ<37> @BASEBOARD_FAB2_LIB.BASEBOARD_FAB2(SCH_1):M_B_DQ(37)   I111 @BASEBOARD_FAB2_LIB.BASEBOARD_FAB2(SCH_1):PAGE45
   249 M_B_DQ<34> @BASEBOARD_FAB2_LIB.BASEBOARD_FAB2(SCH_1):M_B_DQ(34)   I111 @BASEBOARD_FAB2_LIB.BASEBOARD_FAB2(SCH_1):PAGE45
   104 M_B_DQ<35> @BASEBOARD_FAB2_LIB.BASEBOARD_FAB2(SCH_1):M_B_DQ(35)   I111 @BASEBOARD_FAB2_LIB.BASEBOARD_FAB2(SCH_1):PAGE45
   242 M_B_DQ<32> @BASEBOARD_FAB2_LIB.BASEBOARD_FAB2(SCH_1):M_B_DQ(32)   I111 @BASEBOARD_FAB2_LIB.BASEBOARD_FAB2(SCH_1):PAGE45
    97 M_B_DQ<33> @BASEBOARD_FAB2_LIB.BASEBOARD_FAB2(SCH_1):M_B_DQ(33)   I111 @BASEBOARD_FAB2_LIB.BASEBOARD_FAB2(SCH_1):PAGE45
   188 M_B_DQ<30> @BASEBOARD_FAB2_LIB.BASEBOARD_FAB2(SCH_1):M_B_DQ(30)   I111 @BASEBOARD_FAB2_LIB.BASEBOARD_FAB2(SCH_1):PAGE45
    43 M_B_DQ<31> @BASEBOARD_FAB2_LIB.BASEBOARD_FAB2(SCH_1):M_B_DQ(31)   I111 @BASEBOARD_FAB2_LIB.BASEBOARD_FAB2(SCH_1):PAGE45
   181 M_B_DQ<28> @BASEBOARD_FAB2_LIB.BASEBOARD_FAB2(SCH_1):M_B_DQ(28)   I111 @BASEBOARD_FAB2_LIB.BASEBOARD_FAB2(SCH_1):PAGE45
    36 M_B_DQ<29> @BASEBOARD_FAB2_LIB.BASEBOARD_FAB2(SCH_1):M_B_DQ(29)   I111 @BASEBOARD_FAB2_LIB.BASEBOARD_FAB2(SCH_1):PAGE45
   190 M_B_DQ<26> @BASEBOARD_FAB2_LIB.BASEBOARD_FAB2(SCH_1):M_B_DQ(26)   I111 @BASEBOARD_FAB2_LIB.BASEBOARD_FAB2(SCH_1):PAGE45
    45 M_B_DQ<27> @BASEBOARD_FAB2_LIB.BASEBOARD_FAB2(SCH_1):M_B_DQ(27)   I111 @BASEBOARD_FAB2_LIB.BASEBOARD_FAB2(SCH_1):PAGE45
   183 M_B_DQ<24> @BASEBOARD_FAB2_LIB.BASEBOARD_FAB2(SCH_1):M_B_DQ(24)   I111 @BASEBOARD_FAB2_LIB.BASEBOARD_FAB2(SCH_1):PAGE45
    38 M_B_DQ<25> @BASEBOARD_FAB2_LIB.BASEBOARD_FAB2(SCH_1):M_B_DQ(25)   I111 @BASEBOARD_FAB2_LIB.BASEBOARD_FAB2(SCH_1):PAGE45
   177 M_B_DQ<22> @BASEBOARD_FAB2_LIB.BASEBOARD_FAB2(SCH_1):M_B_DQ(22)   I111 @BASEBOARD_FAB2_LIB.BASEBOARD_FAB2(SCH_1):PAGE45
    32 M_B_DQ<23> @BASEBOARD_FAB2_LIB.BASEBOARD_FAB2(SCH_1):M_B_DQ(23)   I111 @BASEBOARD_FAB2_LIB.BASEBOARD_FAB2(SCH_1):PAGE45
   170 M_B_DQ<20> @BASEBOARD_FAB2_LIB.BASEBOARD_FAB2(SCH_1):M_B_DQ(20)   I111 @BASEBOARD_FAB2_LIB.BASEBOARD_FAB2(SCH_1):PAGE45
    25 M_B_DQ<21> @BASEBOARD_FAB2_LIB.BASEBOARD_FAB2(SCH_1):M_B_DQ(21)   I111 @BASEBOARD_FAB2_LIB.BASEBOARD_FAB2(SCH_1):PAGE45
   179 M_B_DQ<18> @BASEBOARD_FAB2_LIB.BASEBOARD_FAB2(SCH_1):M_B_DQ(18)   I111 @BASEBOARD_FAB2_LIB.BASEBOARD_FAB2(SCH_1):PAGE45
    34 M_B_DQ<19> @BASEBOARD_FAB2_LIB.BASEBOARD_FAB2(SCH_1):M_B_DQ(19)   I111 @BASEBOARD_FAB2_LIB.BASEBOARD_FAB2(SCH_1):PAGE45
   172 M_B_DQ<16> @BASEBOARD_FAB2_LIB.BASEBOARD_FAB2(SCH_1):M_B_DQ(16)   I111 @BASEBOARD_FAB2_LIB.BASEBOARD_FAB2(SCH_1):PAGE45
    27 M_B_DQ<17> @BASEBOARD_FAB2_LIB.BASEBOARD_FAB2(SCH_1):M_B_DQ(17)   I111 @BASEBOARD_FAB2_LIB.BASEBOARD_FAB2(SCH_1):PAGE45
   166 M_B_DQ<14> @BASEBOARD_FAB2_LIB.BASEBOARD_FAB2(SCH_1):M_B_DQ(14)   I111 @BASEBOARD_FAB2_LIB.BASEBOARD_FAB2(SCH_1):PAGE45
    21 M_B_DQ<15> @BASEBOARD_FAB2_LIB.BASEBOARD_FAB2(SCH_1):M_B_DQ(15)   I111 @BASEBOARD_FAB2_LIB.BASEBOARD_FAB2(SCH_1):PAGE45
   159 M_B_DQ<12> @BASEBOARD_FAB2_LIB.BASEBOARD_FAB2(SCH_1):M_B_DQ(12)   I111 @BASEBOARD_FAB2_LIB.BASEBOARD_FAB2(SCH_1):PAGE45
    14 M_B_DQ<13> @BASEBOARD_FAB2_LIB.BASEBOARD_FAB2(SCH_1):M_B_DQ(13)   I111 @BASEBOARD_FAB2_LIB.BASEBOARD_FAB2(SCH_1):PAGE45
   168 M_B_DQ<10> @BASEBOARD_FAB2_LIB.BASEBOARD_FAB2(SCH_1):M_B_DQ(10)   I111 @BASEBOARD_FAB2_LIB.BASEBOARD_FAB2(SCH_1):PAGE45
    23 M_B_DQ<11> @BASEBOARD_FAB2_LIB.BASEBOARD_FAB2(SCH_1):M_B_DQ(11)   I111 @BASEBOARD_FAB2_LIB.BASEBOARD_FAB2(SCH_1):PAGE45
   161 M_B_DQ<8> @BASEBOARD_FAB2_LIB.BASEBOARD_FAB2(SCH_1):M_B_DQ(8)   I111 @BASEBOARD_FAB2_LIB.BASEBOARD_FAB2(SCH_1):PAGE45
    16 M_B_DQ<9> @BASEBOARD_FAB2_LIB.BASEBOARD_FAB2(SCH_1):M_B_DQ(9)   I111 @BASEBOARD_FAB2_LIB.BASEBOARD_FAB2(SCH_1):PAGE45
   155 M_B_DQ<6> @BASEBOARD_FAB2_LIB.BASEBOARD_FAB2(SCH_1):M_B_DQ(6)   I111 @BASEBOARD_FAB2_LIB.BASEBOARD_FAB2(SCH_1):PAGE45
    10 M_B_DQ<7> @BASEBOARD_FAB2_LIB.BASEBOARD_FAB2(SCH_1):M_B_DQ(7)   I111 @BASEBOARD_FAB2_LIB.BASEBOARD_FAB2(SCH_1):PAGE45
   148 M_B_DQ<4> @BASEBOARD_FAB2_LIB.BASEBOARD_FAB2(SCH_1):M_B_DQ(4)   I111 @BASEBOARD_FAB2_LIB.BASEBOARD_FAB2(SCH_1):PAGE45
     3 M_B_DQ<5> @BASEBOARD_FAB2_LIB.BASEBOARD_FAB2(SCH_1):M_B_DQ(5)   I111 @BASEBOARD_FAB2_LIB.BASEBOARD_FAB2(SCH_1):PAGE45
   157 M_B_DQ<2> @BASEBOARD_FAB2_LIB.BASEBOARD_FAB2(SCH_1):M_B_DQ(2)   I111 @BASEBOARD_FAB2_LIB.BASEBOARD_FAB2(SCH_1):PAGE45
    12 M_B_DQ<3> @BASEBOARD_FAB2_LIB.BASEBOARD_FAB2(SCH_1):M_B_DQ(3)   I111 @BASEBOARD_FAB2_LIB.BASEBOARD_FAB2(SCH_1):PAGE45
   150 M_B_DQ<0> @BASEBOARD_FAB2_LIB.BASEBOARD_FAB2(SCH_1):M_B_DQ(0)   I111 @BASEBOARD_FAB2_LIB.BASEBOARD_FAB2(SCH_1):PAGE45
     5 M_B_DQ<1> @BASEBOARD_FAB2_LIB.BASEBOARD_FAB2(SCH_1):M_B_DQ(1)   I111 @BASEBOARD_FAB2_LIB.BASEBOARD_FAB2(SCH_1):PAGE45
    78 FM_DIMM_EVENT_COD_N @BASEBOARD_FAB2_LIB.BASEBOARD_FAB2(SCH_1):FM_DIMM_EVENT_COD_N   I111 @BASEBOARD_FAB2_LIB.BASEBOARD_FAB2(SCH_1):PAGE45
    91 M_B_ODT<1> @BASEBOARD_FAB2_LIB.BASEBOARD_FAB2(SCH_1):M_B_ODT(1)   I111 @BASEBOARD_FAB2_LIB.BASEBOARD_FAB2(SCH_1):PAGE45
    87 M_B_ODT<0> @BASEBOARD_FAB2_LIB.BASEBOARD_FAB2(SCH_1):M_B_ODT(0)   I111 @BASEBOARD_FAB2_LIB.BASEBOARD_FAB2(SCH_1):PAGE45
   222 M_B_PAR @BASEBOARD_FAB2_LIB.BASEBOARD_FAB2(SCH_1):M_B_PAR   I111 @BASEBOARD_FAB2_LIB.BASEBOARD_FAB2(SCH_1):PAGE45
    58 M_ABC_RST_N @BASEBOARD_FAB2_LIB.BASEBOARD_FAB2(SCH_1):M_ABC_RST_N   I111 @BASEBOARD_FAB2_LIB.BASEBOARD_FAB2(SCH_1):PAGE45
   144 TP_CH_B_DIMM_B0_RFU_2 @BASEBOARD_FAB2_LIB.BASEBOARD_FAB2(SCH_1):TP_CH_B_DIMM_B0_RFU_2   I111 @BASEBOARD_FAB2_LIB.BASEBOARD_FAB2(SCH_1):PAGE45
   227 TP_CH_B_DIMM_B0_RFU_1 @BASEBOARD_FAB2_LIB.BASEBOARD_FAB2(SCH_1):TP_CH_B_DIMM_B0_RFU_1   I111 @BASEBOARD_FAB2_LIB.BASEBOARD_FAB2(SCH_1):PAGE45
   205 TP_CH_B_DIMM_B0_RFU_0 @BASEBOARD_FAB2_LIB.BASEBOARD_FAB2(SCH_1):TP_CH_B_DIMM_B0_RFU_0   I111 @BASEBOARD_FAB2_LIB.BASEBOARD_FAB2(SCH_1):PAGE45
    84 M_B_CS_N<0> @BASEBOARD_FAB2_LIB.BASEBOARD_FAB2(SCH_1):M_B_CS_N(0)   I111 @BASEBOARD_FAB2_LIB.BASEBOARD_FAB2(SCH_1):PAGE45
    89 M_B_CS_N<1> @BASEBOARD_FAB2_LIB.BASEBOARD_FAB2(SCH_1):M_B_CS_N(1)   I111 @BASEBOARD_FAB2_LIB.BASEBOARD_FAB2(SCH_1):PAGE45
    93 M_B_CS_N<2> @BASEBOARD_FAB2_LIB.BASEBOARD_FAB2(SCH_1):M_B_CS_N(2)   I111 @BASEBOARD_FAB2_LIB.BASEBOARD_FAB2(SCH_1):PAGE45
   237 M_B_CS_N<3> @BASEBOARD_FAB2_LIB.BASEBOARD_FAB2(SCH_1):M_B_CS_N(3)   I111 @BASEBOARD_FAB2_LIB.BASEBOARD_FAB2(SCH_1):PAGE45
   238    GND @BASEBOARD_FAB2_LIB.BASEBOARD_FAB2(SCH_1):GND   I111 @BASEBOARD_FAB2_LIB.BASEBOARD_FAB2(SCH_1):PAGE45
   140 PVPP_ABC @BASEBOARD_FAB2_LIB.BASEBOARD_FAB2(SCH_1):PVPP_ABC   I111 @BASEBOARD_FAB2_LIB.BASEBOARD_FAB2(SCH_1):PAGE45
   139    GND @BASEBOARD_FAB2_LIB.BASEBOARD_FAB2(SCH_1):GND   I111 @BASEBOARD_FAB2_LIB.BASEBOARD_FAB2(SCH_1):PAGE45
   230 FM_ADR_COMPLETE_ABC_N @BASEBOARD_FAB2_LIB.BASEBOARD_FAB2(SCH_1):FM_ADR_COMPLETE_ABC_N   I111 @BASEBOARD_FAB2_LIB.BASEBOARD_FAB2(SCH_1):PAGE45
   141 SMB_DDR_ABC_VPP_SCL @BASEBOARD_FAB2_LIB.BASEBOARD_FAB2(SCH_1):SMB_DDR_ABC_VPP_SCL   I111 @BASEBOARD_FAB2_LIB.BASEBOARD_FAB2(SCH_1):PAGE45
   285 SMB_DDR_ABC_VPP_SDA @BASEBOARD_FAB2_LIB.BASEBOARD_FAB2(SCH_1):SMB_DDR_ABC_VPP_SDA   I111 @BASEBOARD_FAB2_LIB.BASEBOARD_FAB2(SCH_1):PAGE45
   284 PVPP_ABC @BASEBOARD_FAB2_LIB.BASEBOARD_FAB2(SCH_1):PVPP_ABC   I111 @BASEBOARD_FAB2_LIB.BASEBOARD_FAB2(SCH_1):PAGE45
   146 M_B_VREF @BASEBOARD_FAB2_LIB.BASEBOARD_FAB2(SCH_1):M_B_VREF   I111 @BASEBOARD_FAB2_LIB.BASEBOARD_FAB2(SCH_1):PAGE45
   152 M_B_DQS_DN<0> @BASEBOARD_FAB2_LIB.BASEBOARD_FAB2(SCH_1):M_B_DQS_DN(0)    I61 @BASEBOARD_FAB2_LIB.BASEBOARD_FAB2(SCH_1):PAGE45
   153 M_B_DQS_DP<0> @BASEBOARD_FAB2_LIB.BASEBOARD_FAB2(SCH_1):M_B_DQS_DP(0)    I61 @BASEBOARD_FAB2_LIB.BASEBOARD_FAB2(SCH_1):PAGE45
    19 M_B_DQS_DN<10> @BASEBOARD_FAB2_LIB.BASEBOARD_FAB2(SCH_1):M_B_DQS_DN(10)    I61 @BASEBOARD_FAB2_LIB.BASEBOARD_FAB2(SCH_1):PAGE45
    18 M_B_DQS_DP<10> @BASEBOARD_FAB2_LIB.BASEBOARD_FAB2(SCH_1):M_B_DQS_DP(10)    I61 @BASEBOARD_FAB2_LIB.BASEBOARD_FAB2(SCH_1):PAGE45
    30 M_B_DQS_DN<11> @BASEBOARD_FAB2_LIB.BASEBOARD_FAB2(SCH_1):M_B_DQS_DN(11)    I61 @BASEBOARD_FAB2_LIB.BASEBOARD_FAB2(SCH_1):PAGE45
    29 M_B_DQS_DP<11> @BASEBOARD_FAB2_LIB.BASEBOARD_FAB2(SCH_1):M_B_DQS_DP(11)    I61 @BASEBOARD_FAB2_LIB.BASEBOARD_FAB2(SCH_1):PAGE45
    41 M_B_DQS_DN<12> @BASEBOARD_FAB2_LIB.BASEBOARD_FAB2(SCH_1):M_B_DQS_DN(12)    I61 @BASEBOARD_FAB2_LIB.BASEBOARD_FAB2(SCH_1):PAGE45
    40 M_B_DQS_DP<12> @BASEBOARD_FAB2_LIB.BASEBOARD_FAB2(SCH_1):M_B_DQS_DP(12)    I61 @BASEBOARD_FAB2_LIB.BASEBOARD_FAB2(SCH_1):PAGE45
   100 M_B_DQS_DN<13> @BASEBOARD_FAB2_LIB.BASEBOARD_FAB2(SCH_1):M_B_DQS_DN(13)    I61 @BASEBOARD_FAB2_LIB.BASEBOARD_FAB2(SCH_1):PAGE45
    99 M_B_DQS_DP<13> @BASEBOARD_FAB2_LIB.BASEBOARD_FAB2(SCH_1):M_B_DQS_DP(13)    I61 @BASEBOARD_FAB2_LIB.BASEBOARD_FAB2(SCH_1):PAGE45
   111 M_B_DQS_DN<14> @BASEBOARD_FAB2_LIB.BASEBOARD_FAB2(SCH_1):M_B_DQS_DN(14)    I61 @BASEBOARD_FAB2_LIB.BASEBOARD_FAB2(SCH_1):PAGE45
   110 M_B_DQS_DP<14> @BASEBOARD_FAB2_LIB.BASEBOARD_FAB2(SCH_1):M_B_DQS_DP(14)    I61 @BASEBOARD_FAB2_LIB.BASEBOARD_FAB2(SCH_1):PAGE45
   122 M_B_DQS_DN<15> @BASEBOARD_FAB2_LIB.BASEBOARD_FAB2(SCH_1):M_B_DQS_DN(15)    I61 @BASEBOARD_FAB2_LIB.BASEBOARD_FAB2(SCH_1):PAGE45
   121 M_B_DQS_DP<15> @BASEBOARD_FAB2_LIB.BASEBOARD_FAB2(SCH_1):M_B_DQS_DP(15)    I61 @BASEBOARD_FAB2_LIB.BASEBOARD_FAB2(SCH_1):PAGE45
   133 M_B_DQS_DN<16> @BASEBOARD_FAB2_LIB.BASEBOARD_FAB2(SCH_1):M_B_DQS_DN(16)    I61 @BASEBOARD_FAB2_LIB.BASEBOARD_FAB2(SCH_1):PAGE45
   132 M_B_DQS_DP<16> @BASEBOARD_FAB2_LIB.BASEBOARD_FAB2(SCH_1):M_B_DQS_DP(16)    I61 @BASEBOARD_FAB2_LIB.BASEBOARD_FAB2(SCH_1):PAGE45
    52 M_B_DQS_DN<17> @BASEBOARD_FAB2_LIB.BASEBOARD_FAB2(SCH_1):M_B_DQS_DN(17)    I61 @BASEBOARD_FAB2_LIB.BASEBOARD_FAB2(SCH_1):PAGE45
    51 M_B_DQS_DP<17> @BASEBOARD_FAB2_LIB.BASEBOARD_FAB2(SCH_1):M_B_DQS_DP(17)    I61 @BASEBOARD_FAB2_LIB.BASEBOARD_FAB2(SCH_1):PAGE45
   163 M_B_DQS_DN<1> @BASEBOARD_FAB2_LIB.BASEBOARD_FAB2(SCH_1):M_B_DQS_DN(1)    I61 @BASEBOARD_FAB2_LIB.BASEBOARD_FAB2(SCH_1):PAGE45
   164 M_B_DQS_DP<1> @BASEBOARD_FAB2_LIB.BASEBOARD_FAB2(SCH_1):M_B_DQS_DP(1)    I61 @BASEBOARD_FAB2_LIB.BASEBOARD_FAB2(SCH_1):PAGE45
   174 M_B_DQS_DN<2> @BASEBOARD_FAB2_LIB.BASEBOARD_FAB2(SCH_1):M_B_DQS_DN(2)    I61 @BASEBOARD_FAB2_LIB.BASEBOARD_FAB2(SCH_1):PAGE45
   175 M_B_DQS_DP<2> @BASEBOARD_FAB2_LIB.BASEBOARD_FAB2(SCH_1):M_B_DQS_DP(2)    I61 @BASEBOARD_FAB2_LIB.BASEBOARD_FAB2(SCH_1):PAGE45
   185 M_B_DQS_DN<3> @BASEBOARD_FAB2_LIB.BASEBOARD_FAB2(SCH_1):M_B_DQS_DN(3)    I61 @BASEBOARD_FAB2_LIB.BASEBOARD_FAB2(SCH_1):PAGE45
   186 M_B_DQS_DP<3> @BASEBOARD_FAB2_LIB.BASEBOARD_FAB2(SCH_1):M_B_DQS_DP(3)    I61 @BASEBOARD_FAB2_LIB.BASEBOARD_FAB2(SCH_1):PAGE45
   244 M_B_DQS_DN<4> @BASEBOARD_FAB2_LIB.BASEBOARD_FAB2(SCH_1):M_B_DQS_DN(4)    I61 @BASEBOARD_FAB2_LIB.BASEBOARD_FAB2(SCH_1):PAGE45
   245 M_B_DQS_DP<4> @BASEBOARD_FAB2_LIB.BASEBOARD_FAB2(SCH_1):M_B_DQS_DP(4)    I61 @BASEBOARD_FAB2_LIB.BASEBOARD_FAB2(SCH_1):PAGE45
   255 M_B_DQS_DN<5> @BASEBOARD_FAB2_LIB.BASEBOARD_FAB2(SCH_1):M_B_DQS_DN(5)    I61 @BASEBOARD_FAB2_LIB.BASEBOARD_FAB2(SCH_1):PAGE45
   256 M_B_DQS_DP<5> @BASEBOARD_FAB2_LIB.BASEBOARD_FAB2(SCH_1):M_B_DQS_DP(5)    I61 @BASEBOARD_FAB2_LIB.BASEBOARD_FAB2(SCH_1):PAGE45
   266 M_B_DQS_DN<6> @BASEBOARD_FAB2_LIB.BASEBOARD_FAB2(SCH_1):M_B_DQS_DN(6)    I61 @BASEBOARD_FAB2_LIB.BASEBOARD_FAB2(SCH_1):PAGE45
   267 M_B_DQS_DP<6> @BASEBOARD_FAB2_LIB.BASEBOARD_FAB2(SCH_1):M_B_DQS_DP(6)    I61 @BASEBOARD_FAB2_LIB.BASEBOARD_FAB2(SCH_1):PAGE45
   277 M_B_DQS_DN<7> @BASEBOARD_FAB2_LIB.BASEBOARD_FAB2(SCH_1):M_B_DQS_DN(7)    I61 @BASEBOARD_FAB2_LIB.BASEBOARD_FAB2(SCH_1):PAGE45
   278 M_B_DQS_DP<7> @BASEBOARD_FAB2_LIB.BASEBOARD_FAB2(SCH_1):M_B_DQS_DP(7)    I61 @BASEBOARD_FAB2_LIB.BASEBOARD_FAB2(SCH_1):PAGE45
   196 M_B_DQS_DN<8> @BASEBOARD_FAB2_LIB.BASEBOARD_FAB2(SCH_1):M_B_DQS_DN(8)    I61 @BASEBOARD_FAB2_LIB.BASEBOARD_FAB2(SCH_1):PAGE45
   197 M_B_DQS_DP<8> @BASEBOARD_FAB2_LIB.BASEBOARD_FAB2(SCH_1):M_B_DQS_DP(8)    I61 @BASEBOARD_FAB2_LIB.BASEBOARD_FAB2(SCH_1):PAGE45
     8 M_B_DQS_DN<9> @BASEBOARD_FAB2_LIB.BASEBOARD_FAB2(SCH_1):M_B_DQS_DN(9)    I61 @BASEBOARD_FAB2_LIB.BASEBOARD_FAB2(SCH_1):PAGE45
     7 M_B_DQS_DP<9> @BASEBOARD_FAB2_LIB.BASEBOARD_FAB2(SCH_1):M_B_DQS_DP(9)    I61 @BASEBOARD_FAB2_LIB.BASEBOARD_FAB2(SCH_1):PAGE45
     2    GND @BASEBOARD_FAB2_LIB.BASEBOARD_FAB2(SCH_1):GND    I43 @BASEBOARD_FAB2_LIB.BASEBOARD_FAB2(SCH_1):PAGE45
     4    GND @BASEBOARD_FAB2_LIB.BASEBOARD_FAB2(SCH_1):GND    I43 @BASEBOARD_FAB2_LIB.BASEBOARD_FAB2(SCH_1):PAGE45
     6    GND @BASEBOARD_FAB2_LIB.BASEBOARD_FAB2(SCH_1):GND    I43 @BASEBOARD_FAB2_LIB.BASEBOARD_FAB2(SCH_1):PAGE45
     9    GND @BASEBOARD_FAB2_LIB.BASEBOARD_FAB2(SCH_1):GND    I43 @BASEBOARD_FAB2_LIB.BASEBOARD_FAB2(SCH_1):PAGE45
    11    GND @BASEBOARD_FAB2_LIB.BASEBOARD_FAB2(SCH_1):GND    I43 @BASEBOARD_FAB2_LIB.BASEBOARD_FAB2(SCH_1):PAGE45
    13    GND @BASEBOARD_FAB2_LIB.BASEBOARD_FAB2(SCH_1):GND    I43 @BASEBOARD_FAB2_LIB.BASEBOARD_FAB2(SCH_1):PAGE45
    15    GND @BASEBOARD_FAB2_LIB.BASEBOARD_FAB2(SCH_1):GND    I43 @BASEBOARD_FAB2_LIB.BASEBOARD_FAB2(SCH_1):PAGE45
    17    GND @BASEBOARD_FAB2_LIB.BASEBOARD_FAB2(SCH_1):GND    I43 @BASEBOARD_FAB2_LIB.BASEBOARD_FAB2(SCH_1):PAGE45
    20    GND @BASEBOARD_FAB2_LIB.BASEBOARD_FAB2(SCH_1):GND    I43 @BASEBOARD_FAB2_LIB.BASEBOARD_FAB2(SCH_1):PAGE45
    22    GND @BASEBOARD_FAB2_LIB.BASEBOARD_FAB2(SCH_1):GND    I43 @BASEBOARD_FAB2_LIB.BASEBOARD_FAB2(SCH_1):PAGE45
    24    GND @BASEBOARD_FAB2_LIB.BASEBOARD_FAB2(SCH_1):GND    I43 @BASEBOARD_FAB2_LIB.BASEBOARD_FAB2(SCH_1):PAGE45
    26    GND @BASEBOARD_FAB2_LIB.BASEBOARD_FAB2(SCH_1):GND    I43 @BASEBOARD_FAB2_LIB.BASEBOARD_FAB2(SCH_1):PAGE45
    28    GND @BASEBOARD_FAB2_LIB.BASEBOARD_FAB2(SCH_1):GND    I43 @BASEBOARD_FAB2_LIB.BASEBOARD_FAB2(SCH_1):PAGE45
    31    GND @BASEBOARD_FAB2_LIB.BASEBOARD_FAB2(SCH_1):GND    I43 @BASEBOARD_FAB2_LIB.BASEBOARD_FAB2(SCH_1):PAGE45
    33    GND @BASEBOARD_FAB2_LIB.BASEBOARD_FAB2(SCH_1):GND    I43 @BASEBOARD_FAB2_LIB.BASEBOARD_FAB2(SCH_1):PAGE45
    35    GND @BASEBOARD_FAB2_LIB.BASEBOARD_FAB2(SCH_1):GND    I43 @BASEBOARD_FAB2_LIB.BASEBOARD_FAB2(SCH_1):PAGE45
    37    GND @BASEBOARD_FAB2_LIB.BASEBOARD_FAB2(SCH_1):GND    I43 @BASEBOARD_FAB2_LIB.BASEBOARD_FAB2(SCH_1):PAGE45
    39    GND @BASEBOARD_FAB2_LIB.BASEBOARD_FAB2(SCH_1):GND    I43 @BASEBOARD_FAB2_LIB.BASEBOARD_FAB2(SCH_1):PAGE45
    42    GND @BASEBOARD_FAB2_LIB.BASEBOARD_FAB2(SCH_1):GND    I43 @BASEBOARD_FAB2_LIB.BASEBOARD_FAB2(SCH_1):PAGE45
    44    GND @BASEBOARD_FAB2_LIB.BASEBOARD_FAB2(SCH_1):GND    I43 @BASEBOARD_FAB2_LIB.BASEBOARD_FAB2(SCH_1):PAGE45
    46    GND @BASEBOARD_FAB2_LIB.BASEBOARD_FAB2(SCH_1):GND    I43 @BASEBOARD_FAB2_LIB.BASEBOARD_FAB2(SCH_1):PAGE45
    48    GND @BASEBOARD_FAB2_LIB.BASEBOARD_FAB2(SCH_1):GND    I43 @BASEBOARD_FAB2_LIB.BASEBOARD_FAB2(SCH_1):PAGE45
    50    GND @BASEBOARD_FAB2_LIB.BASEBOARD_FAB2(SCH_1):GND    I43 @BASEBOARD_FAB2_LIB.BASEBOARD_FAB2(SCH_1):PAGE45
    53    GND @BASEBOARD_FAB2_LIB.BASEBOARD_FAB2(SCH_1):GND    I43 @BASEBOARD_FAB2_LIB.BASEBOARD_FAB2(SCH_1):PAGE45
    55    GND @BASEBOARD_FAB2_LIB.BASEBOARD_FAB2(SCH_1):GND    I43 @BASEBOARD_FAB2_LIB.BASEBOARD_FAB2(SCH_1):PAGE45
    57    GND @BASEBOARD_FAB2_LIB.BASEBOARD_FAB2(SCH_1):GND    I43 @BASEBOARD_FAB2_LIB.BASEBOARD_FAB2(SCH_1):PAGE45
    94    GND @BASEBOARD_FAB2_LIB.BASEBOARD_FAB2(SCH_1):GND    I43 @BASEBOARD_FAB2_LIB.BASEBOARD_FAB2(SCH_1):PAGE45
    96    GND @BASEBOARD_FAB2_LIB.BASEBOARD_FAB2(SCH_1):GND    I43 @BASEBOARD_FAB2_LIB.BASEBOARD_FAB2(SCH_1):PAGE45
    98    GND @BASEBOARD_FAB2_LIB.BASEBOARD_FAB2(SCH_1):GND    I43 @BASEBOARD_FAB2_LIB.BASEBOARD_FAB2(SCH_1):PAGE45
   101    GND @BASEBOARD_FAB2_LIB.BASEBOARD_FAB2(SCH_1):GND    I43 @BASEBOARD_FAB2_LIB.BASEBOARD_FAB2(SCH_1):PAGE45
   103    GND @BASEBOARD_FAB2_LIB.BASEBOARD_FAB2(SCH_1):GND    I43 @BASEBOARD_FAB2_LIB.BASEBOARD_FAB2(SCH_1):PAGE45
   105    GND @BASEBOARD_FAB2_LIB.BASEBOARD_FAB2(SCH_1):GND    I43 @BASEBOARD_FAB2_LIB.BASEBOARD_FAB2(SCH_1):PAGE45
   107    GND @BASEBOARD_FAB2_LIB.BASEBOARD_FAB2(SCH_1):GND    I43 @BASEBOARD_FAB2_LIB.BASEBOARD_FAB2(SCH_1):PAGE45
   109    GND @BASEBOARD_FAB2_LIB.BASEBOARD_FAB2(SCH_1):GND    I43 @BASEBOARD_FAB2_LIB.BASEBOARD_FAB2(SCH_1):PAGE45
   112    GND @BASEBOARD_FAB2_LIB.BASEBOARD_FAB2(SCH_1):GND    I43 @BASEBOARD_FAB2_LIB.BASEBOARD_FAB2(SCH_1):PAGE45
   114    GND @BASEBOARD_FAB2_LIB.BASEBOARD_FAB2(SCH_1):GND    I43 @BASEBOARD_FAB2_LIB.BASEBOARD_FAB2(SCH_1):PAGE45
   116    GND @BASEBOARD_FAB2_LIB.BASEBOARD_FAB2(SCH_1):GND    I43 @BASEBOARD_FAB2_LIB.BASEBOARD_FAB2(SCH_1):PAGE45
   118    GND @BASEBOARD_FAB2_LIB.BASEBOARD_FAB2(SCH_1):GND    I43 @BASEBOARD_FAB2_LIB.BASEBOARD_FAB2(SCH_1):PAGE45
   120    GND @BASEBOARD_FAB2_LIB.BASEBOARD_FAB2(SCH_1):GND    I43 @BASEBOARD_FAB2_LIB.BASEBOARD_FAB2(SCH_1):PAGE45
   123    GND @BASEBOARD_FAB2_LIB.BASEBOARD_FAB2(SCH_1):GND    I43 @BASEBOARD_FAB2_LIB.BASEBOARD_FAB2(SCH_1):PAGE45
   125    GND @BASEBOARD_FAB2_LIB.BASEBOARD_FAB2(SCH_1):GND    I43 @BASEBOARD_FAB2_LIB.BASEBOARD_FAB2(SCH_1):PAGE45
   127    GND @BASEBOARD_FAB2_LIB.BASEBOARD_FAB2(SCH_1):GND    I43 @BASEBOARD_FAB2_LIB.BASEBOARD_FAB2(SCH_1):PAGE45
   129    GND @BASEBOARD_FAB2_LIB.BASEBOARD_FAB2(SCH_1):GND    I43 @BASEBOARD_FAB2_LIB.BASEBOARD_FAB2(SCH_1):PAGE45
   131    GND @BASEBOARD_FAB2_LIB.BASEBOARD_FAB2(SCH_1):GND    I43 @BASEBOARD_FAB2_LIB.BASEBOARD_FAB2(SCH_1):PAGE45
   134    GND @BASEBOARD_FAB2_LIB.BASEBOARD_FAB2(SCH_1):GND    I43 @BASEBOARD_FAB2_LIB.BASEBOARD_FAB2(SCH_1):PAGE45
   136    GND @BASEBOARD_FAB2_LIB.BASEBOARD_FAB2(SCH_1):GND    I43 @BASEBOARD_FAB2_LIB.BASEBOARD_FAB2(SCH_1):PAGE45
   138    GND @BASEBOARD_FAB2_LIB.BASEBOARD_FAB2(SCH_1):GND    I43 @BASEBOARD_FAB2_LIB.BASEBOARD_FAB2(SCH_1):PAGE45
   147    GND @BASEBOARD_FAB2_LIB.BASEBOARD_FAB2(SCH_1):GND    I43 @BASEBOARD_FAB2_LIB.BASEBOARD_FAB2(SCH_1):PAGE45
   149    GND @BASEBOARD_FAB2_LIB.BASEBOARD_FAB2(SCH_1):GND    I43 @BASEBOARD_FAB2_LIB.BASEBOARD_FAB2(SCH_1):PAGE45
   151    GND @BASEBOARD_FAB2_LIB.BASEBOARD_FAB2(SCH_1):GND    I43 @BASEBOARD_FAB2_LIB.BASEBOARD_FAB2(SCH_1):PAGE45
   154    GND @BASEBOARD_FAB2_LIB.BASEBOARD_FAB2(SCH_1):GND    I43 @BASEBOARD_FAB2_LIB.BASEBOARD_FAB2(SCH_1):PAGE45
   156    GND @BASEBOARD_FAB2_LIB.BASEBOARD_FAB2(SCH_1):GND    I43 @BASEBOARD_FAB2_LIB.BASEBOARD_FAB2(SCH_1):PAGE45
   158    GND @BASEBOARD_FAB2_LIB.BASEBOARD_FAB2(SCH_1):GND    I43 @BASEBOARD_FAB2_LIB.BASEBOARD_FAB2(SCH_1):PAGE45
   160    GND @BASEBOARD_FAB2_LIB.BASEBOARD_FAB2(SCH_1):GND    I43 @BASEBOARD_FAB2_LIB.BASEBOARD_FAB2(SCH_1):PAGE45
   162    GND @BASEBOARD_FAB2_LIB.BASEBOARD_FAB2(SCH_1):GND    I43 @BASEBOARD_FAB2_LIB.BASEBOARD_FAB2(SCH_1):PAGE45
   165    GND @BASEBOARD_FAB2_LIB.BASEBOARD_FAB2(SCH_1):GND    I43 @BASEBOARD_FAB2_LIB.BASEBOARD_FAB2(SCH_1):PAGE45
   167    GND @BASEBOARD_FAB2_LIB.BASEBOARD_FAB2(SCH_1):GND    I43 @BASEBOARD_FAB2_LIB.BASEBOARD_FAB2(SCH_1):PAGE45
   169    GND @BASEBOARD_FAB2_LIB.BASEBOARD_FAB2(SCH_1):GND    I43 @BASEBOARD_FAB2_LIB.BASEBOARD_FAB2(SCH_1):PAGE45
   171    GND @BASEBOARD_FAB2_LIB.BASEBOARD_FAB2(SCH_1):GND    I43 @BASEBOARD_FAB2_LIB.BASEBOARD_FAB2(SCH_1):PAGE45
   173    GND @BASEBOARD_FAB2_LIB.BASEBOARD_FAB2(SCH_1):GND    I43 @BASEBOARD_FAB2_LIB.BASEBOARD_FAB2(SCH_1):PAGE45
   176    GND @BASEBOARD_FAB2_LIB.BASEBOARD_FAB2(SCH_1):GND    I43 @BASEBOARD_FAB2_LIB.BASEBOARD_FAB2(SCH_1):PAGE45
   178    GND @BASEBOARD_FAB2_LIB.BASEBOARD_FAB2(SCH_1):GND    I43 @BASEBOARD_FAB2_LIB.BASEBOARD_FAB2(SCH_1):PAGE45
   180    GND @BASEBOARD_FAB2_LIB.BASEBOARD_FAB2(SCH_1):GND    I43 @BASEBOARD_FAB2_LIB.BASEBOARD_FAB2(SCH_1):PAGE45
   182    GND @BASEBOARD_FAB2_LIB.BASEBOARD_FAB2(SCH_1):GND    I43 @BASEBOARD_FAB2_LIB.BASEBOARD_FAB2(SCH_1):PAGE45
   184    GND @BASEBOARD_FAB2_LIB.BASEBOARD_FAB2(SCH_1):GND    I43 @BASEBOARD_FAB2_LIB.BASEBOARD_FAB2(SCH_1):PAGE45
   187    GND @BASEBOARD_FAB2_LIB.BASEBOARD_FAB2(SCH_1):GND    I43 @BASEBOARD_FAB2_LIB.BASEBOARD_FAB2(SCH_1):PAGE45
   189    GND @BASEBOARD_FAB2_LIB.BASEBOARD_FAB2(SCH_1):GND    I43 @BASEBOARD_FAB2_LIB.BASEBOARD_FAB2(SCH_1):PAGE45
   191    GND @BASEBOARD_FAB2_LIB.BASEBOARD_FAB2(SCH_1):GND    I43 @BASEBOARD_FAB2_LIB.BASEBOARD_FAB2(SCH_1):PAGE45
   193    GND @BASEBOARD_FAB2_LIB.BASEBOARD_FAB2(SCH_1):GND    I43 @BASEBOARD_FAB2_LIB.BASEBOARD_FAB2(SCH_1):PAGE45
   195    GND @BASEBOARD_FAB2_LIB.BASEBOARD_FAB2(SCH_1):GND    I43 @BASEBOARD_FAB2_LIB.BASEBOARD_FAB2(SCH_1):PAGE45
   198    GND @BASEBOARD_FAB2_LIB.BASEBOARD_FAB2(SCH_1):GND    I43 @BASEBOARD_FAB2_LIB.BASEBOARD_FAB2(SCH_1):PAGE45
   200    GND @BASEBOARD_FAB2_LIB.BASEBOARD_FAB2(SCH_1):GND    I43 @BASEBOARD_FAB2_LIB.BASEBOARD_FAB2(SCH_1):PAGE45
   202    GND @BASEBOARD_FAB2_LIB.BASEBOARD_FAB2(SCH_1):GND    I43 @BASEBOARD_FAB2_LIB.BASEBOARD_FAB2(SCH_1):PAGE45
   239    GND @BASEBOARD_FAB2_LIB.BASEBOARD_FAB2(SCH_1):GND    I43 @BASEBOARD_FAB2_LIB.BASEBOARD_FAB2(SCH_1):PAGE45
   241    GND @BASEBOARD_FAB2_LIB.BASEBOARD_FAB2(SCH_1):GND    I43 @BASEBOARD_FAB2_LIB.BASEBOARD_FAB2(SCH_1):PAGE45
   243    GND @BASEBOARD_FAB2_LIB.BASEBOARD_FAB2(SCH_1):GND    I43 @BASEBOARD_FAB2_LIB.BASEBOARD_FAB2(SCH_1):PAGE45
   246    GND @BASEBOARD_FAB2_LIB.BASEBOARD_FAB2(SCH_1):GND    I43 @BASEBOARD_FAB2_LIB.BASEBOARD_FAB2(SCH_1):PAGE45
   248    GND @BASEBOARD_FAB2_LIB.BASEBOARD_FAB2(SCH_1):GND    I43 @BASEBOARD_FAB2_LIB.BASEBOARD_FAB2(SCH_1):PAGE45
   250    GND @BASEBOARD_FAB2_LIB.BASEBOARD_FAB2(SCH_1):GND    I43 @BASEBOARD_FAB2_LIB.BASEBOARD_FAB2(SCH_1):PAGE45
   252    GND @BASEBOARD_FAB2_LIB.BASEBOARD_FAB2(SCH_1):GND    I43 @BASEBOARD_FAB2_LIB.BASEBOARD_FAB2(SCH_1):PAGE45
   254    GND @BASEBOARD_FAB2_LIB.BASEBOARD_FAB2(SCH_1):GND    I43 @BASEBOARD_FAB2_LIB.BASEBOARD_FAB2(SCH_1):PAGE45
   257    GND @BASEBOARD_FAB2_LIB.BASEBOARD_FAB2(SCH_1):GND    I43 @BASEBOARD_FAB2_LIB.BASEBOARD_FAB2(SCH_1):PAGE45
   259    GND @BASEBOARD_FAB2_LIB.BASEBOARD_FAB2(SCH_1):GND    I43 @BASEBOARD_FAB2_LIB.BASEBOARD_FAB2(SCH_1):PAGE45
   261    GND @BASEBOARD_FAB2_LIB.BASEBOARD_FAB2(SCH_1):GND    I43 @BASEBOARD_FAB2_LIB.BASEBOARD_FAB2(SCH_1):PAGE45
   263    GND @BASEBOARD_FAB2_LIB.BASEBOARD_FAB2(SCH_1):GND    I43 @BASEBOARD_FAB2_LIB.BASEBOARD_FAB2(SCH_1):PAGE45
   265    GND @BASEBOARD_FAB2_LIB.BASEBOARD_FAB2(SCH_1):GND    I43 @BASEBOARD_FAB2_LIB.BASEBOARD_FAB2(SCH_1):PAGE45
   268    GND @BASEBOARD_FAB2_LIB.BASEBOARD_FAB2(SCH_1):GND    I43 @BASEBOARD_FAB2_LIB.BASEBOARD_FAB2(SCH_1):PAGE45
   270    GND @BASEBOARD_FAB2_LIB.BASEBOARD_FAB2(SCH_1):GND    I43 @BASEBOARD_FAB2_LIB.BASEBOARD_FAB2(SCH_1):PAGE45
   272    GND @BASEBOARD_FAB2_LIB.BASEBOARD_FAB2(SCH_1):GND    I43 @BASEBOARD_FAB2_LIB.BASEBOARD_FAB2(SCH_1):PAGE45
   274    GND @BASEBOARD_FAB2_LIB.BASEBOARD_FAB2(SCH_1):GND    I43 @BASEBOARD_FAB2_LIB.BASEBOARD_FAB2(SCH_1):PAGE45
   276    GND @BASEBOARD_FAB2_LIB.BASEBOARD_FAB2(SCH_1):GND    I43 @BASEBOARD_FAB2_LIB.BASEBOARD_FAB2(SCH_1):PAGE45
   279    GND @BASEBOARD_FAB2_LIB.BASEBOARD_FAB2(SCH_1):GND    I43 @BASEBOARD_FAB2_LIB.BASEBOARD_FAB2(SCH_1):PAGE45
   281    GND @BASEBOARD_FAB2_LIB.BASEBOARD_FAB2(SCH_1):GND    I43 @BASEBOARD_FAB2_LIB.BASEBOARD_FAB2(SCH_1):PAGE45
   283    GND @BASEBOARD_FAB2_LIB.BASEBOARD_FAB2(SCH_1):GND    I43 @BASEBOARD_FAB2_LIB.BASEBOARD_FAB2(SCH_1):PAGE45
     1 P12V_NVDIMM_ABC @BASEBOARD_FAB2_LIB.BASEBOARD_FAB2(SCH_1):P12V_NVDIMM_ABC   I169 @BASEBOARD_FAB2_LIB.BASEBOARD_FAB2(SCH_1):PAGE45
   145 P12V_NVDIMM_ABC @BASEBOARD_FAB2_LIB.BASEBOARD_FAB2(SCH_1):P12V_NVDIMM_ABC   I169 @BASEBOARD_FAB2_LIB.BASEBOARD_FAB2(SCH_1):PAGE45
    59 PVDDQ_ABC @BASEBOARD_FAB2_LIB.BASEBOARD_FAB2(SCH_1):PVDDQ_ABC   I169 @BASEBOARD_FAB2_LIB.BASEBOARD_FAB2(SCH_1):PAGE45
    61 PVDDQ_ABC @BASEBOARD_FAB2_LIB.BASEBOARD_FAB2(SCH_1):PVDDQ_ABC   I169 @BASEBOARD_FAB2_LIB.BASEBOARD_FAB2(SCH_1):PAGE45
    64 PVDDQ_ABC @BASEBOARD_FAB2_LIB.BASEBOARD_FAB2(SCH_1):PVDDQ_ABC   I169 @BASEBOARD_FAB2_LIB.BASEBOARD_FAB2(SCH_1):PAGE45
    67 PVDDQ_ABC @BASEBOARD_FAB2_LIB.BASEBOARD_FAB2(SCH_1):PVDDQ_ABC   I169 @BASEBOARD_FAB2_LIB.BASEBOARD_FAB2(SCH_1):PAGE45
    70 PVDDQ_ABC @BASEBOARD_FAB2_LIB.BASEBOARD_FAB2(SCH_1):PVDDQ_ABC   I169 @BASEBOARD_FAB2_LIB.BASEBOARD_FAB2(SCH_1):PAGE45
    73 PVDDQ_ABC @BASEBOARD_FAB2_LIB.BASEBOARD_FAB2(SCH_1):PVDDQ_ABC   I169 @BASEBOARD_FAB2_LIB.BASEBOARD_FAB2(SCH_1):PAGE45
    76 PVDDQ_ABC @BASEBOARD_FAB2_LIB.BASEBOARD_FAB2(SCH_1):PVDDQ_ABC   I169 @BASEBOARD_FAB2_LIB.BASEBOARD_FAB2(SCH_1):PAGE45
    80 PVDDQ_ABC @BASEBOARD_FAB2_LIB.BASEBOARD_FAB2(SCH_1):PVDDQ_ABC   I169 @BASEBOARD_FAB2_LIB.BASEBOARD_FAB2(SCH_1):PAGE45
    83 PVDDQ_ABC @BASEBOARD_FAB2_LIB.BASEBOARD_FAB2(SCH_1):PVDDQ_ABC   I169 @BASEBOARD_FAB2_LIB.BASEBOARD_FAB2(SCH_1):PAGE45
    85 PVDDQ_ABC @BASEBOARD_FAB2_LIB.BASEBOARD_FAB2(SCH_1):PVDDQ_ABC   I169 @BASEBOARD_FAB2_LIB.BASEBOARD_FAB2(SCH_1):PAGE45
    88 PVDDQ_ABC @BASEBOARD_FAB2_LIB.BASEBOARD_FAB2(SCH_1):PVDDQ_ABC   I169 @BASEBOARD_FAB2_LIB.BASEBOARD_FAB2(SCH_1):PAGE45
    90 PVDDQ_ABC @BASEBOARD_FAB2_LIB.BASEBOARD_FAB2(SCH_1):PVDDQ_ABC   I169 @BASEBOARD_FAB2_LIB.BASEBOARD_FAB2(SCH_1):PAGE45
    92 PVDDQ_ABC @BASEBOARD_FAB2_LIB.BASEBOARD_FAB2(SCH_1):PVDDQ_ABC   I169 @BASEBOARD_FAB2_LIB.BASEBOARD_FAB2(SCH_1):PAGE45
   204 PVDDQ_ABC @BASEBOARD_FAB2_LIB.BASEBOARD_FAB2(SCH_1):PVDDQ_ABC   I169 @BASEBOARD_FAB2_LIB.BASEBOARD_FAB2(SCH_1):PAGE45
   206 PVDDQ_ABC @BASEBOARD_FAB2_LIB.BASEBOARD_FAB2(SCH_1):PVDDQ_ABC   I169 @BASEBOARD_FAB2_LIB.BASEBOARD_FAB2(SCH_1):PAGE45
   209 PVDDQ_ABC @BASEBOARD_FAB2_LIB.BASEBOARD_FAB2(SCH_1):PVDDQ_ABC   I169 @BASEBOARD_FAB2_LIB.BASEBOARD_FAB2(SCH_1):PAGE45
   212 PVDDQ_ABC @BASEBOARD_FAB2_LIB.BASEBOARD_FAB2(SCH_1):PVDDQ_ABC   I169 @BASEBOARD_FAB2_LIB.BASEBOARD_FAB2(SCH_1):PAGE45
   215 PVDDQ_ABC @BASEBOARD_FAB2_LIB.BASEBOARD_FAB2(SCH_1):PVDDQ_ABC   I169 @BASEBOARD_FAB2_LIB.BASEBOARD_FAB2(SCH_1):PAGE45
   217 PVDDQ_ABC @BASEBOARD_FAB2_LIB.BASEBOARD_FAB2(SCH_1):PVDDQ_ABC   I169 @BASEBOARD_FAB2_LIB.BASEBOARD_FAB2(SCH_1):PAGE45
   220 PVDDQ_ABC @BASEBOARD_FAB2_LIB.BASEBOARD_FAB2(SCH_1):PVDDQ_ABC   I169 @BASEBOARD_FAB2_LIB.BASEBOARD_FAB2(SCH_1):PAGE45
   223 PVDDQ_ABC @BASEBOARD_FAB2_LIB.BASEBOARD_FAB2(SCH_1):PVDDQ_ABC   I169 @BASEBOARD_FAB2_LIB.BASEBOARD_FAB2(SCH_1):PAGE45
   226 PVDDQ_ABC @BASEBOARD_FAB2_LIB.BASEBOARD_FAB2(SCH_1):PVDDQ_ABC   I169 @BASEBOARD_FAB2_LIB.BASEBOARD_FAB2(SCH_1):PAGE45
   229 PVDDQ_ABC @BASEBOARD_FAB2_LIB.BASEBOARD_FAB2(SCH_1):PVDDQ_ABC   I169 @BASEBOARD_FAB2_LIB.BASEBOARD_FAB2(SCH_1):PAGE45
   231 PVDDQ_ABC @BASEBOARD_FAB2_LIB.BASEBOARD_FAB2(SCH_1):PVDDQ_ABC   I169 @BASEBOARD_FAB2_LIB.BASEBOARD_FAB2(SCH_1):PAGE45
   233 PVDDQ_ABC @BASEBOARD_FAB2_LIB.BASEBOARD_FAB2(SCH_1):PVDDQ_ABC   I169 @BASEBOARD_FAB2_LIB.BASEBOARD_FAB2(SCH_1):PAGE45
   236 PVDDQ_ABC @BASEBOARD_FAB2_LIB.BASEBOARD_FAB2(SCH_1):PVDDQ_ABC   I169 @BASEBOARD_FAB2_LIB.BASEBOARD_FAB2(SCH_1):PAGE45
   142 PVPP_ABC @BASEBOARD_FAB2_LIB.BASEBOARD_FAB2(SCH_1):PVPP_ABC   I169 @BASEBOARD_FAB2_LIB.BASEBOARD_FAB2(SCH_1):PAGE45
   143 PVPP_ABC @BASEBOARD_FAB2_LIB.BASEBOARD_FAB2(SCH_1):PVPP_ABC   I169 @BASEBOARD_FAB2_LIB.BASEBOARD_FAB2(SCH_1):PAGE45
   288 PVPP_ABC @BASEBOARD_FAB2_LIB.BASEBOARD_FAB2(SCH_1):PVPP_ABC   I169 @BASEBOARD_FAB2_LIB.BASEBOARD_FAB2(SCH_1):PAGE45
   286 PVPP_ABC @BASEBOARD_FAB2_LIB.BASEBOARD_FAB2(SCH_1):PVPP_ABC   I169 @BASEBOARD_FAB2_LIB.BASEBOARD_FAB2(SCH_1):PAGE45
   287 PVPP_ABC @BASEBOARD_FAB2_LIB.BASEBOARD_FAB2(SCH_1):PVPP_ABC   I169 @BASEBOARD_FAB2_LIB.BASEBOARD_FAB2(SCH_1):PAGE45
    77 PVTT_ABC @BASEBOARD_FAB2_LIB.BASEBOARD_FAB2(SCH_1):PVTT_ABC   I169 @BASEBOARD_FAB2_LIB.BASEBOARD_FAB2(SCH_1):PAGE45
   221 PVTT_ABC @BASEBOARD_FAB2_LIB.BASEBOARD_FAB2(SCH_1):PVTT_ABC   I169 @BASEBOARD_FAB2_LIB.BASEBOARD_FAB2(SCH_1):PAGE45

J4G3 SCONN288_H44441004_PIP-SCONN,HA
    79 M_C_MA<0> @BASEBOARD_FAB2_LIB.BASEBOARD_FAB2(SCH_1):M_C_MA(0)   I111 @BASEBOARD_FAB2_LIB.BASEBOARD_FAB2(SCH_1):PAGE47
    72 M_C_MA<1> @BASEBOARD_FAB2_LIB.BASEBOARD_FAB2(SCH_1):M_C_MA(1)   I111 @BASEBOARD_FAB2_LIB.BASEBOARD_FAB2(SCH_1):PAGE47
   225 M_C_MA<10> @BASEBOARD_FAB2_LIB.BASEBOARD_FAB2(SCH_1):M_C_MA(10)   I111 @BASEBOARD_FAB2_LIB.BASEBOARD_FAB2(SCH_1):PAGE47
   210 M_C_MA<11> @BASEBOARD_FAB2_LIB.BASEBOARD_FAB2(SCH_1):M_C_MA(11)   I111 @BASEBOARD_FAB2_LIB.BASEBOARD_FAB2(SCH_1):PAGE47
    65 M_C_MA<12> @BASEBOARD_FAB2_LIB.BASEBOARD_FAB2(SCH_1):M_C_MA(12)   I111 @BASEBOARD_FAB2_LIB.BASEBOARD_FAB2(SCH_1):PAGE47
   232 M_C_MA<13> @BASEBOARD_FAB2_LIB.BASEBOARD_FAB2(SCH_1):M_C_MA(13)   I111 @BASEBOARD_FAB2_LIB.BASEBOARD_FAB2(SCH_1):PAGE47
   228 M_C_MA<14> @BASEBOARD_FAB2_LIB.BASEBOARD_FAB2(SCH_1):M_C_MA(14)   I111 @BASEBOARD_FAB2_LIB.BASEBOARD_FAB2(SCH_1):PAGE47
    86 M_C_MA<15> @BASEBOARD_FAB2_LIB.BASEBOARD_FAB2(SCH_1):M_C_MA(15)   I111 @BASEBOARD_FAB2_LIB.BASEBOARD_FAB2(SCH_1):PAGE47
    82 M_C_MA<16> @BASEBOARD_FAB2_LIB.BASEBOARD_FAB2(SCH_1):M_C_MA(16)   I111 @BASEBOARD_FAB2_LIB.BASEBOARD_FAB2(SCH_1):PAGE47
   234 M_C_MA<17> @BASEBOARD_FAB2_LIB.BASEBOARD_FAB2(SCH_1):M_C_MA(17)   I111 @BASEBOARD_FAB2_LIB.BASEBOARD_FAB2(SCH_1):PAGE47
   216 M_C_MA<2> @BASEBOARD_FAB2_LIB.BASEBOARD_FAB2(SCH_1):M_C_MA(2)   I111 @BASEBOARD_FAB2_LIB.BASEBOARD_FAB2(SCH_1):PAGE47
    71 M_C_MA<3> @BASEBOARD_FAB2_LIB.BASEBOARD_FAB2(SCH_1):M_C_MA(3)   I111 @BASEBOARD_FAB2_LIB.BASEBOARD_FAB2(SCH_1):PAGE47
   214 M_C_MA<4> @BASEBOARD_FAB2_LIB.BASEBOARD_FAB2(SCH_1):M_C_MA(4)   I111 @BASEBOARD_FAB2_LIB.BASEBOARD_FAB2(SCH_1):PAGE47
   213 M_C_MA<5> @BASEBOARD_FAB2_LIB.BASEBOARD_FAB2(SCH_1):M_C_MA(5)   I111 @BASEBOARD_FAB2_LIB.BASEBOARD_FAB2(SCH_1):PAGE47
    69 M_C_MA<6> @BASEBOARD_FAB2_LIB.BASEBOARD_FAB2(SCH_1):M_C_MA(6)   I111 @BASEBOARD_FAB2_LIB.BASEBOARD_FAB2(SCH_1):PAGE47
   211 M_C_MA<7> @BASEBOARD_FAB2_LIB.BASEBOARD_FAB2(SCH_1):M_C_MA(7)   I111 @BASEBOARD_FAB2_LIB.BASEBOARD_FAB2(SCH_1):PAGE47
    68 M_C_MA<8> @BASEBOARD_FAB2_LIB.BASEBOARD_FAB2(SCH_1):M_C_MA(8)   I111 @BASEBOARD_FAB2_LIB.BASEBOARD_FAB2(SCH_1):PAGE47
    66 M_C_MA<9> @BASEBOARD_FAB2_LIB.BASEBOARD_FAB2(SCH_1):M_C_MA(9)   I111 @BASEBOARD_FAB2_LIB.BASEBOARD_FAB2(SCH_1):PAGE47
    62 M_C_ACT_N @BASEBOARD_FAB2_LIB.BASEBOARD_FAB2(SCH_1):M_C_ACT_N   I111 @BASEBOARD_FAB2_LIB.BASEBOARD_FAB2(SCH_1):PAGE47
   208 M_C_ALERT_N @BASEBOARD_FAB2_LIB.BASEBOARD_FAB2(SCH_1):M_C_ALERT_N   I111 @BASEBOARD_FAB2_LIB.BASEBOARD_FAB2(SCH_1):PAGE47
   224 M_C_BA<1> @BASEBOARD_FAB2_LIB.BASEBOARD_FAB2(SCH_1):M_C_BA(1)   I111 @BASEBOARD_FAB2_LIB.BASEBOARD_FAB2(SCH_1):PAGE47
    81 M_C_BA<0> @BASEBOARD_FAB2_LIB.BASEBOARD_FAB2(SCH_1):M_C_BA(0)   I111 @BASEBOARD_FAB2_LIB.BASEBOARD_FAB2(SCH_1):PAGE47
   207 M_C_BG<1> @BASEBOARD_FAB2_LIB.BASEBOARD_FAB2(SCH_1):M_C_BG(1)   I111 @BASEBOARD_FAB2_LIB.BASEBOARD_FAB2(SCH_1):PAGE47
    63 M_C_BG<0> @BASEBOARD_FAB2_LIB.BASEBOARD_FAB2(SCH_1):M_C_BG(0)   I111 @BASEBOARD_FAB2_LIB.BASEBOARD_FAB2(SCH_1):PAGE47
   235 M_C_C<2> @BASEBOARD_FAB2_LIB.BASEBOARD_FAB2(SCH_1):M_C_C(2)   I111 @BASEBOARD_FAB2_LIB.BASEBOARD_FAB2(SCH_1):PAGE47
   199 M_C_ECC<6> @BASEBOARD_FAB2_LIB.BASEBOARD_FAB2(SCH_1):M_C_ECC(6)   I111 @BASEBOARD_FAB2_LIB.BASEBOARD_FAB2(SCH_1):PAGE47
    54 M_C_ECC<7> @BASEBOARD_FAB2_LIB.BASEBOARD_FAB2(SCH_1):M_C_ECC(7)   I111 @BASEBOARD_FAB2_LIB.BASEBOARD_FAB2(SCH_1):PAGE47
   192 M_C_ECC<4> @BASEBOARD_FAB2_LIB.BASEBOARD_FAB2(SCH_1):M_C_ECC(4)   I111 @BASEBOARD_FAB2_LIB.BASEBOARD_FAB2(SCH_1):PAGE47
    47 M_C_ECC<5> @BASEBOARD_FAB2_LIB.BASEBOARD_FAB2(SCH_1):M_C_ECC(5)   I111 @BASEBOARD_FAB2_LIB.BASEBOARD_FAB2(SCH_1):PAGE47
   201 M_C_ECC<2> @BASEBOARD_FAB2_LIB.BASEBOARD_FAB2(SCH_1):M_C_ECC(2)   I111 @BASEBOARD_FAB2_LIB.BASEBOARD_FAB2(SCH_1):PAGE47
    56 M_C_ECC<3> @BASEBOARD_FAB2_LIB.BASEBOARD_FAB2(SCH_1):M_C_ECC(3)   I111 @BASEBOARD_FAB2_LIB.BASEBOARD_FAB2(SCH_1):PAGE47
   194 M_C_ECC<0> @BASEBOARD_FAB2_LIB.BASEBOARD_FAB2(SCH_1):M_C_ECC(0)   I111 @BASEBOARD_FAB2_LIB.BASEBOARD_FAB2(SCH_1):PAGE47
    49 M_C_ECC<1> @BASEBOARD_FAB2_LIB.BASEBOARD_FAB2(SCH_1):M_C_ECC(1)   I111 @BASEBOARD_FAB2_LIB.BASEBOARD_FAB2(SCH_1):PAGE47
    75 M_C_CLK_DN<0> @BASEBOARD_FAB2_LIB.BASEBOARD_FAB2(SCH_1):M_C_CLK_DN(0)   I111 @BASEBOARD_FAB2_LIB.BASEBOARD_FAB2(SCH_1):PAGE47
    74 M_C_CLK_DP<0> @BASEBOARD_FAB2_LIB.BASEBOARD_FAB2(SCH_1):M_C_CLK_DP(0)   I111 @BASEBOARD_FAB2_LIB.BASEBOARD_FAB2(SCH_1):PAGE47
   219 M_C_CLK_DN<1> @BASEBOARD_FAB2_LIB.BASEBOARD_FAB2(SCH_1):M_C_CLK_DN(1)   I111 @BASEBOARD_FAB2_LIB.BASEBOARD_FAB2(SCH_1):PAGE47
   218 M_C_CLK_DP<1> @BASEBOARD_FAB2_LIB.BASEBOARD_FAB2(SCH_1):M_C_CLK_DP(1)   I111 @BASEBOARD_FAB2_LIB.BASEBOARD_FAB2(SCH_1):PAGE47
   203 M_C_CKE<1> @BASEBOARD_FAB2_LIB.BASEBOARD_FAB2(SCH_1):M_C_CKE(1)   I111 @BASEBOARD_FAB2_LIB.BASEBOARD_FAB2(SCH_1):PAGE47
    60 M_C_CKE<0> @BASEBOARD_FAB2_LIB.BASEBOARD_FAB2(SCH_1):M_C_CKE(0)   I111 @BASEBOARD_FAB2_LIB.BASEBOARD_FAB2(SCH_1):PAGE47
   280 M_C_DQ<62> @BASEBOARD_FAB2_LIB.BASEBOARD_FAB2(SCH_1):M_C_DQ(62)   I111 @BASEBOARD_FAB2_LIB.BASEBOARD_FAB2(SCH_1):PAGE47
   135 M_C_DQ<63> @BASEBOARD_FAB2_LIB.BASEBOARD_FAB2(SCH_1):M_C_DQ(63)   I111 @BASEBOARD_FAB2_LIB.BASEBOARD_FAB2(SCH_1):PAGE47
   273 M_C_DQ<60> @BASEBOARD_FAB2_LIB.BASEBOARD_FAB2(SCH_1):M_C_DQ(60)   I111 @BASEBOARD_FAB2_LIB.BASEBOARD_FAB2(SCH_1):PAGE47
   128 M_C_DQ<61> @BASEBOARD_FAB2_LIB.BASEBOARD_FAB2(SCH_1):M_C_DQ(61)   I111 @BASEBOARD_FAB2_LIB.BASEBOARD_FAB2(SCH_1):PAGE47
   282 M_C_DQ<58> @BASEBOARD_FAB2_LIB.BASEBOARD_FAB2(SCH_1):M_C_DQ(58)   I111 @BASEBOARD_FAB2_LIB.BASEBOARD_FAB2(SCH_1):PAGE47
   137 M_C_DQ<59> @BASEBOARD_FAB2_LIB.BASEBOARD_FAB2(SCH_1):M_C_DQ(59)   I111 @BASEBOARD_FAB2_LIB.BASEBOARD_FAB2(SCH_1):PAGE47
   275 M_C_DQ<56> @BASEBOARD_FAB2_LIB.BASEBOARD_FAB2(SCH_1):M_C_DQ(56)   I111 @BASEBOARD_FAB2_LIB.BASEBOARD_FAB2(SCH_1):PAGE47
   130 M_C_DQ<57> @BASEBOARD_FAB2_LIB.BASEBOARD_FAB2(SCH_1):M_C_DQ(57)   I111 @BASEBOARD_FAB2_LIB.BASEBOARD_FAB2(SCH_1):PAGE47
   269 M_C_DQ<54> @BASEBOARD_FAB2_LIB.BASEBOARD_FAB2(SCH_1):M_C_DQ(54)   I111 @BASEBOARD_FAB2_LIB.BASEBOARD_FAB2(SCH_1):PAGE47
   124 M_C_DQ<55> @BASEBOARD_FAB2_LIB.BASEBOARD_FAB2(SCH_1):M_C_DQ(55)   I111 @BASEBOARD_FAB2_LIB.BASEBOARD_FAB2(SCH_1):PAGE47
   262 M_C_DQ<52> @BASEBOARD_FAB2_LIB.BASEBOARD_FAB2(SCH_1):M_C_DQ(52)   I111 @BASEBOARD_FAB2_LIB.BASEBOARD_FAB2(SCH_1):PAGE47
   117 M_C_DQ<53> @BASEBOARD_FAB2_LIB.BASEBOARD_FAB2(SCH_1):M_C_DQ(53)   I111 @BASEBOARD_FAB2_LIB.BASEBOARD_FAB2(SCH_1):PAGE47
   271 M_C_DQ<50> @BASEBOARD_FAB2_LIB.BASEBOARD_FAB2(SCH_1):M_C_DQ(50)   I111 @BASEBOARD_FAB2_LIB.BASEBOARD_FAB2(SCH_1):PAGE47
   126 M_C_DQ<51> @BASEBOARD_FAB2_LIB.BASEBOARD_FAB2(SCH_1):M_C_DQ(51)   I111 @BASEBOARD_FAB2_LIB.BASEBOARD_FAB2(SCH_1):PAGE47
   264 M_C_DQ<48> @BASEBOARD_FAB2_LIB.BASEBOARD_FAB2(SCH_1):M_C_DQ(48)   I111 @BASEBOARD_FAB2_LIB.BASEBOARD_FAB2(SCH_1):PAGE47
   119 M_C_DQ<49> @BASEBOARD_FAB2_LIB.BASEBOARD_FAB2(SCH_1):M_C_DQ(49)   I111 @BASEBOARD_FAB2_LIB.BASEBOARD_FAB2(SCH_1):PAGE47
   258 M_C_DQ<46> @BASEBOARD_FAB2_LIB.BASEBOARD_FAB2(SCH_1):M_C_DQ(46)   I111 @BASEBOARD_FAB2_LIB.BASEBOARD_FAB2(SCH_1):PAGE47
   113 M_C_DQ<47> @BASEBOARD_FAB2_LIB.BASEBOARD_FAB2(SCH_1):M_C_DQ(47)   I111 @BASEBOARD_FAB2_LIB.BASEBOARD_FAB2(SCH_1):PAGE47
   251 M_C_DQ<44> @BASEBOARD_FAB2_LIB.BASEBOARD_FAB2(SCH_1):M_C_DQ(44)   I111 @BASEBOARD_FAB2_LIB.BASEBOARD_FAB2(SCH_1):PAGE47
   106 M_C_DQ<45> @BASEBOARD_FAB2_LIB.BASEBOARD_FAB2(SCH_1):M_C_DQ(45)   I111 @BASEBOARD_FAB2_LIB.BASEBOARD_FAB2(SCH_1):PAGE47
   260 M_C_DQ<42> @BASEBOARD_FAB2_LIB.BASEBOARD_FAB2(SCH_1):M_C_DQ(42)   I111 @BASEBOARD_FAB2_LIB.BASEBOARD_FAB2(SCH_1):PAGE47
   115 M_C_DQ<43> @BASEBOARD_FAB2_LIB.BASEBOARD_FAB2(SCH_1):M_C_DQ(43)   I111 @BASEBOARD_FAB2_LIB.BASEBOARD_FAB2(SCH_1):PAGE47
   253 M_C_DQ<40> @BASEBOARD_FAB2_LIB.BASEBOARD_FAB2(SCH_1):M_C_DQ(40)   I111 @BASEBOARD_FAB2_LIB.BASEBOARD_FAB2(SCH_1):PAGE47
   108 M_C_DQ<41> @BASEBOARD_FAB2_LIB.BASEBOARD_FAB2(SCH_1):M_C_DQ(41)   I111 @BASEBOARD_FAB2_LIB.BASEBOARD_FAB2(SCH_1):PAGE47
   247 M_C_DQ<38> @BASEBOARD_FAB2_LIB.BASEBOARD_FAB2(SCH_1):M_C_DQ(38)   I111 @BASEBOARD_FAB2_LIB.BASEBOARD_FAB2(SCH_1):PAGE47
   102 M_C_DQ<39> @BASEBOARD_FAB2_LIB.BASEBOARD_FAB2(SCH_1):M_C_DQ(39)   I111 @BASEBOARD_FAB2_LIB.BASEBOARD_FAB2(SCH_1):PAGE47
   240 M_C_DQ<36> @BASEBOARD_FAB2_LIB.BASEBOARD_FAB2(SCH_1):M_C_DQ(36)   I111 @BASEBOARD_FAB2_LIB.BASEBOARD_FAB2(SCH_1):PAGE47
    95 M_C_DQ<37> @BASEBOARD_FAB2_LIB.BASEBOARD_FAB2(SCH_1):M_C_DQ(37)   I111 @BASEBOARD_FAB2_LIB.BASEBOARD_FAB2(SCH_1):PAGE47
   249 M_C_DQ<34> @BASEBOARD_FAB2_LIB.BASEBOARD_FAB2(SCH_1):M_C_DQ(34)   I111 @BASEBOARD_FAB2_LIB.BASEBOARD_FAB2(SCH_1):PAGE47
   104 M_C_DQ<35> @BASEBOARD_FAB2_LIB.BASEBOARD_FAB2(SCH_1):M_C_DQ(35)   I111 @BASEBOARD_FAB2_LIB.BASEBOARD_FAB2(SCH_1):PAGE47
   242 M_C_DQ<32> @BASEBOARD_FAB2_LIB.BASEBOARD_FAB2(SCH_1):M_C_DQ(32)   I111 @BASEBOARD_FAB2_LIB.BASEBOARD_FAB2(SCH_1):PAGE47
    97 M_C_DQ<33> @BASEBOARD_FAB2_LIB.BASEBOARD_FAB2(SCH_1):M_C_DQ(33)   I111 @BASEBOARD_FAB2_LIB.BASEBOARD_FAB2(SCH_1):PAGE47
   188 M_C_DQ<30> @BASEBOARD_FAB2_LIB.BASEBOARD_FAB2(SCH_1):M_C_DQ(30)   I111 @BASEBOARD_FAB2_LIB.BASEBOARD_FAB2(SCH_1):PAGE47
    43 M_C_DQ<31> @BASEBOARD_FAB2_LIB.BASEBOARD_FAB2(SCH_1):M_C_DQ(31)   I111 @BASEBOARD_FAB2_LIB.BASEBOARD_FAB2(SCH_1):PAGE47
   181 M_C_DQ<28> @BASEBOARD_FAB2_LIB.BASEBOARD_FAB2(SCH_1):M_C_DQ(28)   I111 @BASEBOARD_FAB2_LIB.BASEBOARD_FAB2(SCH_1):PAGE47
    36 M_C_DQ<29> @BASEBOARD_FAB2_LIB.BASEBOARD_FAB2(SCH_1):M_C_DQ(29)   I111 @BASEBOARD_FAB2_LIB.BASEBOARD_FAB2(SCH_1):PAGE47
   190 M_C_DQ<26> @BASEBOARD_FAB2_LIB.BASEBOARD_FAB2(SCH_1):M_C_DQ(26)   I111 @BASEBOARD_FAB2_LIB.BASEBOARD_FAB2(SCH_1):PAGE47
    45 M_C_DQ<27> @BASEBOARD_FAB2_LIB.BASEBOARD_FAB2(SCH_1):M_C_DQ(27)   I111 @BASEBOARD_FAB2_LIB.BASEBOARD_FAB2(SCH_1):PAGE47
   183 M_C_DQ<24> @BASEBOARD_FAB2_LIB.BASEBOARD_FAB2(SCH_1):M_C_DQ(24)   I111 @BASEBOARD_FAB2_LIB.BASEBOARD_FAB2(SCH_1):PAGE47
    38 M_C_DQ<25> @BASEBOARD_FAB2_LIB.BASEBOARD_FAB2(SCH_1):M_C_DQ(25)   I111 @BASEBOARD_FAB2_LIB.BASEBOARD_FAB2(SCH_1):PAGE47
   177 M_C_DQ<22> @BASEBOARD_FAB2_LIB.BASEBOARD_FAB2(SCH_1):M_C_DQ(22)   I111 @BASEBOARD_FAB2_LIB.BASEBOARD_FAB2(SCH_1):PAGE47
    32 M_C_DQ<23> @BASEBOARD_FAB2_LIB.BASEBOARD_FAB2(SCH_1):M_C_DQ(23)   I111 @BASEBOARD_FAB2_LIB.BASEBOARD_FAB2(SCH_1):PAGE47
   170 M_C_DQ<20> @BASEBOARD_FAB2_LIB.BASEBOARD_FAB2(SCH_1):M_C_DQ(20)   I111 @BASEBOARD_FAB2_LIB.BASEBOARD_FAB2(SCH_1):PAGE47
    25 M_C_DQ<21> @BASEBOARD_FAB2_LIB.BASEBOARD_FAB2(SCH_1):M_C_DQ(21)   I111 @BASEBOARD_FAB2_LIB.BASEBOARD_FAB2(SCH_1):PAGE47
   179 M_C_DQ<18> @BASEBOARD_FAB2_LIB.BASEBOARD_FAB2(SCH_1):M_C_DQ(18)   I111 @BASEBOARD_FAB2_LIB.BASEBOARD_FAB2(SCH_1):PAGE47
    34 M_C_DQ<19> @BASEBOARD_FAB2_LIB.BASEBOARD_FAB2(SCH_1):M_C_DQ(19)   I111 @BASEBOARD_FAB2_LIB.BASEBOARD_FAB2(SCH_1):PAGE47
   172 M_C_DQ<16> @BASEBOARD_FAB2_LIB.BASEBOARD_FAB2(SCH_1):M_C_DQ(16)   I111 @BASEBOARD_FAB2_LIB.BASEBOARD_FAB2(SCH_1):PAGE47
    27 M_C_DQ<17> @BASEBOARD_FAB2_LIB.BASEBOARD_FAB2(SCH_1):M_C_DQ(17)   I111 @BASEBOARD_FAB2_LIB.BASEBOARD_FAB2(SCH_1):PAGE47
   166 M_C_DQ<14> @BASEBOARD_FAB2_LIB.BASEBOARD_FAB2(SCH_1):M_C_DQ(14)   I111 @BASEBOARD_FAB2_LIB.BASEBOARD_FAB2(SCH_1):PAGE47
    21 M_C_DQ<15> @BASEBOARD_FAB2_LIB.BASEBOARD_FAB2(SCH_1):M_C_DQ(15)   I111 @BASEBOARD_FAB2_LIB.BASEBOARD_FAB2(SCH_1):PAGE47
   159 M_C_DQ<12> @BASEBOARD_FAB2_LIB.BASEBOARD_FAB2(SCH_1):M_C_DQ(12)   I111 @BASEBOARD_FAB2_LIB.BASEBOARD_FAB2(SCH_1):PAGE47
    14 M_C_DQ<13> @BASEBOARD_FAB2_LIB.BASEBOARD_FAB2(SCH_1):M_C_DQ(13)   I111 @BASEBOARD_FAB2_LIB.BASEBOARD_FAB2(SCH_1):PAGE47
   168 M_C_DQ<10> @BASEBOARD_FAB2_LIB.BASEBOARD_FAB2(SCH_1):M_C_DQ(10)   I111 @BASEBOARD_FAB2_LIB.BASEBOARD_FAB2(SCH_1):PAGE47
    23 M_C_DQ<11> @BASEBOARD_FAB2_LIB.BASEBOARD_FAB2(SCH_1):M_C_DQ(11)   I111 @BASEBOARD_FAB2_LIB.BASEBOARD_FAB2(SCH_1):PAGE47
   161 M_C_DQ<8> @BASEBOARD_FAB2_LIB.BASEBOARD_FAB2(SCH_1):M_C_DQ(8)   I111 @BASEBOARD_FAB2_LIB.BASEBOARD_FAB2(SCH_1):PAGE47
    16 M_C_DQ<9> @BASEBOARD_FAB2_LIB.BASEBOARD_FAB2(SCH_1):M_C_DQ(9)   I111 @BASEBOARD_FAB2_LIB.BASEBOARD_FAB2(SCH_1):PAGE47
   155 M_C_DQ<6> @BASEBOARD_FAB2_LIB.BASEBOARD_FAB2(SCH_1):M_C_DQ(6)   I111 @BASEBOARD_FAB2_LIB.BASEBOARD_FAB2(SCH_1):PAGE47
    10 M_C_DQ<7> @BASEBOARD_FAB2_LIB.BASEBOARD_FAB2(SCH_1):M_C_DQ(7)   I111 @BASEBOARD_FAB2_LIB.BASEBOARD_FAB2(SCH_1):PAGE47
   148 M_C_DQ<4> @BASEBOARD_FAB2_LIB.BASEBOARD_FAB2(SCH_1):M_C_DQ(4)   I111 @BASEBOARD_FAB2_LIB.BASEBOARD_FAB2(SCH_1):PAGE47
     3 M_C_DQ<5> @BASEBOARD_FAB2_LIB.BASEBOARD_FAB2(SCH_1):M_C_DQ(5)   I111 @BASEBOARD_FAB2_LIB.BASEBOARD_FAB2(SCH_1):PAGE47
   157 M_C_DQ<2> @BASEBOARD_FAB2_LIB.BASEBOARD_FAB2(SCH_1):M_C_DQ(2)   I111 @BASEBOARD_FAB2_LIB.BASEBOARD_FAB2(SCH_1):PAGE47
    12 M_C_DQ<3> @BASEBOARD_FAB2_LIB.BASEBOARD_FAB2(SCH_1):M_C_DQ(3)   I111 @BASEBOARD_FAB2_LIB.BASEBOARD_FAB2(SCH_1):PAGE47
   150 M_C_DQ<0> @BASEBOARD_FAB2_LIB.BASEBOARD_FAB2(SCH_1):M_C_DQ(0)   I111 @BASEBOARD_FAB2_LIB.BASEBOARD_FAB2(SCH_1):PAGE47
     5 M_C_DQ<1> @BASEBOARD_FAB2_LIB.BASEBOARD_FAB2(SCH_1):M_C_DQ(1)   I111 @BASEBOARD_FAB2_LIB.BASEBOARD_FAB2(SCH_1):PAGE47
    78 FM_DIMM_EVENT_COD_N @BASEBOARD_FAB2_LIB.BASEBOARD_FAB2(SCH_1):FM_DIMM_EVENT_COD_N   I111 @BASEBOARD_FAB2_LIB.BASEBOARD_FAB2(SCH_1):PAGE47
    91 M_C_ODT<1> @BASEBOARD_FAB2_LIB.BASEBOARD_FAB2(SCH_1):M_C_ODT(1)   I111 @BASEBOARD_FAB2_LIB.BASEBOARD_FAB2(SCH_1):PAGE47
    87 M_C_ODT<0> @BASEBOARD_FAB2_LIB.BASEBOARD_FAB2(SCH_1):M_C_ODT(0)   I111 @BASEBOARD_FAB2_LIB.BASEBOARD_FAB2(SCH_1):PAGE47
   222 M_C_PAR @BASEBOARD_FAB2_LIB.BASEBOARD_FAB2(SCH_1):M_C_PAR   I111 @BASEBOARD_FAB2_LIB.BASEBOARD_FAB2(SCH_1):PAGE47
    58 M_ABC_RST_N @BASEBOARD_FAB2_LIB.BASEBOARD_FAB2(SCH_1):M_ABC_RST_N   I111 @BASEBOARD_FAB2_LIB.BASEBOARD_FAB2(SCH_1):PAGE47
   144 TP_CH_C_DIMM_C0_RFU_2 @BASEBOARD_FAB2_LIB.BASEBOARD_FAB2(SCH_1):TP_CH_C_DIMM_C0_RFU_2   I111 @BASEBOARD_FAB2_LIB.BASEBOARD_FAB2(SCH_1):PAGE47
   227 TP_CH_C_DIMM_C0_RFU_1 @BASEBOARD_FAB2_LIB.BASEBOARD_FAB2(SCH_1):TP_CH_C_DIMM_C0_RFU_1   I111 @BASEBOARD_FAB2_LIB.BASEBOARD_FAB2(SCH_1):PAGE47
   205 TP_CH_C_DIMM_C0_RFU_0 @BASEBOARD_FAB2_LIB.BASEBOARD_FAB2(SCH_1):TP_CH_C_DIMM_C0_RFU_0   I111 @BASEBOARD_FAB2_LIB.BASEBOARD_FAB2(SCH_1):PAGE47
    84 M_C_CS_N<0> @BASEBOARD_FAB2_LIB.BASEBOARD_FAB2(SCH_1):M_C_CS_N(0)   I111 @BASEBOARD_FAB2_LIB.BASEBOARD_FAB2(SCH_1):PAGE47
    89 M_C_CS_N<1> @BASEBOARD_FAB2_LIB.BASEBOARD_FAB2(SCH_1):M_C_CS_N(1)   I111 @BASEBOARD_FAB2_LIB.BASEBOARD_FAB2(SCH_1):PAGE47
    93 M_C_CS_N<2> @BASEBOARD_FAB2_LIB.BASEBOARD_FAB2(SCH_1):M_C_CS_N(2)   I111 @BASEBOARD_FAB2_LIB.BASEBOARD_FAB2(SCH_1):PAGE47
   237 M_C_CS_N<3> @BASEBOARD_FAB2_LIB.BASEBOARD_FAB2(SCH_1):M_C_CS_N(3)   I111 @BASEBOARD_FAB2_LIB.BASEBOARD_FAB2(SCH_1):PAGE47
   238 PVPP_ABC @BASEBOARD_FAB2_LIB.BASEBOARD_FAB2(SCH_1):PVPP_ABC   I111 @BASEBOARD_FAB2_LIB.BASEBOARD_FAB2(SCH_1):PAGE47
   140    GND @BASEBOARD_FAB2_LIB.BASEBOARD_FAB2(SCH_1):GND   I111 @BASEBOARD_FAB2_LIB.BASEBOARD_FAB2(SCH_1):PAGE47
   139    GND @BASEBOARD_FAB2_LIB.BASEBOARD_FAB2(SCH_1):GND   I111 @BASEBOARD_FAB2_LIB.BASEBOARD_FAB2(SCH_1):PAGE47
   230 FM_ADR_COMPLETE_ABC_N @BASEBOARD_FAB2_LIB.BASEBOARD_FAB2(SCH_1):FM_ADR_COMPLETE_ABC_N   I111 @BASEBOARD_FAB2_LIB.BASEBOARD_FAB2(SCH_1):PAGE47
   141 SMB_DDR_ABC_VPP_SCL @BASEBOARD_FAB2_LIB.BASEBOARD_FAB2(SCH_1):SMB_DDR_ABC_VPP_SCL   I111 @BASEBOARD_FAB2_LIB.BASEBOARD_FAB2(SCH_1):PAGE47
   285 SMB_DDR_ABC_VPP_SDA @BASEBOARD_FAB2_LIB.BASEBOARD_FAB2(SCH_1):SMB_DDR_ABC_VPP_SDA   I111 @BASEBOARD_FAB2_LIB.BASEBOARD_FAB2(SCH_1):PAGE47
   284 PVPP_ABC @BASEBOARD_FAB2_LIB.BASEBOARD_FAB2(SCH_1):PVPP_ABC   I111 @BASEBOARD_FAB2_LIB.BASEBOARD_FAB2(SCH_1):PAGE47
   146 M_C_VREF @BASEBOARD_FAB2_LIB.BASEBOARD_FAB2(SCH_1):M_C_VREF   I111 @BASEBOARD_FAB2_LIB.BASEBOARD_FAB2(SCH_1):PAGE47
   152 M_C_DQS_DN<0> @BASEBOARD_FAB2_LIB.BASEBOARD_FAB2(SCH_1):M_C_DQS_DN(0)    I61 @BASEBOARD_FAB2_LIB.BASEBOARD_FAB2(SCH_1):PAGE47
   153 M_C_DQS_DP<0> @BASEBOARD_FAB2_LIB.BASEBOARD_FAB2(SCH_1):M_C_DQS_DP(0)    I61 @BASEBOARD_FAB2_LIB.BASEBOARD_FAB2(SCH_1):PAGE47
    19 M_C_DQS_DN<10> @BASEBOARD_FAB2_LIB.BASEBOARD_FAB2(SCH_1):M_C_DQS_DN(10)    I61 @BASEBOARD_FAB2_LIB.BASEBOARD_FAB2(SCH_1):PAGE47
    18 M_C_DQS_DP<10> @BASEBOARD_FAB2_LIB.BASEBOARD_FAB2(SCH_1):M_C_DQS_DP(10)    I61 @BASEBOARD_FAB2_LIB.BASEBOARD_FAB2(SCH_1):PAGE47
    30 M_C_DQS_DN<11> @BASEBOARD_FAB2_LIB.BASEBOARD_FAB2(SCH_1):M_C_DQS_DN(11)    I61 @BASEBOARD_FAB2_LIB.BASEBOARD_FAB2(SCH_1):PAGE47
    29 M_C_DQS_DP<11> @BASEBOARD_FAB2_LIB.BASEBOARD_FAB2(SCH_1):M_C_DQS_DP(11)    I61 @BASEBOARD_FAB2_LIB.BASEBOARD_FAB2(SCH_1):PAGE47
    41 M_C_DQS_DN<12> @BASEBOARD_FAB2_LIB.BASEBOARD_FAB2(SCH_1):M_C_DQS_DN(12)    I61 @BASEBOARD_FAB2_LIB.BASEBOARD_FAB2(SCH_1):PAGE47
    40 M_C_DQS_DP<12> @BASEBOARD_FAB2_LIB.BASEBOARD_FAB2(SCH_1):M_C_DQS_DP(12)    I61 @BASEBOARD_FAB2_LIB.BASEBOARD_FAB2(SCH_1):PAGE47
   100 M_C_DQS_DN<13> @BASEBOARD_FAB2_LIB.BASEBOARD_FAB2(SCH_1):M_C_DQS_DN(13)    I61 @BASEBOARD_FAB2_LIB.BASEBOARD_FAB2(SCH_1):PAGE47
    99 M_C_DQS_DP<13> @BASEBOARD_FAB2_LIB.BASEBOARD_FAB2(SCH_1):M_C_DQS_DP(13)    I61 @BASEBOARD_FAB2_LIB.BASEBOARD_FAB2(SCH_1):PAGE47
   111 M_C_DQS_DN<14> @BASEBOARD_FAB2_LIB.BASEBOARD_FAB2(SCH_1):M_C_DQS_DN(14)    I61 @BASEBOARD_FAB2_LIB.BASEBOARD_FAB2(SCH_1):PAGE47
   110 M_C_DQS_DP<14> @BASEBOARD_FAB2_LIB.BASEBOARD_FAB2(SCH_1):M_C_DQS_DP(14)    I61 @BASEBOARD_FAB2_LIB.BASEBOARD_FAB2(SCH_1):PAGE47
   122 M_C_DQS_DN<15> @BASEBOARD_FAB2_LIB.BASEBOARD_FAB2(SCH_1):M_C_DQS_DN(15)    I61 @BASEBOARD_FAB2_LIB.BASEBOARD_FAB2(SCH_1):PAGE47
   121 M_C_DQS_DP<15> @BASEBOARD_FAB2_LIB.BASEBOARD_FAB2(SCH_1):M_C_DQS_DP(15)    I61 @BASEBOARD_FAB2_LIB.BASEBOARD_FAB2(SCH_1):PAGE47
   133 M_C_DQS_DN<16> @BASEBOARD_FAB2_LIB.BASEBOARD_FAB2(SCH_1):M_C_DQS_DN(16)    I61 @BASEBOARD_FAB2_LIB.BASEBOARD_FAB2(SCH_1):PAGE47
   132 M_C_DQS_DP<16> @BASEBOARD_FAB2_LIB.BASEBOARD_FAB2(SCH_1):M_C_DQS_DP(16)    I61 @BASEBOARD_FAB2_LIB.BASEBOARD_FAB2(SCH_1):PAGE47
    52 M_C_DQS_DN<17> @BASEBOARD_FAB2_LIB.BASEBOARD_FAB2(SCH_1):M_C_DQS_DN(17)    I61 @BASEBOARD_FAB2_LIB.BASEBOARD_FAB2(SCH_1):PAGE47
    51 M_C_DQS_DP<17> @BASEBOARD_FAB2_LIB.BASEBOARD_FAB2(SCH_1):M_C_DQS_DP(17)    I61 @BASEBOARD_FAB2_LIB.BASEBOARD_FAB2(SCH_1):PAGE47
   163 M_C_DQS_DN<1> @BASEBOARD_FAB2_LIB.BASEBOARD_FAB2(SCH_1):M_C_DQS_DN(1)    I61 @BASEBOARD_FAB2_LIB.BASEBOARD_FAB2(SCH_1):PAGE47
   164 M_C_DQS_DP<1> @BASEBOARD_FAB2_LIB.BASEBOARD_FAB2(SCH_1):M_C_DQS_DP(1)    I61 @BASEBOARD_FAB2_LIB.BASEBOARD_FAB2(SCH_1):PAGE47
   174 M_C_DQS_DN<2> @BASEBOARD_FAB2_LIB.BASEBOARD_FAB2(SCH_1):M_C_DQS_DN(2)    I61 @BASEBOARD_FAB2_LIB.BASEBOARD_FAB2(SCH_1):PAGE47
   175 M_C_DQS_DP<2> @BASEBOARD_FAB2_LIB.BASEBOARD_FAB2(SCH_1):M_C_DQS_DP(2)    I61 @BASEBOARD_FAB2_LIB.BASEBOARD_FAB2(SCH_1):PAGE47
   185 M_C_DQS_DN<3> @BASEBOARD_FAB2_LIB.BASEBOARD_FAB2(SCH_1):M_C_DQS_DN(3)    I61 @BASEBOARD_FAB2_LIB.BASEBOARD_FAB2(SCH_1):PAGE47
   186 M_C_DQS_DP<3> @BASEBOARD_FAB2_LIB.BASEBOARD_FAB2(SCH_1):M_C_DQS_DP(3)    I61 @BASEBOARD_FAB2_LIB.BASEBOARD_FAB2(SCH_1):PAGE47
   244 M_C_DQS_DN<4> @BASEBOARD_FAB2_LIB.BASEBOARD_FAB2(SCH_1):M_C_DQS_DN(4)    I61 @BASEBOARD_FAB2_LIB.BASEBOARD_FAB2(SCH_1):PAGE47
   245 M_C_DQS_DP<4> @BASEBOARD_FAB2_LIB.BASEBOARD_FAB2(SCH_1):M_C_DQS_DP(4)    I61 @BASEBOARD_FAB2_LIB.BASEBOARD_FAB2(SCH_1):PAGE47
   255 M_C_DQS_DN<5> @BASEBOARD_FAB2_LIB.BASEBOARD_FAB2(SCH_1):M_C_DQS_DN(5)    I61 @BASEBOARD_FAB2_LIB.BASEBOARD_FAB2(SCH_1):PAGE47
   256 M_C_DQS_DP<5> @BASEBOARD_FAB2_LIB.BASEBOARD_FAB2(SCH_1):M_C_DQS_DP(5)    I61 @BASEBOARD_FAB2_LIB.BASEBOARD_FAB2(SCH_1):PAGE47
   266 M_C_DQS_DN<6> @BASEBOARD_FAB2_LIB.BASEBOARD_FAB2(SCH_1):M_C_DQS_DN(6)    I61 @BASEBOARD_FAB2_LIB.BASEBOARD_FAB2(SCH_1):PAGE47
   267 M_C_DQS_DP<6> @BASEBOARD_FAB2_LIB.BASEBOARD_FAB2(SCH_1):M_C_DQS_DP(6)    I61 @BASEBOARD_FAB2_LIB.BASEBOARD_FAB2(SCH_1):PAGE47
   277 M_C_DQS_DN<7> @BASEBOARD_FAB2_LIB.BASEBOARD_FAB2(SCH_1):M_C_DQS_DN(7)    I61 @BASEBOARD_FAB2_LIB.BASEBOARD_FAB2(SCH_1):PAGE47
   278 M_C_DQS_DP<7> @BASEBOARD_FAB2_LIB.BASEBOARD_FAB2(SCH_1):M_C_DQS_DP(7)    I61 @BASEBOARD_FAB2_LIB.BASEBOARD_FAB2(SCH_1):PAGE47
   196 M_C_DQS_DN<8> @BASEBOARD_FAB2_LIB.BASEBOARD_FAB2(SCH_1):M_C_DQS_DN(8)    I61 @BASEBOARD_FAB2_LIB.BASEBOARD_FAB2(SCH_1):PAGE47
   197 M_C_DQS_DP<8> @BASEBOARD_FAB2_LIB.BASEBOARD_FAB2(SCH_1):M_C_DQS_DP(8)    I61 @BASEBOARD_FAB2_LIB.BASEBOARD_FAB2(SCH_1):PAGE47
     8 M_C_DQS_DN<9> @BASEBOARD_FAB2_LIB.BASEBOARD_FAB2(SCH_1):M_C_DQS_DN(9)    I61 @BASEBOARD_FAB2_LIB.BASEBOARD_FAB2(SCH_1):PAGE47
     7 M_C_DQS_DP<9> @BASEBOARD_FAB2_LIB.BASEBOARD_FAB2(SCH_1):M_C_DQS_DP(9)    I61 @BASEBOARD_FAB2_LIB.BASEBOARD_FAB2(SCH_1):PAGE47
     2    GND @BASEBOARD_FAB2_LIB.BASEBOARD_FAB2(SCH_1):GND    I43 @BASEBOARD_FAB2_LIB.BASEBOARD_FAB2(SCH_1):PAGE47
     4    GND @BASEBOARD_FAB2_LIB.BASEBOARD_FAB2(SCH_1):GND    I43 @BASEBOARD_FAB2_LIB.BASEBOARD_FAB2(SCH_1):PAGE47
     6    GND @BASEBOARD_FAB2_LIB.BASEBOARD_FAB2(SCH_1):GND    I43 @BASEBOARD_FAB2_LIB.BASEBOARD_FAB2(SCH_1):PAGE47
     9    GND @BASEBOARD_FAB2_LIB.BASEBOARD_FAB2(SCH_1):GND    I43 @BASEBOARD_FAB2_LIB.BASEBOARD_FAB2(SCH_1):PAGE47
    11    GND @BASEBOARD_FAB2_LIB.BASEBOARD_FAB2(SCH_1):GND    I43 @BASEBOARD_FAB2_LIB.BASEBOARD_FAB2(SCH_1):PAGE47
    13    GND @BASEBOARD_FAB2_LIB.BASEBOARD_FAB2(SCH_1):GND    I43 @BASEBOARD_FAB2_LIB.BASEBOARD_FAB2(SCH_1):PAGE47
    15    GND @BASEBOARD_FAB2_LIB.BASEBOARD_FAB2(SCH_1):GND    I43 @BASEBOARD_FAB2_LIB.BASEBOARD_FAB2(SCH_1):PAGE47
    17    GND @BASEBOARD_FAB2_LIB.BASEBOARD_FAB2(SCH_1):GND    I43 @BASEBOARD_FAB2_LIB.BASEBOARD_FAB2(SCH_1):PAGE47
    20    GND @BASEBOARD_FAB2_LIB.BASEBOARD_FAB2(SCH_1):GND    I43 @BASEBOARD_FAB2_LIB.BASEBOARD_FAB2(SCH_1):PAGE47
    22    GND @BASEBOARD_FAB2_LIB.BASEBOARD_FAB2(SCH_1):GND    I43 @BASEBOARD_FAB2_LIB.BASEBOARD_FAB2(SCH_1):PAGE47
    24    GND @BASEBOARD_FAB2_LIB.BASEBOARD_FAB2(SCH_1):GND    I43 @BASEBOARD_FAB2_LIB.BASEBOARD_FAB2(SCH_1):PAGE47
    26    GND @BASEBOARD_FAB2_LIB.BASEBOARD_FAB2(SCH_1):GND    I43 @BASEBOARD_FAB2_LIB.BASEBOARD_FAB2(SCH_1):PAGE47
    28    GND @BASEBOARD_FAB2_LIB.BASEBOARD_FAB2(SCH_1):GND    I43 @BASEBOARD_FAB2_LIB.BASEBOARD_FAB2(SCH_1):PAGE47
    31    GND @BASEBOARD_FAB2_LIB.BASEBOARD_FAB2(SCH_1):GND    I43 @BASEBOARD_FAB2_LIB.BASEBOARD_FAB2(SCH_1):PAGE47
    33    GND @BASEBOARD_FAB2_LIB.BASEBOARD_FAB2(SCH_1):GND    I43 @BASEBOARD_FAB2_LIB.BASEBOARD_FAB2(SCH_1):PAGE47
    35    GND @BASEBOARD_FAB2_LIB.BASEBOARD_FAB2(SCH_1):GND    I43 @BASEBOARD_FAB2_LIB.BASEBOARD_FAB2(SCH_1):PAGE47
    37    GND @BASEBOARD_FAB2_LIB.BASEBOARD_FAB2(SCH_1):GND    I43 @BASEBOARD_FAB2_LIB.BASEBOARD_FAB2(SCH_1):PAGE47
    39    GND @BASEBOARD_FAB2_LIB.BASEBOARD_FAB2(SCH_1):GND    I43 @BASEBOARD_FAB2_LIB.BASEBOARD_FAB2(SCH_1):PAGE47
    42    GND @BASEBOARD_FAB2_LIB.BASEBOARD_FAB2(SCH_1):GND    I43 @BASEBOARD_FAB2_LIB.BASEBOARD_FAB2(SCH_1):PAGE47
    44    GND @BASEBOARD_FAB2_LIB.BASEBOARD_FAB2(SCH_1):GND    I43 @BASEBOARD_FAB2_LIB.BASEBOARD_FAB2(SCH_1):PAGE47
    46    GND @BASEBOARD_FAB2_LIB.BASEBOARD_FAB2(SCH_1):GND    I43 @BASEBOARD_FAB2_LIB.BASEBOARD_FAB2(SCH_1):PAGE47
    48    GND @BASEBOARD_FAB2_LIB.BASEBOARD_FAB2(SCH_1):GND    I43 @BASEBOARD_FAB2_LIB.BASEBOARD_FAB2(SCH_1):PAGE47
    50    GND @BASEBOARD_FAB2_LIB.BASEBOARD_FAB2(SCH_1):GND    I43 @BASEBOARD_FAB2_LIB.BASEBOARD_FAB2(SCH_1):PAGE47
    53    GND @BASEBOARD_FAB2_LIB.BASEBOARD_FAB2(SCH_1):GND    I43 @BASEBOARD_FAB2_LIB.BASEBOARD_FAB2(SCH_1):PAGE47
    55    GND @BASEBOARD_FAB2_LIB.BASEBOARD_FAB2(SCH_1):GND    I43 @BASEBOARD_FAB2_LIB.BASEBOARD_FAB2(SCH_1):PAGE47
    57    GND @BASEBOARD_FAB2_LIB.BASEBOARD_FAB2(SCH_1):GND    I43 @BASEBOARD_FAB2_LIB.BASEBOARD_FAB2(SCH_1):PAGE47
    94    GND @BASEBOARD_FAB2_LIB.BASEBOARD_FAB2(SCH_1):GND    I43 @BASEBOARD_FAB2_LIB.BASEBOARD_FAB2(SCH_1):PAGE47
    96    GND @BASEBOARD_FAB2_LIB.BASEBOARD_FAB2(SCH_1):GND    I43 @BASEBOARD_FAB2_LIB.BASEBOARD_FAB2(SCH_1):PAGE47
    98    GND @BASEBOARD_FAB2_LIB.BASEBOARD_FAB2(SCH_1):GND    I43 @BASEBOARD_FAB2_LIB.BASEBOARD_FAB2(SCH_1):PAGE47
   101    GND @BASEBOARD_FAB2_LIB.BASEBOARD_FAB2(SCH_1):GND    I43 @BASEBOARD_FAB2_LIB.BASEBOARD_FAB2(SCH_1):PAGE47
   103    GND @BASEBOARD_FAB2_LIB.BASEBOARD_FAB2(SCH_1):GND    I43 @BASEBOARD_FAB2_LIB.BASEBOARD_FAB2(SCH_1):PAGE47
   105    GND @BASEBOARD_FAB2_LIB.BASEBOARD_FAB2(SCH_1):GND    I43 @BASEBOARD_FAB2_LIB.BASEBOARD_FAB2(SCH_1):PAGE47
   107    GND @BASEBOARD_FAB2_LIB.BASEBOARD_FAB2(SCH_1):GND    I43 @BASEBOARD_FAB2_LIB.BASEBOARD_FAB2(SCH_1):PAGE47
   109    GND @BASEBOARD_FAB2_LIB.BASEBOARD_FAB2(SCH_1):GND    I43 @BASEBOARD_FAB2_LIB.BASEBOARD_FAB2(SCH_1):PAGE47
   112    GND @BASEBOARD_FAB2_LIB.BASEBOARD_FAB2(SCH_1):GND    I43 @BASEBOARD_FAB2_LIB.BASEBOARD_FAB2(SCH_1):PAGE47
   114    GND @BASEBOARD_FAB2_LIB.BASEBOARD_FAB2(SCH_1):GND    I43 @BASEBOARD_FAB2_LIB.BASEBOARD_FAB2(SCH_1):PAGE47
   116    GND @BASEBOARD_FAB2_LIB.BASEBOARD_FAB2(SCH_1):GND    I43 @BASEBOARD_FAB2_LIB.BASEBOARD_FAB2(SCH_1):PAGE47
   118    GND @BASEBOARD_FAB2_LIB.BASEBOARD_FAB2(SCH_1):GND    I43 @BASEBOARD_FAB2_LIB.BASEBOARD_FAB2(SCH_1):PAGE47
   120    GND @BASEBOARD_FAB2_LIB.BASEBOARD_FAB2(SCH_1):GND    I43 @BASEBOARD_FAB2_LIB.BASEBOARD_FAB2(SCH_1):PAGE47
   123    GND @BASEBOARD_FAB2_LIB.BASEBOARD_FAB2(SCH_1):GND    I43 @BASEBOARD_FAB2_LIB.BASEBOARD_FAB2(SCH_1):PAGE47
   125    GND @BASEBOARD_FAB2_LIB.BASEBOARD_FAB2(SCH_1):GND    I43 @BASEBOARD_FAB2_LIB.BASEBOARD_FAB2(SCH_1):PAGE47
   127    GND @BASEBOARD_FAB2_LIB.BASEBOARD_FAB2(SCH_1):GND    I43 @BASEBOARD_FAB2_LIB.BASEBOARD_FAB2(SCH_1):PAGE47
   129    GND @BASEBOARD_FAB2_LIB.BASEBOARD_FAB2(SCH_1):GND    I43 @BASEBOARD_FAB2_LIB.BASEBOARD_FAB2(SCH_1):PAGE47
   131    GND @BASEBOARD_FAB2_LIB.BASEBOARD_FAB2(SCH_1):GND    I43 @BASEBOARD_FAB2_LIB.BASEBOARD_FAB2(SCH_1):PAGE47
   134    GND @BASEBOARD_FAB2_LIB.BASEBOARD_FAB2(SCH_1):GND    I43 @BASEBOARD_FAB2_LIB.BASEBOARD_FAB2(SCH_1):PAGE47
   136    GND @BASEBOARD_FAB2_LIB.BASEBOARD_FAB2(SCH_1):GND    I43 @BASEBOARD_FAB2_LIB.BASEBOARD_FAB2(SCH_1):PAGE47
   138    GND @BASEBOARD_FAB2_LIB.BASEBOARD_FAB2(SCH_1):GND    I43 @BASEBOARD_FAB2_LIB.BASEBOARD_FAB2(SCH_1):PAGE47
   147    GND @BASEBOARD_FAB2_LIB.BASEBOARD_FAB2(SCH_1):GND    I43 @BASEBOARD_FAB2_LIB.BASEBOARD_FAB2(SCH_1):PAGE47
   149    GND @BASEBOARD_FAB2_LIB.BASEBOARD_FAB2(SCH_1):GND    I43 @BASEBOARD_FAB2_LIB.BASEBOARD_FAB2(SCH_1):PAGE47
   151    GND @BASEBOARD_FAB2_LIB.BASEBOARD_FAB2(SCH_1):GND    I43 @BASEBOARD_FAB2_LIB.BASEBOARD_FAB2(SCH_1):PAGE47
   154    GND @BASEBOARD_FAB2_LIB.BASEBOARD_FAB2(SCH_1):GND    I43 @BASEBOARD_FAB2_LIB.BASEBOARD_FAB2(SCH_1):PAGE47
   156    GND @BASEBOARD_FAB2_LIB.BASEBOARD_FAB2(SCH_1):GND    I43 @BASEBOARD_FAB2_LIB.BASEBOARD_FAB2(SCH_1):PAGE47
   158    GND @BASEBOARD_FAB2_LIB.BASEBOARD_FAB2(SCH_1):GND    I43 @BASEBOARD_FAB2_LIB.BASEBOARD_FAB2(SCH_1):PAGE47
   160    GND @BASEBOARD_FAB2_LIB.BASEBOARD_FAB2(SCH_1):GND    I43 @BASEBOARD_FAB2_LIB.BASEBOARD_FAB2(SCH_1):PAGE47
   162    GND @BASEBOARD_FAB2_LIB.BASEBOARD_FAB2(SCH_1):GND    I43 @BASEBOARD_FAB2_LIB.BASEBOARD_FAB2(SCH_1):PAGE47
   165    GND @BASEBOARD_FAB2_LIB.BASEBOARD_FAB2(SCH_1):GND    I43 @BASEBOARD_FAB2_LIB.BASEBOARD_FAB2(SCH_1):PAGE47
   167    GND @BASEBOARD_FAB2_LIB.BASEBOARD_FAB2(SCH_1):GND    I43 @BASEBOARD_FAB2_LIB.BASEBOARD_FAB2(SCH_1):PAGE47
   169    GND @BASEBOARD_FAB2_LIB.BASEBOARD_FAB2(SCH_1):GND    I43 @BASEBOARD_FAB2_LIB.BASEBOARD_FAB2(SCH_1):PAGE47
   171    GND @BASEBOARD_FAB2_LIB.BASEBOARD_FAB2(SCH_1):GND    I43 @BASEBOARD_FAB2_LIB.BASEBOARD_FAB2(SCH_1):PAGE47
   173    GND @BASEBOARD_FAB2_LIB.BASEBOARD_FAB2(SCH_1):GND    I43 @BASEBOARD_FAB2_LIB.BASEBOARD_FAB2(SCH_1):PAGE47
   176    GND @BASEBOARD_FAB2_LIB.BASEBOARD_FAB2(SCH_1):GND    I43 @BASEBOARD_FAB2_LIB.BASEBOARD_FAB2(SCH_1):PAGE47
   178    GND @BASEBOARD_FAB2_LIB.BASEBOARD_FAB2(SCH_1):GND    I43 @BASEBOARD_FAB2_LIB.BASEBOARD_FAB2(SCH_1):PAGE47
   180    GND @BASEBOARD_FAB2_LIB.BASEBOARD_FAB2(SCH_1):GND    I43 @BASEBOARD_FAB2_LIB.BASEBOARD_FAB2(SCH_1):PAGE47
   182    GND @BASEBOARD_FAB2_LIB.BASEBOARD_FAB2(SCH_1):GND    I43 @BASEBOARD_FAB2_LIB.BASEBOARD_FAB2(SCH_1):PAGE47
   184    GND @BASEBOARD_FAB2_LIB.BASEBOARD_FAB2(SCH_1):GND    I43 @BASEBOARD_FAB2_LIB.BASEBOARD_FAB2(SCH_1):PAGE47
   187    GND @BASEBOARD_FAB2_LIB.BASEBOARD_FAB2(SCH_1):GND    I43 @BASEBOARD_FAB2_LIB.BASEBOARD_FAB2(SCH_1):PAGE47
   189    GND @BASEBOARD_FAB2_LIB.BASEBOARD_FAB2(SCH_1):GND    I43 @BASEBOARD_FAB2_LIB.BASEBOARD_FAB2(SCH_1):PAGE47
   191    GND @BASEBOARD_FAB2_LIB.BASEBOARD_FAB2(SCH_1):GND    I43 @BASEBOARD_FAB2_LIB.BASEBOARD_FAB2(SCH_1):PAGE47
   193    GND @BASEBOARD_FAB2_LIB.BASEBOARD_FAB2(SCH_1):GND    I43 @BASEBOARD_FAB2_LIB.BASEBOARD_FAB2(SCH_1):PAGE47
   195    GND @BASEBOARD_FAB2_LIB.BASEBOARD_FAB2(SCH_1):GND    I43 @BASEBOARD_FAB2_LIB.BASEBOARD_FAB2(SCH_1):PAGE47
   198    GND @BASEBOARD_FAB2_LIB.BASEBOARD_FAB2(SCH_1):GND    I43 @BASEBOARD_FAB2_LIB.BASEBOARD_FAB2(SCH_1):PAGE47
   200    GND @BASEBOARD_FAB2_LIB.BASEBOARD_FAB2(SCH_1):GND    I43 @BASEBOARD_FAB2_LIB.BASEBOARD_FAB2(SCH_1):PAGE47
   202    GND @BASEBOARD_FAB2_LIB.BASEBOARD_FAB2(SCH_1):GND    I43 @BASEBOARD_FAB2_LIB.BASEBOARD_FAB2(SCH_1):PAGE47
   239    GND @BASEBOARD_FAB2_LIB.BASEBOARD_FAB2(SCH_1):GND    I43 @BASEBOARD_FAB2_LIB.BASEBOARD_FAB2(SCH_1):PAGE47
   241    GND @BASEBOARD_FAB2_LIB.BASEBOARD_FAB2(SCH_1):GND    I43 @BASEBOARD_FAB2_LIB.BASEBOARD_FAB2(SCH_1):PAGE47
   243    GND @BASEBOARD_FAB2_LIB.BASEBOARD_FAB2(SCH_1):GND    I43 @BASEBOARD_FAB2_LIB.BASEBOARD_FAB2(SCH_1):PAGE47
   246    GND @BASEBOARD_FAB2_LIB.BASEBOARD_FAB2(SCH_1):GND    I43 @BASEBOARD_FAB2_LIB.BASEBOARD_FAB2(SCH_1):PAGE47
   248    GND @BASEBOARD_FAB2_LIB.BASEBOARD_FAB2(SCH_1):GND    I43 @BASEBOARD_FAB2_LIB.BASEBOARD_FAB2(SCH_1):PAGE47
   250    GND @BASEBOARD_FAB2_LIB.BASEBOARD_FAB2(SCH_1):GND    I43 @BASEBOARD_FAB2_LIB.BASEBOARD_FAB2(SCH_1):PAGE47
   252    GND @BASEBOARD_FAB2_LIB.BASEBOARD_FAB2(SCH_1):GND    I43 @BASEBOARD_FAB2_LIB.BASEBOARD_FAB2(SCH_1):PAGE47
   254    GND @BASEBOARD_FAB2_LIB.BASEBOARD_FAB2(SCH_1):GND    I43 @BASEBOARD_FAB2_LIB.BASEBOARD_FAB2(SCH_1):PAGE47
   257    GND @BASEBOARD_FAB2_LIB.BASEBOARD_FAB2(SCH_1):GND    I43 @BASEBOARD_FAB2_LIB.BASEBOARD_FAB2(SCH_1):PAGE47
   259    GND @BASEBOARD_FAB2_LIB.BASEBOARD_FAB2(SCH_1):GND    I43 @BASEBOARD_FAB2_LIB.BASEBOARD_FAB2(SCH_1):PAGE47
   261    GND @BASEBOARD_FAB2_LIB.BASEBOARD_FAB2(SCH_1):GND    I43 @BASEBOARD_FAB2_LIB.BASEBOARD_FAB2(SCH_1):PAGE47
   263    GND @BASEBOARD_FAB2_LIB.BASEBOARD_FAB2(SCH_1):GND    I43 @BASEBOARD_FAB2_LIB.BASEBOARD_FAB2(SCH_1):PAGE47
   265    GND @BASEBOARD_FAB2_LIB.BASEBOARD_FAB2(SCH_1):GND    I43 @BASEBOARD_FAB2_LIB.BASEBOARD_FAB2(SCH_1):PAGE47
   268    GND @BASEBOARD_FAB2_LIB.BASEBOARD_FAB2(SCH_1):GND    I43 @BASEBOARD_FAB2_LIB.BASEBOARD_FAB2(SCH_1):PAGE47
   270    GND @BASEBOARD_FAB2_LIB.BASEBOARD_FAB2(SCH_1):GND    I43 @BASEBOARD_FAB2_LIB.BASEBOARD_FAB2(SCH_1):PAGE47
   272    GND @BASEBOARD_FAB2_LIB.BASEBOARD_FAB2(SCH_1):GND    I43 @BASEBOARD_FAB2_LIB.BASEBOARD_FAB2(SCH_1):PAGE47
   274    GND @BASEBOARD_FAB2_LIB.BASEBOARD_FAB2(SCH_1):GND    I43 @BASEBOARD_FAB2_LIB.BASEBOARD_FAB2(SCH_1):PAGE47
   276    GND @BASEBOARD_FAB2_LIB.BASEBOARD_FAB2(SCH_1):GND    I43 @BASEBOARD_FAB2_LIB.BASEBOARD_FAB2(SCH_1):PAGE47
   279    GND @BASEBOARD_FAB2_LIB.BASEBOARD_FAB2(SCH_1):GND    I43 @BASEBOARD_FAB2_LIB.BASEBOARD_FAB2(SCH_1):PAGE47
   281    GND @BASEBOARD_FAB2_LIB.BASEBOARD_FAB2(SCH_1):GND    I43 @BASEBOARD_FAB2_LIB.BASEBOARD_FAB2(SCH_1):PAGE47
   283    GND @BASEBOARD_FAB2_LIB.BASEBOARD_FAB2(SCH_1):GND    I43 @BASEBOARD_FAB2_LIB.BASEBOARD_FAB2(SCH_1):PAGE47
     1 P12V_NVDIMM_ABC @BASEBOARD_FAB2_LIB.BASEBOARD_FAB2(SCH_1):P12V_NVDIMM_ABC   I179 @BASEBOARD_FAB2_LIB.BASEBOARD_FAB2(SCH_1):PAGE47
   145 P12V_NVDIMM_ABC @BASEBOARD_FAB2_LIB.BASEBOARD_FAB2(SCH_1):P12V_NVDIMM_ABC   I179 @BASEBOARD_FAB2_LIB.BASEBOARD_FAB2(SCH_1):PAGE47
    59 PVDDQ_ABC @BASEBOARD_FAB2_LIB.BASEBOARD_FAB2(SCH_1):PVDDQ_ABC   I179 @BASEBOARD_FAB2_LIB.BASEBOARD_FAB2(SCH_1):PAGE47
    61 PVDDQ_ABC @BASEBOARD_FAB2_LIB.BASEBOARD_FAB2(SCH_1):PVDDQ_ABC   I179 @BASEBOARD_FAB2_LIB.BASEBOARD_FAB2(SCH_1):PAGE47
    64 PVDDQ_ABC @BASEBOARD_FAB2_LIB.BASEBOARD_FAB2(SCH_1):PVDDQ_ABC   I179 @BASEBOARD_FAB2_LIB.BASEBOARD_FAB2(SCH_1):PAGE47
    67 PVDDQ_ABC @BASEBOARD_FAB2_LIB.BASEBOARD_FAB2(SCH_1):PVDDQ_ABC   I179 @BASEBOARD_FAB2_LIB.BASEBOARD_FAB2(SCH_1):PAGE47
    70 PVDDQ_ABC @BASEBOARD_FAB2_LIB.BASEBOARD_FAB2(SCH_1):PVDDQ_ABC   I179 @BASEBOARD_FAB2_LIB.BASEBOARD_FAB2(SCH_1):PAGE47
    73 PVDDQ_ABC @BASEBOARD_FAB2_LIB.BASEBOARD_FAB2(SCH_1):PVDDQ_ABC   I179 @BASEBOARD_FAB2_LIB.BASEBOARD_FAB2(SCH_1):PAGE47
    76 PVDDQ_ABC @BASEBOARD_FAB2_LIB.BASEBOARD_FAB2(SCH_1):PVDDQ_ABC   I179 @BASEBOARD_FAB2_LIB.BASEBOARD_FAB2(SCH_1):PAGE47
    80 PVDDQ_ABC @BASEBOARD_FAB2_LIB.BASEBOARD_FAB2(SCH_1):PVDDQ_ABC   I179 @BASEBOARD_FAB2_LIB.BASEBOARD_FAB2(SCH_1):PAGE47
    83 PVDDQ_ABC @BASEBOARD_FAB2_LIB.BASEBOARD_FAB2(SCH_1):PVDDQ_ABC   I179 @BASEBOARD_FAB2_LIB.BASEBOARD_FAB2(SCH_1):PAGE47
    85 PVDDQ_ABC @BASEBOARD_FAB2_LIB.BASEBOARD_FAB2(SCH_1):PVDDQ_ABC   I179 @BASEBOARD_FAB2_LIB.BASEBOARD_FAB2(SCH_1):PAGE47
    88 PVDDQ_ABC @BASEBOARD_FAB2_LIB.BASEBOARD_FAB2(SCH_1):PVDDQ_ABC   I179 @BASEBOARD_FAB2_LIB.BASEBOARD_FAB2(SCH_1):PAGE47
    90 PVDDQ_ABC @BASEBOARD_FAB2_LIB.BASEBOARD_FAB2(SCH_1):PVDDQ_ABC   I179 @BASEBOARD_FAB2_LIB.BASEBOARD_FAB2(SCH_1):PAGE47
    92 PVDDQ_ABC @BASEBOARD_FAB2_LIB.BASEBOARD_FAB2(SCH_1):PVDDQ_ABC   I179 @BASEBOARD_FAB2_LIB.BASEBOARD_FAB2(SCH_1):PAGE47
   204 PVDDQ_ABC @BASEBOARD_FAB2_LIB.BASEBOARD_FAB2(SCH_1):PVDDQ_ABC   I179 @BASEBOARD_FAB2_LIB.BASEBOARD_FAB2(SCH_1):PAGE47
   206 PVDDQ_ABC @BASEBOARD_FAB2_LIB.BASEBOARD_FAB2(SCH_1):PVDDQ_ABC   I179 @BASEBOARD_FAB2_LIB.BASEBOARD_FAB2(SCH_1):PAGE47
   209 PVDDQ_ABC @BASEBOARD_FAB2_LIB.BASEBOARD_FAB2(SCH_1):PVDDQ_ABC   I179 @BASEBOARD_FAB2_LIB.BASEBOARD_FAB2(SCH_1):PAGE47
   212 PVDDQ_ABC @BASEBOARD_FAB2_LIB.BASEBOARD_FAB2(SCH_1):PVDDQ_ABC   I179 @BASEBOARD_FAB2_LIB.BASEBOARD_FAB2(SCH_1):PAGE47
   215 PVDDQ_ABC @BASEBOARD_FAB2_LIB.BASEBOARD_FAB2(SCH_1):PVDDQ_ABC   I179 @BASEBOARD_FAB2_LIB.BASEBOARD_FAB2(SCH_1):PAGE47
   217 PVDDQ_ABC @BASEBOARD_FAB2_LIB.BASEBOARD_FAB2(SCH_1):PVDDQ_ABC   I179 @BASEBOARD_FAB2_LIB.BASEBOARD_FAB2(SCH_1):PAGE47
   220 PVDDQ_ABC @BASEBOARD_FAB2_LIB.BASEBOARD_FAB2(SCH_1):PVDDQ_ABC   I179 @BASEBOARD_FAB2_LIB.BASEBOARD_FAB2(SCH_1):PAGE47
   223 PVDDQ_ABC @BASEBOARD_FAB2_LIB.BASEBOARD_FAB2(SCH_1):PVDDQ_ABC   I179 @BASEBOARD_FAB2_LIB.BASEBOARD_FAB2(SCH_1):PAGE47
   226 PVDDQ_ABC @BASEBOARD_FAB2_LIB.BASEBOARD_FAB2(SCH_1):PVDDQ_ABC   I179 @BASEBOARD_FAB2_LIB.BASEBOARD_FAB2(SCH_1):PAGE47
   229 PVDDQ_ABC @BASEBOARD_FAB2_LIB.BASEBOARD_FAB2(SCH_1):PVDDQ_ABC   I179 @BASEBOARD_FAB2_LIB.BASEBOARD_FAB2(SCH_1):PAGE47
   231 PVDDQ_ABC @BASEBOARD_FAB2_LIB.BASEBOARD_FAB2(SCH_1):PVDDQ_ABC   I179 @BASEBOARD_FAB2_LIB.BASEBOARD_FAB2(SCH_1):PAGE47
   233 PVDDQ_ABC @BASEBOARD_FAB2_LIB.BASEBOARD_FAB2(SCH_1):PVDDQ_ABC   I179 @BASEBOARD_FAB2_LIB.BASEBOARD_FAB2(SCH_1):PAGE47
   236 PVDDQ_ABC @BASEBOARD_FAB2_LIB.BASEBOARD_FAB2(SCH_1):PVDDQ_ABC   I179 @BASEBOARD_FAB2_LIB.BASEBOARD_FAB2(SCH_1):PAGE47
   142 PVPP_ABC @BASEBOARD_FAB2_LIB.BASEBOARD_FAB2(SCH_1):PVPP_ABC   I179 @BASEBOARD_FAB2_LIB.BASEBOARD_FAB2(SCH_1):PAGE47
   143 PVPP_ABC @BASEBOARD_FAB2_LIB.BASEBOARD_FAB2(SCH_1):PVPP_ABC   I179 @BASEBOARD_FAB2_LIB.BASEBOARD_FAB2(SCH_1):PAGE47
   288 PVPP_ABC @BASEBOARD_FAB2_LIB.BASEBOARD_FAB2(SCH_1):PVPP_ABC   I179 @BASEBOARD_FAB2_LIB.BASEBOARD_FAB2(SCH_1):PAGE47
   286 PVPP_ABC @BASEBOARD_FAB2_LIB.BASEBOARD_FAB2(SCH_1):PVPP_ABC   I179 @BASEBOARD_FAB2_LIB.BASEBOARD_FAB2(SCH_1):PAGE47
   287 PVPP_ABC @BASEBOARD_FAB2_LIB.BASEBOARD_FAB2(SCH_1):PVPP_ABC   I179 @BASEBOARD_FAB2_LIB.BASEBOARD_FAB2(SCH_1):PAGE47
    77 PVTT_ABC @BASEBOARD_FAB2_LIB.BASEBOARD_FAB2(SCH_1):PVTT_ABC   I179 @BASEBOARD_FAB2_LIB.BASEBOARD_FAB2(SCH_1):PAGE47
   221 PVTT_ABC @BASEBOARD_FAB2_LIB.BASEBOARD_FAB2(SCH_1):PVTT_ABC   I179 @BASEBOARD_FAB2_LIB.BASEBOARD_FAB2(SCH_1):PAGE47

J6B1 SCONN120_H61426002_SM-CONN,H61A
    A1 P12V_STBY @BASEBOARD_FAB2_LIB.BASEBOARD_FAB2(SCH_1):P12V_STBY    I56 @BASEBOARD_FAB2_LIB.BASEBOARD_FAB2(SCH_1):PAGE194
   A10    GND @BASEBOARD_FAB2_LIB.BASEBOARD_FAB2(SCH_1):GND    I56 @BASEBOARD_FAB2_LIB.BASEBOARD_FAB2(SCH_1):PAGE194
   A11 P3V3_STBY @BASEBOARD_FAB2_LIB.BASEBOARD_FAB2(SCH_1):P3V3_STBY    I56 @BASEBOARD_FAB2_LIB.BASEBOARD_FAB2(SCH_1):PAGE194
   A12    GND @BASEBOARD_FAB2_LIB.BASEBOARD_FAB2(SCH_1):GND    I56 @BASEBOARD_FAB2_LIB.BASEBOARD_FAB2(SCH_1):PAGE194
   A13 P5V_STBY @BASEBOARD_FAB2_LIB.BASEBOARD_FAB2(SCH_1):P5V_STBY    I56 @BASEBOARD_FAB2_LIB.BASEBOARD_FAB2(SCH_1):PAGE194
   A14    GND @BASEBOARD_FAB2_LIB.BASEBOARD_FAB2(SCH_1):GND    I56 @BASEBOARD_FAB2_LIB.BASEBOARD_FAB2(SCH_1):PAGE194
   A15 FM_P1V8MCP_CPU0_EN @BASEBOARD_FAB2_LIB.BASEBOARD_FAB2(SCH_1):FM_P1V8MCP_CPU0_EN    I56 @BASEBOARD_FAB2_LIB.BASEBOARD_FAB2(SCH_1):PAGE194
   A16 FM_PVCCIOMCP_CPU0_EN @BASEBOARD_FAB2_LIB.BASEBOARD_FAB2(SCH_1):FM_PVCCIOMCP_CPU0_EN    I56 @BASEBOARD_FAB2_LIB.BASEBOARD_FAB2(SCH_1):PAGE194
   A17    GND @BASEBOARD_FAB2_LIB.BASEBOARD_FAB2(SCH_1):GND    I56 @BASEBOARD_FAB2_LIB.BASEBOARD_FAB2(SCH_1):PAGE194
   A18 SMB_VR_STBY_LVC3_SCL @BASEBOARD_FAB2_LIB.BASEBOARD_FAB2(SCH_1):SMB_VR_STBY_LVC3_SCL    I56 @BASEBOARD_FAB2_LIB.BASEBOARD_FAB2(SCH_1):PAGE194
   A19 SVID_ALERT0_CPU0_R_N @BASEBOARD_FAB2_LIB.BASEBOARD_FAB2(SCH_1):SVID_ALERT0_CPU0_R_N    I56 @BASEBOARD_FAB2_LIB.BASEBOARD_FAB2(SCH_1):PAGE194
    A2 P12V_STBY @BASEBOARD_FAB2_LIB.BASEBOARD_FAB2(SCH_1):P12V_STBY    I56 @BASEBOARD_FAB2_LIB.BASEBOARD_FAB2(SCH_1):PAGE194
   A20 SVID_CLK0_CPU0_R @BASEBOARD_FAB2_LIB.BASEBOARD_FAB2(SCH_1):SVID_CLK0_CPU0_R    I56 @BASEBOARD_FAB2_LIB.BASEBOARD_FAB2(SCH_1):PAGE194
    A3 P12V_STBY @BASEBOARD_FAB2_LIB.BASEBOARD_FAB2(SCH_1):P12V_STBY    I56 @BASEBOARD_FAB2_LIB.BASEBOARD_FAB2(SCH_1):PAGE194
    A4 P12V_STBY @BASEBOARD_FAB2_LIB.BASEBOARD_FAB2(SCH_1):P12V_STBY    I56 @BASEBOARD_FAB2_LIB.BASEBOARD_FAB2(SCH_1):PAGE194
    A5 P12V_STBY @BASEBOARD_FAB2_LIB.BASEBOARD_FAB2(SCH_1):P12V_STBY    I56 @BASEBOARD_FAB2_LIB.BASEBOARD_FAB2(SCH_1):PAGE194
    A6 P12V_STBY @BASEBOARD_FAB2_LIB.BASEBOARD_FAB2(SCH_1):P12V_STBY    I56 @BASEBOARD_FAB2_LIB.BASEBOARD_FAB2(SCH_1):PAGE194
    A7 P12V_STBY @BASEBOARD_FAB2_LIB.BASEBOARD_FAB2(SCH_1):P12V_STBY    I56 @BASEBOARD_FAB2_LIB.BASEBOARD_FAB2(SCH_1):PAGE194
    A8 P12V_STBY @BASEBOARD_FAB2_LIB.BASEBOARD_FAB2(SCH_1):P12V_STBY    I56 @BASEBOARD_FAB2_LIB.BASEBOARD_FAB2(SCH_1):PAGE194
    A9    GND @BASEBOARD_FAB2_LIB.BASEBOARD_FAB2(SCH_1):GND    I56 @BASEBOARD_FAB2_LIB.BASEBOARD_FAB2(SCH_1):PAGE194
    B1 P12V_STBY @BASEBOARD_FAB2_LIB.BASEBOARD_FAB2(SCH_1):P12V_STBY    I56 @BASEBOARD_FAB2_LIB.BASEBOARD_FAB2(SCH_1):PAGE194
   B10    GND @BASEBOARD_FAB2_LIB.BASEBOARD_FAB2(SCH_1):GND    I56 @BASEBOARD_FAB2_LIB.BASEBOARD_FAB2(SCH_1):PAGE194
   B11 P3V3_STBY @BASEBOARD_FAB2_LIB.BASEBOARD_FAB2(SCH_1):P3V3_STBY    I56 @BASEBOARD_FAB2_LIB.BASEBOARD_FAB2(SCH_1):PAGE194
   B12    GND @BASEBOARD_FAB2_LIB.BASEBOARD_FAB2(SCH_1):GND    I56 @BASEBOARD_FAB2_LIB.BASEBOARD_FAB2(SCH_1):PAGE194
   B13 P5V_STBY @BASEBOARD_FAB2_LIB.BASEBOARD_FAB2(SCH_1):P5V_STBY    I56 @BASEBOARD_FAB2_LIB.BASEBOARD_FAB2(SCH_1):PAGE194
   B14    GND @BASEBOARD_FAB2_LIB.BASEBOARD_FAB2(SCH_1):GND    I56 @BASEBOARD_FAB2_LIB.BASEBOARD_FAB2(SCH_1):PAGE194
   B15 PWRGD_P1V8MCP_CPU0 @BASEBOARD_FAB2_LIB.BASEBOARD_FAB2(SCH_1):PWRGD_P1V8MCP_CPU0    I56 @BASEBOARD_FAB2_LIB.BASEBOARD_FAB2(SCH_1):PAGE194
   B16 PWRGD_PVCCIOMCP_CPU0 @BASEBOARD_FAB2_LIB.BASEBOARD_FAB2(SCH_1):PWRGD_PVCCIOMCP_CPU0    I56 @BASEBOARD_FAB2_LIB.BASEBOARD_FAB2(SCH_1):PAGE194
   B17    GND @BASEBOARD_FAB2_LIB.BASEBOARD_FAB2(SCH_1):GND    I56 @BASEBOARD_FAB2_LIB.BASEBOARD_FAB2(SCH_1):PAGE194
   B18 SMB_VR_STBY_LVC3_SDA @BASEBOARD_FAB2_LIB.BASEBOARD_FAB2(SCH_1):SMB_VR_STBY_LVC3_SDA    I56 @BASEBOARD_FAB2_LIB.BASEBOARD_FAB2(SCH_1):PAGE194
   B19 SVID_ALERT1_CPU0_R_N @BASEBOARD_FAB2_LIB.BASEBOARD_FAB2(SCH_1):SVID_ALERT1_CPU0_R_N    I56 @BASEBOARD_FAB2_LIB.BASEBOARD_FAB2(SCH_1):PAGE194
    B2 P12V_STBY @BASEBOARD_FAB2_LIB.BASEBOARD_FAB2(SCH_1):P12V_STBY    I56 @BASEBOARD_FAB2_LIB.BASEBOARD_FAB2(SCH_1):PAGE194
   B20 SVID_DIO0_CPU0_R @BASEBOARD_FAB2_LIB.BASEBOARD_FAB2(SCH_1):SVID_DIO0_CPU0_R    I56 @BASEBOARD_FAB2_LIB.BASEBOARD_FAB2(SCH_1):PAGE194
    B3 P12V_STBY @BASEBOARD_FAB2_LIB.BASEBOARD_FAB2(SCH_1):P12V_STBY    I56 @BASEBOARD_FAB2_LIB.BASEBOARD_FAB2(SCH_1):PAGE194
    B4 P12V_STBY @BASEBOARD_FAB2_LIB.BASEBOARD_FAB2(SCH_1):P12V_STBY    I56 @BASEBOARD_FAB2_LIB.BASEBOARD_FAB2(SCH_1):PAGE194
    B5 P12V_STBY @BASEBOARD_FAB2_LIB.BASEBOARD_FAB2(SCH_1):P12V_STBY    I56 @BASEBOARD_FAB2_LIB.BASEBOARD_FAB2(SCH_1):PAGE194
    B6 P12V_STBY @BASEBOARD_FAB2_LIB.BASEBOARD_FAB2(SCH_1):P12V_STBY    I56 @BASEBOARD_FAB2_LIB.BASEBOARD_FAB2(SCH_1):PAGE194
    B7 P12V_STBY @BASEBOARD_FAB2_LIB.BASEBOARD_FAB2(SCH_1):P12V_STBY    I56 @BASEBOARD_FAB2_LIB.BASEBOARD_FAB2(SCH_1):PAGE194
    B8 P12V_STBY @BASEBOARD_FAB2_LIB.BASEBOARD_FAB2(SCH_1):P12V_STBY    I56 @BASEBOARD_FAB2_LIB.BASEBOARD_FAB2(SCH_1):PAGE194
    B9    GND @BASEBOARD_FAB2_LIB.BASEBOARD_FAB2(SCH_1):GND    I56 @BASEBOARD_FAB2_LIB.BASEBOARD_FAB2(SCH_1):PAGE194
    C1    GND @BASEBOARD_FAB2_LIB.BASEBOARD_FAB2(SCH_1):GND    I56 @BASEBOARD_FAB2_LIB.BASEBOARD_FAB2(SCH_1):PAGE194
   C10    GND @BASEBOARD_FAB2_LIB.BASEBOARD_FAB2(SCH_1):GND    I56 @BASEBOARD_FAB2_LIB.BASEBOARD_FAB2(SCH_1):PAGE194
   C11 P3V3_STBY @BASEBOARD_FAB2_LIB.BASEBOARD_FAB2(SCH_1):P3V3_STBY    I56 @BASEBOARD_FAB2_LIB.BASEBOARD_FAB2(SCH_1):PAGE194
   C12    GND @BASEBOARD_FAB2_LIB.BASEBOARD_FAB2(SCH_1):GND    I56 @BASEBOARD_FAB2_LIB.BASEBOARD_FAB2(SCH_1):PAGE194
   C13 P5V_STBY @BASEBOARD_FAB2_LIB.BASEBOARD_FAB2(SCH_1):P5V_STBY    I56 @BASEBOARD_FAB2_LIB.BASEBOARD_FAB2(SCH_1):PAGE194
   C14    GND @BASEBOARD_FAB2_LIB.BASEBOARD_FAB2(SCH_1):GND    I56 @BASEBOARD_FAB2_LIB.BASEBOARD_FAB2(SCH_1):PAGE194
   C15    GND @BASEBOARD_FAB2_LIB.BASEBOARD_FAB2(SCH_1):GND    I56 @BASEBOARD_FAB2_LIB.BASEBOARD_FAB2(SCH_1):PAGE194
   C16    GND @BASEBOARD_FAB2_LIB.BASEBOARD_FAB2(SCH_1):GND    I56 @BASEBOARD_FAB2_LIB.BASEBOARD_FAB2(SCH_1):PAGE194
   C17 PVCCIOMCP_CPU0 @BASEBOARD_FAB2_LIB.BASEBOARD_FAB2(SCH_1):PVCCIOMCP_CPU0    I56 @BASEBOARD_FAB2_LIB.BASEBOARD_FAB2(SCH_1):PAGE194
   C18 PVCCIOMCP_CPU0 @BASEBOARD_FAB2_LIB.BASEBOARD_FAB2(SCH_1):PVCCIOMCP_CPU0    I56 @BASEBOARD_FAB2_LIB.BASEBOARD_FAB2(SCH_1):PAGE194
   C19 PVCCIOMCP_CPU0 @BASEBOARD_FAB2_LIB.BASEBOARD_FAB2(SCH_1):PVCCIOMCP_CPU0    I56 @BASEBOARD_FAB2_LIB.BASEBOARD_FAB2(SCH_1):PAGE194
    C2    GND @BASEBOARD_FAB2_LIB.BASEBOARD_FAB2(SCH_1):GND    I56 @BASEBOARD_FAB2_LIB.BASEBOARD_FAB2(SCH_1):PAGE194
   C20 FM_PVCCMCP_CPU0_EN @BASEBOARD_FAB2_LIB.BASEBOARD_FAB2(SCH_1):FM_PVCCMCP_CPU0_EN    I56 @BASEBOARD_FAB2_LIB.BASEBOARD_FAB2(SCH_1):PAGE194
    C3    GND @BASEBOARD_FAB2_LIB.BASEBOARD_FAB2(SCH_1):GND    I56 @BASEBOARD_FAB2_LIB.BASEBOARD_FAB2(SCH_1):PAGE194
    C4    GND @BASEBOARD_FAB2_LIB.BASEBOARD_FAB2(SCH_1):GND    I56 @BASEBOARD_FAB2_LIB.BASEBOARD_FAB2(SCH_1):PAGE194
    C5    GND @BASEBOARD_FAB2_LIB.BASEBOARD_FAB2(SCH_1):GND    I56 @BASEBOARD_FAB2_LIB.BASEBOARD_FAB2(SCH_1):PAGE194
    C6    GND @BASEBOARD_FAB2_LIB.BASEBOARD_FAB2(SCH_1):GND    I56 @BASEBOARD_FAB2_LIB.BASEBOARD_FAB2(SCH_1):PAGE194
    C7    GND @BASEBOARD_FAB2_LIB.BASEBOARD_FAB2(SCH_1):GND    I56 @BASEBOARD_FAB2_LIB.BASEBOARD_FAB2(SCH_1):PAGE194
    C8    GND @BASEBOARD_FAB2_LIB.BASEBOARD_FAB2(SCH_1):GND    I56 @BASEBOARD_FAB2_LIB.BASEBOARD_FAB2(SCH_1):PAGE194
    C9    GND @BASEBOARD_FAB2_LIB.BASEBOARD_FAB2(SCH_1):GND    I56 @BASEBOARD_FAB2_LIB.BASEBOARD_FAB2(SCH_1):PAGE194
    D1   P3V3 @BASEBOARD_FAB2_LIB.BASEBOARD_FAB2(SCH_1):P3V3    I56 @BASEBOARD_FAB2_LIB.BASEBOARD_FAB2(SCH_1):PAGE194
   D10    GND @BASEBOARD_FAB2_LIB.BASEBOARD_FAB2(SCH_1):GND    I56 @BASEBOARD_FAB2_LIB.BASEBOARD_FAB2(SCH_1):PAGE194
   D11    GND @BASEBOARD_FAB2_LIB.BASEBOARD_FAB2(SCH_1):GND    I56 @BASEBOARD_FAB2_LIB.BASEBOARD_FAB2(SCH_1):PAGE194
   D12    GND @BASEBOARD_FAB2_LIB.BASEBOARD_FAB2(SCH_1):GND    I56 @BASEBOARD_FAB2_LIB.BASEBOARD_FAB2(SCH_1):PAGE194
   D13    GND @BASEBOARD_FAB2_LIB.BASEBOARD_FAB2(SCH_1):GND    I56 @BASEBOARD_FAB2_LIB.BASEBOARD_FAB2(SCH_1):PAGE194
   D14    GND @BASEBOARD_FAB2_LIB.BASEBOARD_FAB2(SCH_1):GND    I56 @BASEBOARD_FAB2_LIB.BASEBOARD_FAB2(SCH_1):PAGE194
   D15    GND @BASEBOARD_FAB2_LIB.BASEBOARD_FAB2(SCH_1):GND    I56 @BASEBOARD_FAB2_LIB.BASEBOARD_FAB2(SCH_1):PAGE194
   D16    GND @BASEBOARD_FAB2_LIB.BASEBOARD_FAB2(SCH_1):GND    I56 @BASEBOARD_FAB2_LIB.BASEBOARD_FAB2(SCH_1):PAGE194
   D17 PVCCIOMCP_CPU0 @BASEBOARD_FAB2_LIB.BASEBOARD_FAB2(SCH_1):PVCCIOMCP_CPU0    I56 @BASEBOARD_FAB2_LIB.BASEBOARD_FAB2(SCH_1):PAGE194
   D18 PVCCIOMCP_CPU0 @BASEBOARD_FAB2_LIB.BASEBOARD_FAB2(SCH_1):PVCCIOMCP_CPU0    I56 @BASEBOARD_FAB2_LIB.BASEBOARD_FAB2(SCH_1):PAGE194
   D19 PVCCIOMCP_CPU0 @BASEBOARD_FAB2_LIB.BASEBOARD_FAB2(SCH_1):PVCCIOMCP_CPU0    I56 @BASEBOARD_FAB2_LIB.BASEBOARD_FAB2(SCH_1):PAGE194
    D2    GND @BASEBOARD_FAB2_LIB.BASEBOARD_FAB2(SCH_1):GND    I56 @BASEBOARD_FAB2_LIB.BASEBOARD_FAB2(SCH_1):PAGE194
   D20 PWRGD_PVCCMCP_CPU0 @BASEBOARD_FAB2_LIB.BASEBOARD_FAB2(SCH_1):PWRGD_PVCCMCP_CPU0    I56 @BASEBOARD_FAB2_LIB.BASEBOARD_FAB2(SCH_1):PAGE194
    D3    GND @BASEBOARD_FAB2_LIB.BASEBOARD_FAB2(SCH_1):GND    I56 @BASEBOARD_FAB2_LIB.BASEBOARD_FAB2(SCH_1):PAGE194
    D4    GND @BASEBOARD_FAB2_LIB.BASEBOARD_FAB2(SCH_1):GND    I56 @BASEBOARD_FAB2_LIB.BASEBOARD_FAB2(SCH_1):PAGE194
    D5    GND @BASEBOARD_FAB2_LIB.BASEBOARD_FAB2(SCH_1):GND    I56 @BASEBOARD_FAB2_LIB.BASEBOARD_FAB2(SCH_1):PAGE194
    D6    GND @BASEBOARD_FAB2_LIB.BASEBOARD_FAB2(SCH_1):GND    I56 @BASEBOARD_FAB2_LIB.BASEBOARD_FAB2(SCH_1):PAGE194
    D7    GND @BASEBOARD_FAB2_LIB.BASEBOARD_FAB2(SCH_1):GND    I56 @BASEBOARD_FAB2_LIB.BASEBOARD_FAB2(SCH_1):PAGE194
    D8    GND @BASEBOARD_FAB2_LIB.BASEBOARD_FAB2(SCH_1):GND    I56 @BASEBOARD_FAB2_LIB.BASEBOARD_FAB2(SCH_1):PAGE194
    D9    GND @BASEBOARD_FAB2_LIB.BASEBOARD_FAB2(SCH_1):GND    I56 @BASEBOARD_FAB2_LIB.BASEBOARD_FAB2(SCH_1):PAGE194
    E1 FM_CPU0_VRM_322M_156M_OSC_EN @BASEBOARD_FAB2_LIB.BASEBOARD_FAB2(SCH_1):FM_CPU0_VRM_322M_156M_OSC_EN    I56 @BASEBOARD_FAB2_LIB.BASEBOARD_FAB2(SCH_1):PAGE194
   E10 VR_PVCCIOMCP_CPU0_XADDR1 @BASEBOARD_FAB2_LIB.BASEBOARD_FAB2(SCH_1):VR_PVCCIOMCP_CPU0_XADDR1    I56 @BASEBOARD_FAB2_LIB.BASEBOARD_FAB2(SCH_1):PAGE194
   E11    GND @BASEBOARD_FAB2_LIB.BASEBOARD_FAB2(SCH_1):GND    I56 @BASEBOARD_FAB2_LIB.BASEBOARD_FAB2(SCH_1):PAGE194
   E12    GND @BASEBOARD_FAB2_LIB.BASEBOARD_FAB2(SCH_1):GND    I56 @BASEBOARD_FAB2_LIB.BASEBOARD_FAB2(SCH_1):PAGE194
   E13    GND @BASEBOARD_FAB2_LIB.BASEBOARD_FAB2(SCH_1):GND    I56 @BASEBOARD_FAB2_LIB.BASEBOARD_FAB2(SCH_1):PAGE194
   E14    GND @BASEBOARD_FAB2_LIB.BASEBOARD_FAB2(SCH_1):GND    I56 @BASEBOARD_FAB2_LIB.BASEBOARD_FAB2(SCH_1):PAGE194
   E15 PVCCIOMCP_CPU0 @BASEBOARD_FAB2_LIB.BASEBOARD_FAB2(SCH_1):PVCCIOMCP_CPU0    I56 @BASEBOARD_FAB2_LIB.BASEBOARD_FAB2(SCH_1):PAGE194
   E16 PVCCIOMCP_CPU0 @BASEBOARD_FAB2_LIB.BASEBOARD_FAB2(SCH_1):PVCCIOMCP_CPU0    I56 @BASEBOARD_FAB2_LIB.BASEBOARD_FAB2(SCH_1):PAGE194
   E17 PVCCIOMCP_CPU0 @BASEBOARD_FAB2_LIB.BASEBOARD_FAB2(SCH_1):PVCCIOMCP_CPU0    I56 @BASEBOARD_FAB2_LIB.BASEBOARD_FAB2(SCH_1):PAGE194
   E18 PVCCIOMCP_CPU0 @BASEBOARD_FAB2_LIB.BASEBOARD_FAB2(SCH_1):PVCCIOMCP_CPU0    I56 @BASEBOARD_FAB2_LIB.BASEBOARD_FAB2(SCH_1):PAGE194
   E19 PVCCIOMCP_CPU0 @BASEBOARD_FAB2_LIB.BASEBOARD_FAB2(SCH_1):PVCCIOMCP_CPU0    I56 @BASEBOARD_FAB2_LIB.BASEBOARD_FAB2(SCH_1):PAGE194
    E2    GND @BASEBOARD_FAB2_LIB.BASEBOARD_FAB2(SCH_1):GND    I56 @BASEBOARD_FAB2_LIB.BASEBOARD_FAB2(SCH_1):PAGE194
   E20 SVID_CLK1_CPU0_R @BASEBOARD_FAB2_LIB.BASEBOARD_FAB2(SCH_1):SVID_CLK1_CPU0_R    I56 @BASEBOARD_FAB2_LIB.BASEBOARD_FAB2(SCH_1):PAGE194
    E3    GND @BASEBOARD_FAB2_LIB.BASEBOARD_FAB2(SCH_1):GND    I56 @BASEBOARD_FAB2_LIB.BASEBOARD_FAB2(SCH_1):PAGE194
    E4    GND @BASEBOARD_FAB2_LIB.BASEBOARD_FAB2(SCH_1):GND    I56 @BASEBOARD_FAB2_LIB.BASEBOARD_FAB2(SCH_1):PAGE194
    E5    GND @BASEBOARD_FAB2_LIB.BASEBOARD_FAB2(SCH_1):GND    I56 @BASEBOARD_FAB2_LIB.BASEBOARD_FAB2(SCH_1):PAGE194
    E6    GND @BASEBOARD_FAB2_LIB.BASEBOARD_FAB2(SCH_1):GND    I56 @BASEBOARD_FAB2_LIB.BASEBOARD_FAB2(SCH_1):PAGE194
    E7    GND @BASEBOARD_FAB2_LIB.BASEBOARD_FAB2(SCH_1):GND    I56 @BASEBOARD_FAB2_LIB.BASEBOARD_FAB2(SCH_1):PAGE194
    E8 VSENSE_PVCCIOMCP_CPU0_SKT_VSEN @BASEBOARD_FAB2_LIB.BASEBOARD_FAB2(SCH_1):VSENSE_PVCCIOMCP_CPU0_SKT_VSEN    I56 @BASEBOARD_FAB2_LIB.BASEBOARD_FAB2(SCH_1):PAGE194
    E9    GND @BASEBOARD_FAB2_LIB.BASEBOARD_FAB2(SCH_1):GND    I56 @BASEBOARD_FAB2_LIB.BASEBOARD_FAB2(SCH_1):PAGE194
    F1 PVCCIO_CPU0 @BASEBOARD_FAB2_LIB.BASEBOARD_FAB2(SCH_1):PVCCIO_CPU0    I56 @BASEBOARD_FAB2_LIB.BASEBOARD_FAB2(SCH_1):PAGE194
   F10 VR_PVCCMCP_CPU0_XADDR2 @BASEBOARD_FAB2_LIB.BASEBOARD_FAB2(SCH_1):VR_PVCCMCP_CPU0_XADDR2    I56 @BASEBOARD_FAB2_LIB.BASEBOARD_FAB2(SCH_1):PAGE194
   F11    GND @BASEBOARD_FAB2_LIB.BASEBOARD_FAB2(SCH_1):GND    I56 @BASEBOARD_FAB2_LIB.BASEBOARD_FAB2(SCH_1):PAGE194
   F12    GND @BASEBOARD_FAB2_LIB.BASEBOARD_FAB2(SCH_1):GND    I56 @BASEBOARD_FAB2_LIB.BASEBOARD_FAB2(SCH_1):PAGE194
   F13    GND @BASEBOARD_FAB2_LIB.BASEBOARD_FAB2(SCH_1):GND    I56 @BASEBOARD_FAB2_LIB.BASEBOARD_FAB2(SCH_1):PAGE194
   F14    GND @BASEBOARD_FAB2_LIB.BASEBOARD_FAB2(SCH_1):GND    I56 @BASEBOARD_FAB2_LIB.BASEBOARD_FAB2(SCH_1):PAGE194
   F15 PVCCIOMCP_CPU0 @BASEBOARD_FAB2_LIB.BASEBOARD_FAB2(SCH_1):PVCCIOMCP_CPU0    I56 @BASEBOARD_FAB2_LIB.BASEBOARD_FAB2(SCH_1):PAGE194
   F16 PVCCIOMCP_CPU0 @BASEBOARD_FAB2_LIB.BASEBOARD_FAB2(SCH_1):PVCCIOMCP_CPU0    I56 @BASEBOARD_FAB2_LIB.BASEBOARD_FAB2(SCH_1):PAGE194
   F17 PVCCIOMCP_CPU0 @BASEBOARD_FAB2_LIB.BASEBOARD_FAB2(SCH_1):PVCCIOMCP_CPU0    I56 @BASEBOARD_FAB2_LIB.BASEBOARD_FAB2(SCH_1):PAGE194
   F18 PVCCIOMCP_CPU0 @BASEBOARD_FAB2_LIB.BASEBOARD_FAB2(SCH_1):PVCCIOMCP_CPU0    I56 @BASEBOARD_FAB2_LIB.BASEBOARD_FAB2(SCH_1):PAGE194
   F19 PVCCIOMCP_CPU0 @BASEBOARD_FAB2_LIB.BASEBOARD_FAB2(SCH_1):PVCCIOMCP_CPU0    I56 @BASEBOARD_FAB2_LIB.BASEBOARD_FAB2(SCH_1):PAGE194
    F2    GND @BASEBOARD_FAB2_LIB.BASEBOARD_FAB2(SCH_1):GND    I56 @BASEBOARD_FAB2_LIB.BASEBOARD_FAB2(SCH_1):PAGE194
   F20 SVID_DIO1_CPU0_R @BASEBOARD_FAB2_LIB.BASEBOARD_FAB2(SCH_1):SVID_DIO1_CPU0_R    I56 @BASEBOARD_FAB2_LIB.BASEBOARD_FAB2(SCH_1):PAGE194
    F3    GND @BASEBOARD_FAB2_LIB.BASEBOARD_FAB2(SCH_1):GND    I56 @BASEBOARD_FAB2_LIB.BASEBOARD_FAB2(SCH_1):PAGE194
    F4    GND @BASEBOARD_FAB2_LIB.BASEBOARD_FAB2(SCH_1):GND    I56 @BASEBOARD_FAB2_LIB.BASEBOARD_FAB2(SCH_1):PAGE194
    F5    GND @BASEBOARD_FAB2_LIB.BASEBOARD_FAB2(SCH_1):GND    I56 @BASEBOARD_FAB2_LIB.BASEBOARD_FAB2(SCH_1):PAGE194
    F6    GND @BASEBOARD_FAB2_LIB.BASEBOARD_FAB2(SCH_1):GND    I56 @BASEBOARD_FAB2_LIB.BASEBOARD_FAB2(SCH_1):PAGE194
    F7    GND @BASEBOARD_FAB2_LIB.BASEBOARD_FAB2(SCH_1):GND    I56 @BASEBOARD_FAB2_LIB.BASEBOARD_FAB2(SCH_1):PAGE194
    F8 VSENSE_PVCCIOMCP_CPU0_SKT_VRTN @BASEBOARD_FAB2_LIB.BASEBOARD_FAB2(SCH_1):VSENSE_PVCCIOMCP_CPU0_SKT_VRTN    I56 @BASEBOARD_FAB2_LIB.BASEBOARD_FAB2(SCH_1):PAGE194
    F9    GND @BASEBOARD_FAB2_LIB.BASEBOARD_FAB2(SCH_1):GND    I56 @BASEBOARD_FAB2_LIB.BASEBOARD_FAB2(SCH_1):PAGE194

J6E1 SCONN120_H61426002_SM-CONN,H61A
    A1 PVCCMCP_CPU0 @BASEBOARD_FAB2_LIB.BASEBOARD_FAB2(SCH_1):PVCCMCP_CPU0    I55 @BASEBOARD_FAB2_LIB.BASEBOARD_FAB2(SCH_1):PAGE194
   A10 PVCCMCP_CPU0 @BASEBOARD_FAB2_LIB.BASEBOARD_FAB2(SCH_1):PVCCMCP_CPU0    I55 @BASEBOARD_FAB2_LIB.BASEBOARD_FAB2(SCH_1):PAGE194
   A11 PVCCMCP_CPU0 @BASEBOARD_FAB2_LIB.BASEBOARD_FAB2(SCH_1):PVCCMCP_CPU0    I55 @BASEBOARD_FAB2_LIB.BASEBOARD_FAB2(SCH_1):PAGE194
   A12 PVCCMCP_CPU0 @BASEBOARD_FAB2_LIB.BASEBOARD_FAB2(SCH_1):PVCCMCP_CPU0    I55 @BASEBOARD_FAB2_LIB.BASEBOARD_FAB2(SCH_1):PAGE194
   A13 PVCCMCP_CPU0 @BASEBOARD_FAB2_LIB.BASEBOARD_FAB2(SCH_1):PVCCMCP_CPU0    I55 @BASEBOARD_FAB2_LIB.BASEBOARD_FAB2(SCH_1):PAGE194
   A14 PVCCMCP_CPU0 @BASEBOARD_FAB2_LIB.BASEBOARD_FAB2(SCH_1):PVCCMCP_CPU0    I55 @BASEBOARD_FAB2_LIB.BASEBOARD_FAB2(SCH_1):PAGE194
   A15 PVCCMCP_CPU0 @BASEBOARD_FAB2_LIB.BASEBOARD_FAB2(SCH_1):PVCCMCP_CPU0    I55 @BASEBOARD_FAB2_LIB.BASEBOARD_FAB2(SCH_1):PAGE194
   A16 PVCCMCP_CPU0 @BASEBOARD_FAB2_LIB.BASEBOARD_FAB2(SCH_1):PVCCMCP_CPU0    I55 @BASEBOARD_FAB2_LIB.BASEBOARD_FAB2(SCH_1):PAGE194
   A17 PVCCMCP_CPU0 @BASEBOARD_FAB2_LIB.BASEBOARD_FAB2(SCH_1):PVCCMCP_CPU0    I55 @BASEBOARD_FAB2_LIB.BASEBOARD_FAB2(SCH_1):PAGE194
   A18 PVCCMCP_CPU0 @BASEBOARD_FAB2_LIB.BASEBOARD_FAB2(SCH_1):PVCCMCP_CPU0    I55 @BASEBOARD_FAB2_LIB.BASEBOARD_FAB2(SCH_1):PAGE194
   A19    GND @BASEBOARD_FAB2_LIB.BASEBOARD_FAB2(SCH_1):GND    I55 @BASEBOARD_FAB2_LIB.BASEBOARD_FAB2(SCH_1):PAGE194
    A2 PVCCMCP_CPU0 @BASEBOARD_FAB2_LIB.BASEBOARD_FAB2(SCH_1):PVCCMCP_CPU0    I55 @BASEBOARD_FAB2_LIB.BASEBOARD_FAB2(SCH_1):PAGE194
   A20    GND @BASEBOARD_FAB2_LIB.BASEBOARD_FAB2(SCH_1):GND    I55 @BASEBOARD_FAB2_LIB.BASEBOARD_FAB2(SCH_1):PAGE194
    A3 PVCCMCP_CPU0 @BASEBOARD_FAB2_LIB.BASEBOARD_FAB2(SCH_1):PVCCMCP_CPU0    I55 @BASEBOARD_FAB2_LIB.BASEBOARD_FAB2(SCH_1):PAGE194
    A4 VSENSE_PVCCMCP_CPU0_SKT_VSEN @BASEBOARD_FAB2_LIB.BASEBOARD_FAB2(SCH_1):VSENSE_PVCCMCP_CPU0_SKT_VSEN    I55 @BASEBOARD_FAB2_LIB.BASEBOARD_FAB2(SCH_1):PAGE194
    A5 PVCCMCP_CPU0 @BASEBOARD_FAB2_LIB.BASEBOARD_FAB2(SCH_1):PVCCMCP_CPU0    I55 @BASEBOARD_FAB2_LIB.BASEBOARD_FAB2(SCH_1):PAGE194
    A6 PVCCMCP_CPU0 @BASEBOARD_FAB2_LIB.BASEBOARD_FAB2(SCH_1):PVCCMCP_CPU0    I55 @BASEBOARD_FAB2_LIB.BASEBOARD_FAB2(SCH_1):PAGE194
    A7 PVCCMCP_CPU0 @BASEBOARD_FAB2_LIB.BASEBOARD_FAB2(SCH_1):PVCCMCP_CPU0    I55 @BASEBOARD_FAB2_LIB.BASEBOARD_FAB2(SCH_1):PAGE194
    A8 PVCCMCP_CPU0 @BASEBOARD_FAB2_LIB.BASEBOARD_FAB2(SCH_1):PVCCMCP_CPU0    I55 @BASEBOARD_FAB2_LIB.BASEBOARD_FAB2(SCH_1):PAGE194
    A9 PVCCMCP_CPU0 @BASEBOARD_FAB2_LIB.BASEBOARD_FAB2(SCH_1):PVCCMCP_CPU0    I55 @BASEBOARD_FAB2_LIB.BASEBOARD_FAB2(SCH_1):PAGE194
    B1 PVCCMCP_CPU0 @BASEBOARD_FAB2_LIB.BASEBOARD_FAB2(SCH_1):PVCCMCP_CPU0    I55 @BASEBOARD_FAB2_LIB.BASEBOARD_FAB2(SCH_1):PAGE194
   B10 PVCCMCP_CPU0 @BASEBOARD_FAB2_LIB.BASEBOARD_FAB2(SCH_1):PVCCMCP_CPU0    I55 @BASEBOARD_FAB2_LIB.BASEBOARD_FAB2(SCH_1):PAGE194
   B11 PVCCMCP_CPU0 @BASEBOARD_FAB2_LIB.BASEBOARD_FAB2(SCH_1):PVCCMCP_CPU0    I55 @BASEBOARD_FAB2_LIB.BASEBOARD_FAB2(SCH_1):PAGE194
   B12 PVCCMCP_CPU0 @BASEBOARD_FAB2_LIB.BASEBOARD_FAB2(SCH_1):PVCCMCP_CPU0    I55 @BASEBOARD_FAB2_LIB.BASEBOARD_FAB2(SCH_1):PAGE194
   B13 PVCCMCP_CPU0 @BASEBOARD_FAB2_LIB.BASEBOARD_FAB2(SCH_1):PVCCMCP_CPU0    I55 @BASEBOARD_FAB2_LIB.BASEBOARD_FAB2(SCH_1):PAGE194
   B14 PVCCMCP_CPU0 @BASEBOARD_FAB2_LIB.BASEBOARD_FAB2(SCH_1):PVCCMCP_CPU0    I55 @BASEBOARD_FAB2_LIB.BASEBOARD_FAB2(SCH_1):PAGE194
   B15 PVCCMCP_CPU0 @BASEBOARD_FAB2_LIB.BASEBOARD_FAB2(SCH_1):PVCCMCP_CPU0    I55 @BASEBOARD_FAB2_LIB.BASEBOARD_FAB2(SCH_1):PAGE194
   B16 PVCCMCP_CPU0 @BASEBOARD_FAB2_LIB.BASEBOARD_FAB2(SCH_1):PVCCMCP_CPU0    I55 @BASEBOARD_FAB2_LIB.BASEBOARD_FAB2(SCH_1):PAGE194
   B17 PVCCMCP_CPU0 @BASEBOARD_FAB2_LIB.BASEBOARD_FAB2(SCH_1):PVCCMCP_CPU0    I55 @BASEBOARD_FAB2_LIB.BASEBOARD_FAB2(SCH_1):PAGE194
   B18 PVCCMCP_CPU0 @BASEBOARD_FAB2_LIB.BASEBOARD_FAB2(SCH_1):PVCCMCP_CPU0    I55 @BASEBOARD_FAB2_LIB.BASEBOARD_FAB2(SCH_1):PAGE194
   B19    GND @BASEBOARD_FAB2_LIB.BASEBOARD_FAB2(SCH_1):GND    I55 @BASEBOARD_FAB2_LIB.BASEBOARD_FAB2(SCH_1):PAGE194
    B2 PVCCMCP_CPU0 @BASEBOARD_FAB2_LIB.BASEBOARD_FAB2(SCH_1):PVCCMCP_CPU0    I55 @BASEBOARD_FAB2_LIB.BASEBOARD_FAB2(SCH_1):PAGE194
   B20    GND @BASEBOARD_FAB2_LIB.BASEBOARD_FAB2(SCH_1):GND    I55 @BASEBOARD_FAB2_LIB.BASEBOARD_FAB2(SCH_1):PAGE194
    B3 PVCCMCP_CPU0 @BASEBOARD_FAB2_LIB.BASEBOARD_FAB2(SCH_1):PVCCMCP_CPU0    I55 @BASEBOARD_FAB2_LIB.BASEBOARD_FAB2(SCH_1):PAGE194
    B4 VSENSE_PVCCMCP_CPU0_SKT_VRTN @BASEBOARD_FAB2_LIB.BASEBOARD_FAB2(SCH_1):VSENSE_PVCCMCP_CPU0_SKT_VRTN    I55 @BASEBOARD_FAB2_LIB.BASEBOARD_FAB2(SCH_1):PAGE194
    B5 PVCCMCP_CPU0 @BASEBOARD_FAB2_LIB.BASEBOARD_FAB2(SCH_1):PVCCMCP_CPU0    I55 @BASEBOARD_FAB2_LIB.BASEBOARD_FAB2(SCH_1):PAGE194
    B6 PVCCMCP_CPU0 @BASEBOARD_FAB2_LIB.BASEBOARD_FAB2(SCH_1):PVCCMCP_CPU0    I55 @BASEBOARD_FAB2_LIB.BASEBOARD_FAB2(SCH_1):PAGE194
    B7 PVCCMCP_CPU0 @BASEBOARD_FAB2_LIB.BASEBOARD_FAB2(SCH_1):PVCCMCP_CPU0    I55 @BASEBOARD_FAB2_LIB.BASEBOARD_FAB2(SCH_1):PAGE194
    B8 PVCCMCP_CPU0 @BASEBOARD_FAB2_LIB.BASEBOARD_FAB2(SCH_1):PVCCMCP_CPU0    I55 @BASEBOARD_FAB2_LIB.BASEBOARD_FAB2(SCH_1):PAGE194
    B9 PVCCMCP_CPU0 @BASEBOARD_FAB2_LIB.BASEBOARD_FAB2(SCH_1):PVCCMCP_CPU0    I55 @BASEBOARD_FAB2_LIB.BASEBOARD_FAB2(SCH_1):PAGE194
    C1 PVCCMCP_CPU0 @BASEBOARD_FAB2_LIB.BASEBOARD_FAB2(SCH_1):PVCCMCP_CPU0    I55 @BASEBOARD_FAB2_LIB.BASEBOARD_FAB2(SCH_1):PAGE194
   C10 PVCCMCP_CPU0 @BASEBOARD_FAB2_LIB.BASEBOARD_FAB2(SCH_1):PVCCMCP_CPU0    I55 @BASEBOARD_FAB2_LIB.BASEBOARD_FAB2(SCH_1):PAGE194
   C11 PVCCMCP_CPU0 @BASEBOARD_FAB2_LIB.BASEBOARD_FAB2(SCH_1):PVCCMCP_CPU0    I55 @BASEBOARD_FAB2_LIB.BASEBOARD_FAB2(SCH_1):PAGE194
   C12 PVCCMCP_CPU0 @BASEBOARD_FAB2_LIB.BASEBOARD_FAB2(SCH_1):PVCCMCP_CPU0    I55 @BASEBOARD_FAB2_LIB.BASEBOARD_FAB2(SCH_1):PAGE194
   C13 PVCCMCP_CPU0 @BASEBOARD_FAB2_LIB.BASEBOARD_FAB2(SCH_1):PVCCMCP_CPU0    I55 @BASEBOARD_FAB2_LIB.BASEBOARD_FAB2(SCH_1):PAGE194
   C14 PVCCMCP_CPU0 @BASEBOARD_FAB2_LIB.BASEBOARD_FAB2(SCH_1):PVCCMCP_CPU0    I55 @BASEBOARD_FAB2_LIB.BASEBOARD_FAB2(SCH_1):PAGE194
   C15 PVCCMCP_CPU0 @BASEBOARD_FAB2_LIB.BASEBOARD_FAB2(SCH_1):PVCCMCP_CPU0    I55 @BASEBOARD_FAB2_LIB.BASEBOARD_FAB2(SCH_1):PAGE194
   C16 PVCCMCP_CPU0 @BASEBOARD_FAB2_LIB.BASEBOARD_FAB2(SCH_1):PVCCMCP_CPU0    I55 @BASEBOARD_FAB2_LIB.BASEBOARD_FAB2(SCH_1):PAGE194
   C17 PVCCMCP_CPU0 @BASEBOARD_FAB2_LIB.BASEBOARD_FAB2(SCH_1):PVCCMCP_CPU0    I55 @BASEBOARD_FAB2_LIB.BASEBOARD_FAB2(SCH_1):PAGE194
   C18 PVCCMCP_CPU0 @BASEBOARD_FAB2_LIB.BASEBOARD_FAB2(SCH_1):PVCCMCP_CPU0    I55 @BASEBOARD_FAB2_LIB.BASEBOARD_FAB2(SCH_1):PAGE194
   C19    GND @BASEBOARD_FAB2_LIB.BASEBOARD_FAB2(SCH_1):GND    I55 @BASEBOARD_FAB2_LIB.BASEBOARD_FAB2(SCH_1):PAGE194
    C2 PVCCMCP_CPU0 @BASEBOARD_FAB2_LIB.BASEBOARD_FAB2(SCH_1):PVCCMCP_CPU0    I55 @BASEBOARD_FAB2_LIB.BASEBOARD_FAB2(SCH_1):PAGE194
   C20    GND @BASEBOARD_FAB2_LIB.BASEBOARD_FAB2(SCH_1):GND    I55 @BASEBOARD_FAB2_LIB.BASEBOARD_FAB2(SCH_1):PAGE194
    C3 PVCCMCP_CPU0 @BASEBOARD_FAB2_LIB.BASEBOARD_FAB2(SCH_1):PVCCMCP_CPU0    I55 @BASEBOARD_FAB2_LIB.BASEBOARD_FAB2(SCH_1):PAGE194
    C4 PVCCMCP_CPU0 @BASEBOARD_FAB2_LIB.BASEBOARD_FAB2(SCH_1):PVCCMCP_CPU0    I55 @BASEBOARD_FAB2_LIB.BASEBOARD_FAB2(SCH_1):PAGE194
    C5 PVCCMCP_CPU0 @BASEBOARD_FAB2_LIB.BASEBOARD_FAB2(SCH_1):PVCCMCP_CPU0    I55 @BASEBOARD_FAB2_LIB.BASEBOARD_FAB2(SCH_1):PAGE194
    C6 PVCCMCP_CPU0 @BASEBOARD_FAB2_LIB.BASEBOARD_FAB2(SCH_1):PVCCMCP_CPU0    I55 @BASEBOARD_FAB2_LIB.BASEBOARD_FAB2(SCH_1):PAGE194
    C7 PVCCMCP_CPU0 @BASEBOARD_FAB2_LIB.BASEBOARD_FAB2(SCH_1):PVCCMCP_CPU0    I55 @BASEBOARD_FAB2_LIB.BASEBOARD_FAB2(SCH_1):PAGE194
    C8 PVCCMCP_CPU0 @BASEBOARD_FAB2_LIB.BASEBOARD_FAB2(SCH_1):PVCCMCP_CPU0    I55 @BASEBOARD_FAB2_LIB.BASEBOARD_FAB2(SCH_1):PAGE194
    C9 PVCCMCP_CPU0 @BASEBOARD_FAB2_LIB.BASEBOARD_FAB2(SCH_1):PVCCMCP_CPU0    I55 @BASEBOARD_FAB2_LIB.BASEBOARD_FAB2(SCH_1):PAGE194
    D1 VSENSE_P1V8MCP_CPU0_SKT_VSEN @BASEBOARD_FAB2_LIB.BASEBOARD_FAB2(SCH_1):VSENSE_P1V8MCP_CPU0_SKT_VSEN    I55 @BASEBOARD_FAB2_LIB.BASEBOARD_FAB2(SCH_1):PAGE194
   D10    GND @BASEBOARD_FAB2_LIB.BASEBOARD_FAB2(SCH_1):GND    I55 @BASEBOARD_FAB2_LIB.BASEBOARD_FAB2(SCH_1):PAGE194
   D11    GND @BASEBOARD_FAB2_LIB.BASEBOARD_FAB2(SCH_1):GND    I55 @BASEBOARD_FAB2_LIB.BASEBOARD_FAB2(SCH_1):PAGE194
   D12    GND @BASEBOARD_FAB2_LIB.BASEBOARD_FAB2(SCH_1):GND    I55 @BASEBOARD_FAB2_LIB.BASEBOARD_FAB2(SCH_1):PAGE194
   D13    GND @BASEBOARD_FAB2_LIB.BASEBOARD_FAB2(SCH_1):GND    I55 @BASEBOARD_FAB2_LIB.BASEBOARD_FAB2(SCH_1):PAGE194
   D14    GND @BASEBOARD_FAB2_LIB.BASEBOARD_FAB2(SCH_1):GND    I55 @BASEBOARD_FAB2_LIB.BASEBOARD_FAB2(SCH_1):PAGE194
   D15    GND @BASEBOARD_FAB2_LIB.BASEBOARD_FAB2(SCH_1):GND    I55 @BASEBOARD_FAB2_LIB.BASEBOARD_FAB2(SCH_1):PAGE194
   D16    GND @BASEBOARD_FAB2_LIB.BASEBOARD_FAB2(SCH_1):GND    I55 @BASEBOARD_FAB2_LIB.BASEBOARD_FAB2(SCH_1):PAGE194
   D17    GND @BASEBOARD_FAB2_LIB.BASEBOARD_FAB2(SCH_1):GND    I55 @BASEBOARD_FAB2_LIB.BASEBOARD_FAB2(SCH_1):PAGE194
   D18    GND @BASEBOARD_FAB2_LIB.BASEBOARD_FAB2(SCH_1):GND    I55 @BASEBOARD_FAB2_LIB.BASEBOARD_FAB2(SCH_1):PAGE194
   D19    GND @BASEBOARD_FAB2_LIB.BASEBOARD_FAB2(SCH_1):GND    I55 @BASEBOARD_FAB2_LIB.BASEBOARD_FAB2(SCH_1):PAGE194
    D2 VSENSE_P1V8MCP_CPU0_SKT_VRTN @BASEBOARD_FAB2_LIB.BASEBOARD_FAB2(SCH_1):VSENSE_P1V8MCP_CPU0_SKT_VRTN    I55 @BASEBOARD_FAB2_LIB.BASEBOARD_FAB2(SCH_1):PAGE194
   D20    GND @BASEBOARD_FAB2_LIB.BASEBOARD_FAB2(SCH_1):GND    I55 @BASEBOARD_FAB2_LIB.BASEBOARD_FAB2(SCH_1):PAGE194
    D3 P1V8_MCP_CPU0 @BASEBOARD_FAB2_LIB.BASEBOARD_FAB2(SCH_1):P1V8_MCP_CPU0    I55 @BASEBOARD_FAB2_LIB.BASEBOARD_FAB2(SCH_1):PAGE194
    D4    GND @BASEBOARD_FAB2_LIB.BASEBOARD_FAB2(SCH_1):GND    I55 @BASEBOARD_FAB2_LIB.BASEBOARD_FAB2(SCH_1):PAGE194
    D5    GND @BASEBOARD_FAB2_LIB.BASEBOARD_FAB2(SCH_1):GND    I55 @BASEBOARD_FAB2_LIB.BASEBOARD_FAB2(SCH_1):PAGE194
    D6    GND @BASEBOARD_FAB2_LIB.BASEBOARD_FAB2(SCH_1):GND    I55 @BASEBOARD_FAB2_LIB.BASEBOARD_FAB2(SCH_1):PAGE194
    D7    GND @BASEBOARD_FAB2_LIB.BASEBOARD_FAB2(SCH_1):GND    I55 @BASEBOARD_FAB2_LIB.BASEBOARD_FAB2(SCH_1):PAGE194
    D8    GND @BASEBOARD_FAB2_LIB.BASEBOARD_FAB2(SCH_1):GND    I55 @BASEBOARD_FAB2_LIB.BASEBOARD_FAB2(SCH_1):PAGE194
    D9    GND @BASEBOARD_FAB2_LIB.BASEBOARD_FAB2(SCH_1):GND    I55 @BASEBOARD_FAB2_LIB.BASEBOARD_FAB2(SCH_1):PAGE194
    E1 P1V8_MCP_CPU0 @BASEBOARD_FAB2_LIB.BASEBOARD_FAB2(SCH_1):P1V8_MCP_CPU0    I55 @BASEBOARD_FAB2_LIB.BASEBOARD_FAB2(SCH_1):PAGE194
   E10    GND @BASEBOARD_FAB2_LIB.BASEBOARD_FAB2(SCH_1):GND    I55 @BASEBOARD_FAB2_LIB.BASEBOARD_FAB2(SCH_1):PAGE194
   E11    GND @BASEBOARD_FAB2_LIB.BASEBOARD_FAB2(SCH_1):GND    I55 @BASEBOARD_FAB2_LIB.BASEBOARD_FAB2(SCH_1):PAGE194
   E12    GND @BASEBOARD_FAB2_LIB.BASEBOARD_FAB2(SCH_1):GND    I55 @BASEBOARD_FAB2_LIB.BASEBOARD_FAB2(SCH_1):PAGE194
   E13    GND @BASEBOARD_FAB2_LIB.BASEBOARD_FAB2(SCH_1):GND    I55 @BASEBOARD_FAB2_LIB.BASEBOARD_FAB2(SCH_1):PAGE194
   E14    GND @BASEBOARD_FAB2_LIB.BASEBOARD_FAB2(SCH_1):GND    I55 @BASEBOARD_FAB2_LIB.BASEBOARD_FAB2(SCH_1):PAGE194
   E15    GND @BASEBOARD_FAB2_LIB.BASEBOARD_FAB2(SCH_1):GND    I55 @BASEBOARD_FAB2_LIB.BASEBOARD_FAB2(SCH_1):PAGE194
   E16    GND @BASEBOARD_FAB2_LIB.BASEBOARD_FAB2(SCH_1):GND    I55 @BASEBOARD_FAB2_LIB.BASEBOARD_FAB2(SCH_1):PAGE194
   E17    GND @BASEBOARD_FAB2_LIB.BASEBOARD_FAB2(SCH_1):GND    I55 @BASEBOARD_FAB2_LIB.BASEBOARD_FAB2(SCH_1):PAGE194
   E18    GND @BASEBOARD_FAB2_LIB.BASEBOARD_FAB2(SCH_1):GND    I55 @BASEBOARD_FAB2_LIB.BASEBOARD_FAB2(SCH_1):PAGE194
   E19    GND @BASEBOARD_FAB2_LIB.BASEBOARD_FAB2(SCH_1):GND    I55 @BASEBOARD_FAB2_LIB.BASEBOARD_FAB2(SCH_1):PAGE194
    E2 P1V8_MCP_CPU0 @BASEBOARD_FAB2_LIB.BASEBOARD_FAB2(SCH_1):P1V8_MCP_CPU0    I55 @BASEBOARD_FAB2_LIB.BASEBOARD_FAB2(SCH_1):PAGE194
   E20    GND @BASEBOARD_FAB2_LIB.BASEBOARD_FAB2(SCH_1):GND    I55 @BASEBOARD_FAB2_LIB.BASEBOARD_FAB2(SCH_1):PAGE194
    E3 P1V8_MCP_CPU0 @BASEBOARD_FAB2_LIB.BASEBOARD_FAB2(SCH_1):P1V8_MCP_CPU0    I55 @BASEBOARD_FAB2_LIB.BASEBOARD_FAB2(SCH_1):PAGE194
    E4    GND @BASEBOARD_FAB2_LIB.BASEBOARD_FAB2(SCH_1):GND    I55 @BASEBOARD_FAB2_LIB.BASEBOARD_FAB2(SCH_1):PAGE194
    E5 CLK_322M_156M_CPU0_OSC_VRM_DP @BASEBOARD_FAB2_LIB.BASEBOARD_FAB2(SCH_1):CLK_322M_156M_CPU0_OSC_VRM_DP    I55 @BASEBOARD_FAB2_LIB.BASEBOARD_FAB2(SCH_1):PAGE194
    E6    GND @BASEBOARD_FAB2_LIB.BASEBOARD_FAB2(SCH_1):GND    I55 @BASEBOARD_FAB2_LIB.BASEBOARD_FAB2(SCH_1):PAGE194
    E7    GND @BASEBOARD_FAB2_LIB.BASEBOARD_FAB2(SCH_1):GND    I55 @BASEBOARD_FAB2_LIB.BASEBOARD_FAB2(SCH_1):PAGE194
    E8    GND @BASEBOARD_FAB2_LIB.BASEBOARD_FAB2(SCH_1):GND    I55 @BASEBOARD_FAB2_LIB.BASEBOARD_FAB2(SCH_1):PAGE194
    E9    GND @BASEBOARD_FAB2_LIB.BASEBOARD_FAB2(SCH_1):GND    I55 @BASEBOARD_FAB2_LIB.BASEBOARD_FAB2(SCH_1):PAGE194
    F1 P1V8_MCP_CPU0 @BASEBOARD_FAB2_LIB.BASEBOARD_FAB2(SCH_1):P1V8_MCP_CPU0    I55 @BASEBOARD_FAB2_LIB.BASEBOARD_FAB2(SCH_1):PAGE194
   F10    GND @BASEBOARD_FAB2_LIB.BASEBOARD_FAB2(SCH_1):GND    I55 @BASEBOARD_FAB2_LIB.BASEBOARD_FAB2(SCH_1):PAGE194
   F11    GND @BASEBOARD_FAB2_LIB.BASEBOARD_FAB2(SCH_1):GND    I55 @BASEBOARD_FAB2_LIB.BASEBOARD_FAB2(SCH_1):PAGE194
   F12    GND @BASEBOARD_FAB2_LIB.BASEBOARD_FAB2(SCH_1):GND    I55 @BASEBOARD_FAB2_LIB.BASEBOARD_FAB2(SCH_1):PAGE194
   F13    GND @BASEBOARD_FAB2_LIB.BASEBOARD_FAB2(SCH_1):GND    I55 @BASEBOARD_FAB2_LIB.BASEBOARD_FAB2(SCH_1):PAGE194
   F14    GND @BASEBOARD_FAB2_LIB.BASEBOARD_FAB2(SCH_1):GND    I55 @BASEBOARD_FAB2_LIB.BASEBOARD_FAB2(SCH_1):PAGE194
   F15    GND @BASEBOARD_FAB2_LIB.BASEBOARD_FAB2(SCH_1):GND    I55 @BASEBOARD_FAB2_LIB.BASEBOARD_FAB2(SCH_1):PAGE194
   F16    GND @BASEBOARD_FAB2_LIB.BASEBOARD_FAB2(SCH_1):GND    I55 @BASEBOARD_FAB2_LIB.BASEBOARD_FAB2(SCH_1):PAGE194
   F17    GND @BASEBOARD_FAB2_LIB.BASEBOARD_FAB2(SCH_1):GND    I55 @BASEBOARD_FAB2_LIB.BASEBOARD_FAB2(SCH_1):PAGE194
   F18    GND @BASEBOARD_FAB2_LIB.BASEBOARD_FAB2(SCH_1):GND    I55 @BASEBOARD_FAB2_LIB.BASEBOARD_FAB2(SCH_1):PAGE194
   F19    GND @BASEBOARD_FAB2_LIB.BASEBOARD_FAB2(SCH_1):GND    I55 @BASEBOARD_FAB2_LIB.BASEBOARD_FAB2(SCH_1):PAGE194
    F2 P1V8_MCP_CPU0 @BASEBOARD_FAB2_LIB.BASEBOARD_FAB2(SCH_1):P1V8_MCP_CPU0    I55 @BASEBOARD_FAB2_LIB.BASEBOARD_FAB2(SCH_1):PAGE194
   F20    GND @BASEBOARD_FAB2_LIB.BASEBOARD_FAB2(SCH_1):GND    I55 @BASEBOARD_FAB2_LIB.BASEBOARD_FAB2(SCH_1):PAGE194
    F3 P1V8_MCP_CPU0 @BASEBOARD_FAB2_LIB.BASEBOARD_FAB2(SCH_1):P1V8_MCP_CPU0    I55 @BASEBOARD_FAB2_LIB.BASEBOARD_FAB2(SCH_1):PAGE194
    F4    GND @BASEBOARD_FAB2_LIB.BASEBOARD_FAB2(SCH_1):GND    I55 @BASEBOARD_FAB2_LIB.BASEBOARD_FAB2(SCH_1):PAGE194
    F5 CLK_322M_156M_CPU0_OSC_VRM_DN @BASEBOARD_FAB2_LIB.BASEBOARD_FAB2(SCH_1):CLK_322M_156M_CPU0_OSC_VRM_DN    I55 @BASEBOARD_FAB2_LIB.BASEBOARD_FAB2(SCH_1):PAGE194
    F6    GND @BASEBOARD_FAB2_LIB.BASEBOARD_FAB2(SCH_1):GND    I55 @BASEBOARD_FAB2_LIB.BASEBOARD_FAB2(SCH_1):PAGE194
    F7    GND @BASEBOARD_FAB2_LIB.BASEBOARD_FAB2(SCH_1):GND    I55 @BASEBOARD_FAB2_LIB.BASEBOARD_FAB2(SCH_1):PAGE194
    F8    GND @BASEBOARD_FAB2_LIB.BASEBOARD_FAB2(SCH_1):GND    I55 @BASEBOARD_FAB2_LIB.BASEBOARD_FAB2(SCH_1):PAGE194
    F9    GND @BASEBOARD_FAB2_LIB.BASEBOARD_FAB2(SCH_1):GND    I55 @BASEBOARD_FAB2_LIB.BASEBOARD_FAB2(SCH_1):PAGE194

J6L1 SCONN288_H44441003_PIP-SCONN,HA
    79 M_F_MA<0> @BASEBOARD_FAB2_LIB.BASEBOARD_FAB2(SCH_1):M_F_MA(0)   I111 @BASEBOARD_FAB2_LIB.BASEBOARD_FAB2(SCH_1):PAGE54
    72 M_F_MA<1> @BASEBOARD_FAB2_LIB.BASEBOARD_FAB2(SCH_1):M_F_MA(1)   I111 @BASEBOARD_FAB2_LIB.BASEBOARD_FAB2(SCH_1):PAGE54
   225 M_F_MA<10> @BASEBOARD_FAB2_LIB.BASEBOARD_FAB2(SCH_1):M_F_MA(10)   I111 @BASEBOARD_FAB2_LIB.BASEBOARD_FAB2(SCH_1):PAGE54
   210 M_F_MA<11> @BASEBOARD_FAB2_LIB.BASEBOARD_FAB2(SCH_1):M_F_MA(11)   I111 @BASEBOARD_FAB2_LIB.BASEBOARD_FAB2(SCH_1):PAGE54
    65 M_F_MA<12> @BASEBOARD_FAB2_LIB.BASEBOARD_FAB2(SCH_1):M_F_MA(12)   I111 @BASEBOARD_FAB2_LIB.BASEBOARD_FAB2(SCH_1):PAGE54
   232 M_F_MA<13> @BASEBOARD_FAB2_LIB.BASEBOARD_FAB2(SCH_1):M_F_MA(13)   I111 @BASEBOARD_FAB2_LIB.BASEBOARD_FAB2(SCH_1):PAGE54
   228 M_F_MA<14> @BASEBOARD_FAB2_LIB.BASEBOARD_FAB2(SCH_1):M_F_MA(14)   I111 @BASEBOARD_FAB2_LIB.BASEBOARD_FAB2(SCH_1):PAGE54
    86 M_F_MA<15> @BASEBOARD_FAB2_LIB.BASEBOARD_FAB2(SCH_1):M_F_MA(15)   I111 @BASEBOARD_FAB2_LIB.BASEBOARD_FAB2(SCH_1):PAGE54
    82 M_F_MA<16> @BASEBOARD_FAB2_LIB.BASEBOARD_FAB2(SCH_1):M_F_MA(16)   I111 @BASEBOARD_FAB2_LIB.BASEBOARD_FAB2(SCH_1):PAGE54
   234 M_F_MA<17> @BASEBOARD_FAB2_LIB.BASEBOARD_FAB2(SCH_1):M_F_MA(17)   I111 @BASEBOARD_FAB2_LIB.BASEBOARD_FAB2(SCH_1):PAGE54
   216 M_F_MA<2> @BASEBOARD_FAB2_LIB.BASEBOARD_FAB2(SCH_1):M_F_MA(2)   I111 @BASEBOARD_FAB2_LIB.BASEBOARD_FAB2(SCH_1):PAGE54
    71 M_F_MA<3> @BASEBOARD_FAB2_LIB.BASEBOARD_FAB2(SCH_1):M_F_MA(3)   I111 @BASEBOARD_FAB2_LIB.BASEBOARD_FAB2(SCH_1):PAGE54
   214 M_F_MA<4> @BASEBOARD_FAB2_LIB.BASEBOARD_FAB2(SCH_1):M_F_MA(4)   I111 @BASEBOARD_FAB2_LIB.BASEBOARD_FAB2(SCH_1):PAGE54
   213 M_F_MA<5> @BASEBOARD_FAB2_LIB.BASEBOARD_FAB2(SCH_1):M_F_MA(5)   I111 @BASEBOARD_FAB2_LIB.BASEBOARD_FAB2(SCH_1):PAGE54
    69 M_F_MA<6> @BASEBOARD_FAB2_LIB.BASEBOARD_FAB2(SCH_1):M_F_MA(6)   I111 @BASEBOARD_FAB2_LIB.BASEBOARD_FAB2(SCH_1):PAGE54
   211 M_F_MA<7> @BASEBOARD_FAB2_LIB.BASEBOARD_FAB2(SCH_1):M_F_MA(7)   I111 @BASEBOARD_FAB2_LIB.BASEBOARD_FAB2(SCH_1):PAGE54
    68 M_F_MA<8> @BASEBOARD_FAB2_LIB.BASEBOARD_FAB2(SCH_1):M_F_MA(8)   I111 @BASEBOARD_FAB2_LIB.BASEBOARD_FAB2(SCH_1):PAGE54
    66 M_F_MA<9> @BASEBOARD_FAB2_LIB.BASEBOARD_FAB2(SCH_1):M_F_MA(9)   I111 @BASEBOARD_FAB2_LIB.BASEBOARD_FAB2(SCH_1):PAGE54
    62 M_F_ACT_N @BASEBOARD_FAB2_LIB.BASEBOARD_FAB2(SCH_1):M_F_ACT_N   I111 @BASEBOARD_FAB2_LIB.BASEBOARD_FAB2(SCH_1):PAGE54
   208 M_F_ALERT_N @BASEBOARD_FAB2_LIB.BASEBOARD_FAB2(SCH_1):M_F_ALERT_N   I111 @BASEBOARD_FAB2_LIB.BASEBOARD_FAB2(SCH_1):PAGE54
   224 M_F_BA<1> @BASEBOARD_FAB2_LIB.BASEBOARD_FAB2(SCH_1):M_F_BA(1)   I111 @BASEBOARD_FAB2_LIB.BASEBOARD_FAB2(SCH_1):PAGE54
    81 M_F_BA<0> @BASEBOARD_FAB2_LIB.BASEBOARD_FAB2(SCH_1):M_F_BA(0)   I111 @BASEBOARD_FAB2_LIB.BASEBOARD_FAB2(SCH_1):PAGE54
   207 M_F_BG<1> @BASEBOARD_FAB2_LIB.BASEBOARD_FAB2(SCH_1):M_F_BG(1)   I111 @BASEBOARD_FAB2_LIB.BASEBOARD_FAB2(SCH_1):PAGE54
    63 M_F_BG<0> @BASEBOARD_FAB2_LIB.BASEBOARD_FAB2(SCH_1):M_F_BG(0)   I111 @BASEBOARD_FAB2_LIB.BASEBOARD_FAB2(SCH_1):PAGE54
   235 M_F_C<2> @BASEBOARD_FAB2_LIB.BASEBOARD_FAB2(SCH_1):M_F_C(2)   I111 @BASEBOARD_FAB2_LIB.BASEBOARD_FAB2(SCH_1):PAGE54
   199 M_F_ECC<7> @BASEBOARD_FAB2_LIB.BASEBOARD_FAB2(SCH_1):M_F_ECC(7)   I111 @BASEBOARD_FAB2_LIB.BASEBOARD_FAB2(SCH_1):PAGE54
    54 M_F_ECC<6> @BASEBOARD_FAB2_LIB.BASEBOARD_FAB2(SCH_1):M_F_ECC(6)   I111 @BASEBOARD_FAB2_LIB.BASEBOARD_FAB2(SCH_1):PAGE54
   192 M_F_ECC<5> @BASEBOARD_FAB2_LIB.BASEBOARD_FAB2(SCH_1):M_F_ECC(5)   I111 @BASEBOARD_FAB2_LIB.BASEBOARD_FAB2(SCH_1):PAGE54
    47 M_F_ECC<4> @BASEBOARD_FAB2_LIB.BASEBOARD_FAB2(SCH_1):M_F_ECC(4)   I111 @BASEBOARD_FAB2_LIB.BASEBOARD_FAB2(SCH_1):PAGE54
   201 M_F_ECC<3> @BASEBOARD_FAB2_LIB.BASEBOARD_FAB2(SCH_1):M_F_ECC(3)   I111 @BASEBOARD_FAB2_LIB.BASEBOARD_FAB2(SCH_1):PAGE54
    56 M_F_ECC<2> @BASEBOARD_FAB2_LIB.BASEBOARD_FAB2(SCH_1):M_F_ECC(2)   I111 @BASEBOARD_FAB2_LIB.BASEBOARD_FAB2(SCH_1):PAGE54
   194 M_F_ECC<1> @BASEBOARD_FAB2_LIB.BASEBOARD_FAB2(SCH_1):M_F_ECC(1)   I111 @BASEBOARD_FAB2_LIB.BASEBOARD_FAB2(SCH_1):PAGE54
    49 M_F_ECC<0> @BASEBOARD_FAB2_LIB.BASEBOARD_FAB2(SCH_1):M_F_ECC(0)   I111 @BASEBOARD_FAB2_LIB.BASEBOARD_FAB2(SCH_1):PAGE54
    75 M_F_CLK_DN<2> @BASEBOARD_FAB2_LIB.BASEBOARD_FAB2(SCH_1):M_F_CLK_DN(2)   I111 @BASEBOARD_FAB2_LIB.BASEBOARD_FAB2(SCH_1):PAGE54
    74 M_F_CLK_DP<2> @BASEBOARD_FAB2_LIB.BASEBOARD_FAB2(SCH_1):M_F_CLK_DP(2)   I111 @BASEBOARD_FAB2_LIB.BASEBOARD_FAB2(SCH_1):PAGE54
   219 M_F_CLK_DN<3> @BASEBOARD_FAB2_LIB.BASEBOARD_FAB2(SCH_1):M_F_CLK_DN(3)   I111 @BASEBOARD_FAB2_LIB.BASEBOARD_FAB2(SCH_1):PAGE54
   218 M_F_CLK_DP<3> @BASEBOARD_FAB2_LIB.BASEBOARD_FAB2(SCH_1):M_F_CLK_DP(3)   I111 @BASEBOARD_FAB2_LIB.BASEBOARD_FAB2(SCH_1):PAGE54
   203 M_F_CKE<3> @BASEBOARD_FAB2_LIB.BASEBOARD_FAB2(SCH_1):M_F_CKE(3)   I111 @BASEBOARD_FAB2_LIB.BASEBOARD_FAB2(SCH_1):PAGE54
    60 M_F_CKE<2> @BASEBOARD_FAB2_LIB.BASEBOARD_FAB2(SCH_1):M_F_CKE(2)   I111 @BASEBOARD_FAB2_LIB.BASEBOARD_FAB2(SCH_1):PAGE54
   280 M_F_DQ<63> @BASEBOARD_FAB2_LIB.BASEBOARD_FAB2(SCH_1):M_F_DQ(63)   I111 @BASEBOARD_FAB2_LIB.BASEBOARD_FAB2(SCH_1):PAGE54
   135 M_F_DQ<62> @BASEBOARD_FAB2_LIB.BASEBOARD_FAB2(SCH_1):M_F_DQ(62)   I111 @BASEBOARD_FAB2_LIB.BASEBOARD_FAB2(SCH_1):PAGE54
   273 M_F_DQ<61> @BASEBOARD_FAB2_LIB.BASEBOARD_FAB2(SCH_1):M_F_DQ(61)   I111 @BASEBOARD_FAB2_LIB.BASEBOARD_FAB2(SCH_1):PAGE54
   128 M_F_DQ<60> @BASEBOARD_FAB2_LIB.BASEBOARD_FAB2(SCH_1):M_F_DQ(60)   I111 @BASEBOARD_FAB2_LIB.BASEBOARD_FAB2(SCH_1):PAGE54
   282 M_F_DQ<59> @BASEBOARD_FAB2_LIB.BASEBOARD_FAB2(SCH_1):M_F_DQ(59)   I111 @BASEBOARD_FAB2_LIB.BASEBOARD_FAB2(SCH_1):PAGE54
   137 M_F_DQ<58> @BASEBOARD_FAB2_LIB.BASEBOARD_FAB2(SCH_1):M_F_DQ(58)   I111 @BASEBOARD_FAB2_LIB.BASEBOARD_FAB2(SCH_1):PAGE54
   275 M_F_DQ<57> @BASEBOARD_FAB2_LIB.BASEBOARD_FAB2(SCH_1):M_F_DQ(57)   I111 @BASEBOARD_FAB2_LIB.BASEBOARD_FAB2(SCH_1):PAGE54
   130 M_F_DQ<56> @BASEBOARD_FAB2_LIB.BASEBOARD_FAB2(SCH_1):M_F_DQ(56)   I111 @BASEBOARD_FAB2_LIB.BASEBOARD_FAB2(SCH_1):PAGE54
   269 M_F_DQ<55> @BASEBOARD_FAB2_LIB.BASEBOARD_FAB2(SCH_1):M_F_DQ(55)   I111 @BASEBOARD_FAB2_LIB.BASEBOARD_FAB2(SCH_1):PAGE54
   124 M_F_DQ<54> @BASEBOARD_FAB2_LIB.BASEBOARD_FAB2(SCH_1):M_F_DQ(54)   I111 @BASEBOARD_FAB2_LIB.BASEBOARD_FAB2(SCH_1):PAGE54
   262 M_F_DQ<53> @BASEBOARD_FAB2_LIB.BASEBOARD_FAB2(SCH_1):M_F_DQ(53)   I111 @BASEBOARD_FAB2_LIB.BASEBOARD_FAB2(SCH_1):PAGE54
   117 M_F_DQ<52> @BASEBOARD_FAB2_LIB.BASEBOARD_FAB2(SCH_1):M_F_DQ(52)   I111 @BASEBOARD_FAB2_LIB.BASEBOARD_FAB2(SCH_1):PAGE54
   271 M_F_DQ<51> @BASEBOARD_FAB2_LIB.BASEBOARD_FAB2(SCH_1):M_F_DQ(51)   I111 @BASEBOARD_FAB2_LIB.BASEBOARD_FAB2(SCH_1):PAGE54
   126 M_F_DQ<50> @BASEBOARD_FAB2_LIB.BASEBOARD_FAB2(SCH_1):M_F_DQ(50)   I111 @BASEBOARD_FAB2_LIB.BASEBOARD_FAB2(SCH_1):PAGE54
   264 M_F_DQ<49> @BASEBOARD_FAB2_LIB.BASEBOARD_FAB2(SCH_1):M_F_DQ(49)   I111 @BASEBOARD_FAB2_LIB.BASEBOARD_FAB2(SCH_1):PAGE54
   119 M_F_DQ<48> @BASEBOARD_FAB2_LIB.BASEBOARD_FAB2(SCH_1):M_F_DQ(48)   I111 @BASEBOARD_FAB2_LIB.BASEBOARD_FAB2(SCH_1):PAGE54
   258 M_F_DQ<47> @BASEBOARD_FAB2_LIB.BASEBOARD_FAB2(SCH_1):M_F_DQ(47)   I111 @BASEBOARD_FAB2_LIB.BASEBOARD_FAB2(SCH_1):PAGE54
   113 M_F_DQ<46> @BASEBOARD_FAB2_LIB.BASEBOARD_FAB2(SCH_1):M_F_DQ(46)   I111 @BASEBOARD_FAB2_LIB.BASEBOARD_FAB2(SCH_1):PAGE54
   251 M_F_DQ<45> @BASEBOARD_FAB2_LIB.BASEBOARD_FAB2(SCH_1):M_F_DQ(45)   I111 @BASEBOARD_FAB2_LIB.BASEBOARD_FAB2(SCH_1):PAGE54
   106 M_F_DQ<44> @BASEBOARD_FAB2_LIB.BASEBOARD_FAB2(SCH_1):M_F_DQ(44)   I111 @BASEBOARD_FAB2_LIB.BASEBOARD_FAB2(SCH_1):PAGE54
   260 M_F_DQ<43> @BASEBOARD_FAB2_LIB.BASEBOARD_FAB2(SCH_1):M_F_DQ(43)   I111 @BASEBOARD_FAB2_LIB.BASEBOARD_FAB2(SCH_1):PAGE54
   115 M_F_DQ<42> @BASEBOARD_FAB2_LIB.BASEBOARD_FAB2(SCH_1):M_F_DQ(42)   I111 @BASEBOARD_FAB2_LIB.BASEBOARD_FAB2(SCH_1):PAGE54
   253 M_F_DQ<41> @BASEBOARD_FAB2_LIB.BASEBOARD_FAB2(SCH_1):M_F_DQ(41)   I111 @BASEBOARD_FAB2_LIB.BASEBOARD_FAB2(SCH_1):PAGE54
   108 M_F_DQ<40> @BASEBOARD_FAB2_LIB.BASEBOARD_FAB2(SCH_1):M_F_DQ(40)   I111 @BASEBOARD_FAB2_LIB.BASEBOARD_FAB2(SCH_1):PAGE54
   247 M_F_DQ<39> @BASEBOARD_FAB2_LIB.BASEBOARD_FAB2(SCH_1):M_F_DQ(39)   I111 @BASEBOARD_FAB2_LIB.BASEBOARD_FAB2(SCH_1):PAGE54
   102 M_F_DQ<38> @BASEBOARD_FAB2_LIB.BASEBOARD_FAB2(SCH_1):M_F_DQ(38)   I111 @BASEBOARD_FAB2_LIB.BASEBOARD_FAB2(SCH_1):PAGE54
   240 M_F_DQ<37> @BASEBOARD_FAB2_LIB.BASEBOARD_FAB2(SCH_1):M_F_DQ(37)   I111 @BASEBOARD_FAB2_LIB.BASEBOARD_FAB2(SCH_1):PAGE54
    95 M_F_DQ<36> @BASEBOARD_FAB2_LIB.BASEBOARD_FAB2(SCH_1):M_F_DQ(36)   I111 @BASEBOARD_FAB2_LIB.BASEBOARD_FAB2(SCH_1):PAGE54
   249 M_F_DQ<35> @BASEBOARD_FAB2_LIB.BASEBOARD_FAB2(SCH_1):M_F_DQ(35)   I111 @BASEBOARD_FAB2_LIB.BASEBOARD_FAB2(SCH_1):PAGE54
   104 M_F_DQ<34> @BASEBOARD_FAB2_LIB.BASEBOARD_FAB2(SCH_1):M_F_DQ(34)   I111 @BASEBOARD_FAB2_LIB.BASEBOARD_FAB2(SCH_1):PAGE54
   242 M_F_DQ<33> @BASEBOARD_FAB2_LIB.BASEBOARD_FAB2(SCH_1):M_F_DQ(33)   I111 @BASEBOARD_FAB2_LIB.BASEBOARD_FAB2(SCH_1):PAGE54
    97 M_F_DQ<32> @BASEBOARD_FAB2_LIB.BASEBOARD_FAB2(SCH_1):M_F_DQ(32)   I111 @BASEBOARD_FAB2_LIB.BASEBOARD_FAB2(SCH_1):PAGE54
   188 M_F_DQ<31> @BASEBOARD_FAB2_LIB.BASEBOARD_FAB2(SCH_1):M_F_DQ(31)   I111 @BASEBOARD_FAB2_LIB.BASEBOARD_FAB2(SCH_1):PAGE54
    43 M_F_DQ<30> @BASEBOARD_FAB2_LIB.BASEBOARD_FAB2(SCH_1):M_F_DQ(30)   I111 @BASEBOARD_FAB2_LIB.BASEBOARD_FAB2(SCH_1):PAGE54
   181 M_F_DQ<29> @BASEBOARD_FAB2_LIB.BASEBOARD_FAB2(SCH_1):M_F_DQ(29)   I111 @BASEBOARD_FAB2_LIB.BASEBOARD_FAB2(SCH_1):PAGE54
    36 M_F_DQ<28> @BASEBOARD_FAB2_LIB.BASEBOARD_FAB2(SCH_1):M_F_DQ(28)   I111 @BASEBOARD_FAB2_LIB.BASEBOARD_FAB2(SCH_1):PAGE54
   190 M_F_DQ<27> @BASEBOARD_FAB2_LIB.BASEBOARD_FAB2(SCH_1):M_F_DQ(27)   I111 @BASEBOARD_FAB2_LIB.BASEBOARD_FAB2(SCH_1):PAGE54
    45 M_F_DQ<26> @BASEBOARD_FAB2_LIB.BASEBOARD_FAB2(SCH_1):M_F_DQ(26)   I111 @BASEBOARD_FAB2_LIB.BASEBOARD_FAB2(SCH_1):PAGE54
   183 M_F_DQ<25> @BASEBOARD_FAB2_LIB.BASEBOARD_FAB2(SCH_1):M_F_DQ(25)   I111 @BASEBOARD_FAB2_LIB.BASEBOARD_FAB2(SCH_1):PAGE54
    38 M_F_DQ<24> @BASEBOARD_FAB2_LIB.BASEBOARD_FAB2(SCH_1):M_F_DQ(24)   I111 @BASEBOARD_FAB2_LIB.BASEBOARD_FAB2(SCH_1):PAGE54
   177 M_F_DQ<23> @BASEBOARD_FAB2_LIB.BASEBOARD_FAB2(SCH_1):M_F_DQ(23)   I111 @BASEBOARD_FAB2_LIB.BASEBOARD_FAB2(SCH_1):PAGE54
    32 M_F_DQ<22> @BASEBOARD_FAB2_LIB.BASEBOARD_FAB2(SCH_1):M_F_DQ(22)   I111 @BASEBOARD_FAB2_LIB.BASEBOARD_FAB2(SCH_1):PAGE54
   170 M_F_DQ<21> @BASEBOARD_FAB2_LIB.BASEBOARD_FAB2(SCH_1):M_F_DQ(21)   I111 @BASEBOARD_FAB2_LIB.BASEBOARD_FAB2(SCH_1):PAGE54
    25 M_F_DQ<20> @BASEBOARD_FAB2_LIB.BASEBOARD_FAB2(SCH_1):M_F_DQ(20)   I111 @BASEBOARD_FAB2_LIB.BASEBOARD_FAB2(SCH_1):PAGE54
   179 M_F_DQ<19> @BASEBOARD_FAB2_LIB.BASEBOARD_FAB2(SCH_1):M_F_DQ(19)   I111 @BASEBOARD_FAB2_LIB.BASEBOARD_FAB2(SCH_1):PAGE54
    34 M_F_DQ<18> @BASEBOARD_FAB2_LIB.BASEBOARD_FAB2(SCH_1):M_F_DQ(18)   I111 @BASEBOARD_FAB2_LIB.BASEBOARD_FAB2(SCH_1):PAGE54
   172 M_F_DQ<17> @BASEBOARD_FAB2_LIB.BASEBOARD_FAB2(SCH_1):M_F_DQ(17)   I111 @BASEBOARD_FAB2_LIB.BASEBOARD_FAB2(SCH_1):PAGE54
    27 M_F_DQ<16> @BASEBOARD_FAB2_LIB.BASEBOARD_FAB2(SCH_1):M_F_DQ(16)   I111 @BASEBOARD_FAB2_LIB.BASEBOARD_FAB2(SCH_1):PAGE54
   166 M_F_DQ<15> @BASEBOARD_FAB2_LIB.BASEBOARD_FAB2(SCH_1):M_F_DQ(15)   I111 @BASEBOARD_FAB2_LIB.BASEBOARD_FAB2(SCH_1):PAGE54
    21 M_F_DQ<14> @BASEBOARD_FAB2_LIB.BASEBOARD_FAB2(SCH_1):M_F_DQ(14)   I111 @BASEBOARD_FAB2_LIB.BASEBOARD_FAB2(SCH_1):PAGE54
   159 M_F_DQ<13> @BASEBOARD_FAB2_LIB.BASEBOARD_FAB2(SCH_1):M_F_DQ(13)   I111 @BASEBOARD_FAB2_LIB.BASEBOARD_FAB2(SCH_1):PAGE54
    14 M_F_DQ<12> @BASEBOARD_FAB2_LIB.BASEBOARD_FAB2(SCH_1):M_F_DQ(12)   I111 @BASEBOARD_FAB2_LIB.BASEBOARD_FAB2(SCH_1):PAGE54
   168 M_F_DQ<11> @BASEBOARD_FAB2_LIB.BASEBOARD_FAB2(SCH_1):M_F_DQ(11)   I111 @BASEBOARD_FAB2_LIB.BASEBOARD_FAB2(SCH_1):PAGE54
    23 M_F_DQ<10> @BASEBOARD_FAB2_LIB.BASEBOARD_FAB2(SCH_1):M_F_DQ(10)   I111 @BASEBOARD_FAB2_LIB.BASEBOARD_FAB2(SCH_1):PAGE54
   161 M_F_DQ<9> @BASEBOARD_FAB2_LIB.BASEBOARD_FAB2(SCH_1):M_F_DQ(9)   I111 @BASEBOARD_FAB2_LIB.BASEBOARD_FAB2(SCH_1):PAGE54
    16 M_F_DQ<8> @BASEBOARD_FAB2_LIB.BASEBOARD_FAB2(SCH_1):M_F_DQ(8)   I111 @BASEBOARD_FAB2_LIB.BASEBOARD_FAB2(SCH_1):PAGE54
   155 M_F_DQ<7> @BASEBOARD_FAB2_LIB.BASEBOARD_FAB2(SCH_1):M_F_DQ(7)   I111 @BASEBOARD_FAB2_LIB.BASEBOARD_FAB2(SCH_1):PAGE54
    10 M_F_DQ<6> @BASEBOARD_FAB2_LIB.BASEBOARD_FAB2(SCH_1):M_F_DQ(6)   I111 @BASEBOARD_FAB2_LIB.BASEBOARD_FAB2(SCH_1):PAGE54
   148 M_F_DQ<5> @BASEBOARD_FAB2_LIB.BASEBOARD_FAB2(SCH_1):M_F_DQ(5)   I111 @BASEBOARD_FAB2_LIB.BASEBOARD_FAB2(SCH_1):PAGE54
     3 M_F_DQ<4> @BASEBOARD_FAB2_LIB.BASEBOARD_FAB2(SCH_1):M_F_DQ(4)   I111 @BASEBOARD_FAB2_LIB.BASEBOARD_FAB2(SCH_1):PAGE54
   157 M_F_DQ<3> @BASEBOARD_FAB2_LIB.BASEBOARD_FAB2(SCH_1):M_F_DQ(3)   I111 @BASEBOARD_FAB2_LIB.BASEBOARD_FAB2(SCH_1):PAGE54
    12 M_F_DQ<2> @BASEBOARD_FAB2_LIB.BASEBOARD_FAB2(SCH_1):M_F_DQ(2)   I111 @BASEBOARD_FAB2_LIB.BASEBOARD_FAB2(SCH_1):PAGE54
   150 M_F_DQ<1> @BASEBOARD_FAB2_LIB.BASEBOARD_FAB2(SCH_1):M_F_DQ(1)   I111 @BASEBOARD_FAB2_LIB.BASEBOARD_FAB2(SCH_1):PAGE54
     5 M_F_DQ<0> @BASEBOARD_FAB2_LIB.BASEBOARD_FAB2(SCH_1):M_F_DQ(0)   I111 @BASEBOARD_FAB2_LIB.BASEBOARD_FAB2(SCH_1):PAGE54
    78 FM_DIMM_EVENT_COD_N @BASEBOARD_FAB2_LIB.BASEBOARD_FAB2(SCH_1):FM_DIMM_EVENT_COD_N   I111 @BASEBOARD_FAB2_LIB.BASEBOARD_FAB2(SCH_1):PAGE54
    91 M_F_ODT<3> @BASEBOARD_FAB2_LIB.BASEBOARD_FAB2(SCH_1):M_F_ODT(3)   I111 @BASEBOARD_FAB2_LIB.BASEBOARD_FAB2(SCH_1):PAGE54
    87 M_F_ODT<2> @BASEBOARD_FAB2_LIB.BASEBOARD_FAB2(SCH_1):M_F_ODT(2)   I111 @BASEBOARD_FAB2_LIB.BASEBOARD_FAB2(SCH_1):PAGE54
   222 M_F_PAR @BASEBOARD_FAB2_LIB.BASEBOARD_FAB2(SCH_1):M_F_PAR   I111 @BASEBOARD_FAB2_LIB.BASEBOARD_FAB2(SCH_1):PAGE54
    58 M_DEF_RST_N @BASEBOARD_FAB2_LIB.BASEBOARD_FAB2(SCH_1):M_DEF_RST_N   I111 @BASEBOARD_FAB2_LIB.BASEBOARD_FAB2(SCH_1):PAGE54
   144 TP_CH_F_DIMM_F1_RFU_2 @BASEBOARD_FAB2_LIB.BASEBOARD_FAB2(SCH_1):TP_CH_F_DIMM_F1_RFU_2   I111 @BASEBOARD_FAB2_LIB.BASEBOARD_FAB2(SCH_1):PAGE54
   227 TP_CH_F_DIMM_F1_RFU_1 @BASEBOARD_FAB2_LIB.BASEBOARD_FAB2(SCH_1):TP_CH_F_DIMM_F1_RFU_1   I111 @BASEBOARD_FAB2_LIB.BASEBOARD_FAB2(SCH_1):PAGE54
   205 TP_CH_F_DIMM_F1_RFU_0 @BASEBOARD_FAB2_LIB.BASEBOARD_FAB2(SCH_1):TP_CH_F_DIMM_F1_RFU_0   I111 @BASEBOARD_FAB2_LIB.BASEBOARD_FAB2(SCH_1):PAGE54
    84 M_F_CS_N<4> @BASEBOARD_FAB2_LIB.BASEBOARD_FAB2(SCH_1):M_F_CS_N(4)   I111 @BASEBOARD_FAB2_LIB.BASEBOARD_FAB2(SCH_1):PAGE54
    89 M_F_CS_N<5> @BASEBOARD_FAB2_LIB.BASEBOARD_FAB2(SCH_1):M_F_CS_N(5)   I111 @BASEBOARD_FAB2_LIB.BASEBOARD_FAB2(SCH_1):PAGE54
    93 M_F_CS_N<6> @BASEBOARD_FAB2_LIB.BASEBOARD_FAB2(SCH_1):M_F_CS_N(6)   I111 @BASEBOARD_FAB2_LIB.BASEBOARD_FAB2(SCH_1):PAGE54
   237 M_F_CS_N<7> @BASEBOARD_FAB2_LIB.BASEBOARD_FAB2(SCH_1):M_F_CS_N(7)   I111 @BASEBOARD_FAB2_LIB.BASEBOARD_FAB2(SCH_1):PAGE54
   238 PVPP_DEF @BASEBOARD_FAB2_LIB.BASEBOARD_FAB2(SCH_1):PVPP_DEF   I111 @BASEBOARD_FAB2_LIB.BASEBOARD_FAB2(SCH_1):PAGE54
   140    GND @BASEBOARD_FAB2_LIB.BASEBOARD_FAB2(SCH_1):GND   I111 @BASEBOARD_FAB2_LIB.BASEBOARD_FAB2(SCH_1):PAGE54
   139 PVPP_DEF @BASEBOARD_FAB2_LIB.BASEBOARD_FAB2(SCH_1):PVPP_DEF   I111 @BASEBOARD_FAB2_LIB.BASEBOARD_FAB2(SCH_1):PAGE54
   230 FM_ADR_COMPLETE_DEF_N @BASEBOARD_FAB2_LIB.BASEBOARD_FAB2(SCH_1):FM_ADR_COMPLETE_DEF_N   I111 @BASEBOARD_FAB2_LIB.BASEBOARD_FAB2(SCH_1):PAGE54
   141 SMB_DDR_DEF_VPP_SCL @BASEBOARD_FAB2_LIB.BASEBOARD_FAB2(SCH_1):SMB_DDR_DEF_VPP_SCL   I111 @BASEBOARD_FAB2_LIB.BASEBOARD_FAB2(SCH_1):PAGE54
   285 SMB_DDR_DEF_VPP_SDA @BASEBOARD_FAB2_LIB.BASEBOARD_FAB2(SCH_1):SMB_DDR_DEF_VPP_SDA   I111 @BASEBOARD_FAB2_LIB.BASEBOARD_FAB2(SCH_1):PAGE54
   284 PVPP_DEF @BASEBOARD_FAB2_LIB.BASEBOARD_FAB2(SCH_1):PVPP_DEF   I111 @BASEBOARD_FAB2_LIB.BASEBOARD_FAB2(SCH_1):PAGE54
   146 M_F_VREF @BASEBOARD_FAB2_LIB.BASEBOARD_FAB2(SCH_1):M_F_VREF   I111 @BASEBOARD_FAB2_LIB.BASEBOARD_FAB2(SCH_1):PAGE54
   152 M_F_DQS_DN<0> @BASEBOARD_FAB2_LIB.BASEBOARD_FAB2(SCH_1):M_F_DQS_DN(0)    I66 @BASEBOARD_FAB2_LIB.BASEBOARD_FAB2(SCH_1):PAGE54
   153 M_F_DQS_DP<0> @BASEBOARD_FAB2_LIB.BASEBOARD_FAB2(SCH_1):M_F_DQS_DP(0)    I66 @BASEBOARD_FAB2_LIB.BASEBOARD_FAB2(SCH_1):PAGE54
    19 M_F_DQS_DN<10> @BASEBOARD_FAB2_LIB.BASEBOARD_FAB2(SCH_1):M_F_DQS_DN(10)    I66 @BASEBOARD_FAB2_LIB.BASEBOARD_FAB2(SCH_1):PAGE54
    18 M_F_DQS_DP<10> @BASEBOARD_FAB2_LIB.BASEBOARD_FAB2(SCH_1):M_F_DQS_DP(10)    I66 @BASEBOARD_FAB2_LIB.BASEBOARD_FAB2(SCH_1):PAGE54
    30 M_F_DQS_DN<11> @BASEBOARD_FAB2_LIB.BASEBOARD_FAB2(SCH_1):M_F_DQS_DN(11)    I66 @BASEBOARD_FAB2_LIB.BASEBOARD_FAB2(SCH_1):PAGE54
    29 M_F_DQS_DP<11> @BASEBOARD_FAB2_LIB.BASEBOARD_FAB2(SCH_1):M_F_DQS_DP(11)    I66 @BASEBOARD_FAB2_LIB.BASEBOARD_FAB2(SCH_1):PAGE54
    41 M_F_DQS_DN<12> @BASEBOARD_FAB2_LIB.BASEBOARD_FAB2(SCH_1):M_F_DQS_DN(12)    I66 @BASEBOARD_FAB2_LIB.BASEBOARD_FAB2(SCH_1):PAGE54
    40 M_F_DQS_DP<12> @BASEBOARD_FAB2_LIB.BASEBOARD_FAB2(SCH_1):M_F_DQS_DP(12)    I66 @BASEBOARD_FAB2_LIB.BASEBOARD_FAB2(SCH_1):PAGE54
   100 M_F_DQS_DN<13> @BASEBOARD_FAB2_LIB.BASEBOARD_FAB2(SCH_1):M_F_DQS_DN(13)    I66 @BASEBOARD_FAB2_LIB.BASEBOARD_FAB2(SCH_1):PAGE54
    99 M_F_DQS_DP<13> @BASEBOARD_FAB2_LIB.BASEBOARD_FAB2(SCH_1):M_F_DQS_DP(13)    I66 @BASEBOARD_FAB2_LIB.BASEBOARD_FAB2(SCH_1):PAGE54
   111 M_F_DQS_DN<14> @BASEBOARD_FAB2_LIB.BASEBOARD_FAB2(SCH_1):M_F_DQS_DN(14)    I66 @BASEBOARD_FAB2_LIB.BASEBOARD_FAB2(SCH_1):PAGE54
   110 M_F_DQS_DP<14> @BASEBOARD_FAB2_LIB.BASEBOARD_FAB2(SCH_1):M_F_DQS_DP(14)    I66 @BASEBOARD_FAB2_LIB.BASEBOARD_FAB2(SCH_1):PAGE54
   122 M_F_DQS_DN<15> @BASEBOARD_FAB2_LIB.BASEBOARD_FAB2(SCH_1):M_F_DQS_DN(15)    I66 @BASEBOARD_FAB2_LIB.BASEBOARD_FAB2(SCH_1):PAGE54
   121 M_F_DQS_DP<15> @BASEBOARD_FAB2_LIB.BASEBOARD_FAB2(SCH_1):M_F_DQS_DP(15)    I66 @BASEBOARD_FAB2_LIB.BASEBOARD_FAB2(SCH_1):PAGE54
   133 M_F_DQS_DN<16> @BASEBOARD_FAB2_LIB.BASEBOARD_FAB2(SCH_1):M_F_DQS_DN(16)    I66 @BASEBOARD_FAB2_LIB.BASEBOARD_FAB2(SCH_1):PAGE54
   132 M_F_DQS_DP<16> @BASEBOARD_FAB2_LIB.BASEBOARD_FAB2(SCH_1):M_F_DQS_DP(16)    I66 @BASEBOARD_FAB2_LIB.BASEBOARD_FAB2(SCH_1):PAGE54
    52 M_F_DQS_DN<17> @BASEBOARD_FAB2_LIB.BASEBOARD_FAB2(SCH_1):M_F_DQS_DN(17)    I66 @BASEBOARD_FAB2_LIB.BASEBOARD_FAB2(SCH_1):PAGE54
    51 M_F_DQS_DP<17> @BASEBOARD_FAB2_LIB.BASEBOARD_FAB2(SCH_1):M_F_DQS_DP(17)    I66 @BASEBOARD_FAB2_LIB.BASEBOARD_FAB2(SCH_1):PAGE54
   163 M_F_DQS_DN<1> @BASEBOARD_FAB2_LIB.BASEBOARD_FAB2(SCH_1):M_F_DQS_DN(1)    I66 @BASEBOARD_FAB2_LIB.BASEBOARD_FAB2(SCH_1):PAGE54
   164 M_F_DQS_DP<1> @BASEBOARD_FAB2_LIB.BASEBOARD_FAB2(SCH_1):M_F_DQS_DP(1)    I66 @BASEBOARD_FAB2_LIB.BASEBOARD_FAB2(SCH_1):PAGE54
   174 M_F_DQS_DN<2> @BASEBOARD_FAB2_LIB.BASEBOARD_FAB2(SCH_1):M_F_DQS_DN(2)    I66 @BASEBOARD_FAB2_LIB.BASEBOARD_FAB2(SCH_1):PAGE54
   175 M_F_DQS_DP<2> @BASEBOARD_FAB2_LIB.BASEBOARD_FAB2(SCH_1):M_F_DQS_DP(2)    I66 @BASEBOARD_FAB2_LIB.BASEBOARD_FAB2(SCH_1):PAGE54
   185 M_F_DQS_DN<3> @BASEBOARD_FAB2_LIB.BASEBOARD_FAB2(SCH_1):M_F_DQS_DN(3)    I66 @BASEBOARD_FAB2_LIB.BASEBOARD_FAB2(SCH_1):PAGE54
   186 M_F_DQS_DP<3> @BASEBOARD_FAB2_LIB.BASEBOARD_FAB2(SCH_1):M_F_DQS_DP(3)    I66 @BASEBOARD_FAB2_LIB.BASEBOARD_FAB2(SCH_1):PAGE54
   244 M_F_DQS_DN<4> @BASEBOARD_FAB2_LIB.BASEBOARD_FAB2(SCH_1):M_F_DQS_DN(4)    I66 @BASEBOARD_FAB2_LIB.BASEBOARD_FAB2(SCH_1):PAGE54
   245 M_F_DQS_DP<4> @BASEBOARD_FAB2_LIB.BASEBOARD_FAB2(SCH_1):M_F_DQS_DP(4)    I66 @BASEBOARD_FAB2_LIB.BASEBOARD_FAB2(SCH_1):PAGE54
   255 M_F_DQS_DN<5> @BASEBOARD_FAB2_LIB.BASEBOARD_FAB2(SCH_1):M_F_DQS_DN(5)    I66 @BASEBOARD_FAB2_LIB.BASEBOARD_FAB2(SCH_1):PAGE54
   256 M_F_DQS_DP<5> @BASEBOARD_FAB2_LIB.BASEBOARD_FAB2(SCH_1):M_F_DQS_DP(5)    I66 @BASEBOARD_FAB2_LIB.BASEBOARD_FAB2(SCH_1):PAGE54
   266 M_F_DQS_DN<6> @BASEBOARD_FAB2_LIB.BASEBOARD_FAB2(SCH_1):M_F_DQS_DN(6)    I66 @BASEBOARD_FAB2_LIB.BASEBOARD_FAB2(SCH_1):PAGE54
   267 M_F_DQS_DP<6> @BASEBOARD_FAB2_LIB.BASEBOARD_FAB2(SCH_1):M_F_DQS_DP(6)    I66 @BASEBOARD_FAB2_LIB.BASEBOARD_FAB2(SCH_1):PAGE54
   277 M_F_DQS_DN<7> @BASEBOARD_FAB2_LIB.BASEBOARD_FAB2(SCH_1):M_F_DQS_DN(7)    I66 @BASEBOARD_FAB2_LIB.BASEBOARD_FAB2(SCH_1):PAGE54
   278 M_F_DQS_DP<7> @BASEBOARD_FAB2_LIB.BASEBOARD_FAB2(SCH_1):M_F_DQS_DP(7)    I66 @BASEBOARD_FAB2_LIB.BASEBOARD_FAB2(SCH_1):PAGE54
   196 M_F_DQS_DN<8> @BASEBOARD_FAB2_LIB.BASEBOARD_FAB2(SCH_1):M_F_DQS_DN(8)    I66 @BASEBOARD_FAB2_LIB.BASEBOARD_FAB2(SCH_1):PAGE54
   197 M_F_DQS_DP<8> @BASEBOARD_FAB2_LIB.BASEBOARD_FAB2(SCH_1):M_F_DQS_DP(8)    I66 @BASEBOARD_FAB2_LIB.BASEBOARD_FAB2(SCH_1):PAGE54
     8 M_F_DQS_DN<9> @BASEBOARD_FAB2_LIB.BASEBOARD_FAB2(SCH_1):M_F_DQS_DN(9)    I66 @BASEBOARD_FAB2_LIB.BASEBOARD_FAB2(SCH_1):PAGE54
     7 M_F_DQS_DP<9> @BASEBOARD_FAB2_LIB.BASEBOARD_FAB2(SCH_1):M_F_DQS_DP(9)    I66 @BASEBOARD_FAB2_LIB.BASEBOARD_FAB2(SCH_1):PAGE54
     2    GND @BASEBOARD_FAB2_LIB.BASEBOARD_FAB2(SCH_1):GND    I43 @BASEBOARD_FAB2_LIB.BASEBOARD_FAB2(SCH_1):PAGE54
     4    GND @BASEBOARD_FAB2_LIB.BASEBOARD_FAB2(SCH_1):GND    I43 @BASEBOARD_FAB2_LIB.BASEBOARD_FAB2(SCH_1):PAGE54
     6    GND @BASEBOARD_FAB2_LIB.BASEBOARD_FAB2(SCH_1):GND    I43 @BASEBOARD_FAB2_LIB.BASEBOARD_FAB2(SCH_1):PAGE54
     9    GND @BASEBOARD_FAB2_LIB.BASEBOARD_FAB2(SCH_1):GND    I43 @BASEBOARD_FAB2_LIB.BASEBOARD_FAB2(SCH_1):PAGE54
    11    GND @BASEBOARD_FAB2_LIB.BASEBOARD_FAB2(SCH_1):GND    I43 @BASEBOARD_FAB2_LIB.BASEBOARD_FAB2(SCH_1):PAGE54
    13    GND @BASEBOARD_FAB2_LIB.BASEBOARD_FAB2(SCH_1):GND    I43 @BASEBOARD_FAB2_LIB.BASEBOARD_FAB2(SCH_1):PAGE54
    15    GND @BASEBOARD_FAB2_LIB.BASEBOARD_FAB2(SCH_1):GND    I43 @BASEBOARD_FAB2_LIB.BASEBOARD_FAB2(SCH_1):PAGE54
    17    GND @BASEBOARD_FAB2_LIB.BASEBOARD_FAB2(SCH_1):GND    I43 @BASEBOARD_FAB2_LIB.BASEBOARD_FAB2(SCH_1):PAGE54
    20    GND @BASEBOARD_FAB2_LIB.BASEBOARD_FAB2(SCH_1):GND    I43 @BASEBOARD_FAB2_LIB.BASEBOARD_FAB2(SCH_1):PAGE54
    22    GND @BASEBOARD_FAB2_LIB.BASEBOARD_FAB2(SCH_1):GND    I43 @BASEBOARD_FAB2_LIB.BASEBOARD_FAB2(SCH_1):PAGE54
    24    GND @BASEBOARD_FAB2_LIB.BASEBOARD_FAB2(SCH_1):GND    I43 @BASEBOARD_FAB2_LIB.BASEBOARD_FAB2(SCH_1):PAGE54
    26    GND @BASEBOARD_FAB2_LIB.BASEBOARD_FAB2(SCH_1):GND    I43 @BASEBOARD_FAB2_LIB.BASEBOARD_FAB2(SCH_1):PAGE54
    28    GND @BASEBOARD_FAB2_LIB.BASEBOARD_FAB2(SCH_1):GND    I43 @BASEBOARD_FAB2_LIB.BASEBOARD_FAB2(SCH_1):PAGE54
    31    GND @BASEBOARD_FAB2_LIB.BASEBOARD_FAB2(SCH_1):GND    I43 @BASEBOARD_FAB2_LIB.BASEBOARD_FAB2(SCH_1):PAGE54
    33    GND @BASEBOARD_FAB2_LIB.BASEBOARD_FAB2(SCH_1):GND    I43 @BASEBOARD_FAB2_LIB.BASEBOARD_FAB2(SCH_1):PAGE54
    35    GND @BASEBOARD_FAB2_LIB.BASEBOARD_FAB2(SCH_1):GND    I43 @BASEBOARD_FAB2_LIB.BASEBOARD_FAB2(SCH_1):PAGE54
    37    GND @BASEBOARD_FAB2_LIB.BASEBOARD_FAB2(SCH_1):GND    I43 @BASEBOARD_FAB2_LIB.BASEBOARD_FAB2(SCH_1):PAGE54
    39    GND @BASEBOARD_FAB2_LIB.BASEBOARD_FAB2(SCH_1):GND    I43 @BASEBOARD_FAB2_LIB.BASEBOARD_FAB2(SCH_1):PAGE54
    42    GND @BASEBOARD_FAB2_LIB.BASEBOARD_FAB2(SCH_1):GND    I43 @BASEBOARD_FAB2_LIB.BASEBOARD_FAB2(SCH_1):PAGE54
    44    GND @BASEBOARD_FAB2_LIB.BASEBOARD_FAB2(SCH_1):GND    I43 @BASEBOARD_FAB2_LIB.BASEBOARD_FAB2(SCH_1):PAGE54
    46    GND @BASEBOARD_FAB2_LIB.BASEBOARD_FAB2(SCH_1):GND    I43 @BASEBOARD_FAB2_LIB.BASEBOARD_FAB2(SCH_1):PAGE54
    48    GND @BASEBOARD_FAB2_LIB.BASEBOARD_FAB2(SCH_1):GND    I43 @BASEBOARD_FAB2_LIB.BASEBOARD_FAB2(SCH_1):PAGE54
    50    GND @BASEBOARD_FAB2_LIB.BASEBOARD_FAB2(SCH_1):GND    I43 @BASEBOARD_FAB2_LIB.BASEBOARD_FAB2(SCH_1):PAGE54
    53    GND @BASEBOARD_FAB2_LIB.BASEBOARD_FAB2(SCH_1):GND    I43 @BASEBOARD_FAB2_LIB.BASEBOARD_FAB2(SCH_1):PAGE54
    55    GND @BASEBOARD_FAB2_LIB.BASEBOARD_FAB2(SCH_1):GND    I43 @BASEBOARD_FAB2_LIB.BASEBOARD_FAB2(SCH_1):PAGE54
    57    GND @BASEBOARD_FAB2_LIB.BASEBOARD_FAB2(SCH_1):GND    I43 @BASEBOARD_FAB2_LIB.BASEBOARD_FAB2(SCH_1):PAGE54
    94    GND @BASEBOARD_FAB2_LIB.BASEBOARD_FAB2(SCH_1):GND    I43 @BASEBOARD_FAB2_LIB.BASEBOARD_FAB2(SCH_1):PAGE54
    96    GND @BASEBOARD_FAB2_LIB.BASEBOARD_FAB2(SCH_1):GND    I43 @BASEBOARD_FAB2_LIB.BASEBOARD_FAB2(SCH_1):PAGE54
    98    GND @BASEBOARD_FAB2_LIB.BASEBOARD_FAB2(SCH_1):GND    I43 @BASEBOARD_FAB2_LIB.BASEBOARD_FAB2(SCH_1):PAGE54
   101    GND @BASEBOARD_FAB2_LIB.BASEBOARD_FAB2(SCH_1):GND    I43 @BASEBOARD_FAB2_LIB.BASEBOARD_FAB2(SCH_1):PAGE54
   103    GND @BASEBOARD_FAB2_LIB.BASEBOARD_FAB2(SCH_1):GND    I43 @BASEBOARD_FAB2_LIB.BASEBOARD_FAB2(SCH_1):PAGE54
   105    GND @BASEBOARD_FAB2_LIB.BASEBOARD_FAB2(SCH_1):GND    I43 @BASEBOARD_FAB2_LIB.BASEBOARD_FAB2(SCH_1):PAGE54
   107    GND @BASEBOARD_FAB2_LIB.BASEBOARD_FAB2(SCH_1):GND    I43 @BASEBOARD_FAB2_LIB.BASEBOARD_FAB2(SCH_1):PAGE54
   109    GND @BASEBOARD_FAB2_LIB.BASEBOARD_FAB2(SCH_1):GND    I43 @BASEBOARD_FAB2_LIB.BASEBOARD_FAB2(SCH_1):PAGE54
   112    GND @BASEBOARD_FAB2_LIB.BASEBOARD_FAB2(SCH_1):GND    I43 @BASEBOARD_FAB2_LIB.BASEBOARD_FAB2(SCH_1):PAGE54
   114    GND @BASEBOARD_FAB2_LIB.BASEBOARD_FAB2(SCH_1):GND    I43 @BASEBOARD_FAB2_LIB.BASEBOARD_FAB2(SCH_1):PAGE54
   116    GND @BASEBOARD_FAB2_LIB.BASEBOARD_FAB2(SCH_1):GND    I43 @BASEBOARD_FAB2_LIB.BASEBOARD_FAB2(SCH_1):PAGE54
   118    GND @BASEBOARD_FAB2_LIB.BASEBOARD_FAB2(SCH_1):GND    I43 @BASEBOARD_FAB2_LIB.BASEBOARD_FAB2(SCH_1):PAGE54
   120    GND @BASEBOARD_FAB2_LIB.BASEBOARD_FAB2(SCH_1):GND    I43 @BASEBOARD_FAB2_LIB.BASEBOARD_FAB2(SCH_1):PAGE54
   123    GND @BASEBOARD_FAB2_LIB.BASEBOARD_FAB2(SCH_1):GND    I43 @BASEBOARD_FAB2_LIB.BASEBOARD_FAB2(SCH_1):PAGE54
   125    GND @BASEBOARD_FAB2_LIB.BASEBOARD_FAB2(SCH_1):GND    I43 @BASEBOARD_FAB2_LIB.BASEBOARD_FAB2(SCH_1):PAGE54
   127    GND @BASEBOARD_FAB2_LIB.BASEBOARD_FAB2(SCH_1):GND    I43 @BASEBOARD_FAB2_LIB.BASEBOARD_FAB2(SCH_1):PAGE54
   129    GND @BASEBOARD_FAB2_LIB.BASEBOARD_FAB2(SCH_1):GND    I43 @BASEBOARD_FAB2_LIB.BASEBOARD_FAB2(SCH_1):PAGE54
   131    GND @BASEBOARD_FAB2_LIB.BASEBOARD_FAB2(SCH_1):GND    I43 @BASEBOARD_FAB2_LIB.BASEBOARD_FAB2(SCH_1):PAGE54
   134    GND @BASEBOARD_FAB2_LIB.BASEBOARD_FAB2(SCH_1):GND    I43 @BASEBOARD_FAB2_LIB.BASEBOARD_FAB2(SCH_1):PAGE54
   136    GND @BASEBOARD_FAB2_LIB.BASEBOARD_FAB2(SCH_1):GND    I43 @BASEBOARD_FAB2_LIB.BASEBOARD_FAB2(SCH_1):PAGE54
   138    GND @BASEBOARD_FAB2_LIB.BASEBOARD_FAB2(SCH_1):GND    I43 @BASEBOARD_FAB2_LIB.BASEBOARD_FAB2(SCH_1):PAGE54
   147    GND @BASEBOARD_FAB2_LIB.BASEBOARD_FAB2(SCH_1):GND    I43 @BASEBOARD_FAB2_LIB.BASEBOARD_FAB2(SCH_1):PAGE54
   149    GND @BASEBOARD_FAB2_LIB.BASEBOARD_FAB2(SCH_1):GND    I43 @BASEBOARD_FAB2_LIB.BASEBOARD_FAB2(SCH_1):PAGE54
   151    GND @BASEBOARD_FAB2_LIB.BASEBOARD_FAB2(SCH_1):GND    I43 @BASEBOARD_FAB2_LIB.BASEBOARD_FAB2(SCH_1):PAGE54
   154    GND @BASEBOARD_FAB2_LIB.BASEBOARD_FAB2(SCH_1):GND    I43 @BASEBOARD_FAB2_LIB.BASEBOARD_FAB2(SCH_1):PAGE54
   156    GND @BASEBOARD_FAB2_LIB.BASEBOARD_FAB2(SCH_1):GND    I43 @BASEBOARD_FAB2_LIB.BASEBOARD_FAB2(SCH_1):PAGE54
   158    GND @BASEBOARD_FAB2_LIB.BASEBOARD_FAB2(SCH_1):GND    I43 @BASEBOARD_FAB2_LIB.BASEBOARD_FAB2(SCH_1):PAGE54
   160    GND @BASEBOARD_FAB2_LIB.BASEBOARD_FAB2(SCH_1):GND    I43 @BASEBOARD_FAB2_LIB.BASEBOARD_FAB2(SCH_1):PAGE54
   162    GND @BASEBOARD_FAB2_LIB.BASEBOARD_FAB2(SCH_1):GND    I43 @BASEBOARD_FAB2_LIB.BASEBOARD_FAB2(SCH_1):PAGE54
   165    GND @BASEBOARD_FAB2_LIB.BASEBOARD_FAB2(SCH_1):GND    I43 @BASEBOARD_FAB2_LIB.BASEBOARD_FAB2(SCH_1):PAGE54
   167    GND @BASEBOARD_FAB2_LIB.BASEBOARD_FAB2(SCH_1):GND    I43 @BASEBOARD_FAB2_LIB.BASEBOARD_FAB2(SCH_1):PAGE54
   169    GND @BASEBOARD_FAB2_LIB.BASEBOARD_FAB2(SCH_1):GND    I43 @BASEBOARD_FAB2_LIB.BASEBOARD_FAB2(SCH_1):PAGE54
   171    GND @BASEBOARD_FAB2_LIB.BASEBOARD_FAB2(SCH_1):GND    I43 @BASEBOARD_FAB2_LIB.BASEBOARD_FAB2(SCH_1):PAGE54
   173    GND @BASEBOARD_FAB2_LIB.BASEBOARD_FAB2(SCH_1):GND    I43 @BASEBOARD_FAB2_LIB.BASEBOARD_FAB2(SCH_1):PAGE54
   176    GND @BASEBOARD_FAB2_LIB.BASEBOARD_FAB2(SCH_1):GND    I43 @BASEBOARD_FAB2_LIB.BASEBOARD_FAB2(SCH_1):PAGE54
   178    GND @BASEBOARD_FAB2_LIB.BASEBOARD_FAB2(SCH_1):GND    I43 @BASEBOARD_FAB2_LIB.BASEBOARD_FAB2(SCH_1):PAGE54
   180    GND @BASEBOARD_FAB2_LIB.BASEBOARD_FAB2(SCH_1):GND    I43 @BASEBOARD_FAB2_LIB.BASEBOARD_FAB2(SCH_1):PAGE54
   182    GND @BASEBOARD_FAB2_LIB.BASEBOARD_FAB2(SCH_1):GND    I43 @BASEBOARD_FAB2_LIB.BASEBOARD_FAB2(SCH_1):PAGE54
   184    GND @BASEBOARD_FAB2_LIB.BASEBOARD_FAB2(SCH_1):GND    I43 @BASEBOARD_FAB2_LIB.BASEBOARD_FAB2(SCH_1):PAGE54
   187    GND @BASEBOARD_FAB2_LIB.BASEBOARD_FAB2(SCH_1):GND    I43 @BASEBOARD_FAB2_LIB.BASEBOARD_FAB2(SCH_1):PAGE54
   189    GND @BASEBOARD_FAB2_LIB.BASEBOARD_FAB2(SCH_1):GND    I43 @BASEBOARD_FAB2_LIB.BASEBOARD_FAB2(SCH_1):PAGE54
   191    GND @BASEBOARD_FAB2_LIB.BASEBOARD_FAB2(SCH_1):GND    I43 @BASEBOARD_FAB2_LIB.BASEBOARD_FAB2(SCH_1):PAGE54
   193    GND @BASEBOARD_FAB2_LIB.BASEBOARD_FAB2(SCH_1):GND    I43 @BASEBOARD_FAB2_LIB.BASEBOARD_FAB2(SCH_1):PAGE54
   195    GND @BASEBOARD_FAB2_LIB.BASEBOARD_FAB2(SCH_1):GND    I43 @BASEBOARD_FAB2_LIB.BASEBOARD_FAB2(SCH_1):PAGE54
   198    GND @BASEBOARD_FAB2_LIB.BASEBOARD_FAB2(SCH_1):GND    I43 @BASEBOARD_FAB2_LIB.BASEBOARD_FAB2(SCH_1):PAGE54
   200    GND @BASEBOARD_FAB2_LIB.BASEBOARD_FAB2(SCH_1):GND    I43 @BASEBOARD_FAB2_LIB.BASEBOARD_FAB2(SCH_1):PAGE54
   202    GND @BASEBOARD_FAB2_LIB.BASEBOARD_FAB2(SCH_1):GND    I43 @BASEBOARD_FAB2_LIB.BASEBOARD_FAB2(SCH_1):PAGE54
   239    GND @BASEBOARD_FAB2_LIB.BASEBOARD_FAB2(SCH_1):GND    I43 @BASEBOARD_FAB2_LIB.BASEBOARD_FAB2(SCH_1):PAGE54
   241    GND @BASEBOARD_FAB2_LIB.BASEBOARD_FAB2(SCH_1):GND    I43 @BASEBOARD_FAB2_LIB.BASEBOARD_FAB2(SCH_1):PAGE54
   243    GND @BASEBOARD_FAB2_LIB.BASEBOARD_FAB2(SCH_1):GND    I43 @BASEBOARD_FAB2_LIB.BASEBOARD_FAB2(SCH_1):PAGE54
   246    GND @BASEBOARD_FAB2_LIB.BASEBOARD_FAB2(SCH_1):GND    I43 @BASEBOARD_FAB2_LIB.BASEBOARD_FAB2(SCH_1):PAGE54
   248    GND @BASEBOARD_FAB2_LIB.BASEBOARD_FAB2(SCH_1):GND    I43 @BASEBOARD_FAB2_LIB.BASEBOARD_FAB2(SCH_1):PAGE54
   250    GND @BASEBOARD_FAB2_LIB.BASEBOARD_FAB2(SCH_1):GND    I43 @BASEBOARD_FAB2_LIB.BASEBOARD_FAB2(SCH_1):PAGE54
   252    GND @BASEBOARD_FAB2_LIB.BASEBOARD_FAB2(SCH_1):GND    I43 @BASEBOARD_FAB2_LIB.BASEBOARD_FAB2(SCH_1):PAGE54
   254    GND @BASEBOARD_FAB2_LIB.BASEBOARD_FAB2(SCH_1):GND    I43 @BASEBOARD_FAB2_LIB.BASEBOARD_FAB2(SCH_1):PAGE54
   257    GND @BASEBOARD_FAB2_LIB.BASEBOARD_FAB2(SCH_1):GND    I43 @BASEBOARD_FAB2_LIB.BASEBOARD_FAB2(SCH_1):PAGE54
   259    GND @BASEBOARD_FAB2_LIB.BASEBOARD_FAB2(SCH_1):GND    I43 @BASEBOARD_FAB2_LIB.BASEBOARD_FAB2(SCH_1):PAGE54
   261    GND @BASEBOARD_FAB2_LIB.BASEBOARD_FAB2(SCH_1):GND    I43 @BASEBOARD_FAB2_LIB.BASEBOARD_FAB2(SCH_1):PAGE54
   263    GND @BASEBOARD_FAB2_LIB.BASEBOARD_FAB2(SCH_1):GND    I43 @BASEBOARD_FAB2_LIB.BASEBOARD_FAB2(SCH_1):PAGE54
   265    GND @BASEBOARD_FAB2_LIB.BASEBOARD_FAB2(SCH_1):GND    I43 @BASEBOARD_FAB2_LIB.BASEBOARD_FAB2(SCH_1):PAGE54
   268    GND @BASEBOARD_FAB2_LIB.BASEBOARD_FAB2(SCH_1):GND    I43 @BASEBOARD_FAB2_LIB.BASEBOARD_FAB2(SCH_1):PAGE54
   270    GND @BASEBOARD_FAB2_LIB.BASEBOARD_FAB2(SCH_1):GND    I43 @BASEBOARD_FAB2_LIB.BASEBOARD_FAB2(SCH_1):PAGE54
   272    GND @BASEBOARD_FAB2_LIB.BASEBOARD_FAB2(SCH_1):GND    I43 @BASEBOARD_FAB2_LIB.BASEBOARD_FAB2(SCH_1):PAGE54
   274    GND @BASEBOARD_FAB2_LIB.BASEBOARD_FAB2(SCH_1):GND    I43 @BASEBOARD_FAB2_LIB.BASEBOARD_FAB2(SCH_1):PAGE54
   276    GND @BASEBOARD_FAB2_LIB.BASEBOARD_FAB2(SCH_1):GND    I43 @BASEBOARD_FAB2_LIB.BASEBOARD_FAB2(SCH_1):PAGE54
   279    GND @BASEBOARD_FAB2_LIB.BASEBOARD_FAB2(SCH_1):GND    I43 @BASEBOARD_FAB2_LIB.BASEBOARD_FAB2(SCH_1):PAGE54
   281    GND @BASEBOARD_FAB2_LIB.BASEBOARD_FAB2(SCH_1):GND    I43 @BASEBOARD_FAB2_LIB.BASEBOARD_FAB2(SCH_1):PAGE54
   283    GND @BASEBOARD_FAB2_LIB.BASEBOARD_FAB2(SCH_1):GND    I43 @BASEBOARD_FAB2_LIB.BASEBOARD_FAB2(SCH_1):PAGE54
     1 P12V_NVDIMM_DEF @BASEBOARD_FAB2_LIB.BASEBOARD_FAB2(SCH_1):P12V_NVDIMM_DEF   I170 @BASEBOARD_FAB2_LIB.BASEBOARD_FAB2(SCH_1):PAGE54
   145 P12V_NVDIMM_DEF @BASEBOARD_FAB2_LIB.BASEBOARD_FAB2(SCH_1):P12V_NVDIMM_DEF   I170 @BASEBOARD_FAB2_LIB.BASEBOARD_FAB2(SCH_1):PAGE54
    59 PVDDQ_DEF @BASEBOARD_FAB2_LIB.BASEBOARD_FAB2(SCH_1):PVDDQ_DEF   I170 @BASEBOARD_FAB2_LIB.BASEBOARD_FAB2(SCH_1):PAGE54
    61 PVDDQ_DEF @BASEBOARD_FAB2_LIB.BASEBOARD_FAB2(SCH_1):PVDDQ_DEF   I170 @BASEBOARD_FAB2_LIB.BASEBOARD_FAB2(SCH_1):PAGE54
    64 PVDDQ_DEF @BASEBOARD_FAB2_LIB.BASEBOARD_FAB2(SCH_1):PVDDQ_DEF   I170 @BASEBOARD_FAB2_LIB.BASEBOARD_FAB2(SCH_1):PAGE54
    67 PVDDQ_DEF @BASEBOARD_FAB2_LIB.BASEBOARD_FAB2(SCH_1):PVDDQ_DEF   I170 @BASEBOARD_FAB2_LIB.BASEBOARD_FAB2(SCH_1):PAGE54
    70 PVDDQ_DEF @BASEBOARD_FAB2_LIB.BASEBOARD_FAB2(SCH_1):PVDDQ_DEF   I170 @BASEBOARD_FAB2_LIB.BASEBOARD_FAB2(SCH_1):PAGE54
    73 PVDDQ_DEF @BASEBOARD_FAB2_LIB.BASEBOARD_FAB2(SCH_1):PVDDQ_DEF   I170 @BASEBOARD_FAB2_LIB.BASEBOARD_FAB2(SCH_1):PAGE54
    76 PVDDQ_DEF @BASEBOARD_FAB2_LIB.BASEBOARD_FAB2(SCH_1):PVDDQ_DEF   I170 @BASEBOARD_FAB2_LIB.BASEBOARD_FAB2(SCH_1):PAGE54
    80 PVDDQ_DEF @BASEBOARD_FAB2_LIB.BASEBOARD_FAB2(SCH_1):PVDDQ_DEF   I170 @BASEBOARD_FAB2_LIB.BASEBOARD_FAB2(SCH_1):PAGE54
    83 PVDDQ_DEF @BASEBOARD_FAB2_LIB.BASEBOARD_FAB2(SCH_1):PVDDQ_DEF   I170 @BASEBOARD_FAB2_LIB.BASEBOARD_FAB2(SCH_1):PAGE54
    85 PVDDQ_DEF @BASEBOARD_FAB2_LIB.BASEBOARD_FAB2(SCH_1):PVDDQ_DEF   I170 @BASEBOARD_FAB2_LIB.BASEBOARD_FAB2(SCH_1):PAGE54
    88 PVDDQ_DEF @BASEBOARD_FAB2_LIB.BASEBOARD_FAB2(SCH_1):PVDDQ_DEF   I170 @BASEBOARD_FAB2_LIB.BASEBOARD_FAB2(SCH_1):PAGE54
    90 PVDDQ_DEF @BASEBOARD_FAB2_LIB.BASEBOARD_FAB2(SCH_1):PVDDQ_DEF   I170 @BASEBOARD_FAB2_LIB.BASEBOARD_FAB2(SCH_1):PAGE54
    92 PVDDQ_DEF @BASEBOARD_FAB2_LIB.BASEBOARD_FAB2(SCH_1):PVDDQ_DEF   I170 @BASEBOARD_FAB2_LIB.BASEBOARD_FAB2(SCH_1):PAGE54
   204 PVDDQ_DEF @BASEBOARD_FAB2_LIB.BASEBOARD_FAB2(SCH_1):PVDDQ_DEF   I170 @BASEBOARD_FAB2_LIB.BASEBOARD_FAB2(SCH_1):PAGE54
   206 PVDDQ_DEF @BASEBOARD_FAB2_LIB.BASEBOARD_FAB2(SCH_1):PVDDQ_DEF   I170 @BASEBOARD_FAB2_LIB.BASEBOARD_FAB2(SCH_1):PAGE54
   209 PVDDQ_DEF @BASEBOARD_FAB2_LIB.BASEBOARD_FAB2(SCH_1):PVDDQ_DEF   I170 @BASEBOARD_FAB2_LIB.BASEBOARD_FAB2(SCH_1):PAGE54
   212 PVDDQ_DEF @BASEBOARD_FAB2_LIB.BASEBOARD_FAB2(SCH_1):PVDDQ_DEF   I170 @BASEBOARD_FAB2_LIB.BASEBOARD_FAB2(SCH_1):PAGE54
   215 PVDDQ_DEF @BASEBOARD_FAB2_LIB.BASEBOARD_FAB2(SCH_1):PVDDQ_DEF   I170 @BASEBOARD_FAB2_LIB.BASEBOARD_FAB2(SCH_1):PAGE54
   217 PVDDQ_DEF @BASEBOARD_FAB2_LIB.BASEBOARD_FAB2(SCH_1):PVDDQ_DEF   I170 @BASEBOARD_FAB2_LIB.BASEBOARD_FAB2(SCH_1):PAGE54
   220 PVDDQ_DEF @BASEBOARD_FAB2_LIB.BASEBOARD_FAB2(SCH_1):PVDDQ_DEF   I170 @BASEBOARD_FAB2_LIB.BASEBOARD_FAB2(SCH_1):PAGE54
   223 PVDDQ_DEF @BASEBOARD_FAB2_LIB.BASEBOARD_FAB2(SCH_1):PVDDQ_DEF   I170 @BASEBOARD_FAB2_LIB.BASEBOARD_FAB2(SCH_1):PAGE54
   226 PVDDQ_DEF @BASEBOARD_FAB2_LIB.BASEBOARD_FAB2(SCH_1):PVDDQ_DEF   I170 @BASEBOARD_FAB2_LIB.BASEBOARD_FAB2(SCH_1):PAGE54
   229 PVDDQ_DEF @BASEBOARD_FAB2_LIB.BASEBOARD_FAB2(SCH_1):PVDDQ_DEF   I170 @BASEBOARD_FAB2_LIB.BASEBOARD_FAB2(SCH_1):PAGE54
   231 PVDDQ_DEF @BASEBOARD_FAB2_LIB.BASEBOARD_FAB2(SCH_1):PVDDQ_DEF   I170 @BASEBOARD_FAB2_LIB.BASEBOARD_FAB2(SCH_1):PAGE54
   233 PVDDQ_DEF @BASEBOARD_FAB2_LIB.BASEBOARD_FAB2(SCH_1):PVDDQ_DEF   I170 @BASEBOARD_FAB2_LIB.BASEBOARD_FAB2(SCH_1):PAGE54
   236 PVDDQ_DEF @BASEBOARD_FAB2_LIB.BASEBOARD_FAB2(SCH_1):PVDDQ_DEF   I170 @BASEBOARD_FAB2_LIB.BASEBOARD_FAB2(SCH_1):PAGE54
   142 PVPP_DEF @BASEBOARD_FAB2_LIB.BASEBOARD_FAB2(SCH_1):PVPP_DEF   I170 @BASEBOARD_FAB2_LIB.BASEBOARD_FAB2(SCH_1):PAGE54
   143 PVPP_DEF @BASEBOARD_FAB2_LIB.BASEBOARD_FAB2(SCH_1):PVPP_DEF   I170 @BASEBOARD_FAB2_LIB.BASEBOARD_FAB2(SCH_1):PAGE54
   288 PVPP_DEF @BASEBOARD_FAB2_LIB.BASEBOARD_FAB2(SCH_1):PVPP_DEF   I170 @BASEBOARD_FAB2_LIB.BASEBOARD_FAB2(SCH_1):PAGE54
   286 PVPP_DEF @BASEBOARD_FAB2_LIB.BASEBOARD_FAB2(SCH_1):PVPP_DEF   I170 @BASEBOARD_FAB2_LIB.BASEBOARD_FAB2(SCH_1):PAGE54
   287 PVPP_DEF @BASEBOARD_FAB2_LIB.BASEBOARD_FAB2(SCH_1):PVPP_DEF   I170 @BASEBOARD_FAB2_LIB.BASEBOARD_FAB2(SCH_1):PAGE54
    77 PVTT_DEF @BASEBOARD_FAB2_LIB.BASEBOARD_FAB2(SCH_1):PVTT_DEF   I170 @BASEBOARD_FAB2_LIB.BASEBOARD_FAB2(SCH_1):PAGE54
   221 PVTT_DEF @BASEBOARD_FAB2_LIB.BASEBOARD_FAB2(SCH_1):PVTT_DEF   I170 @BASEBOARD_FAB2_LIB.BASEBOARD_FAB2(SCH_1):PAGE54

J6L2 SCONN288_H44441003_PIP-SCONN,HA
    79 M_E_MA<0> @BASEBOARD_FAB2_LIB.BASEBOARD_FAB2(SCH_1):M_E_MA(0)    I12 @BASEBOARD_FAB2_LIB.BASEBOARD_FAB2(SCH_1):PAGE52
    72 M_E_MA<1> @BASEBOARD_FAB2_LIB.BASEBOARD_FAB2(SCH_1):M_E_MA(1)    I12 @BASEBOARD_FAB2_LIB.BASEBOARD_FAB2(SCH_1):PAGE52
   225 M_E_MA<10> @BASEBOARD_FAB2_LIB.BASEBOARD_FAB2(SCH_1):M_E_MA(10)    I12 @BASEBOARD_FAB2_LIB.BASEBOARD_FAB2(SCH_1):PAGE52
   210 M_E_MA<11> @BASEBOARD_FAB2_LIB.BASEBOARD_FAB2(SCH_1):M_E_MA(11)    I12 @BASEBOARD_FAB2_LIB.BASEBOARD_FAB2(SCH_1):PAGE52
    65 M_E_MA<12> @BASEBOARD_FAB2_LIB.BASEBOARD_FAB2(SCH_1):M_E_MA(12)    I12 @BASEBOARD_FAB2_LIB.BASEBOARD_FAB2(SCH_1):PAGE52
   232 M_E_MA<13> @BASEBOARD_FAB2_LIB.BASEBOARD_FAB2(SCH_1):M_E_MA(13)    I12 @BASEBOARD_FAB2_LIB.BASEBOARD_FAB2(SCH_1):PAGE52
   228 M_E_MA<14> @BASEBOARD_FAB2_LIB.BASEBOARD_FAB2(SCH_1):M_E_MA(14)    I12 @BASEBOARD_FAB2_LIB.BASEBOARD_FAB2(SCH_1):PAGE52
    86 M_E_MA<15> @BASEBOARD_FAB2_LIB.BASEBOARD_FAB2(SCH_1):M_E_MA(15)    I12 @BASEBOARD_FAB2_LIB.BASEBOARD_FAB2(SCH_1):PAGE52
    82 M_E_MA<16> @BASEBOARD_FAB2_LIB.BASEBOARD_FAB2(SCH_1):M_E_MA(16)    I12 @BASEBOARD_FAB2_LIB.BASEBOARD_FAB2(SCH_1):PAGE52
   234 M_E_MA<17> @BASEBOARD_FAB2_LIB.BASEBOARD_FAB2(SCH_1):M_E_MA(17)    I12 @BASEBOARD_FAB2_LIB.BASEBOARD_FAB2(SCH_1):PAGE52
   216 M_E_MA<2> @BASEBOARD_FAB2_LIB.BASEBOARD_FAB2(SCH_1):M_E_MA(2)    I12 @BASEBOARD_FAB2_LIB.BASEBOARD_FAB2(SCH_1):PAGE52
    71 M_E_MA<3> @BASEBOARD_FAB2_LIB.BASEBOARD_FAB2(SCH_1):M_E_MA(3)    I12 @BASEBOARD_FAB2_LIB.BASEBOARD_FAB2(SCH_1):PAGE52
   214 M_E_MA<4> @BASEBOARD_FAB2_LIB.BASEBOARD_FAB2(SCH_1):M_E_MA(4)    I12 @BASEBOARD_FAB2_LIB.BASEBOARD_FAB2(SCH_1):PAGE52
   213 M_E_MA<5> @BASEBOARD_FAB2_LIB.BASEBOARD_FAB2(SCH_1):M_E_MA(5)    I12 @BASEBOARD_FAB2_LIB.BASEBOARD_FAB2(SCH_1):PAGE52
    69 M_E_MA<6> @BASEBOARD_FAB2_LIB.BASEBOARD_FAB2(SCH_1):M_E_MA(6)    I12 @BASEBOARD_FAB2_LIB.BASEBOARD_FAB2(SCH_1):PAGE52
   211 M_E_MA<7> @BASEBOARD_FAB2_LIB.BASEBOARD_FAB2(SCH_1):M_E_MA(7)    I12 @BASEBOARD_FAB2_LIB.BASEBOARD_FAB2(SCH_1):PAGE52
    68 M_E_MA<8> @BASEBOARD_FAB2_LIB.BASEBOARD_FAB2(SCH_1):M_E_MA(8)    I12 @BASEBOARD_FAB2_LIB.BASEBOARD_FAB2(SCH_1):PAGE52
    66 M_E_MA<9> @BASEBOARD_FAB2_LIB.BASEBOARD_FAB2(SCH_1):M_E_MA(9)    I12 @BASEBOARD_FAB2_LIB.BASEBOARD_FAB2(SCH_1):PAGE52
    62 M_E_ACT_N @BASEBOARD_FAB2_LIB.BASEBOARD_FAB2(SCH_1):M_E_ACT_N    I12 @BASEBOARD_FAB2_LIB.BASEBOARD_FAB2(SCH_1):PAGE52
   208 M_E_ALERT_N @BASEBOARD_FAB2_LIB.BASEBOARD_FAB2(SCH_1):M_E_ALERT_N    I12 @BASEBOARD_FAB2_LIB.BASEBOARD_FAB2(SCH_1):PAGE52
   224 M_E_BA<1> @BASEBOARD_FAB2_LIB.BASEBOARD_FAB2(SCH_1):M_E_BA(1)    I12 @BASEBOARD_FAB2_LIB.BASEBOARD_FAB2(SCH_1):PAGE52
    81 M_E_BA<0> @BASEBOARD_FAB2_LIB.BASEBOARD_FAB2(SCH_1):M_E_BA(0)    I12 @BASEBOARD_FAB2_LIB.BASEBOARD_FAB2(SCH_1):PAGE52
   207 M_E_BG<1> @BASEBOARD_FAB2_LIB.BASEBOARD_FAB2(SCH_1):M_E_BG(1)    I12 @BASEBOARD_FAB2_LIB.BASEBOARD_FAB2(SCH_1):PAGE52
    63 M_E_BG<0> @BASEBOARD_FAB2_LIB.BASEBOARD_FAB2(SCH_1):M_E_BG(0)    I12 @BASEBOARD_FAB2_LIB.BASEBOARD_FAB2(SCH_1):PAGE52
   235 M_E_C<2> @BASEBOARD_FAB2_LIB.BASEBOARD_FAB2(SCH_1):M_E_C(2)    I12 @BASEBOARD_FAB2_LIB.BASEBOARD_FAB2(SCH_1):PAGE52
   199 M_E_ECC<7> @BASEBOARD_FAB2_LIB.BASEBOARD_FAB2(SCH_1):M_E_ECC(7)    I12 @BASEBOARD_FAB2_LIB.BASEBOARD_FAB2(SCH_1):PAGE52
    54 M_E_ECC<6> @BASEBOARD_FAB2_LIB.BASEBOARD_FAB2(SCH_1):M_E_ECC(6)    I12 @BASEBOARD_FAB2_LIB.BASEBOARD_FAB2(SCH_1):PAGE52
   192 M_E_ECC<5> @BASEBOARD_FAB2_LIB.BASEBOARD_FAB2(SCH_1):M_E_ECC(5)    I12 @BASEBOARD_FAB2_LIB.BASEBOARD_FAB2(SCH_1):PAGE52
    47 M_E_ECC<4> @BASEBOARD_FAB2_LIB.BASEBOARD_FAB2(SCH_1):M_E_ECC(4)    I12 @BASEBOARD_FAB2_LIB.BASEBOARD_FAB2(SCH_1):PAGE52
   201 M_E_ECC<3> @BASEBOARD_FAB2_LIB.BASEBOARD_FAB2(SCH_1):M_E_ECC(3)    I12 @BASEBOARD_FAB2_LIB.BASEBOARD_FAB2(SCH_1):PAGE52
    56 M_E_ECC<2> @BASEBOARD_FAB2_LIB.BASEBOARD_FAB2(SCH_1):M_E_ECC(2)    I12 @BASEBOARD_FAB2_LIB.BASEBOARD_FAB2(SCH_1):PAGE52
   194 M_E_ECC<1> @BASEBOARD_FAB2_LIB.BASEBOARD_FAB2(SCH_1):M_E_ECC(1)    I12 @BASEBOARD_FAB2_LIB.BASEBOARD_FAB2(SCH_1):PAGE52
    49 M_E_ECC<0> @BASEBOARD_FAB2_LIB.BASEBOARD_FAB2(SCH_1):M_E_ECC(0)    I12 @BASEBOARD_FAB2_LIB.BASEBOARD_FAB2(SCH_1):PAGE52
    75 M_E_CLK_DN<2> @BASEBOARD_FAB2_LIB.BASEBOARD_FAB2(SCH_1):M_E_CLK_DN(2)    I12 @BASEBOARD_FAB2_LIB.BASEBOARD_FAB2(SCH_1):PAGE52
    74 M_E_CLK_DP<2> @BASEBOARD_FAB2_LIB.BASEBOARD_FAB2(SCH_1):M_E_CLK_DP(2)    I12 @BASEBOARD_FAB2_LIB.BASEBOARD_FAB2(SCH_1):PAGE52
   219 M_E_CLK_DN<3> @BASEBOARD_FAB2_LIB.BASEBOARD_FAB2(SCH_1):M_E_CLK_DN(3)    I12 @BASEBOARD_FAB2_LIB.BASEBOARD_FAB2(SCH_1):PAGE52
   218 M_E_CLK_DP<3> @BASEBOARD_FAB2_LIB.BASEBOARD_FAB2(SCH_1):M_E_CLK_DP(3)    I12 @BASEBOARD_FAB2_LIB.BASEBOARD_FAB2(SCH_1):PAGE52
   203 M_E_CKE<3> @BASEBOARD_FAB2_LIB.BASEBOARD_FAB2(SCH_1):M_E_CKE(3)    I12 @BASEBOARD_FAB2_LIB.BASEBOARD_FAB2(SCH_1):PAGE52
    60 M_E_CKE<2> @BASEBOARD_FAB2_LIB.BASEBOARD_FAB2(SCH_1):M_E_CKE(2)    I12 @BASEBOARD_FAB2_LIB.BASEBOARD_FAB2(SCH_1):PAGE52
   280 M_E_DQ<63> @BASEBOARD_FAB2_LIB.BASEBOARD_FAB2(SCH_1):M_E_DQ(63)    I12 @BASEBOARD_FAB2_LIB.BASEBOARD_FAB2(SCH_1):PAGE52
   135 M_E_DQ<62> @BASEBOARD_FAB2_LIB.BASEBOARD_FAB2(SCH_1):M_E_DQ(62)    I12 @BASEBOARD_FAB2_LIB.BASEBOARD_FAB2(SCH_1):PAGE52
   273 M_E_DQ<61> @BASEBOARD_FAB2_LIB.BASEBOARD_FAB2(SCH_1):M_E_DQ(61)    I12 @BASEBOARD_FAB2_LIB.BASEBOARD_FAB2(SCH_1):PAGE52
   128 M_E_DQ<60> @BASEBOARD_FAB2_LIB.BASEBOARD_FAB2(SCH_1):M_E_DQ(60)    I12 @BASEBOARD_FAB2_LIB.BASEBOARD_FAB2(SCH_1):PAGE52
   282 M_E_DQ<59> @BASEBOARD_FAB2_LIB.BASEBOARD_FAB2(SCH_1):M_E_DQ(59)    I12 @BASEBOARD_FAB2_LIB.BASEBOARD_FAB2(SCH_1):PAGE52
   137 M_E_DQ<58> @BASEBOARD_FAB2_LIB.BASEBOARD_FAB2(SCH_1):M_E_DQ(58)    I12 @BASEBOARD_FAB2_LIB.BASEBOARD_FAB2(SCH_1):PAGE52
   275 M_E_DQ<57> @BASEBOARD_FAB2_LIB.BASEBOARD_FAB2(SCH_1):M_E_DQ(57)    I12 @BASEBOARD_FAB2_LIB.BASEBOARD_FAB2(SCH_1):PAGE52
   130 M_E_DQ<56> @BASEBOARD_FAB2_LIB.BASEBOARD_FAB2(SCH_1):M_E_DQ(56)    I12 @BASEBOARD_FAB2_LIB.BASEBOARD_FAB2(SCH_1):PAGE52
   269 M_E_DQ<55> @BASEBOARD_FAB2_LIB.BASEBOARD_FAB2(SCH_1):M_E_DQ(55)    I12 @BASEBOARD_FAB2_LIB.BASEBOARD_FAB2(SCH_1):PAGE52
   124 M_E_DQ<54> @BASEBOARD_FAB2_LIB.BASEBOARD_FAB2(SCH_1):M_E_DQ(54)    I12 @BASEBOARD_FAB2_LIB.BASEBOARD_FAB2(SCH_1):PAGE52
   262 M_E_DQ<53> @BASEBOARD_FAB2_LIB.BASEBOARD_FAB2(SCH_1):M_E_DQ(53)    I12 @BASEBOARD_FAB2_LIB.BASEBOARD_FAB2(SCH_1):PAGE52
   117 M_E_DQ<52> @BASEBOARD_FAB2_LIB.BASEBOARD_FAB2(SCH_1):M_E_DQ(52)    I12 @BASEBOARD_FAB2_LIB.BASEBOARD_FAB2(SCH_1):PAGE52
   271 M_E_DQ<51> @BASEBOARD_FAB2_LIB.BASEBOARD_FAB2(SCH_1):M_E_DQ(51)    I12 @BASEBOARD_FAB2_LIB.BASEBOARD_FAB2(SCH_1):PAGE52
   126 M_E_DQ<50> @BASEBOARD_FAB2_LIB.BASEBOARD_FAB2(SCH_1):M_E_DQ(50)    I12 @BASEBOARD_FAB2_LIB.BASEBOARD_FAB2(SCH_1):PAGE52
   264 M_E_DQ<49> @BASEBOARD_FAB2_LIB.BASEBOARD_FAB2(SCH_1):M_E_DQ(49)    I12 @BASEBOARD_FAB2_LIB.BASEBOARD_FAB2(SCH_1):PAGE52
   119 M_E_DQ<48> @BASEBOARD_FAB2_LIB.BASEBOARD_FAB2(SCH_1):M_E_DQ(48)    I12 @BASEBOARD_FAB2_LIB.BASEBOARD_FAB2(SCH_1):PAGE52
   258 M_E_DQ<47> @BASEBOARD_FAB2_LIB.BASEBOARD_FAB2(SCH_1):M_E_DQ(47)    I12 @BASEBOARD_FAB2_LIB.BASEBOARD_FAB2(SCH_1):PAGE52
   113 M_E_DQ<46> @BASEBOARD_FAB2_LIB.BASEBOARD_FAB2(SCH_1):M_E_DQ(46)    I12 @BASEBOARD_FAB2_LIB.BASEBOARD_FAB2(SCH_1):PAGE52
   251 M_E_DQ<45> @BASEBOARD_FAB2_LIB.BASEBOARD_FAB2(SCH_1):M_E_DQ(45)    I12 @BASEBOARD_FAB2_LIB.BASEBOARD_FAB2(SCH_1):PAGE52
   106 M_E_DQ<44> @BASEBOARD_FAB2_LIB.BASEBOARD_FAB2(SCH_1):M_E_DQ(44)    I12 @BASEBOARD_FAB2_LIB.BASEBOARD_FAB2(SCH_1):PAGE52
   260 M_E_DQ<43> @BASEBOARD_FAB2_LIB.BASEBOARD_FAB2(SCH_1):M_E_DQ(43)    I12 @BASEBOARD_FAB2_LIB.BASEBOARD_FAB2(SCH_1):PAGE52
   115 M_E_DQ<42> @BASEBOARD_FAB2_LIB.BASEBOARD_FAB2(SCH_1):M_E_DQ(42)    I12 @BASEBOARD_FAB2_LIB.BASEBOARD_FAB2(SCH_1):PAGE52
   253 M_E_DQ<41> @BASEBOARD_FAB2_LIB.BASEBOARD_FAB2(SCH_1):M_E_DQ(41)    I12 @BASEBOARD_FAB2_LIB.BASEBOARD_FAB2(SCH_1):PAGE52
   108 M_E_DQ<40> @BASEBOARD_FAB2_LIB.BASEBOARD_FAB2(SCH_1):M_E_DQ(40)    I12 @BASEBOARD_FAB2_LIB.BASEBOARD_FAB2(SCH_1):PAGE52
   247 M_E_DQ<39> @BASEBOARD_FAB2_LIB.BASEBOARD_FAB2(SCH_1):M_E_DQ(39)    I12 @BASEBOARD_FAB2_LIB.BASEBOARD_FAB2(SCH_1):PAGE52
   102 M_E_DQ<38> @BASEBOARD_FAB2_LIB.BASEBOARD_FAB2(SCH_1):M_E_DQ(38)    I12 @BASEBOARD_FAB2_LIB.BASEBOARD_FAB2(SCH_1):PAGE52
   240 M_E_DQ<37> @BASEBOARD_FAB2_LIB.BASEBOARD_FAB2(SCH_1):M_E_DQ(37)    I12 @BASEBOARD_FAB2_LIB.BASEBOARD_FAB2(SCH_1):PAGE52
    95 M_E_DQ<36> @BASEBOARD_FAB2_LIB.BASEBOARD_FAB2(SCH_1):M_E_DQ(36)    I12 @BASEBOARD_FAB2_LIB.BASEBOARD_FAB2(SCH_1):PAGE52
   249 M_E_DQ<35> @BASEBOARD_FAB2_LIB.BASEBOARD_FAB2(SCH_1):M_E_DQ(35)    I12 @BASEBOARD_FAB2_LIB.BASEBOARD_FAB2(SCH_1):PAGE52
   104 M_E_DQ<34> @BASEBOARD_FAB2_LIB.BASEBOARD_FAB2(SCH_1):M_E_DQ(34)    I12 @BASEBOARD_FAB2_LIB.BASEBOARD_FAB2(SCH_1):PAGE52
   242 M_E_DQ<33> @BASEBOARD_FAB2_LIB.BASEBOARD_FAB2(SCH_1):M_E_DQ(33)    I12 @BASEBOARD_FAB2_LIB.BASEBOARD_FAB2(SCH_1):PAGE52
    97 M_E_DQ<32> @BASEBOARD_FAB2_LIB.BASEBOARD_FAB2(SCH_1):M_E_DQ(32)    I12 @BASEBOARD_FAB2_LIB.BASEBOARD_FAB2(SCH_1):PAGE52
   188 M_E_DQ<31> @BASEBOARD_FAB2_LIB.BASEBOARD_FAB2(SCH_1):M_E_DQ(31)    I12 @BASEBOARD_FAB2_LIB.BASEBOARD_FAB2(SCH_1):PAGE52
    43 M_E_DQ<30> @BASEBOARD_FAB2_LIB.BASEBOARD_FAB2(SCH_1):M_E_DQ(30)    I12 @BASEBOARD_FAB2_LIB.BASEBOARD_FAB2(SCH_1):PAGE52
   181 M_E_DQ<29> @BASEBOARD_FAB2_LIB.BASEBOARD_FAB2(SCH_1):M_E_DQ(29)    I12 @BASEBOARD_FAB2_LIB.BASEBOARD_FAB2(SCH_1):PAGE52
    36 M_E_DQ<28> @BASEBOARD_FAB2_LIB.BASEBOARD_FAB2(SCH_1):M_E_DQ(28)    I12 @BASEBOARD_FAB2_LIB.BASEBOARD_FAB2(SCH_1):PAGE52
   190 M_E_DQ<27> @BASEBOARD_FAB2_LIB.BASEBOARD_FAB2(SCH_1):M_E_DQ(27)    I12 @BASEBOARD_FAB2_LIB.BASEBOARD_FAB2(SCH_1):PAGE52
    45 M_E_DQ<26> @BASEBOARD_FAB2_LIB.BASEBOARD_FAB2(SCH_1):M_E_DQ(26)    I12 @BASEBOARD_FAB2_LIB.BASEBOARD_FAB2(SCH_1):PAGE52
   183 M_E_DQ<25> @BASEBOARD_FAB2_LIB.BASEBOARD_FAB2(SCH_1):M_E_DQ(25)    I12 @BASEBOARD_FAB2_LIB.BASEBOARD_FAB2(SCH_1):PAGE52
    38 M_E_DQ<24> @BASEBOARD_FAB2_LIB.BASEBOARD_FAB2(SCH_1):M_E_DQ(24)    I12 @BASEBOARD_FAB2_LIB.BASEBOARD_FAB2(SCH_1):PAGE52
   177 M_E_DQ<23> @BASEBOARD_FAB2_LIB.BASEBOARD_FAB2(SCH_1):M_E_DQ(23)    I12 @BASEBOARD_FAB2_LIB.BASEBOARD_FAB2(SCH_1):PAGE52
    32 M_E_DQ<22> @BASEBOARD_FAB2_LIB.BASEBOARD_FAB2(SCH_1):M_E_DQ(22)    I12 @BASEBOARD_FAB2_LIB.BASEBOARD_FAB2(SCH_1):PAGE52
   170 M_E_DQ<21> @BASEBOARD_FAB2_LIB.BASEBOARD_FAB2(SCH_1):M_E_DQ(21)    I12 @BASEBOARD_FAB2_LIB.BASEBOARD_FAB2(SCH_1):PAGE52
    25 M_E_DQ<20> @BASEBOARD_FAB2_LIB.BASEBOARD_FAB2(SCH_1):M_E_DQ(20)    I12 @BASEBOARD_FAB2_LIB.BASEBOARD_FAB2(SCH_1):PAGE52
   179 M_E_DQ<19> @BASEBOARD_FAB2_LIB.BASEBOARD_FAB2(SCH_1):M_E_DQ(19)    I12 @BASEBOARD_FAB2_LIB.BASEBOARD_FAB2(SCH_1):PAGE52
    34 M_E_DQ<18> @BASEBOARD_FAB2_LIB.BASEBOARD_FAB2(SCH_1):M_E_DQ(18)    I12 @BASEBOARD_FAB2_LIB.BASEBOARD_FAB2(SCH_1):PAGE52
   172 M_E_DQ<17> @BASEBOARD_FAB2_LIB.BASEBOARD_FAB2(SCH_1):M_E_DQ(17)    I12 @BASEBOARD_FAB2_LIB.BASEBOARD_FAB2(SCH_1):PAGE52
    27 M_E_DQ<16> @BASEBOARD_FAB2_LIB.BASEBOARD_FAB2(SCH_1):M_E_DQ(16)    I12 @BASEBOARD_FAB2_LIB.BASEBOARD_FAB2(SCH_1):PAGE52
   166 M_E_DQ<15> @BASEBOARD_FAB2_LIB.BASEBOARD_FAB2(SCH_1):M_E_DQ(15)    I12 @BASEBOARD_FAB2_LIB.BASEBOARD_FAB2(SCH_1):PAGE52
    21 M_E_DQ<14> @BASEBOARD_FAB2_LIB.BASEBOARD_FAB2(SCH_1):M_E_DQ(14)    I12 @BASEBOARD_FAB2_LIB.BASEBOARD_FAB2(SCH_1):PAGE52
   159 M_E_DQ<13> @BASEBOARD_FAB2_LIB.BASEBOARD_FAB2(SCH_1):M_E_DQ(13)    I12 @BASEBOARD_FAB2_LIB.BASEBOARD_FAB2(SCH_1):PAGE52
    14 M_E_DQ<12> @BASEBOARD_FAB2_LIB.BASEBOARD_FAB2(SCH_1):M_E_DQ(12)    I12 @BASEBOARD_FAB2_LIB.BASEBOARD_FAB2(SCH_1):PAGE52
   168 M_E_DQ<11> @BASEBOARD_FAB2_LIB.BASEBOARD_FAB2(SCH_1):M_E_DQ(11)    I12 @BASEBOARD_FAB2_LIB.BASEBOARD_FAB2(SCH_1):PAGE52
    23 M_E_DQ<10> @BASEBOARD_FAB2_LIB.BASEBOARD_FAB2(SCH_1):M_E_DQ(10)    I12 @BASEBOARD_FAB2_LIB.BASEBOARD_FAB2(SCH_1):PAGE52
   161 M_E_DQ<9> @BASEBOARD_FAB2_LIB.BASEBOARD_FAB2(SCH_1):M_E_DQ(9)    I12 @BASEBOARD_FAB2_LIB.BASEBOARD_FAB2(SCH_1):PAGE52
    16 M_E_DQ<8> @BASEBOARD_FAB2_LIB.BASEBOARD_FAB2(SCH_1):M_E_DQ(8)    I12 @BASEBOARD_FAB2_LIB.BASEBOARD_FAB2(SCH_1):PAGE52
   155 M_E_DQ<7> @BASEBOARD_FAB2_LIB.BASEBOARD_FAB2(SCH_1):M_E_DQ(7)    I12 @BASEBOARD_FAB2_LIB.BASEBOARD_FAB2(SCH_1):PAGE52
    10 M_E_DQ<6> @BASEBOARD_FAB2_LIB.BASEBOARD_FAB2(SCH_1):M_E_DQ(6)    I12 @BASEBOARD_FAB2_LIB.BASEBOARD_FAB2(SCH_1):PAGE52
   148 M_E_DQ<5> @BASEBOARD_FAB2_LIB.BASEBOARD_FAB2(SCH_1):M_E_DQ(5)    I12 @BASEBOARD_FAB2_LIB.BASEBOARD_FAB2(SCH_1):PAGE52
     3 M_E_DQ<4> @BASEBOARD_FAB2_LIB.BASEBOARD_FAB2(SCH_1):M_E_DQ(4)    I12 @BASEBOARD_FAB2_LIB.BASEBOARD_FAB2(SCH_1):PAGE52
   157 M_E_DQ<3> @BASEBOARD_FAB2_LIB.BASEBOARD_FAB2(SCH_1):M_E_DQ(3)    I12 @BASEBOARD_FAB2_LIB.BASEBOARD_FAB2(SCH_1):PAGE52
    12 M_E_DQ<2> @BASEBOARD_FAB2_LIB.BASEBOARD_FAB2(SCH_1):M_E_DQ(2)    I12 @BASEBOARD_FAB2_LIB.BASEBOARD_FAB2(SCH_1):PAGE52
   150 M_E_DQ<1> @BASEBOARD_FAB2_LIB.BASEBOARD_FAB2(SCH_1):M_E_DQ(1)    I12 @BASEBOARD_FAB2_LIB.BASEBOARD_FAB2(SCH_1):PAGE52
     5 M_E_DQ<0> @BASEBOARD_FAB2_LIB.BASEBOARD_FAB2(SCH_1):M_E_DQ(0)    I12 @BASEBOARD_FAB2_LIB.BASEBOARD_FAB2(SCH_1):PAGE52
    78 FM_DIMM_EVENT_COD_N @BASEBOARD_FAB2_LIB.BASEBOARD_FAB2(SCH_1):FM_DIMM_EVENT_COD_N    I12 @BASEBOARD_FAB2_LIB.BASEBOARD_FAB2(SCH_1):PAGE52
    91 M_E_ODT<3> @BASEBOARD_FAB2_LIB.BASEBOARD_FAB2(SCH_1):M_E_ODT(3)    I12 @BASEBOARD_FAB2_LIB.BASEBOARD_FAB2(SCH_1):PAGE52
    87 M_E_ODT<2> @BASEBOARD_FAB2_LIB.BASEBOARD_FAB2(SCH_1):M_E_ODT(2)    I12 @BASEBOARD_FAB2_LIB.BASEBOARD_FAB2(SCH_1):PAGE52
   222 M_E_PAR @BASEBOARD_FAB2_LIB.BASEBOARD_FAB2(SCH_1):M_E_PAR    I12 @BASEBOARD_FAB2_LIB.BASEBOARD_FAB2(SCH_1):PAGE52
    58 M_DEF_RST_N @BASEBOARD_FAB2_LIB.BASEBOARD_FAB2(SCH_1):M_DEF_RST_N    I12 @BASEBOARD_FAB2_LIB.BASEBOARD_FAB2(SCH_1):PAGE52
   144 TP_CH_E_DIMM_E1_RFU_2 @BASEBOARD_FAB2_LIB.BASEBOARD_FAB2(SCH_1):TP_CH_E_DIMM_E1_RFU_2    I12 @BASEBOARD_FAB2_LIB.BASEBOARD_FAB2(SCH_1):PAGE52
   227 TP_CH_E_DIMM_E1_RFU_1 @BASEBOARD_FAB2_LIB.BASEBOARD_FAB2(SCH_1):TP_CH_E_DIMM_E1_RFU_1    I12 @BASEBOARD_FAB2_LIB.BASEBOARD_FAB2(SCH_1):PAGE52
   205 TP_CH_E_DIMM_E1_RFU_0 @BASEBOARD_FAB2_LIB.BASEBOARD_FAB2(SCH_1):TP_CH_E_DIMM_E1_RFU_0    I12 @BASEBOARD_FAB2_LIB.BASEBOARD_FAB2(SCH_1):PAGE52
    84 M_E_CS_N<4> @BASEBOARD_FAB2_LIB.BASEBOARD_FAB2(SCH_1):M_E_CS_N(4)    I12 @BASEBOARD_FAB2_LIB.BASEBOARD_FAB2(SCH_1):PAGE52
    89 M_E_CS_N<5> @BASEBOARD_FAB2_LIB.BASEBOARD_FAB2(SCH_1):M_E_CS_N(5)    I12 @BASEBOARD_FAB2_LIB.BASEBOARD_FAB2(SCH_1):PAGE52
    93 M_E_CS_N<6> @BASEBOARD_FAB2_LIB.BASEBOARD_FAB2(SCH_1):M_E_CS_N(6)    I12 @BASEBOARD_FAB2_LIB.BASEBOARD_FAB2(SCH_1):PAGE52
   237 M_E_CS_N<7> @BASEBOARD_FAB2_LIB.BASEBOARD_FAB2(SCH_1):M_E_CS_N(7)    I12 @BASEBOARD_FAB2_LIB.BASEBOARD_FAB2(SCH_1):PAGE52
   238    GND @BASEBOARD_FAB2_LIB.BASEBOARD_FAB2(SCH_1):GND    I12 @BASEBOARD_FAB2_LIB.BASEBOARD_FAB2(SCH_1):PAGE52
   140 PVPP_DEF @BASEBOARD_FAB2_LIB.BASEBOARD_FAB2(SCH_1):PVPP_DEF    I12 @BASEBOARD_FAB2_LIB.BASEBOARD_FAB2(SCH_1):PAGE52
   139 PVPP_DEF @BASEBOARD_FAB2_LIB.BASEBOARD_FAB2(SCH_1):PVPP_DEF    I12 @BASEBOARD_FAB2_LIB.BASEBOARD_FAB2(SCH_1):PAGE52
   230 FM_ADR_COMPLETE_DEF_N @BASEBOARD_FAB2_LIB.BASEBOARD_FAB2(SCH_1):FM_ADR_COMPLETE_DEF_N    I12 @BASEBOARD_FAB2_LIB.BASEBOARD_FAB2(SCH_1):PAGE52
   141 SMB_DDR_DEF_VPP_SCL @BASEBOARD_FAB2_LIB.BASEBOARD_FAB2(SCH_1):SMB_DDR_DEF_VPP_SCL    I12 @BASEBOARD_FAB2_LIB.BASEBOARD_FAB2(SCH_1):PAGE52
   285 SMB_DDR_DEF_VPP_SDA @BASEBOARD_FAB2_LIB.BASEBOARD_FAB2(SCH_1):SMB_DDR_DEF_VPP_SDA    I12 @BASEBOARD_FAB2_LIB.BASEBOARD_FAB2(SCH_1):PAGE52
   284 PVPP_DEF @BASEBOARD_FAB2_LIB.BASEBOARD_FAB2(SCH_1):PVPP_DEF    I12 @BASEBOARD_FAB2_LIB.BASEBOARD_FAB2(SCH_1):PAGE52
   146 M_E_VREF @BASEBOARD_FAB2_LIB.BASEBOARD_FAB2(SCH_1):M_E_VREF    I12 @BASEBOARD_FAB2_LIB.BASEBOARD_FAB2(SCH_1):PAGE52
   152 M_E_DQS_DN<0> @BASEBOARD_FAB2_LIB.BASEBOARD_FAB2(SCH_1):M_E_DQS_DN(0)   I100 @BASEBOARD_FAB2_LIB.BASEBOARD_FAB2(SCH_1):PAGE52
   153 M_E_DQS_DP<0> @BASEBOARD_FAB2_LIB.BASEBOARD_FAB2(SCH_1):M_E_DQS_DP(0)   I100 @BASEBOARD_FAB2_LIB.BASEBOARD_FAB2(SCH_1):PAGE52
    19 M_E_DQS_DN<10> @BASEBOARD_FAB2_LIB.BASEBOARD_FAB2(SCH_1):M_E_DQS_DN(10)   I100 @BASEBOARD_FAB2_LIB.BASEBOARD_FAB2(SCH_1):PAGE52
    18 M_E_DQS_DP<10> @BASEBOARD_FAB2_LIB.BASEBOARD_FAB2(SCH_1):M_E_DQS_DP(10)   I100 @BASEBOARD_FAB2_LIB.BASEBOARD_FAB2(SCH_1):PAGE52
    30 M_E_DQS_DN<11> @BASEBOARD_FAB2_LIB.BASEBOARD_FAB2(SCH_1):M_E_DQS_DN(11)   I100 @BASEBOARD_FAB2_LIB.BASEBOARD_FAB2(SCH_1):PAGE52
    29 M_E_DQS_DP<11> @BASEBOARD_FAB2_LIB.BASEBOARD_FAB2(SCH_1):M_E_DQS_DP(11)   I100 @BASEBOARD_FAB2_LIB.BASEBOARD_FAB2(SCH_1):PAGE52
    41 M_E_DQS_DN<12> @BASEBOARD_FAB2_LIB.BASEBOARD_FAB2(SCH_1):M_E_DQS_DN(12)   I100 @BASEBOARD_FAB2_LIB.BASEBOARD_FAB2(SCH_1):PAGE52
    40 M_E_DQS_DP<12> @BASEBOARD_FAB2_LIB.BASEBOARD_FAB2(SCH_1):M_E_DQS_DP(12)   I100 @BASEBOARD_FAB2_LIB.BASEBOARD_FAB2(SCH_1):PAGE52
   100 M_E_DQS_DN<13> @BASEBOARD_FAB2_LIB.BASEBOARD_FAB2(SCH_1):M_E_DQS_DN(13)   I100 @BASEBOARD_FAB2_LIB.BASEBOARD_FAB2(SCH_1):PAGE52
    99 M_E_DQS_DP<13> @BASEBOARD_FAB2_LIB.BASEBOARD_FAB2(SCH_1):M_E_DQS_DP(13)   I100 @BASEBOARD_FAB2_LIB.BASEBOARD_FAB2(SCH_1):PAGE52
   111 M_E_DQS_DN<14> @BASEBOARD_FAB2_LIB.BASEBOARD_FAB2(SCH_1):M_E_DQS_DN(14)   I100 @BASEBOARD_FAB2_LIB.BASEBOARD_FAB2(SCH_1):PAGE52
   110 M_E_DQS_DP<14> @BASEBOARD_FAB2_LIB.BASEBOARD_FAB2(SCH_1):M_E_DQS_DP(14)   I100 @BASEBOARD_FAB2_LIB.BASEBOARD_FAB2(SCH_1):PAGE52
   122 M_E_DQS_DN<15> @BASEBOARD_FAB2_LIB.BASEBOARD_FAB2(SCH_1):M_E_DQS_DN(15)   I100 @BASEBOARD_FAB2_LIB.BASEBOARD_FAB2(SCH_1):PAGE52
   121 M_E_DQS_DP<15> @BASEBOARD_FAB2_LIB.BASEBOARD_FAB2(SCH_1):M_E_DQS_DP(15)   I100 @BASEBOARD_FAB2_LIB.BASEBOARD_FAB2(SCH_1):PAGE52
   133 M_E_DQS_DN<16> @BASEBOARD_FAB2_LIB.BASEBOARD_FAB2(SCH_1):M_E_DQS_DN(16)   I100 @BASEBOARD_FAB2_LIB.BASEBOARD_FAB2(SCH_1):PAGE52
   132 M_E_DQS_DP<16> @BASEBOARD_FAB2_LIB.BASEBOARD_FAB2(SCH_1):M_E_DQS_DP(16)   I100 @BASEBOARD_FAB2_LIB.BASEBOARD_FAB2(SCH_1):PAGE52
    52 M_E_DQS_DN<17> @BASEBOARD_FAB2_LIB.BASEBOARD_FAB2(SCH_1):M_E_DQS_DN(17)   I100 @BASEBOARD_FAB2_LIB.BASEBOARD_FAB2(SCH_1):PAGE52
    51 M_E_DQS_DP<17> @BASEBOARD_FAB2_LIB.BASEBOARD_FAB2(SCH_1):M_E_DQS_DP(17)   I100 @BASEBOARD_FAB2_LIB.BASEBOARD_FAB2(SCH_1):PAGE52
   163 M_E_DQS_DN<1> @BASEBOARD_FAB2_LIB.BASEBOARD_FAB2(SCH_1):M_E_DQS_DN(1)   I100 @BASEBOARD_FAB2_LIB.BASEBOARD_FAB2(SCH_1):PAGE52
   164 M_E_DQS_DP<1> @BASEBOARD_FAB2_LIB.BASEBOARD_FAB2(SCH_1):M_E_DQS_DP(1)   I100 @BASEBOARD_FAB2_LIB.BASEBOARD_FAB2(SCH_1):PAGE52
   174 M_E_DQS_DN<2> @BASEBOARD_FAB2_LIB.BASEBOARD_FAB2(SCH_1):M_E_DQS_DN(2)   I100 @BASEBOARD_FAB2_LIB.BASEBOARD_FAB2(SCH_1):PAGE52
   175 M_E_DQS_DP<2> @BASEBOARD_FAB2_LIB.BASEBOARD_FAB2(SCH_1):M_E_DQS_DP(2)   I100 @BASEBOARD_FAB2_LIB.BASEBOARD_FAB2(SCH_1):PAGE52
   185 M_E_DQS_DN<3> @BASEBOARD_FAB2_LIB.BASEBOARD_FAB2(SCH_1):M_E_DQS_DN(3)   I100 @BASEBOARD_FAB2_LIB.BASEBOARD_FAB2(SCH_1):PAGE52
   186 M_E_DQS_DP<3> @BASEBOARD_FAB2_LIB.BASEBOARD_FAB2(SCH_1):M_E_DQS_DP(3)   I100 @BASEBOARD_FAB2_LIB.BASEBOARD_FAB2(SCH_1):PAGE52
   244 M_E_DQS_DN<4> @BASEBOARD_FAB2_LIB.BASEBOARD_FAB2(SCH_1):M_E_DQS_DN(4)   I100 @BASEBOARD_FAB2_LIB.BASEBOARD_FAB2(SCH_1):PAGE52
   245 M_E_DQS_DP<4> @BASEBOARD_FAB2_LIB.BASEBOARD_FAB2(SCH_1):M_E_DQS_DP(4)   I100 @BASEBOARD_FAB2_LIB.BASEBOARD_FAB2(SCH_1):PAGE52
   255 M_E_DQS_DN<5> @BASEBOARD_FAB2_LIB.BASEBOARD_FAB2(SCH_1):M_E_DQS_DN(5)   I100 @BASEBOARD_FAB2_LIB.BASEBOARD_FAB2(SCH_1):PAGE52
   256 M_E_DQS_DP<5> @BASEBOARD_FAB2_LIB.BASEBOARD_FAB2(SCH_1):M_E_DQS_DP(5)   I100 @BASEBOARD_FAB2_LIB.BASEBOARD_FAB2(SCH_1):PAGE52
   266 M_E_DQS_DN<6> @BASEBOARD_FAB2_LIB.BASEBOARD_FAB2(SCH_1):M_E_DQS_DN(6)   I100 @BASEBOARD_FAB2_LIB.BASEBOARD_FAB2(SCH_1):PAGE52
   267 M_E_DQS_DP<6> @BASEBOARD_FAB2_LIB.BASEBOARD_FAB2(SCH_1):M_E_DQS_DP(6)   I100 @BASEBOARD_FAB2_LIB.BASEBOARD_FAB2(SCH_1):PAGE52
   277 M_E_DQS_DN<7> @BASEBOARD_FAB2_LIB.BASEBOARD_FAB2(SCH_1):M_E_DQS_DN(7)   I100 @BASEBOARD_FAB2_LIB.BASEBOARD_FAB2(SCH_1):PAGE52
   278 M_E_DQS_DP<7> @BASEBOARD_FAB2_LIB.BASEBOARD_FAB2(SCH_1):M_E_DQS_DP(7)   I100 @BASEBOARD_FAB2_LIB.BASEBOARD_FAB2(SCH_1):PAGE52
   196 M_E_DQS_DN<8> @BASEBOARD_FAB2_LIB.BASEBOARD_FAB2(SCH_1):M_E_DQS_DN(8)   I100 @BASEBOARD_FAB2_LIB.BASEBOARD_FAB2(SCH_1):PAGE52
   197 M_E_DQS_DP<8> @BASEBOARD_FAB2_LIB.BASEBOARD_FAB2(SCH_1):M_E_DQS_DP(8)   I100 @BASEBOARD_FAB2_LIB.BASEBOARD_FAB2(SCH_1):PAGE52
     8 M_E_DQS_DN<9> @BASEBOARD_FAB2_LIB.BASEBOARD_FAB2(SCH_1):M_E_DQS_DN(9)   I100 @BASEBOARD_FAB2_LIB.BASEBOARD_FAB2(SCH_1):PAGE52
     7 M_E_DQS_DP<9> @BASEBOARD_FAB2_LIB.BASEBOARD_FAB2(SCH_1):M_E_DQS_DP(9)   I100 @BASEBOARD_FAB2_LIB.BASEBOARD_FAB2(SCH_1):PAGE52
     2    GND @BASEBOARD_FAB2_LIB.BASEBOARD_FAB2(SCH_1):GND   I138 @BASEBOARD_FAB2_LIB.BASEBOARD_FAB2(SCH_1):PAGE52
     4    GND @BASEBOARD_FAB2_LIB.BASEBOARD_FAB2(SCH_1):GND   I138 @BASEBOARD_FAB2_LIB.BASEBOARD_FAB2(SCH_1):PAGE52
     6    GND @BASEBOARD_FAB2_LIB.BASEBOARD_FAB2(SCH_1):GND   I138 @BASEBOARD_FAB2_LIB.BASEBOARD_FAB2(SCH_1):PAGE52
     9    GND @BASEBOARD_FAB2_LIB.BASEBOARD_FAB2(SCH_1):GND   I138 @BASEBOARD_FAB2_LIB.BASEBOARD_FAB2(SCH_1):PAGE52
    11    GND @BASEBOARD_FAB2_LIB.BASEBOARD_FAB2(SCH_1):GND   I138 @BASEBOARD_FAB2_LIB.BASEBOARD_FAB2(SCH_1):PAGE52
    13    GND @BASEBOARD_FAB2_LIB.BASEBOARD_FAB2(SCH_1):GND   I138 @BASEBOARD_FAB2_LIB.BASEBOARD_FAB2(SCH_1):PAGE52
    15    GND @BASEBOARD_FAB2_LIB.BASEBOARD_FAB2(SCH_1):GND   I138 @BASEBOARD_FAB2_LIB.BASEBOARD_FAB2(SCH_1):PAGE52
    17    GND @BASEBOARD_FAB2_LIB.BASEBOARD_FAB2(SCH_1):GND   I138 @BASEBOARD_FAB2_LIB.BASEBOARD_FAB2(SCH_1):PAGE52
    20    GND @BASEBOARD_FAB2_LIB.BASEBOARD_FAB2(SCH_1):GND   I138 @BASEBOARD_FAB2_LIB.BASEBOARD_FAB2(SCH_1):PAGE52
    22    GND @BASEBOARD_FAB2_LIB.BASEBOARD_FAB2(SCH_1):GND   I138 @BASEBOARD_FAB2_LIB.BASEBOARD_FAB2(SCH_1):PAGE52
    24    GND @BASEBOARD_FAB2_LIB.BASEBOARD_FAB2(SCH_1):GND   I138 @BASEBOARD_FAB2_LIB.BASEBOARD_FAB2(SCH_1):PAGE52
    26    GND @BASEBOARD_FAB2_LIB.BASEBOARD_FAB2(SCH_1):GND   I138 @BASEBOARD_FAB2_LIB.BASEBOARD_FAB2(SCH_1):PAGE52
    28    GND @BASEBOARD_FAB2_LIB.BASEBOARD_FAB2(SCH_1):GND   I138 @BASEBOARD_FAB2_LIB.BASEBOARD_FAB2(SCH_1):PAGE52
    31    GND @BASEBOARD_FAB2_LIB.BASEBOARD_FAB2(SCH_1):GND   I138 @BASEBOARD_FAB2_LIB.BASEBOARD_FAB2(SCH_1):PAGE52
    33    GND @BASEBOARD_FAB2_LIB.BASEBOARD_FAB2(SCH_1):GND   I138 @BASEBOARD_FAB2_LIB.BASEBOARD_FAB2(SCH_1):PAGE52
    35    GND @BASEBOARD_FAB2_LIB.BASEBOARD_FAB2(SCH_1):GND   I138 @BASEBOARD_FAB2_LIB.BASEBOARD_FAB2(SCH_1):PAGE52
    37    GND @BASEBOARD_FAB2_LIB.BASEBOARD_FAB2(SCH_1):GND   I138 @BASEBOARD_FAB2_LIB.BASEBOARD_FAB2(SCH_1):PAGE52
    39    GND @BASEBOARD_FAB2_LIB.BASEBOARD_FAB2(SCH_1):GND   I138 @BASEBOARD_FAB2_LIB.BASEBOARD_FAB2(SCH_1):PAGE52
    42    GND @BASEBOARD_FAB2_LIB.BASEBOARD_FAB2(SCH_1):GND   I138 @BASEBOARD_FAB2_LIB.BASEBOARD_FAB2(SCH_1):PAGE52
    44    GND @BASEBOARD_FAB2_LIB.BASEBOARD_FAB2(SCH_1):GND   I138 @BASEBOARD_FAB2_LIB.BASEBOARD_FAB2(SCH_1):PAGE52
    46    GND @BASEBOARD_FAB2_LIB.BASEBOARD_FAB2(SCH_1):GND   I138 @BASEBOARD_FAB2_LIB.BASEBOARD_FAB2(SCH_1):PAGE52
    48    GND @BASEBOARD_FAB2_LIB.BASEBOARD_FAB2(SCH_1):GND   I138 @BASEBOARD_FAB2_LIB.BASEBOARD_FAB2(SCH_1):PAGE52
    50    GND @BASEBOARD_FAB2_LIB.BASEBOARD_FAB2(SCH_1):GND   I138 @BASEBOARD_FAB2_LIB.BASEBOARD_FAB2(SCH_1):PAGE52
    53    GND @BASEBOARD_FAB2_LIB.BASEBOARD_FAB2(SCH_1):GND   I138 @BASEBOARD_FAB2_LIB.BASEBOARD_FAB2(SCH_1):PAGE52
    55    GND @BASEBOARD_FAB2_LIB.BASEBOARD_FAB2(SCH_1):GND   I138 @BASEBOARD_FAB2_LIB.BASEBOARD_FAB2(SCH_1):PAGE52
    57    GND @BASEBOARD_FAB2_LIB.BASEBOARD_FAB2(SCH_1):GND   I138 @BASEBOARD_FAB2_LIB.BASEBOARD_FAB2(SCH_1):PAGE52
    94    GND @BASEBOARD_FAB2_LIB.BASEBOARD_FAB2(SCH_1):GND   I138 @BASEBOARD_FAB2_LIB.BASEBOARD_FAB2(SCH_1):PAGE52
    96    GND @BASEBOARD_FAB2_LIB.BASEBOARD_FAB2(SCH_1):GND   I138 @BASEBOARD_FAB2_LIB.BASEBOARD_FAB2(SCH_1):PAGE52
    98    GND @BASEBOARD_FAB2_LIB.BASEBOARD_FAB2(SCH_1):GND   I138 @BASEBOARD_FAB2_LIB.BASEBOARD_FAB2(SCH_1):PAGE52
   101    GND @BASEBOARD_FAB2_LIB.BASEBOARD_FAB2(SCH_1):GND   I138 @BASEBOARD_FAB2_LIB.BASEBOARD_FAB2(SCH_1):PAGE52
   103    GND @BASEBOARD_FAB2_LIB.BASEBOARD_FAB2(SCH_1):GND   I138 @BASEBOARD_FAB2_LIB.BASEBOARD_FAB2(SCH_1):PAGE52
   105    GND @BASEBOARD_FAB2_LIB.BASEBOARD_FAB2(SCH_1):GND   I138 @BASEBOARD_FAB2_LIB.BASEBOARD_FAB2(SCH_1):PAGE52
   107    GND @BASEBOARD_FAB2_LIB.BASEBOARD_FAB2(SCH_1):GND   I138 @BASEBOARD_FAB2_LIB.BASEBOARD_FAB2(SCH_1):PAGE52
   109    GND @BASEBOARD_FAB2_LIB.BASEBOARD_FAB2(SCH_1):GND   I138 @BASEBOARD_FAB2_LIB.BASEBOARD_FAB2(SCH_1):PAGE52
   112    GND @BASEBOARD_FAB2_LIB.BASEBOARD_FAB2(SCH_1):GND   I138 @BASEBOARD_FAB2_LIB.BASEBOARD_FAB2(SCH_1):PAGE52
   114    GND @BASEBOARD_FAB2_LIB.BASEBOARD_FAB2(SCH_1):GND   I138 @BASEBOARD_FAB2_LIB.BASEBOARD_FAB2(SCH_1):PAGE52
   116    GND @BASEBOARD_FAB2_LIB.BASEBOARD_FAB2(SCH_1):GND   I138 @BASEBOARD_FAB2_LIB.BASEBOARD_FAB2(SCH_1):PAGE52
   118    GND @BASEBOARD_FAB2_LIB.BASEBOARD_FAB2(SCH_1):GND   I138 @BASEBOARD_FAB2_LIB.BASEBOARD_FAB2(SCH_1):PAGE52
   120    GND @BASEBOARD_FAB2_LIB.BASEBOARD_FAB2(SCH_1):GND   I138 @BASEBOARD_FAB2_LIB.BASEBOARD_FAB2(SCH_1):PAGE52
   123    GND @BASEBOARD_FAB2_LIB.BASEBOARD_FAB2(SCH_1):GND   I138 @BASEBOARD_FAB2_LIB.BASEBOARD_FAB2(SCH_1):PAGE52
   125    GND @BASEBOARD_FAB2_LIB.BASEBOARD_FAB2(SCH_1):GND   I138 @BASEBOARD_FAB2_LIB.BASEBOARD_FAB2(SCH_1):PAGE52
   127    GND @BASEBOARD_FAB2_LIB.BASEBOARD_FAB2(SCH_1):GND   I138 @BASEBOARD_FAB2_LIB.BASEBOARD_FAB2(SCH_1):PAGE52
   129    GND @BASEBOARD_FAB2_LIB.BASEBOARD_FAB2(SCH_1):GND   I138 @BASEBOARD_FAB2_LIB.BASEBOARD_FAB2(SCH_1):PAGE52
   131    GND @BASEBOARD_FAB2_LIB.BASEBOARD_FAB2(SCH_1):GND   I138 @BASEBOARD_FAB2_LIB.BASEBOARD_FAB2(SCH_1):PAGE52
   134    GND @BASEBOARD_FAB2_LIB.BASEBOARD_FAB2(SCH_1):GND   I138 @BASEBOARD_FAB2_LIB.BASEBOARD_FAB2(SCH_1):PAGE52
   136    GND @BASEBOARD_FAB2_LIB.BASEBOARD_FAB2(SCH_1):GND   I138 @BASEBOARD_FAB2_LIB.BASEBOARD_FAB2(SCH_1):PAGE52
   138    GND @BASEBOARD_FAB2_LIB.BASEBOARD_FAB2(SCH_1):GND   I138 @BASEBOARD_FAB2_LIB.BASEBOARD_FAB2(SCH_1):PAGE52
   147    GND @BASEBOARD_FAB2_LIB.BASEBOARD_FAB2(SCH_1):GND   I138 @BASEBOARD_FAB2_LIB.BASEBOARD_FAB2(SCH_1):PAGE52
   149    GND @BASEBOARD_FAB2_LIB.BASEBOARD_FAB2(SCH_1):GND   I138 @BASEBOARD_FAB2_LIB.BASEBOARD_FAB2(SCH_1):PAGE52
   151    GND @BASEBOARD_FAB2_LIB.BASEBOARD_FAB2(SCH_1):GND   I138 @BASEBOARD_FAB2_LIB.BASEBOARD_FAB2(SCH_1):PAGE52
   154    GND @BASEBOARD_FAB2_LIB.BASEBOARD_FAB2(SCH_1):GND   I138 @BASEBOARD_FAB2_LIB.BASEBOARD_FAB2(SCH_1):PAGE52
   156    GND @BASEBOARD_FAB2_LIB.BASEBOARD_FAB2(SCH_1):GND   I138 @BASEBOARD_FAB2_LIB.BASEBOARD_FAB2(SCH_1):PAGE52
   158    GND @BASEBOARD_FAB2_LIB.BASEBOARD_FAB2(SCH_1):GND   I138 @BASEBOARD_FAB2_LIB.BASEBOARD_FAB2(SCH_1):PAGE52
   160    GND @BASEBOARD_FAB2_LIB.BASEBOARD_FAB2(SCH_1):GND   I138 @BASEBOARD_FAB2_LIB.BASEBOARD_FAB2(SCH_1):PAGE52
   162    GND @BASEBOARD_FAB2_LIB.BASEBOARD_FAB2(SCH_1):GND   I138 @BASEBOARD_FAB2_LIB.BASEBOARD_FAB2(SCH_1):PAGE52
   165    GND @BASEBOARD_FAB2_LIB.BASEBOARD_FAB2(SCH_1):GND   I138 @BASEBOARD_FAB2_LIB.BASEBOARD_FAB2(SCH_1):PAGE52
   167    GND @BASEBOARD_FAB2_LIB.BASEBOARD_FAB2(SCH_1):GND   I138 @BASEBOARD_FAB2_LIB.BASEBOARD_FAB2(SCH_1):PAGE52
   169    GND @BASEBOARD_FAB2_LIB.BASEBOARD_FAB2(SCH_1):GND   I138 @BASEBOARD_FAB2_LIB.BASEBOARD_FAB2(SCH_1):PAGE52
   171    GND @BASEBOARD_FAB2_LIB.BASEBOARD_FAB2(SCH_1):GND   I138 @BASEBOARD_FAB2_LIB.BASEBOARD_FAB2(SCH_1):PAGE52
   173    GND @BASEBOARD_FAB2_LIB.BASEBOARD_FAB2(SCH_1):GND   I138 @BASEBOARD_FAB2_LIB.BASEBOARD_FAB2(SCH_1):PAGE52
   176    GND @BASEBOARD_FAB2_LIB.BASEBOARD_FAB2(SCH_1):GND   I138 @BASEBOARD_FAB2_LIB.BASEBOARD_FAB2(SCH_1):PAGE52
   178    GND @BASEBOARD_FAB2_LIB.BASEBOARD_FAB2(SCH_1):GND   I138 @BASEBOARD_FAB2_LIB.BASEBOARD_FAB2(SCH_1):PAGE52
   180    GND @BASEBOARD_FAB2_LIB.BASEBOARD_FAB2(SCH_1):GND   I138 @BASEBOARD_FAB2_LIB.BASEBOARD_FAB2(SCH_1):PAGE52
   182    GND @BASEBOARD_FAB2_LIB.BASEBOARD_FAB2(SCH_1):GND   I138 @BASEBOARD_FAB2_LIB.BASEBOARD_FAB2(SCH_1):PAGE52
   184    GND @BASEBOARD_FAB2_LIB.BASEBOARD_FAB2(SCH_1):GND   I138 @BASEBOARD_FAB2_LIB.BASEBOARD_FAB2(SCH_1):PAGE52
   187    GND @BASEBOARD_FAB2_LIB.BASEBOARD_FAB2(SCH_1):GND   I138 @BASEBOARD_FAB2_LIB.BASEBOARD_FAB2(SCH_1):PAGE52
   189    GND @BASEBOARD_FAB2_LIB.BASEBOARD_FAB2(SCH_1):GND   I138 @BASEBOARD_FAB2_LIB.BASEBOARD_FAB2(SCH_1):PAGE52
   191    GND @BASEBOARD_FAB2_LIB.BASEBOARD_FAB2(SCH_1):GND   I138 @BASEBOARD_FAB2_LIB.BASEBOARD_FAB2(SCH_1):PAGE52
   193    GND @BASEBOARD_FAB2_LIB.BASEBOARD_FAB2(SCH_1):GND   I138 @BASEBOARD_FAB2_LIB.BASEBOARD_FAB2(SCH_1):PAGE52
   195    GND @BASEBOARD_FAB2_LIB.BASEBOARD_FAB2(SCH_1):GND   I138 @BASEBOARD_FAB2_LIB.BASEBOARD_FAB2(SCH_1):PAGE52
   198    GND @BASEBOARD_FAB2_LIB.BASEBOARD_FAB2(SCH_1):GND   I138 @BASEBOARD_FAB2_LIB.BASEBOARD_FAB2(SCH_1):PAGE52
   200    GND @BASEBOARD_FAB2_LIB.BASEBOARD_FAB2(SCH_1):GND   I138 @BASEBOARD_FAB2_LIB.BASEBOARD_FAB2(SCH_1):PAGE52
   202    GND @BASEBOARD_FAB2_LIB.BASEBOARD_FAB2(SCH_1):GND   I138 @BASEBOARD_FAB2_LIB.BASEBOARD_FAB2(SCH_1):PAGE52
   239    GND @BASEBOARD_FAB2_LIB.BASEBOARD_FAB2(SCH_1):GND   I138 @BASEBOARD_FAB2_LIB.BASEBOARD_FAB2(SCH_1):PAGE52
   241    GND @BASEBOARD_FAB2_LIB.BASEBOARD_FAB2(SCH_1):GND   I138 @BASEBOARD_FAB2_LIB.BASEBOARD_FAB2(SCH_1):PAGE52
   243    GND @BASEBOARD_FAB2_LIB.BASEBOARD_FAB2(SCH_1):GND   I138 @BASEBOARD_FAB2_LIB.BASEBOARD_FAB2(SCH_1):PAGE52
   246    GND @BASEBOARD_FAB2_LIB.BASEBOARD_FAB2(SCH_1):GND   I138 @BASEBOARD_FAB2_LIB.BASEBOARD_FAB2(SCH_1):PAGE52
   248    GND @BASEBOARD_FAB2_LIB.BASEBOARD_FAB2(SCH_1):GND   I138 @BASEBOARD_FAB2_LIB.BASEBOARD_FAB2(SCH_1):PAGE52
   250    GND @BASEBOARD_FAB2_LIB.BASEBOARD_FAB2(SCH_1):GND   I138 @BASEBOARD_FAB2_LIB.BASEBOARD_FAB2(SCH_1):PAGE52
   252    GND @BASEBOARD_FAB2_LIB.BASEBOARD_FAB2(SCH_1):GND   I138 @BASEBOARD_FAB2_LIB.BASEBOARD_FAB2(SCH_1):PAGE52
   254    GND @BASEBOARD_FAB2_LIB.BASEBOARD_FAB2(SCH_1):GND   I138 @BASEBOARD_FAB2_LIB.BASEBOARD_FAB2(SCH_1):PAGE52
   257    GND @BASEBOARD_FAB2_LIB.BASEBOARD_FAB2(SCH_1):GND   I138 @BASEBOARD_FAB2_LIB.BASEBOARD_FAB2(SCH_1):PAGE52
   259    GND @BASEBOARD_FAB2_LIB.BASEBOARD_FAB2(SCH_1):GND   I138 @BASEBOARD_FAB2_LIB.BASEBOARD_FAB2(SCH_1):PAGE52
   261    GND @BASEBOARD_FAB2_LIB.BASEBOARD_FAB2(SCH_1):GND   I138 @BASEBOARD_FAB2_LIB.BASEBOARD_FAB2(SCH_1):PAGE52
   263    GND @BASEBOARD_FAB2_LIB.BASEBOARD_FAB2(SCH_1):GND   I138 @BASEBOARD_FAB2_LIB.BASEBOARD_FAB2(SCH_1):PAGE52
   265    GND @BASEBOARD_FAB2_LIB.BASEBOARD_FAB2(SCH_1):GND   I138 @BASEBOARD_FAB2_LIB.BASEBOARD_FAB2(SCH_1):PAGE52
   268    GND @BASEBOARD_FAB2_LIB.BASEBOARD_FAB2(SCH_1):GND   I138 @BASEBOARD_FAB2_LIB.BASEBOARD_FAB2(SCH_1):PAGE52
   270    GND @BASEBOARD_FAB2_LIB.BASEBOARD_FAB2(SCH_1):GND   I138 @BASEBOARD_FAB2_LIB.BASEBOARD_FAB2(SCH_1):PAGE52
   272    GND @BASEBOARD_FAB2_LIB.BASEBOARD_FAB2(SCH_1):GND   I138 @BASEBOARD_FAB2_LIB.BASEBOARD_FAB2(SCH_1):PAGE52
   274    GND @BASEBOARD_FAB2_LIB.BASEBOARD_FAB2(SCH_1):GND   I138 @BASEBOARD_FAB2_LIB.BASEBOARD_FAB2(SCH_1):PAGE52
   276    GND @BASEBOARD_FAB2_LIB.BASEBOARD_FAB2(SCH_1):GND   I138 @BASEBOARD_FAB2_LIB.BASEBOARD_FAB2(SCH_1):PAGE52
   279    GND @BASEBOARD_FAB2_LIB.BASEBOARD_FAB2(SCH_1):GND   I138 @BASEBOARD_FAB2_LIB.BASEBOARD_FAB2(SCH_1):PAGE52
   281    GND @BASEBOARD_FAB2_LIB.BASEBOARD_FAB2(SCH_1):GND   I138 @BASEBOARD_FAB2_LIB.BASEBOARD_FAB2(SCH_1):PAGE52
   283    GND @BASEBOARD_FAB2_LIB.BASEBOARD_FAB2(SCH_1):GND   I138 @BASEBOARD_FAB2_LIB.BASEBOARD_FAB2(SCH_1):PAGE52
     1 P12V_NVDIMM_DEF @BASEBOARD_FAB2_LIB.BASEBOARD_FAB2(SCH_1):P12V_NVDIMM_DEF    I55 @BASEBOARD_FAB2_LIB.BASEBOARD_FAB2(SCH_1):PAGE52
   145 P12V_NVDIMM_DEF @BASEBOARD_FAB2_LIB.BASEBOARD_FAB2(SCH_1):P12V_NVDIMM_DEF    I55 @BASEBOARD_FAB2_LIB.BASEBOARD_FAB2(SCH_1):PAGE52
    59 PVDDQ_DEF @BASEBOARD_FAB2_LIB.BASEBOARD_FAB2(SCH_1):PVDDQ_DEF    I55 @BASEBOARD_FAB2_LIB.BASEBOARD_FAB2(SCH_1):PAGE52
    61 PVDDQ_DEF @BASEBOARD_FAB2_LIB.BASEBOARD_FAB2(SCH_1):PVDDQ_DEF    I55 @BASEBOARD_FAB2_LIB.BASEBOARD_FAB2(SCH_1):PAGE52
    64 PVDDQ_DEF @BASEBOARD_FAB2_LIB.BASEBOARD_FAB2(SCH_1):PVDDQ_DEF    I55 @BASEBOARD_FAB2_LIB.BASEBOARD_FAB2(SCH_1):PAGE52
    67 PVDDQ_DEF @BASEBOARD_FAB2_LIB.BASEBOARD_FAB2(SCH_1):PVDDQ_DEF    I55 @BASEBOARD_FAB2_LIB.BASEBOARD_FAB2(SCH_1):PAGE52
    70 PVDDQ_DEF @BASEBOARD_FAB2_LIB.BASEBOARD_FAB2(SCH_1):PVDDQ_DEF    I55 @BASEBOARD_FAB2_LIB.BASEBOARD_FAB2(SCH_1):PAGE52
    73 PVDDQ_DEF @BASEBOARD_FAB2_LIB.BASEBOARD_FAB2(SCH_1):PVDDQ_DEF    I55 @BASEBOARD_FAB2_LIB.BASEBOARD_FAB2(SCH_1):PAGE52
    76 PVDDQ_DEF @BASEBOARD_FAB2_LIB.BASEBOARD_FAB2(SCH_1):PVDDQ_DEF    I55 @BASEBOARD_FAB2_LIB.BASEBOARD_FAB2(SCH_1):PAGE52
    80 PVDDQ_DEF @BASEBOARD_FAB2_LIB.BASEBOARD_FAB2(SCH_1):PVDDQ_DEF    I55 @BASEBOARD_FAB2_LIB.BASEBOARD_FAB2(SCH_1):PAGE52
    83 PVDDQ_DEF @BASEBOARD_FAB2_LIB.BASEBOARD_FAB2(SCH_1):PVDDQ_DEF    I55 @BASEBOARD_FAB2_LIB.BASEBOARD_FAB2(SCH_1):PAGE52
    85 PVDDQ_DEF @BASEBOARD_FAB2_LIB.BASEBOARD_FAB2(SCH_1):PVDDQ_DEF    I55 @BASEBOARD_FAB2_LIB.BASEBOARD_FAB2(SCH_1):PAGE52
    88 PVDDQ_DEF @BASEBOARD_FAB2_LIB.BASEBOARD_FAB2(SCH_1):PVDDQ_DEF    I55 @BASEBOARD_FAB2_LIB.BASEBOARD_FAB2(SCH_1):PAGE52
    90 PVDDQ_DEF @BASEBOARD_FAB2_LIB.BASEBOARD_FAB2(SCH_1):PVDDQ_DEF    I55 @BASEBOARD_FAB2_LIB.BASEBOARD_FAB2(SCH_1):PAGE52
    92 PVDDQ_DEF @BASEBOARD_FAB2_LIB.BASEBOARD_FAB2(SCH_1):PVDDQ_DEF    I55 @BASEBOARD_FAB2_LIB.BASEBOARD_FAB2(SCH_1):PAGE52
   204 PVDDQ_DEF @BASEBOARD_FAB2_LIB.BASEBOARD_FAB2(SCH_1):PVDDQ_DEF    I55 @BASEBOARD_FAB2_LIB.BASEBOARD_FAB2(SCH_1):PAGE52
   206 PVDDQ_DEF @BASEBOARD_FAB2_LIB.BASEBOARD_FAB2(SCH_1):PVDDQ_DEF    I55 @BASEBOARD_FAB2_LIB.BASEBOARD_FAB2(SCH_1):PAGE52
   209 PVDDQ_DEF @BASEBOARD_FAB2_LIB.BASEBOARD_FAB2(SCH_1):PVDDQ_DEF    I55 @BASEBOARD_FAB2_LIB.BASEBOARD_FAB2(SCH_1):PAGE52
   212 PVDDQ_DEF @BASEBOARD_FAB2_LIB.BASEBOARD_FAB2(SCH_1):PVDDQ_DEF    I55 @BASEBOARD_FAB2_LIB.BASEBOARD_FAB2(SCH_1):PAGE52
   215 PVDDQ_DEF @BASEBOARD_FAB2_LIB.BASEBOARD_FAB2(SCH_1):PVDDQ_DEF    I55 @BASEBOARD_FAB2_LIB.BASEBOARD_FAB2(SCH_1):PAGE52
   217 PVDDQ_DEF @BASEBOARD_FAB2_LIB.BASEBOARD_FAB2(SCH_1):PVDDQ_DEF    I55 @BASEBOARD_FAB2_LIB.BASEBOARD_FAB2(SCH_1):PAGE52
   220 PVDDQ_DEF @BASEBOARD_FAB2_LIB.BASEBOARD_FAB2(SCH_1):PVDDQ_DEF    I55 @BASEBOARD_FAB2_LIB.BASEBOARD_FAB2(SCH_1):PAGE52
   223 PVDDQ_DEF @BASEBOARD_FAB2_LIB.BASEBOARD_FAB2(SCH_1):PVDDQ_DEF    I55 @BASEBOARD_FAB2_LIB.BASEBOARD_FAB2(SCH_1):PAGE52
   226 PVDDQ_DEF @BASEBOARD_FAB2_LIB.BASEBOARD_FAB2(SCH_1):PVDDQ_DEF    I55 @BASEBOARD_FAB2_LIB.BASEBOARD_FAB2(SCH_1):PAGE52
   229 PVDDQ_DEF @BASEBOARD_FAB2_LIB.BASEBOARD_FAB2(SCH_1):PVDDQ_DEF    I55 @BASEBOARD_FAB2_LIB.BASEBOARD_FAB2(SCH_1):PAGE52
   231 PVDDQ_DEF @BASEBOARD_FAB2_LIB.BASEBOARD_FAB2(SCH_1):PVDDQ_DEF    I55 @BASEBOARD_FAB2_LIB.BASEBOARD_FAB2(SCH_1):PAGE52
   233 PVDDQ_DEF @BASEBOARD_FAB2_LIB.BASEBOARD_FAB2(SCH_1):PVDDQ_DEF    I55 @BASEBOARD_FAB2_LIB.BASEBOARD_FAB2(SCH_1):PAGE52
   236 PVDDQ_DEF @BASEBOARD_FAB2_LIB.BASEBOARD_FAB2(SCH_1):PVDDQ_DEF    I55 @BASEBOARD_FAB2_LIB.BASEBOARD_FAB2(SCH_1):PAGE52
   142 PVPP_DEF @BASEBOARD_FAB2_LIB.BASEBOARD_FAB2(SCH_1):PVPP_DEF    I55 @BASEBOARD_FAB2_LIB.BASEBOARD_FAB2(SCH_1):PAGE52
   143 PVPP_DEF @BASEBOARD_FAB2_LIB.BASEBOARD_FAB2(SCH_1):PVPP_DEF    I55 @BASEBOARD_FAB2_LIB.BASEBOARD_FAB2(SCH_1):PAGE52
   288 PVPP_DEF @BASEBOARD_FAB2_LIB.BASEBOARD_FAB2(SCH_1):PVPP_DEF    I55 @BASEBOARD_FAB2_LIB.BASEBOARD_FAB2(SCH_1):PAGE52
   286 PVPP_DEF @BASEBOARD_FAB2_LIB.BASEBOARD_FAB2(SCH_1):PVPP_DEF    I55 @BASEBOARD_FAB2_LIB.BASEBOARD_FAB2(SCH_1):PAGE52
   287 PVPP_DEF @BASEBOARD_FAB2_LIB.BASEBOARD_FAB2(SCH_1):PVPP_DEF    I55 @BASEBOARD_FAB2_LIB.BASEBOARD_FAB2(SCH_1):PAGE52
    77 PVTT_DEF @BASEBOARD_FAB2_LIB.BASEBOARD_FAB2(SCH_1):PVTT_DEF    I55 @BASEBOARD_FAB2_LIB.BASEBOARD_FAB2(SCH_1):PAGE52
   221 PVTT_DEF @BASEBOARD_FAB2_LIB.BASEBOARD_FAB2(SCH_1):PVTT_DEF    I55 @BASEBOARD_FAB2_LIB.BASEBOARD_FAB2(SCH_1):PAGE52

J6M1 SCONN288_H44441003_PIP-SCONN,HA
    79 M_D_MA<0> @BASEBOARD_FAB2_LIB.BASEBOARD_FAB2(SCH_1):M_D_MA(0)   I158 @BASEBOARD_FAB2_LIB.BASEBOARD_FAB2(SCH_1):PAGE50
    72 M_D_MA<1> @BASEBOARD_FAB2_LIB.BASEBOARD_FAB2(SCH_1):M_D_MA(1)   I158 @BASEBOARD_FAB2_LIB.BASEBOARD_FAB2(SCH_1):PAGE50
   225 M_D_MA<10> @BASEBOARD_FAB2_LIB.BASEBOARD_FAB2(SCH_1):M_D_MA(10)   I158 @BASEBOARD_FAB2_LIB.BASEBOARD_FAB2(SCH_1):PAGE50
   210 M_D_MA<11> @BASEBOARD_FAB2_LIB.BASEBOARD_FAB2(SCH_1):M_D_MA(11)   I158 @BASEBOARD_FAB2_LIB.BASEBOARD_FAB2(SCH_1):PAGE50
    65 M_D_MA<12> @BASEBOARD_FAB2_LIB.BASEBOARD_FAB2(SCH_1):M_D_MA(12)   I158 @BASEBOARD_FAB2_LIB.BASEBOARD_FAB2(SCH_1):PAGE50
   232 M_D_MA<13> @BASEBOARD_FAB2_LIB.BASEBOARD_FAB2(SCH_1):M_D_MA(13)   I158 @BASEBOARD_FAB2_LIB.BASEBOARD_FAB2(SCH_1):PAGE50
   228 M_D_MA<14> @BASEBOARD_FAB2_LIB.BASEBOARD_FAB2(SCH_1):M_D_MA(14)   I158 @BASEBOARD_FAB2_LIB.BASEBOARD_FAB2(SCH_1):PAGE50
    86 M_D_MA<15> @BASEBOARD_FAB2_LIB.BASEBOARD_FAB2(SCH_1):M_D_MA(15)   I158 @BASEBOARD_FAB2_LIB.BASEBOARD_FAB2(SCH_1):PAGE50
    82 M_D_MA<16> @BASEBOARD_FAB2_LIB.BASEBOARD_FAB2(SCH_1):M_D_MA(16)   I158 @BASEBOARD_FAB2_LIB.BASEBOARD_FAB2(SCH_1):PAGE50
   234 M_D_MA<17> @BASEBOARD_FAB2_LIB.BASEBOARD_FAB2(SCH_1):M_D_MA(17)   I158 @BASEBOARD_FAB2_LIB.BASEBOARD_FAB2(SCH_1):PAGE50
   216 M_D_MA<2> @BASEBOARD_FAB2_LIB.BASEBOARD_FAB2(SCH_1):M_D_MA(2)   I158 @BASEBOARD_FAB2_LIB.BASEBOARD_FAB2(SCH_1):PAGE50
    71 M_D_MA<3> @BASEBOARD_FAB2_LIB.BASEBOARD_FAB2(SCH_1):M_D_MA(3)   I158 @BASEBOARD_FAB2_LIB.BASEBOARD_FAB2(SCH_1):PAGE50
   214 M_D_MA<4> @BASEBOARD_FAB2_LIB.BASEBOARD_FAB2(SCH_1):M_D_MA(4)   I158 @BASEBOARD_FAB2_LIB.BASEBOARD_FAB2(SCH_1):PAGE50
   213 M_D_MA<5> @BASEBOARD_FAB2_LIB.BASEBOARD_FAB2(SCH_1):M_D_MA(5)   I158 @BASEBOARD_FAB2_LIB.BASEBOARD_FAB2(SCH_1):PAGE50
    69 M_D_MA<6> @BASEBOARD_FAB2_LIB.BASEBOARD_FAB2(SCH_1):M_D_MA(6)   I158 @BASEBOARD_FAB2_LIB.BASEBOARD_FAB2(SCH_1):PAGE50
   211 M_D_MA<7> @BASEBOARD_FAB2_LIB.BASEBOARD_FAB2(SCH_1):M_D_MA(7)   I158 @BASEBOARD_FAB2_LIB.BASEBOARD_FAB2(SCH_1):PAGE50
    68 M_D_MA<8> @BASEBOARD_FAB2_LIB.BASEBOARD_FAB2(SCH_1):M_D_MA(8)   I158 @BASEBOARD_FAB2_LIB.BASEBOARD_FAB2(SCH_1):PAGE50
    66 M_D_MA<9> @BASEBOARD_FAB2_LIB.BASEBOARD_FAB2(SCH_1):M_D_MA(9)   I158 @BASEBOARD_FAB2_LIB.BASEBOARD_FAB2(SCH_1):PAGE50
    62 M_D_ACT_N @BASEBOARD_FAB2_LIB.BASEBOARD_FAB2(SCH_1):M_D_ACT_N   I158 @BASEBOARD_FAB2_LIB.BASEBOARD_FAB2(SCH_1):PAGE50
   208 M_D_ALERT_N @BASEBOARD_FAB2_LIB.BASEBOARD_FAB2(SCH_1):M_D_ALERT_N   I158 @BASEBOARD_FAB2_LIB.BASEBOARD_FAB2(SCH_1):PAGE50
   224 M_D_BA<1> @BASEBOARD_FAB2_LIB.BASEBOARD_FAB2(SCH_1):M_D_BA(1)   I158 @BASEBOARD_FAB2_LIB.BASEBOARD_FAB2(SCH_1):PAGE50
    81 M_D_BA<0> @BASEBOARD_FAB2_LIB.BASEBOARD_FAB2(SCH_1):M_D_BA(0)   I158 @BASEBOARD_FAB2_LIB.BASEBOARD_FAB2(SCH_1):PAGE50
   207 M_D_BG<1> @BASEBOARD_FAB2_LIB.BASEBOARD_FAB2(SCH_1):M_D_BG(1)   I158 @BASEBOARD_FAB2_LIB.BASEBOARD_FAB2(SCH_1):PAGE50
    63 M_D_BG<0> @BASEBOARD_FAB2_LIB.BASEBOARD_FAB2(SCH_1):M_D_BG(0)   I158 @BASEBOARD_FAB2_LIB.BASEBOARD_FAB2(SCH_1):PAGE50
   235 M_D_C<2> @BASEBOARD_FAB2_LIB.BASEBOARD_FAB2(SCH_1):M_D_C(2)   I158 @BASEBOARD_FAB2_LIB.BASEBOARD_FAB2(SCH_1):PAGE50
   199 M_D_ECC<7> @BASEBOARD_FAB2_LIB.BASEBOARD_FAB2(SCH_1):M_D_ECC(7)   I158 @BASEBOARD_FAB2_LIB.BASEBOARD_FAB2(SCH_1):PAGE50
    54 M_D_ECC<6> @BASEBOARD_FAB2_LIB.BASEBOARD_FAB2(SCH_1):M_D_ECC(6)   I158 @BASEBOARD_FAB2_LIB.BASEBOARD_FAB2(SCH_1):PAGE50
   192 M_D_ECC<5> @BASEBOARD_FAB2_LIB.BASEBOARD_FAB2(SCH_1):M_D_ECC(5)   I158 @BASEBOARD_FAB2_LIB.BASEBOARD_FAB2(SCH_1):PAGE50
    47 M_D_ECC<4> @BASEBOARD_FAB2_LIB.BASEBOARD_FAB2(SCH_1):M_D_ECC(4)   I158 @BASEBOARD_FAB2_LIB.BASEBOARD_FAB2(SCH_1):PAGE50
   201 M_D_ECC<3> @BASEBOARD_FAB2_LIB.BASEBOARD_FAB2(SCH_1):M_D_ECC(3)   I158 @BASEBOARD_FAB2_LIB.BASEBOARD_FAB2(SCH_1):PAGE50
    56 M_D_ECC<2> @BASEBOARD_FAB2_LIB.BASEBOARD_FAB2(SCH_1):M_D_ECC(2)   I158 @BASEBOARD_FAB2_LIB.BASEBOARD_FAB2(SCH_1):PAGE50
   194 M_D_ECC<1> @BASEBOARD_FAB2_LIB.BASEBOARD_FAB2(SCH_1):M_D_ECC(1)   I158 @BASEBOARD_FAB2_LIB.BASEBOARD_FAB2(SCH_1):PAGE50
    49 M_D_ECC<0> @BASEBOARD_FAB2_LIB.BASEBOARD_FAB2(SCH_1):M_D_ECC(0)   I158 @BASEBOARD_FAB2_LIB.BASEBOARD_FAB2(SCH_1):PAGE50
    75 M_D_CLK_DN<2> @BASEBOARD_FAB2_LIB.BASEBOARD_FAB2(SCH_1):M_D_CLK_DN(2)   I158 @BASEBOARD_FAB2_LIB.BASEBOARD_FAB2(SCH_1):PAGE50
    74 M_D_CLK_DP<2> @BASEBOARD_FAB2_LIB.BASEBOARD_FAB2(SCH_1):M_D_CLK_DP(2)   I158 @BASEBOARD_FAB2_LIB.BASEBOARD_FAB2(SCH_1):PAGE50
   219 M_D_CLK_DN<3> @BASEBOARD_FAB2_LIB.BASEBOARD_FAB2(SCH_1):M_D_CLK_DN(3)   I158 @BASEBOARD_FAB2_LIB.BASEBOARD_FAB2(SCH_1):PAGE50
   218 M_D_CLK_DP<3> @BASEBOARD_FAB2_LIB.BASEBOARD_FAB2(SCH_1):M_D_CLK_DP(3)   I158 @BASEBOARD_FAB2_LIB.BASEBOARD_FAB2(SCH_1):PAGE50
   203 M_D_CKE<3> @BASEBOARD_FAB2_LIB.BASEBOARD_FAB2(SCH_1):M_D_CKE(3)   I158 @BASEBOARD_FAB2_LIB.BASEBOARD_FAB2(SCH_1):PAGE50
    60 M_D_CKE<2> @BASEBOARD_FAB2_LIB.BASEBOARD_FAB2(SCH_1):M_D_CKE(2)   I158 @BASEBOARD_FAB2_LIB.BASEBOARD_FAB2(SCH_1):PAGE50
   280 M_D_DQ<63> @BASEBOARD_FAB2_LIB.BASEBOARD_FAB2(SCH_1):M_D_DQ(63)   I158 @BASEBOARD_FAB2_LIB.BASEBOARD_FAB2(SCH_1):PAGE50
   135 M_D_DQ<62> @BASEBOARD_FAB2_LIB.BASEBOARD_FAB2(SCH_1):M_D_DQ(62)   I158 @BASEBOARD_FAB2_LIB.BASEBOARD_FAB2(SCH_1):PAGE50
   273 M_D_DQ<61> @BASEBOARD_FAB2_LIB.BASEBOARD_FAB2(SCH_1):M_D_DQ(61)   I158 @BASEBOARD_FAB2_LIB.BASEBOARD_FAB2(SCH_1):PAGE50
   128 M_D_DQ<60> @BASEBOARD_FAB2_LIB.BASEBOARD_FAB2(SCH_1):M_D_DQ(60)   I158 @BASEBOARD_FAB2_LIB.BASEBOARD_FAB2(SCH_1):PAGE50
   282 M_D_DQ<59> @BASEBOARD_FAB2_LIB.BASEBOARD_FAB2(SCH_1):M_D_DQ(59)   I158 @BASEBOARD_FAB2_LIB.BASEBOARD_FAB2(SCH_1):PAGE50
   137 M_D_DQ<58> @BASEBOARD_FAB2_LIB.BASEBOARD_FAB2(SCH_1):M_D_DQ(58)   I158 @BASEBOARD_FAB2_LIB.BASEBOARD_FAB2(SCH_1):PAGE50
   275 M_D_DQ<57> @BASEBOARD_FAB2_LIB.BASEBOARD_FAB2(SCH_1):M_D_DQ(57)   I158 @BASEBOARD_FAB2_LIB.BASEBOARD_FAB2(SCH_1):PAGE50
   130 M_D_DQ<56> @BASEBOARD_FAB2_LIB.BASEBOARD_FAB2(SCH_1):M_D_DQ(56)   I158 @BASEBOARD_FAB2_LIB.BASEBOARD_FAB2(SCH_1):PAGE50
   269 M_D_DQ<55> @BASEBOARD_FAB2_LIB.BASEBOARD_FAB2(SCH_1):M_D_DQ(55)   I158 @BASEBOARD_FAB2_LIB.BASEBOARD_FAB2(SCH_1):PAGE50
   124 M_D_DQ<54> @BASEBOARD_FAB2_LIB.BASEBOARD_FAB2(SCH_1):M_D_DQ(54)   I158 @BASEBOARD_FAB2_LIB.BASEBOARD_FAB2(SCH_1):PAGE50
   262 M_D_DQ<53> @BASEBOARD_FAB2_LIB.BASEBOARD_FAB2(SCH_1):M_D_DQ(53)   I158 @BASEBOARD_FAB2_LIB.BASEBOARD_FAB2(SCH_1):PAGE50
   117 M_D_DQ<52> @BASEBOARD_FAB2_LIB.BASEBOARD_FAB2(SCH_1):M_D_DQ(52)   I158 @BASEBOARD_FAB2_LIB.BASEBOARD_FAB2(SCH_1):PAGE50
   271 M_D_DQ<51> @BASEBOARD_FAB2_LIB.BASEBOARD_FAB2(SCH_1):M_D_DQ(51)   I158 @BASEBOARD_FAB2_LIB.BASEBOARD_FAB2(SCH_1):PAGE50
   126 M_D_DQ<50> @BASEBOARD_FAB2_LIB.BASEBOARD_FAB2(SCH_1):M_D_DQ(50)   I158 @BASEBOARD_FAB2_LIB.BASEBOARD_FAB2(SCH_1):PAGE50
   264 M_D_DQ<49> @BASEBOARD_FAB2_LIB.BASEBOARD_FAB2(SCH_1):M_D_DQ(49)   I158 @BASEBOARD_FAB2_LIB.BASEBOARD_FAB2(SCH_1):PAGE50
   119 M_D_DQ<48> @BASEBOARD_FAB2_LIB.BASEBOARD_FAB2(SCH_1):M_D_DQ(48)   I158 @BASEBOARD_FAB2_LIB.BASEBOARD_FAB2(SCH_1):PAGE50
   258 M_D_DQ<47> @BASEBOARD_FAB2_LIB.BASEBOARD_FAB2(SCH_1):M_D_DQ(47)   I158 @BASEBOARD_FAB2_LIB.BASEBOARD_FAB2(SCH_1):PAGE50
   113 M_D_DQ<46> @BASEBOARD_FAB2_LIB.BASEBOARD_FAB2(SCH_1):M_D_DQ(46)   I158 @BASEBOARD_FAB2_LIB.BASEBOARD_FAB2(SCH_1):PAGE50
   251 M_D_DQ<45> @BASEBOARD_FAB2_LIB.BASEBOARD_FAB2(SCH_1):M_D_DQ(45)   I158 @BASEBOARD_FAB2_LIB.BASEBOARD_FAB2(SCH_1):PAGE50
   106 M_D_DQ<44> @BASEBOARD_FAB2_LIB.BASEBOARD_FAB2(SCH_1):M_D_DQ(44)   I158 @BASEBOARD_FAB2_LIB.BASEBOARD_FAB2(SCH_1):PAGE50
   260 M_D_DQ<43> @BASEBOARD_FAB2_LIB.BASEBOARD_FAB2(SCH_1):M_D_DQ(43)   I158 @BASEBOARD_FAB2_LIB.BASEBOARD_FAB2(SCH_1):PAGE50
   115 M_D_DQ<42> @BASEBOARD_FAB2_LIB.BASEBOARD_FAB2(SCH_1):M_D_DQ(42)   I158 @BASEBOARD_FAB2_LIB.BASEBOARD_FAB2(SCH_1):PAGE50
   253 M_D_DQ<41> @BASEBOARD_FAB2_LIB.BASEBOARD_FAB2(SCH_1):M_D_DQ(41)   I158 @BASEBOARD_FAB2_LIB.BASEBOARD_FAB2(SCH_1):PAGE50
   108 M_D_DQ<40> @BASEBOARD_FAB2_LIB.BASEBOARD_FAB2(SCH_1):M_D_DQ(40)   I158 @BASEBOARD_FAB2_LIB.BASEBOARD_FAB2(SCH_1):PAGE50
   247 M_D_DQ<39> @BASEBOARD_FAB2_LIB.BASEBOARD_FAB2(SCH_1):M_D_DQ(39)   I158 @BASEBOARD_FAB2_LIB.BASEBOARD_FAB2(SCH_1):PAGE50
   102 M_D_DQ<38> @BASEBOARD_FAB2_LIB.BASEBOARD_FAB2(SCH_1):M_D_DQ(38)   I158 @BASEBOARD_FAB2_LIB.BASEBOARD_FAB2(SCH_1):PAGE50
   240 M_D_DQ<37> @BASEBOARD_FAB2_LIB.BASEBOARD_FAB2(SCH_1):M_D_DQ(37)   I158 @BASEBOARD_FAB2_LIB.BASEBOARD_FAB2(SCH_1):PAGE50
    95 M_D_DQ<36> @BASEBOARD_FAB2_LIB.BASEBOARD_FAB2(SCH_1):M_D_DQ(36)   I158 @BASEBOARD_FAB2_LIB.BASEBOARD_FAB2(SCH_1):PAGE50
   249 M_D_DQ<35> @BASEBOARD_FAB2_LIB.BASEBOARD_FAB2(SCH_1):M_D_DQ(35)   I158 @BASEBOARD_FAB2_LIB.BASEBOARD_FAB2(SCH_1):PAGE50
   104 M_D_DQ<34> @BASEBOARD_FAB2_LIB.BASEBOARD_FAB2(SCH_1):M_D_DQ(34)   I158 @BASEBOARD_FAB2_LIB.BASEBOARD_FAB2(SCH_1):PAGE50
   242 M_D_DQ<33> @BASEBOARD_FAB2_LIB.BASEBOARD_FAB2(SCH_1):M_D_DQ(33)   I158 @BASEBOARD_FAB2_LIB.BASEBOARD_FAB2(SCH_1):PAGE50
    97 M_D_DQ<32> @BASEBOARD_FAB2_LIB.BASEBOARD_FAB2(SCH_1):M_D_DQ(32)   I158 @BASEBOARD_FAB2_LIB.BASEBOARD_FAB2(SCH_1):PAGE50
   188 M_D_DQ<31> @BASEBOARD_FAB2_LIB.BASEBOARD_FAB2(SCH_1):M_D_DQ(31)   I158 @BASEBOARD_FAB2_LIB.BASEBOARD_FAB2(SCH_1):PAGE50
    43 M_D_DQ<30> @BASEBOARD_FAB2_LIB.BASEBOARD_FAB2(SCH_1):M_D_DQ(30)   I158 @BASEBOARD_FAB2_LIB.BASEBOARD_FAB2(SCH_1):PAGE50
   181 M_D_DQ<29> @BASEBOARD_FAB2_LIB.BASEBOARD_FAB2(SCH_1):M_D_DQ(29)   I158 @BASEBOARD_FAB2_LIB.BASEBOARD_FAB2(SCH_1):PAGE50
    36 M_D_DQ<28> @BASEBOARD_FAB2_LIB.BASEBOARD_FAB2(SCH_1):M_D_DQ(28)   I158 @BASEBOARD_FAB2_LIB.BASEBOARD_FAB2(SCH_1):PAGE50
   190 M_D_DQ<27> @BASEBOARD_FAB2_LIB.BASEBOARD_FAB2(SCH_1):M_D_DQ(27)   I158 @BASEBOARD_FAB2_LIB.BASEBOARD_FAB2(SCH_1):PAGE50
    45 M_D_DQ<26> @BASEBOARD_FAB2_LIB.BASEBOARD_FAB2(SCH_1):M_D_DQ(26)   I158 @BASEBOARD_FAB2_LIB.BASEBOARD_FAB2(SCH_1):PAGE50
   183 M_D_DQ<25> @BASEBOARD_FAB2_LIB.BASEBOARD_FAB2(SCH_1):M_D_DQ(25)   I158 @BASEBOARD_FAB2_LIB.BASEBOARD_FAB2(SCH_1):PAGE50
    38 M_D_DQ<24> @BASEBOARD_FAB2_LIB.BASEBOARD_FAB2(SCH_1):M_D_DQ(24)   I158 @BASEBOARD_FAB2_LIB.BASEBOARD_FAB2(SCH_1):PAGE50
   177 M_D_DQ<23> @BASEBOARD_FAB2_LIB.BASEBOARD_FAB2(SCH_1):M_D_DQ(23)   I158 @BASEBOARD_FAB2_LIB.BASEBOARD_FAB2(SCH_1):PAGE50
    32 M_D_DQ<22> @BASEBOARD_FAB2_LIB.BASEBOARD_FAB2(SCH_1):M_D_DQ(22)   I158 @BASEBOARD_FAB2_LIB.BASEBOARD_FAB2(SCH_1):PAGE50
   170 M_D_DQ<21> @BASEBOARD_FAB2_LIB.BASEBOARD_FAB2(SCH_1):M_D_DQ(21)   I158 @BASEBOARD_FAB2_LIB.BASEBOARD_FAB2(SCH_1):PAGE50
    25 M_D_DQ<20> @BASEBOARD_FAB2_LIB.BASEBOARD_FAB2(SCH_1):M_D_DQ(20)   I158 @BASEBOARD_FAB2_LIB.BASEBOARD_FAB2(SCH_1):PAGE50
   179 M_D_DQ<19> @BASEBOARD_FAB2_LIB.BASEBOARD_FAB2(SCH_1):M_D_DQ(19)   I158 @BASEBOARD_FAB2_LIB.BASEBOARD_FAB2(SCH_1):PAGE50
    34 M_D_DQ<18> @BASEBOARD_FAB2_LIB.BASEBOARD_FAB2(SCH_1):M_D_DQ(18)   I158 @BASEBOARD_FAB2_LIB.BASEBOARD_FAB2(SCH_1):PAGE50
   172 M_D_DQ<17> @BASEBOARD_FAB2_LIB.BASEBOARD_FAB2(SCH_1):M_D_DQ(17)   I158 @BASEBOARD_FAB2_LIB.BASEBOARD_FAB2(SCH_1):PAGE50
    27 M_D_DQ<16> @BASEBOARD_FAB2_LIB.BASEBOARD_FAB2(SCH_1):M_D_DQ(16)   I158 @BASEBOARD_FAB2_LIB.BASEBOARD_FAB2(SCH_1):PAGE50
   166 M_D_DQ<15> @BASEBOARD_FAB2_LIB.BASEBOARD_FAB2(SCH_1):M_D_DQ(15)   I158 @BASEBOARD_FAB2_LIB.BASEBOARD_FAB2(SCH_1):PAGE50
    21 M_D_DQ<14> @BASEBOARD_FAB2_LIB.BASEBOARD_FAB2(SCH_1):M_D_DQ(14)   I158 @BASEBOARD_FAB2_LIB.BASEBOARD_FAB2(SCH_1):PAGE50
   159 M_D_DQ<13> @BASEBOARD_FAB2_LIB.BASEBOARD_FAB2(SCH_1):M_D_DQ(13)   I158 @BASEBOARD_FAB2_LIB.BASEBOARD_FAB2(SCH_1):PAGE50
    14 M_D_DQ<12> @BASEBOARD_FAB2_LIB.BASEBOARD_FAB2(SCH_1):M_D_DQ(12)   I158 @BASEBOARD_FAB2_LIB.BASEBOARD_FAB2(SCH_1):PAGE50
   168 M_D_DQ<11> @BASEBOARD_FAB2_LIB.BASEBOARD_FAB2(SCH_1):M_D_DQ(11)   I158 @BASEBOARD_FAB2_LIB.BASEBOARD_FAB2(SCH_1):PAGE50
    23 M_D_DQ<10> @BASEBOARD_FAB2_LIB.BASEBOARD_FAB2(SCH_1):M_D_DQ(10)   I158 @BASEBOARD_FAB2_LIB.BASEBOARD_FAB2(SCH_1):PAGE50
   161 M_D_DQ<9> @BASEBOARD_FAB2_LIB.BASEBOARD_FAB2(SCH_1):M_D_DQ(9)   I158 @BASEBOARD_FAB2_LIB.BASEBOARD_FAB2(SCH_1):PAGE50
    16 M_D_DQ<8> @BASEBOARD_FAB2_LIB.BASEBOARD_FAB2(SCH_1):M_D_DQ(8)   I158 @BASEBOARD_FAB2_LIB.BASEBOARD_FAB2(SCH_1):PAGE50
   155 M_D_DQ<7> @BASEBOARD_FAB2_LIB.BASEBOARD_FAB2(SCH_1):M_D_DQ(7)   I158 @BASEBOARD_FAB2_LIB.BASEBOARD_FAB2(SCH_1):PAGE50
    10 M_D_DQ<6> @BASEBOARD_FAB2_LIB.BASEBOARD_FAB2(SCH_1):M_D_DQ(6)   I158 @BASEBOARD_FAB2_LIB.BASEBOARD_FAB2(SCH_1):PAGE50
   148 M_D_DQ<5> @BASEBOARD_FAB2_LIB.BASEBOARD_FAB2(SCH_1):M_D_DQ(5)   I158 @BASEBOARD_FAB2_LIB.BASEBOARD_FAB2(SCH_1):PAGE50
     3 M_D_DQ<4> @BASEBOARD_FAB2_LIB.BASEBOARD_FAB2(SCH_1):M_D_DQ(4)   I158 @BASEBOARD_FAB2_LIB.BASEBOARD_FAB2(SCH_1):PAGE50
   157 M_D_DQ<3> @BASEBOARD_FAB2_LIB.BASEBOARD_FAB2(SCH_1):M_D_DQ(3)   I158 @BASEBOARD_FAB2_LIB.BASEBOARD_FAB2(SCH_1):PAGE50
    12 M_D_DQ<2> @BASEBOARD_FAB2_LIB.BASEBOARD_FAB2(SCH_1):M_D_DQ(2)   I158 @BASEBOARD_FAB2_LIB.BASEBOARD_FAB2(SCH_1):PAGE50
   150 M_D_DQ<1> @BASEBOARD_FAB2_LIB.BASEBOARD_FAB2(SCH_1):M_D_DQ(1)   I158 @BASEBOARD_FAB2_LIB.BASEBOARD_FAB2(SCH_1):PAGE50
     5 M_D_DQ<0> @BASEBOARD_FAB2_LIB.BASEBOARD_FAB2(SCH_1):M_D_DQ(0)   I158 @BASEBOARD_FAB2_LIB.BASEBOARD_FAB2(SCH_1):PAGE50
    78 FM_DIMM_EVENT_COD_N @BASEBOARD_FAB2_LIB.BASEBOARD_FAB2(SCH_1):FM_DIMM_EVENT_COD_N   I158 @BASEBOARD_FAB2_LIB.BASEBOARD_FAB2(SCH_1):PAGE50
    91 M_D_ODT<3> @BASEBOARD_FAB2_LIB.BASEBOARD_FAB2(SCH_1):M_D_ODT(3)   I158 @BASEBOARD_FAB2_LIB.BASEBOARD_FAB2(SCH_1):PAGE50
    87 M_D_ODT<2> @BASEBOARD_FAB2_LIB.BASEBOARD_FAB2(SCH_1):M_D_ODT(2)   I158 @BASEBOARD_FAB2_LIB.BASEBOARD_FAB2(SCH_1):PAGE50
   222 M_D_PAR @BASEBOARD_FAB2_LIB.BASEBOARD_FAB2(SCH_1):M_D_PAR   I158 @BASEBOARD_FAB2_LIB.BASEBOARD_FAB2(SCH_1):PAGE50
    58 M_DEF_RST_N @BASEBOARD_FAB2_LIB.BASEBOARD_FAB2(SCH_1):M_DEF_RST_N   I158 @BASEBOARD_FAB2_LIB.BASEBOARD_FAB2(SCH_1):PAGE50
   144 TP_CH_D_DIMM_D1_RFU_2 @BASEBOARD_FAB2_LIB.BASEBOARD_FAB2(SCH_1):TP_CH_D_DIMM_D1_RFU_2   I158 @BASEBOARD_FAB2_LIB.BASEBOARD_FAB2(SCH_1):PAGE50
   227 TP_CH_D_DIMM_D1_RFU_1 @BASEBOARD_FAB2_LIB.BASEBOARD_FAB2(SCH_1):TP_CH_D_DIMM_D1_RFU_1   I158 @BASEBOARD_FAB2_LIB.BASEBOARD_FAB2(SCH_1):PAGE50
   205 TP_CH_D_DIMM_D1_RFU_0 @BASEBOARD_FAB2_LIB.BASEBOARD_FAB2(SCH_1):TP_CH_D_DIMM_D1_RFU_0   I158 @BASEBOARD_FAB2_LIB.BASEBOARD_FAB2(SCH_1):PAGE50
    84 M_D_CS_N<4> @BASEBOARD_FAB2_LIB.BASEBOARD_FAB2(SCH_1):M_D_CS_N(4)   I158 @BASEBOARD_FAB2_LIB.BASEBOARD_FAB2(SCH_1):PAGE50
    89 M_D_CS_N<5> @BASEBOARD_FAB2_LIB.BASEBOARD_FAB2(SCH_1):M_D_CS_N(5)   I158 @BASEBOARD_FAB2_LIB.BASEBOARD_FAB2(SCH_1):PAGE50
    93 M_D_CS_N<6> @BASEBOARD_FAB2_LIB.BASEBOARD_FAB2(SCH_1):M_D_CS_N(6)   I158 @BASEBOARD_FAB2_LIB.BASEBOARD_FAB2(SCH_1):PAGE50
   237 M_D_CS_N<7> @BASEBOARD_FAB2_LIB.BASEBOARD_FAB2(SCH_1):M_D_CS_N(7)   I158 @BASEBOARD_FAB2_LIB.BASEBOARD_FAB2(SCH_1):PAGE50
   238    GND @BASEBOARD_FAB2_LIB.BASEBOARD_FAB2(SCH_1):GND   I158 @BASEBOARD_FAB2_LIB.BASEBOARD_FAB2(SCH_1):PAGE50
   140    GND @BASEBOARD_FAB2_LIB.BASEBOARD_FAB2(SCH_1):GND   I158 @BASEBOARD_FAB2_LIB.BASEBOARD_FAB2(SCH_1):PAGE50
   139 PVPP_DEF @BASEBOARD_FAB2_LIB.BASEBOARD_FAB2(SCH_1):PVPP_DEF   I158 @BASEBOARD_FAB2_LIB.BASEBOARD_FAB2(SCH_1):PAGE50
   230 FM_ADR_COMPLETE_DEF_N @BASEBOARD_FAB2_LIB.BASEBOARD_FAB2(SCH_1):FM_ADR_COMPLETE_DEF_N   I158 @BASEBOARD_FAB2_LIB.BASEBOARD_FAB2(SCH_1):PAGE50
   141 SMB_DDR_DEF_VPP_SCL @BASEBOARD_FAB2_LIB.BASEBOARD_FAB2(SCH_1):SMB_DDR_DEF_VPP_SCL   I158 @BASEBOARD_FAB2_LIB.BASEBOARD_FAB2(SCH_1):PAGE50
   285 SMB_DDR_DEF_VPP_SDA @BASEBOARD_FAB2_LIB.BASEBOARD_FAB2(SCH_1):SMB_DDR_DEF_VPP_SDA   I158 @BASEBOARD_FAB2_LIB.BASEBOARD_FAB2(SCH_1):PAGE50
   284 PVPP_DEF @BASEBOARD_FAB2_LIB.BASEBOARD_FAB2(SCH_1):PVPP_DEF   I158 @BASEBOARD_FAB2_LIB.BASEBOARD_FAB2(SCH_1):PAGE50
   146 M_D_VREF @BASEBOARD_FAB2_LIB.BASEBOARD_FAB2(SCH_1):M_D_VREF   I158 @BASEBOARD_FAB2_LIB.BASEBOARD_FAB2(SCH_1):PAGE50
   152 M_D_DQS_DN<0> @BASEBOARD_FAB2_LIB.BASEBOARD_FAB2(SCH_1):M_D_DQS_DN(0)    I46 @BASEBOARD_FAB2_LIB.BASEBOARD_FAB2(SCH_1):PAGE50
   153 M_D_DQS_DP<0> @BASEBOARD_FAB2_LIB.BASEBOARD_FAB2(SCH_1):M_D_DQS_DP(0)    I46 @BASEBOARD_FAB2_LIB.BASEBOARD_FAB2(SCH_1):PAGE50
    19 M_D_DQS_DN<10> @BASEBOARD_FAB2_LIB.BASEBOARD_FAB2(SCH_1):M_D_DQS_DN(10)    I46 @BASEBOARD_FAB2_LIB.BASEBOARD_FAB2(SCH_1):PAGE50
    18 M_D_DQS_DP<10> @BASEBOARD_FAB2_LIB.BASEBOARD_FAB2(SCH_1):M_D_DQS_DP(10)    I46 @BASEBOARD_FAB2_LIB.BASEBOARD_FAB2(SCH_1):PAGE50
    30 M_D_DQS_DN<11> @BASEBOARD_FAB2_LIB.BASEBOARD_FAB2(SCH_1):M_D_DQS_DN(11)    I46 @BASEBOARD_FAB2_LIB.BASEBOARD_FAB2(SCH_1):PAGE50
    29 M_D_DQS_DP<11> @BASEBOARD_FAB2_LIB.BASEBOARD_FAB2(SCH_1):M_D_DQS_DP(11)    I46 @BASEBOARD_FAB2_LIB.BASEBOARD_FAB2(SCH_1):PAGE50
    41 M_D_DQS_DN<12> @BASEBOARD_FAB2_LIB.BASEBOARD_FAB2(SCH_1):M_D_DQS_DN(12)    I46 @BASEBOARD_FAB2_LIB.BASEBOARD_FAB2(SCH_1):PAGE50
    40 M_D_DQS_DP<12> @BASEBOARD_FAB2_LIB.BASEBOARD_FAB2(SCH_1):M_D_DQS_DP(12)    I46 @BASEBOARD_FAB2_LIB.BASEBOARD_FAB2(SCH_1):PAGE50
   100 M_D_DQS_DN<13> @BASEBOARD_FAB2_LIB.BASEBOARD_FAB2(SCH_1):M_D_DQS_DN(13)    I46 @BASEBOARD_FAB2_LIB.BASEBOARD_FAB2(SCH_1):PAGE50
    99 M_D_DQS_DP<13> @BASEBOARD_FAB2_LIB.BASEBOARD_FAB2(SCH_1):M_D_DQS_DP(13)    I46 @BASEBOARD_FAB2_LIB.BASEBOARD_FAB2(SCH_1):PAGE50
   111 M_D_DQS_DN<14> @BASEBOARD_FAB2_LIB.BASEBOARD_FAB2(SCH_1):M_D_DQS_DN(14)    I46 @BASEBOARD_FAB2_LIB.BASEBOARD_FAB2(SCH_1):PAGE50
   110 M_D_DQS_DP<14> @BASEBOARD_FAB2_LIB.BASEBOARD_FAB2(SCH_1):M_D_DQS_DP(14)    I46 @BASEBOARD_FAB2_LIB.BASEBOARD_FAB2(SCH_1):PAGE50
   122 M_D_DQS_DN<15> @BASEBOARD_FAB2_LIB.BASEBOARD_FAB2(SCH_1):M_D_DQS_DN(15)    I46 @BASEBOARD_FAB2_LIB.BASEBOARD_FAB2(SCH_1):PAGE50
   121 M_D_DQS_DP<15> @BASEBOARD_FAB2_LIB.BASEBOARD_FAB2(SCH_1):M_D_DQS_DP(15)    I46 @BASEBOARD_FAB2_LIB.BASEBOARD_FAB2(SCH_1):PAGE50
   133 M_D_DQS_DN<16> @BASEBOARD_FAB2_LIB.BASEBOARD_FAB2(SCH_1):M_D_DQS_DN(16)    I46 @BASEBOARD_FAB2_LIB.BASEBOARD_FAB2(SCH_1):PAGE50
   132 M_D_DQS_DP<16> @BASEBOARD_FAB2_LIB.BASEBOARD_FAB2(SCH_1):M_D_DQS_DP(16)    I46 @BASEBOARD_FAB2_LIB.BASEBOARD_FAB2(SCH_1):PAGE50
    52 M_D_DQS_DN<17> @BASEBOARD_FAB2_LIB.BASEBOARD_FAB2(SCH_1):M_D_DQS_DN(17)    I46 @BASEBOARD_FAB2_LIB.BASEBOARD_FAB2(SCH_1):PAGE50
    51 M_D_DQS_DP<17> @BASEBOARD_FAB2_LIB.BASEBOARD_FAB2(SCH_1):M_D_DQS_DP(17)    I46 @BASEBOARD_FAB2_LIB.BASEBOARD_FAB2(SCH_1):PAGE50
   163 M_D_DQS_DN<1> @BASEBOARD_FAB2_LIB.BASEBOARD_FAB2(SCH_1):M_D_DQS_DN(1)    I46 @BASEBOARD_FAB2_LIB.BASEBOARD_FAB2(SCH_1):PAGE50
   164 M_D_DQS_DP<1> @BASEBOARD_FAB2_LIB.BASEBOARD_FAB2(SCH_1):M_D_DQS_DP(1)    I46 @BASEBOARD_FAB2_LIB.BASEBOARD_FAB2(SCH_1):PAGE50
   174 M_D_DQS_DN<2> @BASEBOARD_FAB2_LIB.BASEBOARD_FAB2(SCH_1):M_D_DQS_DN(2)    I46 @BASEBOARD_FAB2_LIB.BASEBOARD_FAB2(SCH_1):PAGE50
   175 M_D_DQS_DP<2> @BASEBOARD_FAB2_LIB.BASEBOARD_FAB2(SCH_1):M_D_DQS_DP(2)    I46 @BASEBOARD_FAB2_LIB.BASEBOARD_FAB2(SCH_1):PAGE50
   185 M_D_DQS_DN<3> @BASEBOARD_FAB2_LIB.BASEBOARD_FAB2(SCH_1):M_D_DQS_DN(3)    I46 @BASEBOARD_FAB2_LIB.BASEBOARD_FAB2(SCH_1):PAGE50
   186 M_D_DQS_DP<3> @BASEBOARD_FAB2_LIB.BASEBOARD_FAB2(SCH_1):M_D_DQS_DP(3)    I46 @BASEBOARD_FAB2_LIB.BASEBOARD_FAB2(SCH_1):PAGE50
   244 M_D_DQS_DN<4> @BASEBOARD_FAB2_LIB.BASEBOARD_FAB2(SCH_1):M_D_DQS_DN(4)    I46 @BASEBOARD_FAB2_LIB.BASEBOARD_FAB2(SCH_1):PAGE50
   245 M_D_DQS_DP<4> @BASEBOARD_FAB2_LIB.BASEBOARD_FAB2(SCH_1):M_D_DQS_DP(4)    I46 @BASEBOARD_FAB2_LIB.BASEBOARD_FAB2(SCH_1):PAGE50
   255 M_D_DQS_DN<5> @BASEBOARD_FAB2_LIB.BASEBOARD_FAB2(SCH_1):M_D_DQS_DN(5)    I46 @BASEBOARD_FAB2_LIB.BASEBOARD_FAB2(SCH_1):PAGE50
   256 M_D_DQS_DP<5> @BASEBOARD_FAB2_LIB.BASEBOARD_FAB2(SCH_1):M_D_DQS_DP(5)    I46 @BASEBOARD_FAB2_LIB.BASEBOARD_FAB2(SCH_1):PAGE50
   266 M_D_DQS_DN<6> @BASEBOARD_FAB2_LIB.BASEBOARD_FAB2(SCH_1):M_D_DQS_DN(6)    I46 @BASEBOARD_FAB2_LIB.BASEBOARD_FAB2(SCH_1):PAGE50
   267 M_D_DQS_DP<6> @BASEBOARD_FAB2_LIB.BASEBOARD_FAB2(SCH_1):M_D_DQS_DP(6)    I46 @BASEBOARD_FAB2_LIB.BASEBOARD_FAB2(SCH_1):PAGE50
   277 M_D_DQS_DN<7> @BASEBOARD_FAB2_LIB.BASEBOARD_FAB2(SCH_1):M_D_DQS_DN(7)    I46 @BASEBOARD_FAB2_LIB.BASEBOARD_FAB2(SCH_1):PAGE50
   278 M_D_DQS_DP<7> @BASEBOARD_FAB2_LIB.BASEBOARD_FAB2(SCH_1):M_D_DQS_DP(7)    I46 @BASEBOARD_FAB2_LIB.BASEBOARD_FAB2(SCH_1):PAGE50
   196 M_D_DQS_DN<8> @BASEBOARD_FAB2_LIB.BASEBOARD_FAB2(SCH_1):M_D_DQS_DN(8)    I46 @BASEBOARD_FAB2_LIB.BASEBOARD_FAB2(SCH_1):PAGE50
   197 M_D_DQS_DP<8> @BASEBOARD_FAB2_LIB.BASEBOARD_FAB2(SCH_1):M_D_DQS_DP(8)    I46 @BASEBOARD_FAB2_LIB.BASEBOARD_FAB2(SCH_1):PAGE50
     8 M_D_DQS_DN<9> @BASEBOARD_FAB2_LIB.BASEBOARD_FAB2(SCH_1):M_D_DQS_DN(9)    I46 @BASEBOARD_FAB2_LIB.BASEBOARD_FAB2(SCH_1):PAGE50
     7 M_D_DQS_DP<9> @BASEBOARD_FAB2_LIB.BASEBOARD_FAB2(SCH_1):M_D_DQS_DP(9)    I46 @BASEBOARD_FAB2_LIB.BASEBOARD_FAB2(SCH_1):PAGE50
     2    GND @BASEBOARD_FAB2_LIB.BASEBOARD_FAB2(SCH_1):GND    I44 @BASEBOARD_FAB2_LIB.BASEBOARD_FAB2(SCH_1):PAGE50
     4    GND @BASEBOARD_FAB2_LIB.BASEBOARD_FAB2(SCH_1):GND    I44 @BASEBOARD_FAB2_LIB.BASEBOARD_FAB2(SCH_1):PAGE50
     6    GND @BASEBOARD_FAB2_LIB.BASEBOARD_FAB2(SCH_1):GND    I44 @BASEBOARD_FAB2_LIB.BASEBOARD_FAB2(SCH_1):PAGE50
     9    GND @BASEBOARD_FAB2_LIB.BASEBOARD_FAB2(SCH_1):GND    I44 @BASEBOARD_FAB2_LIB.BASEBOARD_FAB2(SCH_1):PAGE50
    11    GND @BASEBOARD_FAB2_LIB.BASEBOARD_FAB2(SCH_1):GND    I44 @BASEBOARD_FAB2_LIB.BASEBOARD_FAB2(SCH_1):PAGE50
    13    GND @BASEBOARD_FAB2_LIB.BASEBOARD_FAB2(SCH_1):GND    I44 @BASEBOARD_FAB2_LIB.BASEBOARD_FAB2(SCH_1):PAGE50
    15    GND @BASEBOARD_FAB2_LIB.BASEBOARD_FAB2(SCH_1):GND    I44 @BASEBOARD_FAB2_LIB.BASEBOARD_FAB2(SCH_1):PAGE50
    17    GND @BASEBOARD_FAB2_LIB.BASEBOARD_FAB2(SCH_1):GND    I44 @BASEBOARD_FAB2_LIB.BASEBOARD_FAB2(SCH_1):PAGE50
    20    GND @BASEBOARD_FAB2_LIB.BASEBOARD_FAB2(SCH_1):GND    I44 @BASEBOARD_FAB2_LIB.BASEBOARD_FAB2(SCH_1):PAGE50
    22    GND @BASEBOARD_FAB2_LIB.BASEBOARD_FAB2(SCH_1):GND    I44 @BASEBOARD_FAB2_LIB.BASEBOARD_FAB2(SCH_1):PAGE50
    24    GND @BASEBOARD_FAB2_LIB.BASEBOARD_FAB2(SCH_1):GND    I44 @BASEBOARD_FAB2_LIB.BASEBOARD_FAB2(SCH_1):PAGE50
    26    GND @BASEBOARD_FAB2_LIB.BASEBOARD_FAB2(SCH_1):GND    I44 @BASEBOARD_FAB2_LIB.BASEBOARD_FAB2(SCH_1):PAGE50
    28    GND @BASEBOARD_FAB2_LIB.BASEBOARD_FAB2(SCH_1):GND    I44 @BASEBOARD_FAB2_LIB.BASEBOARD_FAB2(SCH_1):PAGE50
    31    GND @BASEBOARD_FAB2_LIB.BASEBOARD_FAB2(SCH_1):GND    I44 @BASEBOARD_FAB2_LIB.BASEBOARD_FAB2(SCH_1):PAGE50
    33    GND @BASEBOARD_FAB2_LIB.BASEBOARD_FAB2(SCH_1):GND    I44 @BASEBOARD_FAB2_LIB.BASEBOARD_FAB2(SCH_1):PAGE50
    35    GND @BASEBOARD_FAB2_LIB.BASEBOARD_FAB2(SCH_1):GND    I44 @BASEBOARD_FAB2_LIB.BASEBOARD_FAB2(SCH_1):PAGE50
    37    GND @BASEBOARD_FAB2_LIB.BASEBOARD_FAB2(SCH_1):GND    I44 @BASEBOARD_FAB2_LIB.BASEBOARD_FAB2(SCH_1):PAGE50
    39    GND @BASEBOARD_FAB2_LIB.BASEBOARD_FAB2(SCH_1):GND    I44 @BASEBOARD_FAB2_LIB.BASEBOARD_FAB2(SCH_1):PAGE50
    42    GND @BASEBOARD_FAB2_LIB.BASEBOARD_FAB2(SCH_1):GND    I44 @BASEBOARD_FAB2_LIB.BASEBOARD_FAB2(SCH_1):PAGE50
    44    GND @BASEBOARD_FAB2_LIB.BASEBOARD_FAB2(SCH_1):GND    I44 @BASEBOARD_FAB2_LIB.BASEBOARD_FAB2(SCH_1):PAGE50
    46    GND @BASEBOARD_FAB2_LIB.BASEBOARD_FAB2(SCH_1):GND    I44 @BASEBOARD_FAB2_LIB.BASEBOARD_FAB2(SCH_1):PAGE50
    48    GND @BASEBOARD_FAB2_LIB.BASEBOARD_FAB2(SCH_1):GND    I44 @BASEBOARD_FAB2_LIB.BASEBOARD_FAB2(SCH_1):PAGE50
    50    GND @BASEBOARD_FAB2_LIB.BASEBOARD_FAB2(SCH_1):GND    I44 @BASEBOARD_FAB2_LIB.BASEBOARD_FAB2(SCH_1):PAGE50
    53    GND @BASEBOARD_FAB2_LIB.BASEBOARD_FAB2(SCH_1):GND    I44 @BASEBOARD_FAB2_LIB.BASEBOARD_FAB2(SCH_1):PAGE50
    55    GND @BASEBOARD_FAB2_LIB.BASEBOARD_FAB2(SCH_1):GND    I44 @BASEBOARD_FAB2_LIB.BASEBOARD_FAB2(SCH_1):PAGE50
    57    GND @BASEBOARD_FAB2_LIB.BASEBOARD_FAB2(SCH_1):GND    I44 @BASEBOARD_FAB2_LIB.BASEBOARD_FAB2(SCH_1):PAGE50
    94    GND @BASEBOARD_FAB2_LIB.BASEBOARD_FAB2(SCH_1):GND    I44 @BASEBOARD_FAB2_LIB.BASEBOARD_FAB2(SCH_1):PAGE50
    96    GND @BASEBOARD_FAB2_LIB.BASEBOARD_FAB2(SCH_1):GND    I44 @BASEBOARD_FAB2_LIB.BASEBOARD_FAB2(SCH_1):PAGE50
    98    GND @BASEBOARD_FAB2_LIB.BASEBOARD_FAB2(SCH_1):GND    I44 @BASEBOARD_FAB2_LIB.BASEBOARD_FAB2(SCH_1):PAGE50
   101    GND @BASEBOARD_FAB2_LIB.BASEBOARD_FAB2(SCH_1):GND    I44 @BASEBOARD_FAB2_LIB.BASEBOARD_FAB2(SCH_1):PAGE50
   103    GND @BASEBOARD_FAB2_LIB.BASEBOARD_FAB2(SCH_1):GND    I44 @BASEBOARD_FAB2_LIB.BASEBOARD_FAB2(SCH_1):PAGE50
   105    GND @BASEBOARD_FAB2_LIB.BASEBOARD_FAB2(SCH_1):GND    I44 @BASEBOARD_FAB2_LIB.BASEBOARD_FAB2(SCH_1):PAGE50
   107    GND @BASEBOARD_FAB2_LIB.BASEBOARD_FAB2(SCH_1):GND    I44 @BASEBOARD_FAB2_LIB.BASEBOARD_FAB2(SCH_1):PAGE50
   109    GND @BASEBOARD_FAB2_LIB.BASEBOARD_FAB2(SCH_1):GND    I44 @BASEBOARD_FAB2_LIB.BASEBOARD_FAB2(SCH_1):PAGE50
   112    GND @BASEBOARD_FAB2_LIB.BASEBOARD_FAB2(SCH_1):GND    I44 @BASEBOARD_FAB2_LIB.BASEBOARD_FAB2(SCH_1):PAGE50
   114    GND @BASEBOARD_FAB2_LIB.BASEBOARD_FAB2(SCH_1):GND    I44 @BASEBOARD_FAB2_LIB.BASEBOARD_FAB2(SCH_1):PAGE50
   116    GND @BASEBOARD_FAB2_LIB.BASEBOARD_FAB2(SCH_1):GND    I44 @BASEBOARD_FAB2_LIB.BASEBOARD_FAB2(SCH_1):PAGE50
   118    GND @BASEBOARD_FAB2_LIB.BASEBOARD_FAB2(SCH_1):GND    I44 @BASEBOARD_FAB2_LIB.BASEBOARD_FAB2(SCH_1):PAGE50
   120    GND @BASEBOARD_FAB2_LIB.BASEBOARD_FAB2(SCH_1):GND    I44 @BASEBOARD_FAB2_LIB.BASEBOARD_FAB2(SCH_1):PAGE50
   123    GND @BASEBOARD_FAB2_LIB.BASEBOARD_FAB2(SCH_1):GND    I44 @BASEBOARD_FAB2_LIB.BASEBOARD_FAB2(SCH_1):PAGE50
   125    GND @BASEBOARD_FAB2_LIB.BASEBOARD_FAB2(SCH_1):GND    I44 @BASEBOARD_FAB2_LIB.BASEBOARD_FAB2(SCH_1):PAGE50
   127    GND @BASEBOARD_FAB2_LIB.BASEBOARD_FAB2(SCH_1):GND    I44 @BASEBOARD_FAB2_LIB.BASEBOARD_FAB2(SCH_1):PAGE50
   129    GND @BASEBOARD_FAB2_LIB.BASEBOARD_FAB2(SCH_1):GND    I44 @BASEBOARD_FAB2_LIB.BASEBOARD_FAB2(SCH_1):PAGE50
   131    GND @BASEBOARD_FAB2_LIB.BASEBOARD_FAB2(SCH_1):GND    I44 @BASEBOARD_FAB2_LIB.BASEBOARD_FAB2(SCH_1):PAGE50
   134    GND @BASEBOARD_FAB2_LIB.BASEBOARD_FAB2(SCH_1):GND    I44 @BASEBOARD_FAB2_LIB.BASEBOARD_FAB2(SCH_1):PAGE50
   136    GND @BASEBOARD_FAB2_LIB.BASEBOARD_FAB2(SCH_1):GND    I44 @BASEBOARD_FAB2_LIB.BASEBOARD_FAB2(SCH_1):PAGE50
   138    GND @BASEBOARD_FAB2_LIB.BASEBOARD_FAB2(SCH_1):GND    I44 @BASEBOARD_FAB2_LIB.BASEBOARD_FAB2(SCH_1):PAGE50
   147    GND @BASEBOARD_FAB2_LIB.BASEBOARD_FAB2(SCH_1):GND    I44 @BASEBOARD_FAB2_LIB.BASEBOARD_FAB2(SCH_1):PAGE50
   149    GND @BASEBOARD_FAB2_LIB.BASEBOARD_FAB2(SCH_1):GND    I44 @BASEBOARD_FAB2_LIB.BASEBOARD_FAB2(SCH_1):PAGE50
   151    GND @BASEBOARD_FAB2_LIB.BASEBOARD_FAB2(SCH_1):GND    I44 @BASEBOARD_FAB2_LIB.BASEBOARD_FAB2(SCH_1):PAGE50
   154    GND @BASEBOARD_FAB2_LIB.BASEBOARD_FAB2(SCH_1):GND    I44 @BASEBOARD_FAB2_LIB.BASEBOARD_FAB2(SCH_1):PAGE50
   156    GND @BASEBOARD_FAB2_LIB.BASEBOARD_FAB2(SCH_1):GND    I44 @BASEBOARD_FAB2_LIB.BASEBOARD_FAB2(SCH_1):PAGE50
   158    GND @BASEBOARD_FAB2_LIB.BASEBOARD_FAB2(SCH_1):GND    I44 @BASEBOARD_FAB2_LIB.BASEBOARD_FAB2(SCH_1):PAGE50
   160    GND @BASEBOARD_FAB2_LIB.BASEBOARD_FAB2(SCH_1):GND    I44 @BASEBOARD_FAB2_LIB.BASEBOARD_FAB2(SCH_1):PAGE50
   162    GND @BASEBOARD_FAB2_LIB.BASEBOARD_FAB2(SCH_1):GND    I44 @BASEBOARD_FAB2_LIB.BASEBOARD_FAB2(SCH_1):PAGE50
   165    GND @BASEBOARD_FAB2_LIB.BASEBOARD_FAB2(SCH_1):GND    I44 @BASEBOARD_FAB2_LIB.BASEBOARD_FAB2(SCH_1):PAGE50
   167    GND @BASEBOARD_FAB2_LIB.BASEBOARD_FAB2(SCH_1):GND    I44 @BASEBOARD_FAB2_LIB.BASEBOARD_FAB2(SCH_1):PAGE50
   169    GND @BASEBOARD_FAB2_LIB.BASEBOARD_FAB2(SCH_1):GND    I44 @BASEBOARD_FAB2_LIB.BASEBOARD_FAB2(SCH_1):PAGE50
   171    GND @BASEBOARD_FAB2_LIB.BASEBOARD_FAB2(SCH_1):GND    I44 @BASEBOARD_FAB2_LIB.BASEBOARD_FAB2(SCH_1):PAGE50
   173    GND @BASEBOARD_FAB2_LIB.BASEBOARD_FAB2(SCH_1):GND    I44 @BASEBOARD_FAB2_LIB.BASEBOARD_FAB2(SCH_1):PAGE50
   176    GND @BASEBOARD_FAB2_LIB.BASEBOARD_FAB2(SCH_1):GND    I44 @BASEBOARD_FAB2_LIB.BASEBOARD_FAB2(SCH_1):PAGE50
   178    GND @BASEBOARD_FAB2_LIB.BASEBOARD_FAB2(SCH_1):GND    I44 @BASEBOARD_FAB2_LIB.BASEBOARD_FAB2(SCH_1):PAGE50
   180    GND @BASEBOARD_FAB2_LIB.BASEBOARD_FAB2(SCH_1):GND    I44 @BASEBOARD_FAB2_LIB.BASEBOARD_FAB2(SCH_1):PAGE50
   182    GND @BASEBOARD_FAB2_LIB.BASEBOARD_FAB2(SCH_1):GND    I44 @BASEBOARD_FAB2_LIB.BASEBOARD_FAB2(SCH_1):PAGE50
   184    GND @BASEBOARD_FAB2_LIB.BASEBOARD_FAB2(SCH_1):GND    I44 @BASEBOARD_FAB2_LIB.BASEBOARD_FAB2(SCH_1):PAGE50
   187    GND @BASEBOARD_FAB2_LIB.BASEBOARD_FAB2(SCH_1):GND    I44 @BASEBOARD_FAB2_LIB.BASEBOARD_FAB2(SCH_1):PAGE50
   189    GND @BASEBOARD_FAB2_LIB.BASEBOARD_FAB2(SCH_1):GND    I44 @BASEBOARD_FAB2_LIB.BASEBOARD_FAB2(SCH_1):PAGE50
   191    GND @BASEBOARD_FAB2_LIB.BASEBOARD_FAB2(SCH_1):GND    I44 @BASEBOARD_FAB2_LIB.BASEBOARD_FAB2(SCH_1):PAGE50
   193    GND @BASEBOARD_FAB2_LIB.BASEBOARD_FAB2(SCH_1):GND    I44 @BASEBOARD_FAB2_LIB.BASEBOARD_FAB2(SCH_1):PAGE50
   195    GND @BASEBOARD_FAB2_LIB.BASEBOARD_FAB2(SCH_1):GND    I44 @BASEBOARD_FAB2_LIB.BASEBOARD_FAB2(SCH_1):PAGE50
   198    GND @BASEBOARD_FAB2_LIB.BASEBOARD_FAB2(SCH_1):GND    I44 @BASEBOARD_FAB2_LIB.BASEBOARD_FAB2(SCH_1):PAGE50
   200    GND @BASEBOARD_FAB2_LIB.BASEBOARD_FAB2(SCH_1):GND    I44 @BASEBOARD_FAB2_LIB.BASEBOARD_FAB2(SCH_1):PAGE50
   202    GND @BASEBOARD_FAB2_LIB.BASEBOARD_FAB2(SCH_1):GND    I44 @BASEBOARD_FAB2_LIB.BASEBOARD_FAB2(SCH_1):PAGE50
   239    GND @BASEBOARD_FAB2_LIB.BASEBOARD_FAB2(SCH_1):GND    I44 @BASEBOARD_FAB2_LIB.BASEBOARD_FAB2(SCH_1):PAGE50
   241    GND @BASEBOARD_FAB2_LIB.BASEBOARD_FAB2(SCH_1):GND    I44 @BASEBOARD_FAB2_LIB.BASEBOARD_FAB2(SCH_1):PAGE50
   243    GND @BASEBOARD_FAB2_LIB.BASEBOARD_FAB2(SCH_1):GND    I44 @BASEBOARD_FAB2_LIB.BASEBOARD_FAB2(SCH_1):PAGE50
   246    GND @BASEBOARD_FAB2_LIB.BASEBOARD_FAB2(SCH_1):GND    I44 @BASEBOARD_FAB2_LIB.BASEBOARD_FAB2(SCH_1):PAGE50
   248    GND @BASEBOARD_FAB2_LIB.BASEBOARD_FAB2(SCH_1):GND    I44 @BASEBOARD_FAB2_LIB.BASEBOARD_FAB2(SCH_1):PAGE50
   250    GND @BASEBOARD_FAB2_LIB.BASEBOARD_FAB2(SCH_1):GND    I44 @BASEBOARD_FAB2_LIB.BASEBOARD_FAB2(SCH_1):PAGE50
   252    GND @BASEBOARD_FAB2_LIB.BASEBOARD_FAB2(SCH_1):GND    I44 @BASEBOARD_FAB2_LIB.BASEBOARD_FAB2(SCH_1):PAGE50
   254    GND @BASEBOARD_FAB2_LIB.BASEBOARD_FAB2(SCH_1):GND    I44 @BASEBOARD_FAB2_LIB.BASEBOARD_FAB2(SCH_1):PAGE50
   257    GND @BASEBOARD_FAB2_LIB.BASEBOARD_FAB2(SCH_1):GND    I44 @BASEBOARD_FAB2_LIB.BASEBOARD_FAB2(SCH_1):PAGE50
   259    GND @BASEBOARD_FAB2_LIB.BASEBOARD_FAB2(SCH_1):GND    I44 @BASEBOARD_FAB2_LIB.BASEBOARD_FAB2(SCH_1):PAGE50
   261    GND @BASEBOARD_FAB2_LIB.BASEBOARD_FAB2(SCH_1):GND    I44 @BASEBOARD_FAB2_LIB.BASEBOARD_FAB2(SCH_1):PAGE50
   263    GND @BASEBOARD_FAB2_LIB.BASEBOARD_FAB2(SCH_1):GND    I44 @BASEBOARD_FAB2_LIB.BASEBOARD_FAB2(SCH_1):PAGE50
   265    GND @BASEBOARD_FAB2_LIB.BASEBOARD_FAB2(SCH_1):GND    I44 @BASEBOARD_FAB2_LIB.BASEBOARD_FAB2(SCH_1):PAGE50
   268    GND @BASEBOARD_FAB2_LIB.BASEBOARD_FAB2(SCH_1):GND    I44 @BASEBOARD_FAB2_LIB.BASEBOARD_FAB2(SCH_1):PAGE50
   270    GND @BASEBOARD_FAB2_LIB.BASEBOARD_FAB2(SCH_1):GND    I44 @BASEBOARD_FAB2_LIB.BASEBOARD_FAB2(SCH_1):PAGE50
   272    GND @BASEBOARD_FAB2_LIB.BASEBOARD_FAB2(SCH_1):GND    I44 @BASEBOARD_FAB2_LIB.BASEBOARD_FAB2(SCH_1):PAGE50
   274    GND @BASEBOARD_FAB2_LIB.BASEBOARD_FAB2(SCH_1):GND    I44 @BASEBOARD_FAB2_LIB.BASEBOARD_FAB2(SCH_1):PAGE50
   276    GND @BASEBOARD_FAB2_LIB.BASEBOARD_FAB2(SCH_1):GND    I44 @BASEBOARD_FAB2_LIB.BASEBOARD_FAB2(SCH_1):PAGE50
   279    GND @BASEBOARD_FAB2_LIB.BASEBOARD_FAB2(SCH_1):GND    I44 @BASEBOARD_FAB2_LIB.BASEBOARD_FAB2(SCH_1):PAGE50
   281    GND @BASEBOARD_FAB2_LIB.BASEBOARD_FAB2(SCH_1):GND    I44 @BASEBOARD_FAB2_LIB.BASEBOARD_FAB2(SCH_1):PAGE50
   283    GND @BASEBOARD_FAB2_LIB.BASEBOARD_FAB2(SCH_1):GND    I44 @BASEBOARD_FAB2_LIB.BASEBOARD_FAB2(SCH_1):PAGE50
     1 P12V_NVDIMM_DEF @BASEBOARD_FAB2_LIB.BASEBOARD_FAB2(SCH_1):P12V_NVDIMM_DEF    I50 @BASEBOARD_FAB2_LIB.BASEBOARD_FAB2(SCH_1):PAGE50
   145 P12V_NVDIMM_DEF @BASEBOARD_FAB2_LIB.BASEBOARD_FAB2(SCH_1):P12V_NVDIMM_DEF    I50 @BASEBOARD_FAB2_LIB.BASEBOARD_FAB2(SCH_1):PAGE50
    59 PVDDQ_DEF @BASEBOARD_FAB2_LIB.BASEBOARD_FAB2(SCH_1):PVDDQ_DEF    I50 @BASEBOARD_FAB2_LIB.BASEBOARD_FAB2(SCH_1):PAGE50
    61 PVDDQ_DEF @BASEBOARD_FAB2_LIB.BASEBOARD_FAB2(SCH_1):PVDDQ_DEF    I50 @BASEBOARD_FAB2_LIB.BASEBOARD_FAB2(SCH_1):PAGE50
    64 PVDDQ_DEF @BASEBOARD_FAB2_LIB.BASEBOARD_FAB2(SCH_1):PVDDQ_DEF    I50 @BASEBOARD_FAB2_LIB.BASEBOARD_FAB2(SCH_1):PAGE50
    67 PVDDQ_DEF @BASEBOARD_FAB2_LIB.BASEBOARD_FAB2(SCH_1):PVDDQ_DEF    I50 @BASEBOARD_FAB2_LIB.BASEBOARD_FAB2(SCH_1):PAGE50
    70 PVDDQ_DEF @BASEBOARD_FAB2_LIB.BASEBOARD_FAB2(SCH_1):PVDDQ_DEF    I50 @BASEBOARD_FAB2_LIB.BASEBOARD_FAB2(SCH_1):PAGE50
    73 PVDDQ_DEF @BASEBOARD_FAB2_LIB.BASEBOARD_FAB2(SCH_1):PVDDQ_DEF    I50 @BASEBOARD_FAB2_LIB.BASEBOARD_FAB2(SCH_1):PAGE50
    76 PVDDQ_DEF @BASEBOARD_FAB2_LIB.BASEBOARD_FAB2(SCH_1):PVDDQ_DEF    I50 @BASEBOARD_FAB2_LIB.BASEBOARD_FAB2(SCH_1):PAGE50
    80 PVDDQ_DEF @BASEBOARD_FAB2_LIB.BASEBOARD_FAB2(SCH_1):PVDDQ_DEF    I50 @BASEBOARD_FAB2_LIB.BASEBOARD_FAB2(SCH_1):PAGE50
    83 PVDDQ_DEF @BASEBOARD_FAB2_LIB.BASEBOARD_FAB2(SCH_1):PVDDQ_DEF    I50 @BASEBOARD_FAB2_LIB.BASEBOARD_FAB2(SCH_1):PAGE50
    85 PVDDQ_DEF @BASEBOARD_FAB2_LIB.BASEBOARD_FAB2(SCH_1):PVDDQ_DEF    I50 @BASEBOARD_FAB2_LIB.BASEBOARD_FAB2(SCH_1):PAGE50
    88 PVDDQ_DEF @BASEBOARD_FAB2_LIB.BASEBOARD_FAB2(SCH_1):PVDDQ_DEF    I50 @BASEBOARD_FAB2_LIB.BASEBOARD_FAB2(SCH_1):PAGE50
    90 PVDDQ_DEF @BASEBOARD_FAB2_LIB.BASEBOARD_FAB2(SCH_1):PVDDQ_DEF    I50 @BASEBOARD_FAB2_LIB.BASEBOARD_FAB2(SCH_1):PAGE50
    92 PVDDQ_DEF @BASEBOARD_FAB2_LIB.BASEBOARD_FAB2(SCH_1):PVDDQ_DEF    I50 @BASEBOARD_FAB2_LIB.BASEBOARD_FAB2(SCH_1):PAGE50
   204 PVDDQ_DEF @BASEBOARD_FAB2_LIB.BASEBOARD_FAB2(SCH_1):PVDDQ_DEF    I50 @BASEBOARD_FAB2_LIB.BASEBOARD_FAB2(SCH_1):PAGE50
   206 PVDDQ_DEF @BASEBOARD_FAB2_LIB.BASEBOARD_FAB2(SCH_1):PVDDQ_DEF    I50 @BASEBOARD_FAB2_LIB.BASEBOARD_FAB2(SCH_1):PAGE50
   209 PVDDQ_DEF @BASEBOARD_FAB2_LIB.BASEBOARD_FAB2(SCH_1):PVDDQ_DEF    I50 @BASEBOARD_FAB2_LIB.BASEBOARD_FAB2(SCH_1):PAGE50
   212 PVDDQ_DEF @BASEBOARD_FAB2_LIB.BASEBOARD_FAB2(SCH_1):PVDDQ_DEF    I50 @BASEBOARD_FAB2_LIB.BASEBOARD_FAB2(SCH_1):PAGE50
   215 PVDDQ_DEF @BASEBOARD_FAB2_LIB.BASEBOARD_FAB2(SCH_1):PVDDQ_DEF    I50 @BASEBOARD_FAB2_LIB.BASEBOARD_FAB2(SCH_1):PAGE50
   217 PVDDQ_DEF @BASEBOARD_FAB2_LIB.BASEBOARD_FAB2(SCH_1):PVDDQ_DEF    I50 @BASEBOARD_FAB2_LIB.BASEBOARD_FAB2(SCH_1):PAGE50
   220 PVDDQ_DEF @BASEBOARD_FAB2_LIB.BASEBOARD_FAB2(SCH_1):PVDDQ_DEF    I50 @BASEBOARD_FAB2_LIB.BASEBOARD_FAB2(SCH_1):PAGE50
   223 PVDDQ_DEF @BASEBOARD_FAB2_LIB.BASEBOARD_FAB2(SCH_1):PVDDQ_DEF    I50 @BASEBOARD_FAB2_LIB.BASEBOARD_FAB2(SCH_1):PAGE50
   226 PVDDQ_DEF @BASEBOARD_FAB2_LIB.BASEBOARD_FAB2(SCH_1):PVDDQ_DEF    I50 @BASEBOARD_FAB2_LIB.BASEBOARD_FAB2(SCH_1):PAGE50
   229 PVDDQ_DEF @BASEBOARD_FAB2_LIB.BASEBOARD_FAB2(SCH_1):PVDDQ_DEF    I50 @BASEBOARD_FAB2_LIB.BASEBOARD_FAB2(SCH_1):PAGE50
   231 PVDDQ_DEF @BASEBOARD_FAB2_LIB.BASEBOARD_FAB2(SCH_1):PVDDQ_DEF    I50 @BASEBOARD_FAB2_LIB.BASEBOARD_FAB2(SCH_1):PAGE50
   233 PVDDQ_DEF @BASEBOARD_FAB2_LIB.BASEBOARD_FAB2(SCH_1):PVDDQ_DEF    I50 @BASEBOARD_FAB2_LIB.BASEBOARD_FAB2(SCH_1):PAGE50
   236 PVDDQ_DEF @BASEBOARD_FAB2_LIB.BASEBOARD_FAB2(SCH_1):PVDDQ_DEF    I50 @BASEBOARD_FAB2_LIB.BASEBOARD_FAB2(SCH_1):PAGE50
   142 PVPP_DEF @BASEBOARD_FAB2_LIB.BASEBOARD_FAB2(SCH_1):PVPP_DEF    I50 @BASEBOARD_FAB2_LIB.BASEBOARD_FAB2(SCH_1):PAGE50
   143 PVPP_DEF @BASEBOARD_FAB2_LIB.BASEBOARD_FAB2(SCH_1):PVPP_DEF    I50 @BASEBOARD_FAB2_LIB.BASEBOARD_FAB2(SCH_1):PAGE50
   288 PVPP_DEF @BASEBOARD_FAB2_LIB.BASEBOARD_FAB2(SCH_1):PVPP_DEF    I50 @BASEBOARD_FAB2_LIB.BASEBOARD_FAB2(SCH_1):PAGE50
   286 PVPP_DEF @BASEBOARD_FAB2_LIB.BASEBOARD_FAB2(SCH_1):PVPP_DEF    I50 @BASEBOARD_FAB2_LIB.BASEBOARD_FAB2(SCH_1):PAGE50
   287 PVPP_DEF @BASEBOARD_FAB2_LIB.BASEBOARD_FAB2(SCH_1):PVPP_DEF    I50 @BASEBOARD_FAB2_LIB.BASEBOARD_FAB2(SCH_1):PAGE50
    77 PVTT_DEF @BASEBOARD_FAB2_LIB.BASEBOARD_FAB2(SCH_1):PVTT_DEF    I50 @BASEBOARD_FAB2_LIB.BASEBOARD_FAB2(SCH_1):PAGE50
   221 PVTT_DEF @BASEBOARD_FAB2_LIB.BASEBOARD_FAB2(SCH_1):PVTT_DEF    I50 @BASEBOARD_FAB2_LIB.BASEBOARD_FAB2(SCH_1):PAGE50

J6T1 SCONN288_H44441003_PIP-SCONN,HA
    79 M_A_MA<0> @BASEBOARD_FAB2_LIB.BASEBOARD_FAB2(SCH_1):M_A_MA(0)    I13 @BASEBOARD_FAB2_LIB.BASEBOARD_FAB2(SCH_1):PAGE44
    72 M_A_MA<1> @BASEBOARD_FAB2_LIB.BASEBOARD_FAB2(SCH_1):M_A_MA(1)    I13 @BASEBOARD_FAB2_LIB.BASEBOARD_FAB2(SCH_1):PAGE44
   225 M_A_MA<10> @BASEBOARD_FAB2_LIB.BASEBOARD_FAB2(SCH_1):M_A_MA(10)    I13 @BASEBOARD_FAB2_LIB.BASEBOARD_FAB2(SCH_1):PAGE44
   210 M_A_MA<11> @BASEBOARD_FAB2_LIB.BASEBOARD_FAB2(SCH_1):M_A_MA(11)    I13 @BASEBOARD_FAB2_LIB.BASEBOARD_FAB2(SCH_1):PAGE44
    65 M_A_MA<12> @BASEBOARD_FAB2_LIB.BASEBOARD_FAB2(SCH_1):M_A_MA(12)    I13 @BASEBOARD_FAB2_LIB.BASEBOARD_FAB2(SCH_1):PAGE44
   232 M_A_MA<13> @BASEBOARD_FAB2_LIB.BASEBOARD_FAB2(SCH_1):M_A_MA(13)    I13 @BASEBOARD_FAB2_LIB.BASEBOARD_FAB2(SCH_1):PAGE44
   228 M_A_MA<14> @BASEBOARD_FAB2_LIB.BASEBOARD_FAB2(SCH_1):M_A_MA(14)    I13 @BASEBOARD_FAB2_LIB.BASEBOARD_FAB2(SCH_1):PAGE44
    86 M_A_MA<15> @BASEBOARD_FAB2_LIB.BASEBOARD_FAB2(SCH_1):M_A_MA(15)    I13 @BASEBOARD_FAB2_LIB.BASEBOARD_FAB2(SCH_1):PAGE44
    82 M_A_MA<16> @BASEBOARD_FAB2_LIB.BASEBOARD_FAB2(SCH_1):M_A_MA(16)    I13 @BASEBOARD_FAB2_LIB.BASEBOARD_FAB2(SCH_1):PAGE44
   234 M_A_MA<17> @BASEBOARD_FAB2_LIB.BASEBOARD_FAB2(SCH_1):M_A_MA(17)    I13 @BASEBOARD_FAB2_LIB.BASEBOARD_FAB2(SCH_1):PAGE44
   216 M_A_MA<2> @BASEBOARD_FAB2_LIB.BASEBOARD_FAB2(SCH_1):M_A_MA(2)    I13 @BASEBOARD_FAB2_LIB.BASEBOARD_FAB2(SCH_1):PAGE44
    71 M_A_MA<3> @BASEBOARD_FAB2_LIB.BASEBOARD_FAB2(SCH_1):M_A_MA(3)    I13 @BASEBOARD_FAB2_LIB.BASEBOARD_FAB2(SCH_1):PAGE44
   214 M_A_MA<4> @BASEBOARD_FAB2_LIB.BASEBOARD_FAB2(SCH_1):M_A_MA(4)    I13 @BASEBOARD_FAB2_LIB.BASEBOARD_FAB2(SCH_1):PAGE44
   213 M_A_MA<5> @BASEBOARD_FAB2_LIB.BASEBOARD_FAB2(SCH_1):M_A_MA(5)    I13 @BASEBOARD_FAB2_LIB.BASEBOARD_FAB2(SCH_1):PAGE44
    69 M_A_MA<6> @BASEBOARD_FAB2_LIB.BASEBOARD_FAB2(SCH_1):M_A_MA(6)    I13 @BASEBOARD_FAB2_LIB.BASEBOARD_FAB2(SCH_1):PAGE44
   211 M_A_MA<7> @BASEBOARD_FAB2_LIB.BASEBOARD_FAB2(SCH_1):M_A_MA(7)    I13 @BASEBOARD_FAB2_LIB.BASEBOARD_FAB2(SCH_1):PAGE44
    68 M_A_MA<8> @BASEBOARD_FAB2_LIB.BASEBOARD_FAB2(SCH_1):M_A_MA(8)    I13 @BASEBOARD_FAB2_LIB.BASEBOARD_FAB2(SCH_1):PAGE44
    66 M_A_MA<9> @BASEBOARD_FAB2_LIB.BASEBOARD_FAB2(SCH_1):M_A_MA(9)    I13 @BASEBOARD_FAB2_LIB.BASEBOARD_FAB2(SCH_1):PAGE44
    62 M_A_ACT_N @BASEBOARD_FAB2_LIB.BASEBOARD_FAB2(SCH_1):M_A_ACT_N    I13 @BASEBOARD_FAB2_LIB.BASEBOARD_FAB2(SCH_1):PAGE44
   208 M_A_ALERT_N @BASEBOARD_FAB2_LIB.BASEBOARD_FAB2(SCH_1):M_A_ALERT_N    I13 @BASEBOARD_FAB2_LIB.BASEBOARD_FAB2(SCH_1):PAGE44
   224 M_A_BA<1> @BASEBOARD_FAB2_LIB.BASEBOARD_FAB2(SCH_1):M_A_BA(1)    I13 @BASEBOARD_FAB2_LIB.BASEBOARD_FAB2(SCH_1):PAGE44
    81 M_A_BA<0> @BASEBOARD_FAB2_LIB.BASEBOARD_FAB2(SCH_1):M_A_BA(0)    I13 @BASEBOARD_FAB2_LIB.BASEBOARD_FAB2(SCH_1):PAGE44
   207 M_A_BG<1> @BASEBOARD_FAB2_LIB.BASEBOARD_FAB2(SCH_1):M_A_BG(1)    I13 @BASEBOARD_FAB2_LIB.BASEBOARD_FAB2(SCH_1):PAGE44
    63 M_A_BG<0> @BASEBOARD_FAB2_LIB.BASEBOARD_FAB2(SCH_1):M_A_BG(0)    I13 @BASEBOARD_FAB2_LIB.BASEBOARD_FAB2(SCH_1):PAGE44
   235 M_A_C<2> @BASEBOARD_FAB2_LIB.BASEBOARD_FAB2(SCH_1):M_A_C(2)    I13 @BASEBOARD_FAB2_LIB.BASEBOARD_FAB2(SCH_1):PAGE44
   199 M_A_ECC<7> @BASEBOARD_FAB2_LIB.BASEBOARD_FAB2(SCH_1):M_A_ECC(7)    I13 @BASEBOARD_FAB2_LIB.BASEBOARD_FAB2(SCH_1):PAGE44
    54 M_A_ECC<6> @BASEBOARD_FAB2_LIB.BASEBOARD_FAB2(SCH_1):M_A_ECC(6)    I13 @BASEBOARD_FAB2_LIB.BASEBOARD_FAB2(SCH_1):PAGE44
   192 M_A_ECC<5> @BASEBOARD_FAB2_LIB.BASEBOARD_FAB2(SCH_1):M_A_ECC(5)    I13 @BASEBOARD_FAB2_LIB.BASEBOARD_FAB2(SCH_1):PAGE44
    47 M_A_ECC<4> @BASEBOARD_FAB2_LIB.BASEBOARD_FAB2(SCH_1):M_A_ECC(4)    I13 @BASEBOARD_FAB2_LIB.BASEBOARD_FAB2(SCH_1):PAGE44
   201 M_A_ECC<3> @BASEBOARD_FAB2_LIB.BASEBOARD_FAB2(SCH_1):M_A_ECC(3)    I13 @BASEBOARD_FAB2_LIB.BASEBOARD_FAB2(SCH_1):PAGE44
    56 M_A_ECC<2> @BASEBOARD_FAB2_LIB.BASEBOARD_FAB2(SCH_1):M_A_ECC(2)    I13 @BASEBOARD_FAB2_LIB.BASEBOARD_FAB2(SCH_1):PAGE44
   194 M_A_ECC<1> @BASEBOARD_FAB2_LIB.BASEBOARD_FAB2(SCH_1):M_A_ECC(1)    I13 @BASEBOARD_FAB2_LIB.BASEBOARD_FAB2(SCH_1):PAGE44
    49 M_A_ECC<0> @BASEBOARD_FAB2_LIB.BASEBOARD_FAB2(SCH_1):M_A_ECC(0)    I13 @BASEBOARD_FAB2_LIB.BASEBOARD_FAB2(SCH_1):PAGE44
    75 M_A_CLK_DN<2> @BASEBOARD_FAB2_LIB.BASEBOARD_FAB2(SCH_1):M_A_CLK_DN(2)    I13 @BASEBOARD_FAB2_LIB.BASEBOARD_FAB2(SCH_1):PAGE44
    74 M_A_CLK_DP<2> @BASEBOARD_FAB2_LIB.BASEBOARD_FAB2(SCH_1):M_A_CLK_DP(2)    I13 @BASEBOARD_FAB2_LIB.BASEBOARD_FAB2(SCH_1):PAGE44
   219 M_A_CLK_DN<3> @BASEBOARD_FAB2_LIB.BASEBOARD_FAB2(SCH_1):M_A_CLK_DN(3)    I13 @BASEBOARD_FAB2_LIB.BASEBOARD_FAB2(SCH_1):PAGE44
   218 M_A_CLK_DP<3> @BASEBOARD_FAB2_LIB.BASEBOARD_FAB2(SCH_1):M_A_CLK_DP(3)    I13 @BASEBOARD_FAB2_LIB.BASEBOARD_FAB2(SCH_1):PAGE44
   203 M_A_CKE<3> @BASEBOARD_FAB2_LIB.BASEBOARD_FAB2(SCH_1):M_A_CKE(3)    I13 @BASEBOARD_FAB2_LIB.BASEBOARD_FAB2(SCH_1):PAGE44
    60 M_A_CKE<2> @BASEBOARD_FAB2_LIB.BASEBOARD_FAB2(SCH_1):M_A_CKE(2)    I13 @BASEBOARD_FAB2_LIB.BASEBOARD_FAB2(SCH_1):PAGE44
   280 M_A_DQ<63> @BASEBOARD_FAB2_LIB.BASEBOARD_FAB2(SCH_1):M_A_DQ(63)    I13 @BASEBOARD_FAB2_LIB.BASEBOARD_FAB2(SCH_1):PAGE44
   135 M_A_DQ<62> @BASEBOARD_FAB2_LIB.BASEBOARD_FAB2(SCH_1):M_A_DQ(62)    I13 @BASEBOARD_FAB2_LIB.BASEBOARD_FAB2(SCH_1):PAGE44
   273 M_A_DQ<61> @BASEBOARD_FAB2_LIB.BASEBOARD_FAB2(SCH_1):M_A_DQ(61)    I13 @BASEBOARD_FAB2_LIB.BASEBOARD_FAB2(SCH_1):PAGE44
   128 M_A_DQ<60> @BASEBOARD_FAB2_LIB.BASEBOARD_FAB2(SCH_1):M_A_DQ(60)    I13 @BASEBOARD_FAB2_LIB.BASEBOARD_FAB2(SCH_1):PAGE44
   282 M_A_DQ<59> @BASEBOARD_FAB2_LIB.BASEBOARD_FAB2(SCH_1):M_A_DQ(59)    I13 @BASEBOARD_FAB2_LIB.BASEBOARD_FAB2(SCH_1):PAGE44
   137 M_A_DQ<58> @BASEBOARD_FAB2_LIB.BASEBOARD_FAB2(SCH_1):M_A_DQ(58)    I13 @BASEBOARD_FAB2_LIB.BASEBOARD_FAB2(SCH_1):PAGE44
   275 M_A_DQ<57> @BASEBOARD_FAB2_LIB.BASEBOARD_FAB2(SCH_1):M_A_DQ(57)    I13 @BASEBOARD_FAB2_LIB.BASEBOARD_FAB2(SCH_1):PAGE44
   130 M_A_DQ<56> @BASEBOARD_FAB2_LIB.BASEBOARD_FAB2(SCH_1):M_A_DQ(56)    I13 @BASEBOARD_FAB2_LIB.BASEBOARD_FAB2(SCH_1):PAGE44
   269 M_A_DQ<55> @BASEBOARD_FAB2_LIB.BASEBOARD_FAB2(SCH_1):M_A_DQ(55)    I13 @BASEBOARD_FAB2_LIB.BASEBOARD_FAB2(SCH_1):PAGE44
   124 M_A_DQ<54> @BASEBOARD_FAB2_LIB.BASEBOARD_FAB2(SCH_1):M_A_DQ(54)    I13 @BASEBOARD_FAB2_LIB.BASEBOARD_FAB2(SCH_1):PAGE44
   262 M_A_DQ<53> @BASEBOARD_FAB2_LIB.BASEBOARD_FAB2(SCH_1):M_A_DQ(53)    I13 @BASEBOARD_FAB2_LIB.BASEBOARD_FAB2(SCH_1):PAGE44
   117 M_A_DQ<52> @BASEBOARD_FAB2_LIB.BASEBOARD_FAB2(SCH_1):M_A_DQ(52)    I13 @BASEBOARD_FAB2_LIB.BASEBOARD_FAB2(SCH_1):PAGE44
   271 M_A_DQ<51> @BASEBOARD_FAB2_LIB.BASEBOARD_FAB2(SCH_1):M_A_DQ(51)    I13 @BASEBOARD_FAB2_LIB.BASEBOARD_FAB2(SCH_1):PAGE44
   126 M_A_DQ<50> @BASEBOARD_FAB2_LIB.BASEBOARD_FAB2(SCH_1):M_A_DQ(50)    I13 @BASEBOARD_FAB2_LIB.BASEBOARD_FAB2(SCH_1):PAGE44
   264 M_A_DQ<49> @BASEBOARD_FAB2_LIB.BASEBOARD_FAB2(SCH_1):M_A_DQ(49)    I13 @BASEBOARD_FAB2_LIB.BASEBOARD_FAB2(SCH_1):PAGE44
   119 M_A_DQ<48> @BASEBOARD_FAB2_LIB.BASEBOARD_FAB2(SCH_1):M_A_DQ(48)    I13 @BASEBOARD_FAB2_LIB.BASEBOARD_FAB2(SCH_1):PAGE44
   258 M_A_DQ<47> @BASEBOARD_FAB2_LIB.BASEBOARD_FAB2(SCH_1):M_A_DQ(47)    I13 @BASEBOARD_FAB2_LIB.BASEBOARD_FAB2(SCH_1):PAGE44
   113 M_A_DQ<46> @BASEBOARD_FAB2_LIB.BASEBOARD_FAB2(SCH_1):M_A_DQ(46)    I13 @BASEBOARD_FAB2_LIB.BASEBOARD_FAB2(SCH_1):PAGE44
   251 M_A_DQ<45> @BASEBOARD_FAB2_LIB.BASEBOARD_FAB2(SCH_1):M_A_DQ(45)    I13 @BASEBOARD_FAB2_LIB.BASEBOARD_FAB2(SCH_1):PAGE44
   106 M_A_DQ<44> @BASEBOARD_FAB2_LIB.BASEBOARD_FAB2(SCH_1):M_A_DQ(44)    I13 @BASEBOARD_FAB2_LIB.BASEBOARD_FAB2(SCH_1):PAGE44
   260 M_A_DQ<43> @BASEBOARD_FAB2_LIB.BASEBOARD_FAB2(SCH_1):M_A_DQ(43)    I13 @BASEBOARD_FAB2_LIB.BASEBOARD_FAB2(SCH_1):PAGE44
   115 M_A_DQ<42> @BASEBOARD_FAB2_LIB.BASEBOARD_FAB2(SCH_1):M_A_DQ(42)    I13 @BASEBOARD_FAB2_LIB.BASEBOARD_FAB2(SCH_1):PAGE44
   253 M_A_DQ<41> @BASEBOARD_FAB2_LIB.BASEBOARD_FAB2(SCH_1):M_A_DQ(41)    I13 @BASEBOARD_FAB2_LIB.BASEBOARD_FAB2(SCH_1):PAGE44
   108 M_A_DQ<40> @BASEBOARD_FAB2_LIB.BASEBOARD_FAB2(SCH_1):M_A_DQ(40)    I13 @BASEBOARD_FAB2_LIB.BASEBOARD_FAB2(SCH_1):PAGE44
   247 M_A_DQ<39> @BASEBOARD_FAB2_LIB.BASEBOARD_FAB2(SCH_1):M_A_DQ(39)    I13 @BASEBOARD_FAB2_LIB.BASEBOARD_FAB2(SCH_1):PAGE44
   102 M_A_DQ<38> @BASEBOARD_FAB2_LIB.BASEBOARD_FAB2(SCH_1):M_A_DQ(38)    I13 @BASEBOARD_FAB2_LIB.BASEBOARD_FAB2(SCH_1):PAGE44
   240 M_A_DQ<37> @BASEBOARD_FAB2_LIB.BASEBOARD_FAB2(SCH_1):M_A_DQ(37)    I13 @BASEBOARD_FAB2_LIB.BASEBOARD_FAB2(SCH_1):PAGE44
    95 M_A_DQ<36> @BASEBOARD_FAB2_LIB.BASEBOARD_FAB2(SCH_1):M_A_DQ(36)    I13 @BASEBOARD_FAB2_LIB.BASEBOARD_FAB2(SCH_1):PAGE44
   249 M_A_DQ<35> @BASEBOARD_FAB2_LIB.BASEBOARD_FAB2(SCH_1):M_A_DQ(35)    I13 @BASEBOARD_FAB2_LIB.BASEBOARD_FAB2(SCH_1):PAGE44
   104 M_A_DQ<34> @BASEBOARD_FAB2_LIB.BASEBOARD_FAB2(SCH_1):M_A_DQ(34)    I13 @BASEBOARD_FAB2_LIB.BASEBOARD_FAB2(SCH_1):PAGE44
   242 M_A_DQ<33> @BASEBOARD_FAB2_LIB.BASEBOARD_FAB2(SCH_1):M_A_DQ(33)    I13 @BASEBOARD_FAB2_LIB.BASEBOARD_FAB2(SCH_1):PAGE44
    97 M_A_DQ<32> @BASEBOARD_FAB2_LIB.BASEBOARD_FAB2(SCH_1):M_A_DQ(32)    I13 @BASEBOARD_FAB2_LIB.BASEBOARD_FAB2(SCH_1):PAGE44
   188 M_A_DQ<31> @BASEBOARD_FAB2_LIB.BASEBOARD_FAB2(SCH_1):M_A_DQ(31)    I13 @BASEBOARD_FAB2_LIB.BASEBOARD_FAB2(SCH_1):PAGE44
    43 M_A_DQ<30> @BASEBOARD_FAB2_LIB.BASEBOARD_FAB2(SCH_1):M_A_DQ(30)    I13 @BASEBOARD_FAB2_LIB.BASEBOARD_FAB2(SCH_1):PAGE44
   181 M_A_DQ<29> @BASEBOARD_FAB2_LIB.BASEBOARD_FAB2(SCH_1):M_A_DQ(29)    I13 @BASEBOARD_FAB2_LIB.BASEBOARD_FAB2(SCH_1):PAGE44
    36 M_A_DQ<28> @BASEBOARD_FAB2_LIB.BASEBOARD_FAB2(SCH_1):M_A_DQ(28)    I13 @BASEBOARD_FAB2_LIB.BASEBOARD_FAB2(SCH_1):PAGE44
   190 M_A_DQ<27> @BASEBOARD_FAB2_LIB.BASEBOARD_FAB2(SCH_1):M_A_DQ(27)    I13 @BASEBOARD_FAB2_LIB.BASEBOARD_FAB2(SCH_1):PAGE44
    45 M_A_DQ<26> @BASEBOARD_FAB2_LIB.BASEBOARD_FAB2(SCH_1):M_A_DQ(26)    I13 @BASEBOARD_FAB2_LIB.BASEBOARD_FAB2(SCH_1):PAGE44
   183 M_A_DQ<25> @BASEBOARD_FAB2_LIB.BASEBOARD_FAB2(SCH_1):M_A_DQ(25)    I13 @BASEBOARD_FAB2_LIB.BASEBOARD_FAB2(SCH_1):PAGE44
    38 M_A_DQ<24> @BASEBOARD_FAB2_LIB.BASEBOARD_FAB2(SCH_1):M_A_DQ(24)    I13 @BASEBOARD_FAB2_LIB.BASEBOARD_FAB2(SCH_1):PAGE44
   177 M_A_DQ<23> @BASEBOARD_FAB2_LIB.BASEBOARD_FAB2(SCH_1):M_A_DQ(23)    I13 @BASEBOARD_FAB2_LIB.BASEBOARD_FAB2(SCH_1):PAGE44
    32 M_A_DQ<22> @BASEBOARD_FAB2_LIB.BASEBOARD_FAB2(SCH_1):M_A_DQ(22)    I13 @BASEBOARD_FAB2_LIB.BASEBOARD_FAB2(SCH_1):PAGE44
   170 M_A_DQ<21> @BASEBOARD_FAB2_LIB.BASEBOARD_FAB2(SCH_1):M_A_DQ(21)    I13 @BASEBOARD_FAB2_LIB.BASEBOARD_FAB2(SCH_1):PAGE44
    25 M_A_DQ<20> @BASEBOARD_FAB2_LIB.BASEBOARD_FAB2(SCH_1):M_A_DQ(20)    I13 @BASEBOARD_FAB2_LIB.BASEBOARD_FAB2(SCH_1):PAGE44
   179 M_A_DQ<19> @BASEBOARD_FAB2_LIB.BASEBOARD_FAB2(SCH_1):M_A_DQ(19)    I13 @BASEBOARD_FAB2_LIB.BASEBOARD_FAB2(SCH_1):PAGE44
    34 M_A_DQ<18> @BASEBOARD_FAB2_LIB.BASEBOARD_FAB2(SCH_1):M_A_DQ(18)    I13 @BASEBOARD_FAB2_LIB.BASEBOARD_FAB2(SCH_1):PAGE44
   172 M_A_DQ<17> @BASEBOARD_FAB2_LIB.BASEBOARD_FAB2(SCH_1):M_A_DQ(17)    I13 @BASEBOARD_FAB2_LIB.BASEBOARD_FAB2(SCH_1):PAGE44
    27 M_A_DQ<16> @BASEBOARD_FAB2_LIB.BASEBOARD_FAB2(SCH_1):M_A_DQ(16)    I13 @BASEBOARD_FAB2_LIB.BASEBOARD_FAB2(SCH_1):PAGE44
   166 M_A_DQ<15> @BASEBOARD_FAB2_LIB.BASEBOARD_FAB2(SCH_1):M_A_DQ(15)    I13 @BASEBOARD_FAB2_LIB.BASEBOARD_FAB2(SCH_1):PAGE44
    21 M_A_DQ<14> @BASEBOARD_FAB2_LIB.BASEBOARD_FAB2(SCH_1):M_A_DQ(14)    I13 @BASEBOARD_FAB2_LIB.BASEBOARD_FAB2(SCH_1):PAGE44
   159 M_A_DQ<13> @BASEBOARD_FAB2_LIB.BASEBOARD_FAB2(SCH_1):M_A_DQ(13)    I13 @BASEBOARD_FAB2_LIB.BASEBOARD_FAB2(SCH_1):PAGE44
    14 M_A_DQ<12> @BASEBOARD_FAB2_LIB.BASEBOARD_FAB2(SCH_1):M_A_DQ(12)    I13 @BASEBOARD_FAB2_LIB.BASEBOARD_FAB2(SCH_1):PAGE44
   168 M_A_DQ<11> @BASEBOARD_FAB2_LIB.BASEBOARD_FAB2(SCH_1):M_A_DQ(11)    I13 @BASEBOARD_FAB2_LIB.BASEBOARD_FAB2(SCH_1):PAGE44
    23 M_A_DQ<10> @BASEBOARD_FAB2_LIB.BASEBOARD_FAB2(SCH_1):M_A_DQ(10)    I13 @BASEBOARD_FAB2_LIB.BASEBOARD_FAB2(SCH_1):PAGE44
   161 M_A_DQ<9> @BASEBOARD_FAB2_LIB.BASEBOARD_FAB2(SCH_1):M_A_DQ(9)    I13 @BASEBOARD_FAB2_LIB.BASEBOARD_FAB2(SCH_1):PAGE44
    16 M_A_DQ<8> @BASEBOARD_FAB2_LIB.BASEBOARD_FAB2(SCH_1):M_A_DQ(8)    I13 @BASEBOARD_FAB2_LIB.BASEBOARD_FAB2(SCH_1):PAGE44
   155 M_A_DQ<7> @BASEBOARD_FAB2_LIB.BASEBOARD_FAB2(SCH_1):M_A_DQ(7)    I13 @BASEBOARD_FAB2_LIB.BASEBOARD_FAB2(SCH_1):PAGE44
    10 M_A_DQ<6> @BASEBOARD_FAB2_LIB.BASEBOARD_FAB2(SCH_1):M_A_DQ(6)    I13 @BASEBOARD_FAB2_LIB.BASEBOARD_FAB2(SCH_1):PAGE44
   148 M_A_DQ<5> @BASEBOARD_FAB2_LIB.BASEBOARD_FAB2(SCH_1):M_A_DQ(5)    I13 @BASEBOARD_FAB2_LIB.BASEBOARD_FAB2(SCH_1):PAGE44
     3 M_A_DQ<4> @BASEBOARD_FAB2_LIB.BASEBOARD_FAB2(SCH_1):M_A_DQ(4)    I13 @BASEBOARD_FAB2_LIB.BASEBOARD_FAB2(SCH_1):PAGE44
   157 M_A_DQ<3> @BASEBOARD_FAB2_LIB.BASEBOARD_FAB2(SCH_1):M_A_DQ(3)    I13 @BASEBOARD_FAB2_LIB.BASEBOARD_FAB2(SCH_1):PAGE44
    12 M_A_DQ<2> @BASEBOARD_FAB2_LIB.BASEBOARD_FAB2(SCH_1):M_A_DQ(2)    I13 @BASEBOARD_FAB2_LIB.BASEBOARD_FAB2(SCH_1):PAGE44
   150 M_A_DQ<1> @BASEBOARD_FAB2_LIB.BASEBOARD_FAB2(SCH_1):M_A_DQ(1)    I13 @BASEBOARD_FAB2_LIB.BASEBOARD_FAB2(SCH_1):PAGE44
     5 M_A_DQ<0> @BASEBOARD_FAB2_LIB.BASEBOARD_FAB2(SCH_1):M_A_DQ(0)    I13 @BASEBOARD_FAB2_LIB.BASEBOARD_FAB2(SCH_1):PAGE44
    78 FM_DIMM_EVENT_COD_N @BASEBOARD_FAB2_LIB.BASEBOARD_FAB2(SCH_1):FM_DIMM_EVENT_COD_N    I13 @BASEBOARD_FAB2_LIB.BASEBOARD_FAB2(SCH_1):PAGE44
    91 M_A_ODT<3> @BASEBOARD_FAB2_LIB.BASEBOARD_FAB2(SCH_1):M_A_ODT(3)    I13 @BASEBOARD_FAB2_LIB.BASEBOARD_FAB2(SCH_1):PAGE44
    87 M_A_ODT<2> @BASEBOARD_FAB2_LIB.BASEBOARD_FAB2(SCH_1):M_A_ODT(2)    I13 @BASEBOARD_FAB2_LIB.BASEBOARD_FAB2(SCH_1):PAGE44
   222 M_A_PAR @BASEBOARD_FAB2_LIB.BASEBOARD_FAB2(SCH_1):M_A_PAR    I13 @BASEBOARD_FAB2_LIB.BASEBOARD_FAB2(SCH_1):PAGE44
    58 M_ABC_RST_N @BASEBOARD_FAB2_LIB.BASEBOARD_FAB2(SCH_1):M_ABC_RST_N    I13 @BASEBOARD_FAB2_LIB.BASEBOARD_FAB2(SCH_1):PAGE44
   144 TP_CH_A_DIMM_A1_RFU_2 @BASEBOARD_FAB2_LIB.BASEBOARD_FAB2(SCH_1):TP_CH_A_DIMM_A1_RFU_2    I13 @BASEBOARD_FAB2_LIB.BASEBOARD_FAB2(SCH_1):PAGE44
   227 TP_CH_A_DIMM_A1_RFU_1 @BASEBOARD_FAB2_LIB.BASEBOARD_FAB2(SCH_1):TP_CH_A_DIMM_A1_RFU_1    I13 @BASEBOARD_FAB2_LIB.BASEBOARD_FAB2(SCH_1):PAGE44
   205 TP_CH_A_DIMM_A1_RFU_0 @BASEBOARD_FAB2_LIB.BASEBOARD_FAB2(SCH_1):TP_CH_A_DIMM_A1_RFU_0    I13 @BASEBOARD_FAB2_LIB.BASEBOARD_FAB2(SCH_1):PAGE44
    84 M_A_CS_N<4> @BASEBOARD_FAB2_LIB.BASEBOARD_FAB2(SCH_1):M_A_CS_N(4)    I13 @BASEBOARD_FAB2_LIB.BASEBOARD_FAB2(SCH_1):PAGE44
    89 M_A_CS_N<5> @BASEBOARD_FAB2_LIB.BASEBOARD_FAB2(SCH_1):M_A_CS_N(5)    I13 @BASEBOARD_FAB2_LIB.BASEBOARD_FAB2(SCH_1):PAGE44
    93 M_A_CS_N<6> @BASEBOARD_FAB2_LIB.BASEBOARD_FAB2(SCH_1):M_A_CS_N(6)    I13 @BASEBOARD_FAB2_LIB.BASEBOARD_FAB2(SCH_1):PAGE44
   237 M_A_CS_N<7> @BASEBOARD_FAB2_LIB.BASEBOARD_FAB2(SCH_1):M_A_CS_N(7)    I13 @BASEBOARD_FAB2_LIB.BASEBOARD_FAB2(SCH_1):PAGE44
   238    GND @BASEBOARD_FAB2_LIB.BASEBOARD_FAB2(SCH_1):GND    I13 @BASEBOARD_FAB2_LIB.BASEBOARD_FAB2(SCH_1):PAGE44
   140    GND @BASEBOARD_FAB2_LIB.BASEBOARD_FAB2(SCH_1):GND    I13 @BASEBOARD_FAB2_LIB.BASEBOARD_FAB2(SCH_1):PAGE44
   139 PVPP_ABC @BASEBOARD_FAB2_LIB.BASEBOARD_FAB2(SCH_1):PVPP_ABC    I13 @BASEBOARD_FAB2_LIB.BASEBOARD_FAB2(SCH_1):PAGE44
   230 FM_ADR_COMPLETE_ABC_N @BASEBOARD_FAB2_LIB.BASEBOARD_FAB2(SCH_1):FM_ADR_COMPLETE_ABC_N    I13 @BASEBOARD_FAB2_LIB.BASEBOARD_FAB2(SCH_1):PAGE44
   141 SMB_DDR_ABC_VPP_SCL @BASEBOARD_FAB2_LIB.BASEBOARD_FAB2(SCH_1):SMB_DDR_ABC_VPP_SCL    I13 @BASEBOARD_FAB2_LIB.BASEBOARD_FAB2(SCH_1):PAGE44
   285 SMB_DDR_ABC_VPP_SDA @BASEBOARD_FAB2_LIB.BASEBOARD_FAB2(SCH_1):SMB_DDR_ABC_VPP_SDA    I13 @BASEBOARD_FAB2_LIB.BASEBOARD_FAB2(SCH_1):PAGE44
   284 PVPP_ABC @BASEBOARD_FAB2_LIB.BASEBOARD_FAB2(SCH_1):PVPP_ABC    I13 @BASEBOARD_FAB2_LIB.BASEBOARD_FAB2(SCH_1):PAGE44
   146 M_A_VREF @BASEBOARD_FAB2_LIB.BASEBOARD_FAB2(SCH_1):M_A_VREF    I13 @BASEBOARD_FAB2_LIB.BASEBOARD_FAB2(SCH_1):PAGE44
   152 M_A_DQS_DN<0> @BASEBOARD_FAB2_LIB.BASEBOARD_FAB2(SCH_1):M_A_DQS_DN(0)   I120 @BASEBOARD_FAB2_LIB.BASEBOARD_FAB2(SCH_1):PAGE44
   153 M_A_DQS_DP<0> @BASEBOARD_FAB2_LIB.BASEBOARD_FAB2(SCH_1):M_A_DQS_DP(0)   I120 @BASEBOARD_FAB2_LIB.BASEBOARD_FAB2(SCH_1):PAGE44
    19 M_A_DQS_DN<10> @BASEBOARD_FAB2_LIB.BASEBOARD_FAB2(SCH_1):M_A_DQS_DN(10)   I120 @BASEBOARD_FAB2_LIB.BASEBOARD_FAB2(SCH_1):PAGE44
    18 M_A_DQS_DP<10> @BASEBOARD_FAB2_LIB.BASEBOARD_FAB2(SCH_1):M_A_DQS_DP(10)   I120 @BASEBOARD_FAB2_LIB.BASEBOARD_FAB2(SCH_1):PAGE44
    30 M_A_DQS_DN<11> @BASEBOARD_FAB2_LIB.BASEBOARD_FAB2(SCH_1):M_A_DQS_DN(11)   I120 @BASEBOARD_FAB2_LIB.BASEBOARD_FAB2(SCH_1):PAGE44
    29 M_A_DQS_DP<11> @BASEBOARD_FAB2_LIB.BASEBOARD_FAB2(SCH_1):M_A_DQS_DP(11)   I120 @BASEBOARD_FAB2_LIB.BASEBOARD_FAB2(SCH_1):PAGE44
    41 M_A_DQS_DN<12> @BASEBOARD_FAB2_LIB.BASEBOARD_FAB2(SCH_1):M_A_DQS_DN(12)   I120 @BASEBOARD_FAB2_LIB.BASEBOARD_FAB2(SCH_1):PAGE44
    40 M_A_DQS_DP<12> @BASEBOARD_FAB2_LIB.BASEBOARD_FAB2(SCH_1):M_A_DQS_DP(12)   I120 @BASEBOARD_FAB2_LIB.BASEBOARD_FAB2(SCH_1):PAGE44
   100 M_A_DQS_DN<13> @BASEBOARD_FAB2_LIB.BASEBOARD_FAB2(SCH_1):M_A_DQS_DN(13)   I120 @BASEBOARD_FAB2_LIB.BASEBOARD_FAB2(SCH_1):PAGE44
    99 M_A_DQS_DP<13> @BASEBOARD_FAB2_LIB.BASEBOARD_FAB2(SCH_1):M_A_DQS_DP(13)   I120 @BASEBOARD_FAB2_LIB.BASEBOARD_FAB2(SCH_1):PAGE44
   111 M_A_DQS_DN<14> @BASEBOARD_FAB2_LIB.BASEBOARD_FAB2(SCH_1):M_A_DQS_DN(14)   I120 @BASEBOARD_FAB2_LIB.BASEBOARD_FAB2(SCH_1):PAGE44
   110 M_A_DQS_DP<14> @BASEBOARD_FAB2_LIB.BASEBOARD_FAB2(SCH_1):M_A_DQS_DP(14)   I120 @BASEBOARD_FAB2_LIB.BASEBOARD_FAB2(SCH_1):PAGE44
   122 M_A_DQS_DN<15> @BASEBOARD_FAB2_LIB.BASEBOARD_FAB2(SCH_1):M_A_DQS_DN(15)   I120 @BASEBOARD_FAB2_LIB.BASEBOARD_FAB2(SCH_1):PAGE44
   121 M_A_DQS_DP<15> @BASEBOARD_FAB2_LIB.BASEBOARD_FAB2(SCH_1):M_A_DQS_DP(15)   I120 @BASEBOARD_FAB2_LIB.BASEBOARD_FAB2(SCH_1):PAGE44
   133 M_A_DQS_DN<16> @BASEBOARD_FAB2_LIB.BASEBOARD_FAB2(SCH_1):M_A_DQS_DN(16)   I120 @BASEBOARD_FAB2_LIB.BASEBOARD_FAB2(SCH_1):PAGE44
   132 M_A_DQS_DP<16> @BASEBOARD_FAB2_LIB.BASEBOARD_FAB2(SCH_1):M_A_DQS_DP(16)   I120 @BASEBOARD_FAB2_LIB.BASEBOARD_FAB2(SCH_1):PAGE44
    52 M_A_DQS_DN<17> @BASEBOARD_FAB2_LIB.BASEBOARD_FAB2(SCH_1):M_A_DQS_DN(17)   I120 @BASEBOARD_FAB2_LIB.BASEBOARD_FAB2(SCH_1):PAGE44
    51 M_A_DQS_DP<17> @BASEBOARD_FAB2_LIB.BASEBOARD_FAB2(SCH_1):M_A_DQS_DP(17)   I120 @BASEBOARD_FAB2_LIB.BASEBOARD_FAB2(SCH_1):PAGE44
   163 M_A_DQS_DN<1> @BASEBOARD_FAB2_LIB.BASEBOARD_FAB2(SCH_1):M_A_DQS_DN(1)   I120 @BASEBOARD_FAB2_LIB.BASEBOARD_FAB2(SCH_1):PAGE44
   164 M_A_DQS_DP<1> @BASEBOARD_FAB2_LIB.BASEBOARD_FAB2(SCH_1):M_A_DQS_DP(1)   I120 @BASEBOARD_FAB2_LIB.BASEBOARD_FAB2(SCH_1):PAGE44
   174 M_A_DQS_DN<2> @BASEBOARD_FAB2_LIB.BASEBOARD_FAB2(SCH_1):M_A_DQS_DN(2)   I120 @BASEBOARD_FAB2_LIB.BASEBOARD_FAB2(SCH_1):PAGE44
   175 M_A_DQS_DP<2> @BASEBOARD_FAB2_LIB.BASEBOARD_FAB2(SCH_1):M_A_DQS_DP(2)   I120 @BASEBOARD_FAB2_LIB.BASEBOARD_FAB2(SCH_1):PAGE44
   185 M_A_DQS_DN<3> @BASEBOARD_FAB2_LIB.BASEBOARD_FAB2(SCH_1):M_A_DQS_DN(3)   I120 @BASEBOARD_FAB2_LIB.BASEBOARD_FAB2(SCH_1):PAGE44
   186 M_A_DQS_DP<3> @BASEBOARD_FAB2_LIB.BASEBOARD_FAB2(SCH_1):M_A_DQS_DP(3)   I120 @BASEBOARD_FAB2_LIB.BASEBOARD_FAB2(SCH_1):PAGE44
   244 M_A_DQS_DN<4> @BASEBOARD_FAB2_LIB.BASEBOARD_FAB2(SCH_1):M_A_DQS_DN(4)   I120 @BASEBOARD_FAB2_LIB.BASEBOARD_FAB2(SCH_1):PAGE44
   245 M_A_DQS_DP<4> @BASEBOARD_FAB2_LIB.BASEBOARD_FAB2(SCH_1):M_A_DQS_DP(4)   I120 @BASEBOARD_FAB2_LIB.BASEBOARD_FAB2(SCH_1):PAGE44
   255 M_A_DQS_DN<5> @BASEBOARD_FAB2_LIB.BASEBOARD_FAB2(SCH_1):M_A_DQS_DN(5)   I120 @BASEBOARD_FAB2_LIB.BASEBOARD_FAB2(SCH_1):PAGE44
   256 M_A_DQS_DP<5> @BASEBOARD_FAB2_LIB.BASEBOARD_FAB2(SCH_1):M_A_DQS_DP(5)   I120 @BASEBOARD_FAB2_LIB.BASEBOARD_FAB2(SCH_1):PAGE44
   266 M_A_DQS_DN<6> @BASEBOARD_FAB2_LIB.BASEBOARD_FAB2(SCH_1):M_A_DQS_DN(6)   I120 @BASEBOARD_FAB2_LIB.BASEBOARD_FAB2(SCH_1):PAGE44
   267 M_A_DQS_DP<6> @BASEBOARD_FAB2_LIB.BASEBOARD_FAB2(SCH_1):M_A_DQS_DP(6)   I120 @BASEBOARD_FAB2_LIB.BASEBOARD_FAB2(SCH_1):PAGE44
   277 M_A_DQS_DN<7> @BASEBOARD_FAB2_LIB.BASEBOARD_FAB2(SCH_1):M_A_DQS_DN(7)   I120 @BASEBOARD_FAB2_LIB.BASEBOARD_FAB2(SCH_1):PAGE44
   278 M_A_DQS_DP<7> @BASEBOARD_FAB2_LIB.BASEBOARD_FAB2(SCH_1):M_A_DQS_DP(7)   I120 @BASEBOARD_FAB2_LIB.BASEBOARD_FAB2(SCH_1):PAGE44
   196 M_A_DQS_DN<8> @BASEBOARD_FAB2_LIB.BASEBOARD_FAB2(SCH_1):M_A_DQS_DN(8)   I120 @BASEBOARD_FAB2_LIB.BASEBOARD_FAB2(SCH_1):PAGE44
   197 M_A_DQS_DP<8> @BASEBOARD_FAB2_LIB.BASEBOARD_FAB2(SCH_1):M_A_DQS_DP(8)   I120 @BASEBOARD_FAB2_LIB.BASEBOARD_FAB2(SCH_1):PAGE44
     8 M_A_DQS_DN<9> @BASEBOARD_FAB2_LIB.BASEBOARD_FAB2(SCH_1):M_A_DQS_DN(9)   I120 @BASEBOARD_FAB2_LIB.BASEBOARD_FAB2(SCH_1):PAGE44
     7 M_A_DQS_DP<9> @BASEBOARD_FAB2_LIB.BASEBOARD_FAB2(SCH_1):M_A_DQS_DP(9)   I120 @BASEBOARD_FAB2_LIB.BASEBOARD_FAB2(SCH_1):PAGE44
     2    GND @BASEBOARD_FAB2_LIB.BASEBOARD_FAB2(SCH_1):GND   I139 @BASEBOARD_FAB2_LIB.BASEBOARD_FAB2(SCH_1):PAGE44
     4    GND @BASEBOARD_FAB2_LIB.BASEBOARD_FAB2(SCH_1):GND   I139 @BASEBOARD_FAB2_LIB.BASEBOARD_FAB2(SCH_1):PAGE44
     6    GND @BASEBOARD_FAB2_LIB.BASEBOARD_FAB2(SCH_1):GND   I139 @BASEBOARD_FAB2_LIB.BASEBOARD_FAB2(SCH_1):PAGE44
     9    GND @BASEBOARD_FAB2_LIB.BASEBOARD_FAB2(SCH_1):GND   I139 @BASEBOARD_FAB2_LIB.BASEBOARD_FAB2(SCH_1):PAGE44
    11    GND @BASEBOARD_FAB2_LIB.BASEBOARD_FAB2(SCH_1):GND   I139 @BASEBOARD_FAB2_LIB.BASEBOARD_FAB2(SCH_1):PAGE44
    13    GND @BASEBOARD_FAB2_LIB.BASEBOARD_FAB2(SCH_1):GND   I139 @BASEBOARD_FAB2_LIB.BASEBOARD_FAB2(SCH_1):PAGE44
    15    GND @BASEBOARD_FAB2_LIB.BASEBOARD_FAB2(SCH_1):GND   I139 @BASEBOARD_FAB2_LIB.BASEBOARD_FAB2(SCH_1):PAGE44
    17    GND @BASEBOARD_FAB2_LIB.BASEBOARD_FAB2(SCH_1):GND   I139 @BASEBOARD_FAB2_LIB.BASEBOARD_FAB2(SCH_1):PAGE44
    20    GND @BASEBOARD_FAB2_LIB.BASEBOARD_FAB2(SCH_1):GND   I139 @BASEBOARD_FAB2_LIB.BASEBOARD_FAB2(SCH_1):PAGE44
    22    GND @BASEBOARD_FAB2_LIB.BASEBOARD_FAB2(SCH_1):GND   I139 @BASEBOARD_FAB2_LIB.BASEBOARD_FAB2(SCH_1):PAGE44
    24    GND @BASEBOARD_FAB2_LIB.BASEBOARD_FAB2(SCH_1):GND   I139 @BASEBOARD_FAB2_LIB.BASEBOARD_FAB2(SCH_1):PAGE44
    26    GND @BASEBOARD_FAB2_LIB.BASEBOARD_FAB2(SCH_1):GND   I139 @BASEBOARD_FAB2_LIB.BASEBOARD_FAB2(SCH_1):PAGE44
    28    GND @BASEBOARD_FAB2_LIB.BASEBOARD_FAB2(SCH_1):GND   I139 @BASEBOARD_FAB2_LIB.BASEBOARD_FAB2(SCH_1):PAGE44
    31    GND @BASEBOARD_FAB2_LIB.BASEBOARD_FAB2(SCH_1):GND   I139 @BASEBOARD_FAB2_LIB.BASEBOARD_FAB2(SCH_1):PAGE44
    33    GND @BASEBOARD_FAB2_LIB.BASEBOARD_FAB2(SCH_1):GND   I139 @BASEBOARD_FAB2_LIB.BASEBOARD_FAB2(SCH_1):PAGE44
    35    GND @BASEBOARD_FAB2_LIB.BASEBOARD_FAB2(SCH_1):GND   I139 @BASEBOARD_FAB2_LIB.BASEBOARD_FAB2(SCH_1):PAGE44
    37    GND @BASEBOARD_FAB2_LIB.BASEBOARD_FAB2(SCH_1):GND   I139 @BASEBOARD_FAB2_LIB.BASEBOARD_FAB2(SCH_1):PAGE44
    39    GND @BASEBOARD_FAB2_LIB.BASEBOARD_FAB2(SCH_1):GND   I139 @BASEBOARD_FAB2_LIB.BASEBOARD_FAB2(SCH_1):PAGE44
    42    GND @BASEBOARD_FAB2_LIB.BASEBOARD_FAB2(SCH_1):GND   I139 @BASEBOARD_FAB2_LIB.BASEBOARD_FAB2(SCH_1):PAGE44
    44    GND @BASEBOARD_FAB2_LIB.BASEBOARD_FAB2(SCH_1):GND   I139 @BASEBOARD_FAB2_LIB.BASEBOARD_FAB2(SCH_1):PAGE44
    46    GND @BASEBOARD_FAB2_LIB.BASEBOARD_FAB2(SCH_1):GND   I139 @BASEBOARD_FAB2_LIB.BASEBOARD_FAB2(SCH_1):PAGE44
    48    GND @BASEBOARD_FAB2_LIB.BASEBOARD_FAB2(SCH_1):GND   I139 @BASEBOARD_FAB2_LIB.BASEBOARD_FAB2(SCH_1):PAGE44
    50    GND @BASEBOARD_FAB2_LIB.BASEBOARD_FAB2(SCH_1):GND   I139 @BASEBOARD_FAB2_LIB.BASEBOARD_FAB2(SCH_1):PAGE44
    53    GND @BASEBOARD_FAB2_LIB.BASEBOARD_FAB2(SCH_1):GND   I139 @BASEBOARD_FAB2_LIB.BASEBOARD_FAB2(SCH_1):PAGE44
    55    GND @BASEBOARD_FAB2_LIB.BASEBOARD_FAB2(SCH_1):GND   I139 @BASEBOARD_FAB2_LIB.BASEBOARD_FAB2(SCH_1):PAGE44
    57    GND @BASEBOARD_FAB2_LIB.BASEBOARD_FAB2(SCH_1):GND   I139 @BASEBOARD_FAB2_LIB.BASEBOARD_FAB2(SCH_1):PAGE44
    94    GND @BASEBOARD_FAB2_LIB.BASEBOARD_FAB2(SCH_1):GND   I139 @BASEBOARD_FAB2_LIB.BASEBOARD_FAB2(SCH_1):PAGE44
    96    GND @BASEBOARD_FAB2_LIB.BASEBOARD_FAB2(SCH_1):GND   I139 @BASEBOARD_FAB2_LIB.BASEBOARD_FAB2(SCH_1):PAGE44
    98    GND @BASEBOARD_FAB2_LIB.BASEBOARD_FAB2(SCH_1):GND   I139 @BASEBOARD_FAB2_LIB.BASEBOARD_FAB2(SCH_1):PAGE44
   101    GND @BASEBOARD_FAB2_LIB.BASEBOARD_FAB2(SCH_1):GND   I139 @BASEBOARD_FAB2_LIB.BASEBOARD_FAB2(SCH_1):PAGE44
   103    GND @BASEBOARD_FAB2_LIB.BASEBOARD_FAB2(SCH_1):GND   I139 @BASEBOARD_FAB2_LIB.BASEBOARD_FAB2(SCH_1):PAGE44
   105    GND @BASEBOARD_FAB2_LIB.BASEBOARD_FAB2(SCH_1):GND   I139 @BASEBOARD_FAB2_LIB.BASEBOARD_FAB2(SCH_1):PAGE44
   107    GND @BASEBOARD_FAB2_LIB.BASEBOARD_FAB2(SCH_1):GND   I139 @BASEBOARD_FAB2_LIB.BASEBOARD_FAB2(SCH_1):PAGE44
   109    GND @BASEBOARD_FAB2_LIB.BASEBOARD_FAB2(SCH_1):GND   I139 @BASEBOARD_FAB2_LIB.BASEBOARD_FAB2(SCH_1):PAGE44
   112    GND @BASEBOARD_FAB2_LIB.BASEBOARD_FAB2(SCH_1):GND   I139 @BASEBOARD_FAB2_LIB.BASEBOARD_FAB2(SCH_1):PAGE44
   114    GND @BASEBOARD_FAB2_LIB.BASEBOARD_FAB2(SCH_1):GND   I139 @BASEBOARD_FAB2_LIB.BASEBOARD_FAB2(SCH_1):PAGE44
   116    GND @BASEBOARD_FAB2_LIB.BASEBOARD_FAB2(SCH_1):GND   I139 @BASEBOARD_FAB2_LIB.BASEBOARD_FAB2(SCH_1):PAGE44
   118    GND @BASEBOARD_FAB2_LIB.BASEBOARD_FAB2(SCH_1):GND   I139 @BASEBOARD_FAB2_LIB.BASEBOARD_FAB2(SCH_1):PAGE44
   120    GND @BASEBOARD_FAB2_LIB.BASEBOARD_FAB2(SCH_1):GND   I139 @BASEBOARD_FAB2_LIB.BASEBOARD_FAB2(SCH_1):PAGE44
   123    GND @BASEBOARD_FAB2_LIB.BASEBOARD_FAB2(SCH_1):GND   I139 @BASEBOARD_FAB2_LIB.BASEBOARD_FAB2(SCH_1):PAGE44
   125    GND @BASEBOARD_FAB2_LIB.BASEBOARD_FAB2(SCH_1):GND   I139 @BASEBOARD_FAB2_LIB.BASEBOARD_FAB2(SCH_1):PAGE44
   127    GND @BASEBOARD_FAB2_LIB.BASEBOARD_FAB2(SCH_1):GND   I139 @BASEBOARD_FAB2_LIB.BASEBOARD_FAB2(SCH_1):PAGE44
   129    GND @BASEBOARD_FAB2_LIB.BASEBOARD_FAB2(SCH_1):GND   I139 @BASEBOARD_FAB2_LIB.BASEBOARD_FAB2(SCH_1):PAGE44
   131    GND @BASEBOARD_FAB2_LIB.BASEBOARD_FAB2(SCH_1):GND   I139 @BASEBOARD_FAB2_LIB.BASEBOARD_FAB2(SCH_1):PAGE44
   134    GND @BASEBOARD_FAB2_LIB.BASEBOARD_FAB2(SCH_1):GND   I139 @BASEBOARD_FAB2_LIB.BASEBOARD_FAB2(SCH_1):PAGE44
   136    GND @BASEBOARD_FAB2_LIB.BASEBOARD_FAB2(SCH_1):GND   I139 @BASEBOARD_FAB2_LIB.BASEBOARD_FAB2(SCH_1):PAGE44
   138    GND @BASEBOARD_FAB2_LIB.BASEBOARD_FAB2(SCH_1):GND   I139 @BASEBOARD_FAB2_LIB.BASEBOARD_FAB2(SCH_1):PAGE44
   147    GND @BASEBOARD_FAB2_LIB.BASEBOARD_FAB2(SCH_1):GND   I139 @BASEBOARD_FAB2_LIB.BASEBOARD_FAB2(SCH_1):PAGE44
   149    GND @BASEBOARD_FAB2_LIB.BASEBOARD_FAB2(SCH_1):GND   I139 @BASEBOARD_FAB2_LIB.BASEBOARD_FAB2(SCH_1):PAGE44
   151    GND @BASEBOARD_FAB2_LIB.BASEBOARD_FAB2(SCH_1):GND   I139 @BASEBOARD_FAB2_LIB.BASEBOARD_FAB2(SCH_1):PAGE44
   154    GND @BASEBOARD_FAB2_LIB.BASEBOARD_FAB2(SCH_1):GND   I139 @BASEBOARD_FAB2_LIB.BASEBOARD_FAB2(SCH_1):PAGE44
   156    GND @BASEBOARD_FAB2_LIB.BASEBOARD_FAB2(SCH_1):GND   I139 @BASEBOARD_FAB2_LIB.BASEBOARD_FAB2(SCH_1):PAGE44
   158    GND @BASEBOARD_FAB2_LIB.BASEBOARD_FAB2(SCH_1):GND   I139 @BASEBOARD_FAB2_LIB.BASEBOARD_FAB2(SCH_1):PAGE44
   160    GND @BASEBOARD_FAB2_LIB.BASEBOARD_FAB2(SCH_1):GND   I139 @BASEBOARD_FAB2_LIB.BASEBOARD_FAB2(SCH_1):PAGE44
   162    GND @BASEBOARD_FAB2_LIB.BASEBOARD_FAB2(SCH_1):GND   I139 @BASEBOARD_FAB2_LIB.BASEBOARD_FAB2(SCH_1):PAGE44
   165    GND @BASEBOARD_FAB2_LIB.BASEBOARD_FAB2(SCH_1):GND   I139 @BASEBOARD_FAB2_LIB.BASEBOARD_FAB2(SCH_1):PAGE44
   167    GND @BASEBOARD_FAB2_LIB.BASEBOARD_FAB2(SCH_1):GND   I139 @BASEBOARD_FAB2_LIB.BASEBOARD_FAB2(SCH_1):PAGE44
   169    GND @BASEBOARD_FAB2_LIB.BASEBOARD_FAB2(SCH_1):GND   I139 @BASEBOARD_FAB2_LIB.BASEBOARD_FAB2(SCH_1):PAGE44
   171    GND @BASEBOARD_FAB2_LIB.BASEBOARD_FAB2(SCH_1):GND   I139 @BASEBOARD_FAB2_LIB.BASEBOARD_FAB2(SCH_1):PAGE44
   173    GND @BASEBOARD_FAB2_LIB.BASEBOARD_FAB2(SCH_1):GND   I139 @BASEBOARD_FAB2_LIB.BASEBOARD_FAB2(SCH_1):PAGE44
   176    GND @BASEBOARD_FAB2_LIB.BASEBOARD_FAB2(SCH_1):GND   I139 @BASEBOARD_FAB2_LIB.BASEBOARD_FAB2(SCH_1):PAGE44
   178    GND @BASEBOARD_FAB2_LIB.BASEBOARD_FAB2(SCH_1):GND   I139 @BASEBOARD_FAB2_LIB.BASEBOARD_FAB2(SCH_1):PAGE44
   180    GND @BASEBOARD_FAB2_LIB.BASEBOARD_FAB2(SCH_1):GND   I139 @BASEBOARD_FAB2_LIB.BASEBOARD_FAB2(SCH_1):PAGE44
   182    GND @BASEBOARD_FAB2_LIB.BASEBOARD_FAB2(SCH_1):GND   I139 @BASEBOARD_FAB2_LIB.BASEBOARD_FAB2(SCH_1):PAGE44
   184    GND @BASEBOARD_FAB2_LIB.BASEBOARD_FAB2(SCH_1):GND   I139 @BASEBOARD_FAB2_LIB.BASEBOARD_FAB2(SCH_1):PAGE44
   187    GND @BASEBOARD_FAB2_LIB.BASEBOARD_FAB2(SCH_1):GND   I139 @BASEBOARD_FAB2_LIB.BASEBOARD_FAB2(SCH_1):PAGE44
   189    GND @BASEBOARD_FAB2_LIB.BASEBOARD_FAB2(SCH_1):GND   I139 @BASEBOARD_FAB2_LIB.BASEBOARD_FAB2(SCH_1):PAGE44
   191    GND @BASEBOARD_FAB2_LIB.BASEBOARD_FAB2(SCH_1):GND   I139 @BASEBOARD_FAB2_LIB.BASEBOARD_FAB2(SCH_1):PAGE44
   193    GND @BASEBOARD_FAB2_LIB.BASEBOARD_FAB2(SCH_1):GND   I139 @BASEBOARD_FAB2_LIB.BASEBOARD_FAB2(SCH_1):PAGE44
   195    GND @BASEBOARD_FAB2_LIB.BASEBOARD_FAB2(SCH_1):GND   I139 @BASEBOARD_FAB2_LIB.BASEBOARD_FAB2(SCH_1):PAGE44
   198    GND @BASEBOARD_FAB2_LIB.BASEBOARD_FAB2(SCH_1):GND   I139 @BASEBOARD_FAB2_LIB.BASEBOARD_FAB2(SCH_1):PAGE44
   200    GND @BASEBOARD_FAB2_LIB.BASEBOARD_FAB2(SCH_1):GND   I139 @BASEBOARD_FAB2_LIB.BASEBOARD_FAB2(SCH_1):PAGE44
   202    GND @BASEBOARD_FAB2_LIB.BASEBOARD_FAB2(SCH_1):GND   I139 @BASEBOARD_FAB2_LIB.BASEBOARD_FAB2(SCH_1):PAGE44
   239    GND @BASEBOARD_FAB2_LIB.BASEBOARD_FAB2(SCH_1):GND   I139 @BASEBOARD_FAB2_LIB.BASEBOARD_FAB2(SCH_1):PAGE44
   241    GND @BASEBOARD_FAB2_LIB.BASEBOARD_FAB2(SCH_1):GND   I139 @BASEBOARD_FAB2_LIB.BASEBOARD_FAB2(SCH_1):PAGE44
   243    GND @BASEBOARD_FAB2_LIB.BASEBOARD_FAB2(SCH_1):GND   I139 @BASEBOARD_FAB2_LIB.BASEBOARD_FAB2(SCH_1):PAGE44
   246    GND @BASEBOARD_FAB2_LIB.BASEBOARD_FAB2(SCH_1):GND   I139 @BASEBOARD_FAB2_LIB.BASEBOARD_FAB2(SCH_1):PAGE44
   248    GND @BASEBOARD_FAB2_LIB.BASEBOARD_FAB2(SCH_1):GND   I139 @BASEBOARD_FAB2_LIB.BASEBOARD_FAB2(SCH_1):PAGE44
   250    GND @BASEBOARD_FAB2_LIB.BASEBOARD_FAB2(SCH_1):GND   I139 @BASEBOARD_FAB2_LIB.BASEBOARD_FAB2(SCH_1):PAGE44
   252    GND @BASEBOARD_FAB2_LIB.BASEBOARD_FAB2(SCH_1):GND   I139 @BASEBOARD_FAB2_LIB.BASEBOARD_FAB2(SCH_1):PAGE44
   254    GND @BASEBOARD_FAB2_LIB.BASEBOARD_FAB2(SCH_1):GND   I139 @BASEBOARD_FAB2_LIB.BASEBOARD_FAB2(SCH_1):PAGE44
   257    GND @BASEBOARD_FAB2_LIB.BASEBOARD_FAB2(SCH_1):GND   I139 @BASEBOARD_FAB2_LIB.BASEBOARD_FAB2(SCH_1):PAGE44
   259    GND @BASEBOARD_FAB2_LIB.BASEBOARD_FAB2(SCH_1):GND   I139 @BASEBOARD_FAB2_LIB.BASEBOARD_FAB2(SCH_1):PAGE44
   261    GND @BASEBOARD_FAB2_LIB.BASEBOARD_FAB2(SCH_1):GND   I139 @BASEBOARD_FAB2_LIB.BASEBOARD_FAB2(SCH_1):PAGE44
   263    GND @BASEBOARD_FAB2_LIB.BASEBOARD_FAB2(SCH_1):GND   I139 @BASEBOARD_FAB2_LIB.BASEBOARD_FAB2(SCH_1):PAGE44
   265    GND @BASEBOARD_FAB2_LIB.BASEBOARD_FAB2(SCH_1):GND   I139 @BASEBOARD_FAB2_LIB.BASEBOARD_FAB2(SCH_1):PAGE44
   268    GND @BASEBOARD_FAB2_LIB.BASEBOARD_FAB2(SCH_1):GND   I139 @BASEBOARD_FAB2_LIB.BASEBOARD_FAB2(SCH_1):PAGE44
   270    GND @BASEBOARD_FAB2_LIB.BASEBOARD_FAB2(SCH_1):GND   I139 @BASEBOARD_FAB2_LIB.BASEBOARD_FAB2(SCH_1):PAGE44
   272    GND @BASEBOARD_FAB2_LIB.BASEBOARD_FAB2(SCH_1):GND   I139 @BASEBOARD_FAB2_LIB.BASEBOARD_FAB2(SCH_1):PAGE44
   274    GND @BASEBOARD_FAB2_LIB.BASEBOARD_FAB2(SCH_1):GND   I139 @BASEBOARD_FAB2_LIB.BASEBOARD_FAB2(SCH_1):PAGE44
   276    GND @BASEBOARD_FAB2_LIB.BASEBOARD_FAB2(SCH_1):GND   I139 @BASEBOARD_FAB2_LIB.BASEBOARD_FAB2(SCH_1):PAGE44
   279    GND @BASEBOARD_FAB2_LIB.BASEBOARD_FAB2(SCH_1):GND   I139 @BASEBOARD_FAB2_LIB.BASEBOARD_FAB2(SCH_1):PAGE44
   281    GND @BASEBOARD_FAB2_LIB.BASEBOARD_FAB2(SCH_1):GND   I139 @BASEBOARD_FAB2_LIB.BASEBOARD_FAB2(SCH_1):PAGE44
   283    GND @BASEBOARD_FAB2_LIB.BASEBOARD_FAB2(SCH_1):GND   I139 @BASEBOARD_FAB2_LIB.BASEBOARD_FAB2(SCH_1):PAGE44
     1 P12V_NVDIMM_ABC @BASEBOARD_FAB2_LIB.BASEBOARD_FAB2(SCH_1):P12V_NVDIMM_ABC    I75 @BASEBOARD_FAB2_LIB.BASEBOARD_FAB2(SCH_1):PAGE44
   145 P12V_NVDIMM_ABC @BASEBOARD_FAB2_LIB.BASEBOARD_FAB2(SCH_1):P12V_NVDIMM_ABC    I75 @BASEBOARD_FAB2_LIB.BASEBOARD_FAB2(SCH_1):PAGE44
    59 PVDDQ_ABC @BASEBOARD_FAB2_LIB.BASEBOARD_FAB2(SCH_1):PVDDQ_ABC    I75 @BASEBOARD_FAB2_LIB.BASEBOARD_FAB2(SCH_1):PAGE44
    61 PVDDQ_ABC @BASEBOARD_FAB2_LIB.BASEBOARD_FAB2(SCH_1):PVDDQ_ABC    I75 @BASEBOARD_FAB2_LIB.BASEBOARD_FAB2(SCH_1):PAGE44
    64 PVDDQ_ABC @BASEBOARD_FAB2_LIB.BASEBOARD_FAB2(SCH_1):PVDDQ_ABC    I75 @BASEBOARD_FAB2_LIB.BASEBOARD_FAB2(SCH_1):PAGE44
    67 PVDDQ_ABC @BASEBOARD_FAB2_LIB.BASEBOARD_FAB2(SCH_1):PVDDQ_ABC    I75 @BASEBOARD_FAB2_LIB.BASEBOARD_FAB2(SCH_1):PAGE44
    70 PVDDQ_ABC @BASEBOARD_FAB2_LIB.BASEBOARD_FAB2(SCH_1):PVDDQ_ABC    I75 @BASEBOARD_FAB2_LIB.BASEBOARD_FAB2(SCH_1):PAGE44
    73 PVDDQ_ABC @BASEBOARD_FAB2_LIB.BASEBOARD_FAB2(SCH_1):PVDDQ_ABC    I75 @BASEBOARD_FAB2_LIB.BASEBOARD_FAB2(SCH_1):PAGE44
    76 PVDDQ_ABC @BASEBOARD_FAB2_LIB.BASEBOARD_FAB2(SCH_1):PVDDQ_ABC    I75 @BASEBOARD_FAB2_LIB.BASEBOARD_FAB2(SCH_1):PAGE44
    80 PVDDQ_ABC @BASEBOARD_FAB2_LIB.BASEBOARD_FAB2(SCH_1):PVDDQ_ABC    I75 @BASEBOARD_FAB2_LIB.BASEBOARD_FAB2(SCH_1):PAGE44
    83 PVDDQ_ABC @BASEBOARD_FAB2_LIB.BASEBOARD_FAB2(SCH_1):PVDDQ_ABC    I75 @BASEBOARD_FAB2_LIB.BASEBOARD_FAB2(SCH_1):PAGE44
    85 PVDDQ_ABC @BASEBOARD_FAB2_LIB.BASEBOARD_FAB2(SCH_1):PVDDQ_ABC    I75 @BASEBOARD_FAB2_LIB.BASEBOARD_FAB2(SCH_1):PAGE44
    88 PVDDQ_ABC @BASEBOARD_FAB2_LIB.BASEBOARD_FAB2(SCH_1):PVDDQ_ABC    I75 @BASEBOARD_FAB2_LIB.BASEBOARD_FAB2(SCH_1):PAGE44
    90 PVDDQ_ABC @BASEBOARD_FAB2_LIB.BASEBOARD_FAB2(SCH_1):PVDDQ_ABC    I75 @BASEBOARD_FAB2_LIB.BASEBOARD_FAB2(SCH_1):PAGE44
    92 PVDDQ_ABC @BASEBOARD_FAB2_LIB.BASEBOARD_FAB2(SCH_1):PVDDQ_ABC    I75 @BASEBOARD_FAB2_LIB.BASEBOARD_FAB2(SCH_1):PAGE44
   204 PVDDQ_ABC @BASEBOARD_FAB2_LIB.BASEBOARD_FAB2(SCH_1):PVDDQ_ABC    I75 @BASEBOARD_FAB2_LIB.BASEBOARD_FAB2(SCH_1):PAGE44
   206 PVDDQ_ABC @BASEBOARD_FAB2_LIB.BASEBOARD_FAB2(SCH_1):PVDDQ_ABC    I75 @BASEBOARD_FAB2_LIB.BASEBOARD_FAB2(SCH_1):PAGE44
   209 PVDDQ_ABC @BASEBOARD_FAB2_LIB.BASEBOARD_FAB2(SCH_1):PVDDQ_ABC    I75 @BASEBOARD_FAB2_LIB.BASEBOARD_FAB2(SCH_1):PAGE44
   212 PVDDQ_ABC @BASEBOARD_FAB2_LIB.BASEBOARD_FAB2(SCH_1):PVDDQ_ABC    I75 @BASEBOARD_FAB2_LIB.BASEBOARD_FAB2(SCH_1):PAGE44
   215 PVDDQ_ABC @BASEBOARD_FAB2_LIB.BASEBOARD_FAB2(SCH_1):PVDDQ_ABC    I75 @BASEBOARD_FAB2_LIB.BASEBOARD_FAB2(SCH_1):PAGE44
   217 PVDDQ_ABC @BASEBOARD_FAB2_LIB.BASEBOARD_FAB2(SCH_1):PVDDQ_ABC    I75 @BASEBOARD_FAB2_LIB.BASEBOARD_FAB2(SCH_1):PAGE44
   220 PVDDQ_ABC @BASEBOARD_FAB2_LIB.BASEBOARD_FAB2(SCH_1):PVDDQ_ABC    I75 @BASEBOARD_FAB2_LIB.BASEBOARD_FAB2(SCH_1):PAGE44
   223 PVDDQ_ABC @BASEBOARD_FAB2_LIB.BASEBOARD_FAB2(SCH_1):PVDDQ_ABC    I75 @BASEBOARD_FAB2_LIB.BASEBOARD_FAB2(SCH_1):PAGE44
   226 PVDDQ_ABC @BASEBOARD_FAB2_LIB.BASEBOARD_FAB2(SCH_1):PVDDQ_ABC    I75 @BASEBOARD_FAB2_LIB.BASEBOARD_FAB2(SCH_1):PAGE44
   229 PVDDQ_ABC @BASEBOARD_FAB2_LIB.BASEBOARD_FAB2(SCH_1):PVDDQ_ABC    I75 @BASEBOARD_FAB2_LIB.BASEBOARD_FAB2(SCH_1):PAGE44
   231 PVDDQ_ABC @BASEBOARD_FAB2_LIB.BASEBOARD_FAB2(SCH_1):PVDDQ_ABC    I75 @BASEBOARD_FAB2_LIB.BASEBOARD_FAB2(SCH_1):PAGE44
   233 PVDDQ_ABC @BASEBOARD_FAB2_LIB.BASEBOARD_FAB2(SCH_1):PVDDQ_ABC    I75 @BASEBOARD_FAB2_LIB.BASEBOARD_FAB2(SCH_1):PAGE44
   236 PVDDQ_ABC @BASEBOARD_FAB2_LIB.BASEBOARD_FAB2(SCH_1):PVDDQ_ABC    I75 @BASEBOARD_FAB2_LIB.BASEBOARD_FAB2(SCH_1):PAGE44
   142 PVPP_ABC @BASEBOARD_FAB2_LIB.BASEBOARD_FAB2(SCH_1):PVPP_ABC    I75 @BASEBOARD_FAB2_LIB.BASEBOARD_FAB2(SCH_1):PAGE44
   143 PVPP_ABC @BASEBOARD_FAB2_LIB.BASEBOARD_FAB2(SCH_1):PVPP_ABC    I75 @BASEBOARD_FAB2_LIB.BASEBOARD_FAB2(SCH_1):PAGE44
   288 PVPP_ABC @BASEBOARD_FAB2_LIB.BASEBOARD_FAB2(SCH_1):PVPP_ABC    I75 @BASEBOARD_FAB2_LIB.BASEBOARD_FAB2(SCH_1):PAGE44
   286 PVPP_ABC @BASEBOARD_FAB2_LIB.BASEBOARD_FAB2(SCH_1):PVPP_ABC    I75 @BASEBOARD_FAB2_LIB.BASEBOARD_FAB2(SCH_1):PAGE44
   287 PVPP_ABC @BASEBOARD_FAB2_LIB.BASEBOARD_FAB2(SCH_1):PVPP_ABC    I75 @BASEBOARD_FAB2_LIB.BASEBOARD_FAB2(SCH_1):PAGE44
    77 PVTT_ABC @BASEBOARD_FAB2_LIB.BASEBOARD_FAB2(SCH_1):PVTT_ABC    I75 @BASEBOARD_FAB2_LIB.BASEBOARD_FAB2(SCH_1):PAGE44
   221 PVTT_ABC @BASEBOARD_FAB2_LIB.BASEBOARD_FAB2(SCH_1):PVTT_ABC    I75 @BASEBOARD_FAB2_LIB.BASEBOARD_FAB2(SCH_1):PAGE44

J6U1 SCONN288_H44441003_PIP-SCONN,HA
    79 M_B_MA<0> @BASEBOARD_FAB2_LIB.BASEBOARD_FAB2(SCH_1):M_B_MA(0)    I14 @BASEBOARD_FAB2_LIB.BASEBOARD_FAB2(SCH_1):PAGE46
    72 M_B_MA<1> @BASEBOARD_FAB2_LIB.BASEBOARD_FAB2(SCH_1):M_B_MA(1)    I14 @BASEBOARD_FAB2_LIB.BASEBOARD_FAB2(SCH_1):PAGE46
   225 M_B_MA<10> @BASEBOARD_FAB2_LIB.BASEBOARD_FAB2(SCH_1):M_B_MA(10)    I14 @BASEBOARD_FAB2_LIB.BASEBOARD_FAB2(SCH_1):PAGE46
   210 M_B_MA<11> @BASEBOARD_FAB2_LIB.BASEBOARD_FAB2(SCH_1):M_B_MA(11)    I14 @BASEBOARD_FAB2_LIB.BASEBOARD_FAB2(SCH_1):PAGE46
    65 M_B_MA<12> @BASEBOARD_FAB2_LIB.BASEBOARD_FAB2(SCH_1):M_B_MA(12)    I14 @BASEBOARD_FAB2_LIB.BASEBOARD_FAB2(SCH_1):PAGE46
   232 M_B_MA<13> @BASEBOARD_FAB2_LIB.BASEBOARD_FAB2(SCH_1):M_B_MA(13)    I14 @BASEBOARD_FAB2_LIB.BASEBOARD_FAB2(SCH_1):PAGE46
   228 M_B_MA<14> @BASEBOARD_FAB2_LIB.BASEBOARD_FAB2(SCH_1):M_B_MA(14)    I14 @BASEBOARD_FAB2_LIB.BASEBOARD_FAB2(SCH_1):PAGE46
    86 M_B_MA<15> @BASEBOARD_FAB2_LIB.BASEBOARD_FAB2(SCH_1):M_B_MA(15)    I14 @BASEBOARD_FAB2_LIB.BASEBOARD_FAB2(SCH_1):PAGE46
    82 M_B_MA<16> @BASEBOARD_FAB2_LIB.BASEBOARD_FAB2(SCH_1):M_B_MA(16)    I14 @BASEBOARD_FAB2_LIB.BASEBOARD_FAB2(SCH_1):PAGE46
   234 M_B_MA<17> @BASEBOARD_FAB2_LIB.BASEBOARD_FAB2(SCH_1):M_B_MA(17)    I14 @BASEBOARD_FAB2_LIB.BASEBOARD_FAB2(SCH_1):PAGE46
   216 M_B_MA<2> @BASEBOARD_FAB2_LIB.BASEBOARD_FAB2(SCH_1):M_B_MA(2)    I14 @BASEBOARD_FAB2_LIB.BASEBOARD_FAB2(SCH_1):PAGE46
    71 M_B_MA<3> @BASEBOARD_FAB2_LIB.BASEBOARD_FAB2(SCH_1):M_B_MA(3)    I14 @BASEBOARD_FAB2_LIB.BASEBOARD_FAB2(SCH_1):PAGE46
   214 M_B_MA<4> @BASEBOARD_FAB2_LIB.BASEBOARD_FAB2(SCH_1):M_B_MA(4)    I14 @BASEBOARD_FAB2_LIB.BASEBOARD_FAB2(SCH_1):PAGE46
   213 M_B_MA<5> @BASEBOARD_FAB2_LIB.BASEBOARD_FAB2(SCH_1):M_B_MA(5)    I14 @BASEBOARD_FAB2_LIB.BASEBOARD_FAB2(SCH_1):PAGE46
    69 M_B_MA<6> @BASEBOARD_FAB2_LIB.BASEBOARD_FAB2(SCH_1):M_B_MA(6)    I14 @BASEBOARD_FAB2_LIB.BASEBOARD_FAB2(SCH_1):PAGE46
   211 M_B_MA<7> @BASEBOARD_FAB2_LIB.BASEBOARD_FAB2(SCH_1):M_B_MA(7)    I14 @BASEBOARD_FAB2_LIB.BASEBOARD_FAB2(SCH_1):PAGE46
    68 M_B_MA<8> @BASEBOARD_FAB2_LIB.BASEBOARD_FAB2(SCH_1):M_B_MA(8)    I14 @BASEBOARD_FAB2_LIB.BASEBOARD_FAB2(SCH_1):PAGE46
    66 M_B_MA<9> @BASEBOARD_FAB2_LIB.BASEBOARD_FAB2(SCH_1):M_B_MA(9)    I14 @BASEBOARD_FAB2_LIB.BASEBOARD_FAB2(SCH_1):PAGE46
    62 M_B_ACT_N @BASEBOARD_FAB2_LIB.BASEBOARD_FAB2(SCH_1):M_B_ACT_N    I14 @BASEBOARD_FAB2_LIB.BASEBOARD_FAB2(SCH_1):PAGE46
   208 M_B_ALERT_N @BASEBOARD_FAB2_LIB.BASEBOARD_FAB2(SCH_1):M_B_ALERT_N    I14 @BASEBOARD_FAB2_LIB.BASEBOARD_FAB2(SCH_1):PAGE46
   224 M_B_BA<1> @BASEBOARD_FAB2_LIB.BASEBOARD_FAB2(SCH_1):M_B_BA(1)    I14 @BASEBOARD_FAB2_LIB.BASEBOARD_FAB2(SCH_1):PAGE46
    81 M_B_BA<0> @BASEBOARD_FAB2_LIB.BASEBOARD_FAB2(SCH_1):M_B_BA(0)    I14 @BASEBOARD_FAB2_LIB.BASEBOARD_FAB2(SCH_1):PAGE46
   207 M_B_BG<1> @BASEBOARD_FAB2_LIB.BASEBOARD_FAB2(SCH_1):M_B_BG(1)    I14 @BASEBOARD_FAB2_LIB.BASEBOARD_FAB2(SCH_1):PAGE46
    63 M_B_BG<0> @BASEBOARD_FAB2_LIB.BASEBOARD_FAB2(SCH_1):M_B_BG(0)    I14 @BASEBOARD_FAB2_LIB.BASEBOARD_FAB2(SCH_1):PAGE46
   235 M_B_C<2> @BASEBOARD_FAB2_LIB.BASEBOARD_FAB2(SCH_1):M_B_C(2)    I14 @BASEBOARD_FAB2_LIB.BASEBOARD_FAB2(SCH_1):PAGE46
   199 M_B_ECC<7> @BASEBOARD_FAB2_LIB.BASEBOARD_FAB2(SCH_1):M_B_ECC(7)    I14 @BASEBOARD_FAB2_LIB.BASEBOARD_FAB2(SCH_1):PAGE46
    54 M_B_ECC<6> @BASEBOARD_FAB2_LIB.BASEBOARD_FAB2(SCH_1):M_B_ECC(6)    I14 @BASEBOARD_FAB2_LIB.BASEBOARD_FAB2(SCH_1):PAGE46
   192 M_B_ECC<5> @BASEBOARD_FAB2_LIB.BASEBOARD_FAB2(SCH_1):M_B_ECC(5)    I14 @BASEBOARD_FAB2_LIB.BASEBOARD_FAB2(SCH_1):PAGE46
    47 M_B_ECC<4> @BASEBOARD_FAB2_LIB.BASEBOARD_FAB2(SCH_1):M_B_ECC(4)    I14 @BASEBOARD_FAB2_LIB.BASEBOARD_FAB2(SCH_1):PAGE46
   201 M_B_ECC<3> @BASEBOARD_FAB2_LIB.BASEBOARD_FAB2(SCH_1):M_B_ECC(3)    I14 @BASEBOARD_FAB2_LIB.BASEBOARD_FAB2(SCH_1):PAGE46
    56 M_B_ECC<2> @BASEBOARD_FAB2_LIB.BASEBOARD_FAB2(SCH_1):M_B_ECC(2)    I14 @BASEBOARD_FAB2_LIB.BASEBOARD_FAB2(SCH_1):PAGE46
   194 M_B_ECC<1> @BASEBOARD_FAB2_LIB.BASEBOARD_FAB2(SCH_1):M_B_ECC(1)    I14 @BASEBOARD_FAB2_LIB.BASEBOARD_FAB2(SCH_1):PAGE46
    49 M_B_ECC<0> @BASEBOARD_FAB2_LIB.BASEBOARD_FAB2(SCH_1):M_B_ECC(0)    I14 @BASEBOARD_FAB2_LIB.BASEBOARD_FAB2(SCH_1):PAGE46
    75 M_B_CLK_DN<2> @BASEBOARD_FAB2_LIB.BASEBOARD_FAB2(SCH_1):M_B_CLK_DN(2)    I14 @BASEBOARD_FAB2_LIB.BASEBOARD_FAB2(SCH_1):PAGE46
    74 M_B_CLK_DP<2> @BASEBOARD_FAB2_LIB.BASEBOARD_FAB2(SCH_1):M_B_CLK_DP(2)    I14 @BASEBOARD_FAB2_LIB.BASEBOARD_FAB2(SCH_1):PAGE46
   219 M_B_CLK_DN<3> @BASEBOARD_FAB2_LIB.BASEBOARD_FAB2(SCH_1):M_B_CLK_DN(3)    I14 @BASEBOARD_FAB2_LIB.BASEBOARD_FAB2(SCH_1):PAGE46
   218 M_B_CLK_DP<3> @BASEBOARD_FAB2_LIB.BASEBOARD_FAB2(SCH_1):M_B_CLK_DP(3)    I14 @BASEBOARD_FAB2_LIB.BASEBOARD_FAB2(SCH_1):PAGE46
   203 M_B_CKE<3> @BASEBOARD_FAB2_LIB.BASEBOARD_FAB2(SCH_1):M_B_CKE(3)    I14 @BASEBOARD_FAB2_LIB.BASEBOARD_FAB2(SCH_1):PAGE46
    60 M_B_CKE<2> @BASEBOARD_FAB2_LIB.BASEBOARD_FAB2(SCH_1):M_B_CKE(2)    I14 @BASEBOARD_FAB2_LIB.BASEBOARD_FAB2(SCH_1):PAGE46
   280 M_B_DQ<63> @BASEBOARD_FAB2_LIB.BASEBOARD_FAB2(SCH_1):M_B_DQ(63)    I14 @BASEBOARD_FAB2_LIB.BASEBOARD_FAB2(SCH_1):PAGE46
   135 M_B_DQ<62> @BASEBOARD_FAB2_LIB.BASEBOARD_FAB2(SCH_1):M_B_DQ(62)    I14 @BASEBOARD_FAB2_LIB.BASEBOARD_FAB2(SCH_1):PAGE46
   273 M_B_DQ<61> @BASEBOARD_FAB2_LIB.BASEBOARD_FAB2(SCH_1):M_B_DQ(61)    I14 @BASEBOARD_FAB2_LIB.BASEBOARD_FAB2(SCH_1):PAGE46
   128 M_B_DQ<60> @BASEBOARD_FAB2_LIB.BASEBOARD_FAB2(SCH_1):M_B_DQ(60)    I14 @BASEBOARD_FAB2_LIB.BASEBOARD_FAB2(SCH_1):PAGE46
   282 M_B_DQ<59> @BASEBOARD_FAB2_LIB.BASEBOARD_FAB2(SCH_1):M_B_DQ(59)    I14 @BASEBOARD_FAB2_LIB.BASEBOARD_FAB2(SCH_1):PAGE46
   137 M_B_DQ<58> @BASEBOARD_FAB2_LIB.BASEBOARD_FAB2(SCH_1):M_B_DQ(58)    I14 @BASEBOARD_FAB2_LIB.BASEBOARD_FAB2(SCH_1):PAGE46
   275 M_B_DQ<57> @BASEBOARD_FAB2_LIB.BASEBOARD_FAB2(SCH_1):M_B_DQ(57)    I14 @BASEBOARD_FAB2_LIB.BASEBOARD_FAB2(SCH_1):PAGE46
   130 M_B_DQ<56> @BASEBOARD_FAB2_LIB.BASEBOARD_FAB2(SCH_1):M_B_DQ(56)    I14 @BASEBOARD_FAB2_LIB.BASEBOARD_FAB2(SCH_1):PAGE46
   269 M_B_DQ<55> @BASEBOARD_FAB2_LIB.BASEBOARD_FAB2(SCH_1):M_B_DQ(55)    I14 @BASEBOARD_FAB2_LIB.BASEBOARD_FAB2(SCH_1):PAGE46
   124 M_B_DQ<54> @BASEBOARD_FAB2_LIB.BASEBOARD_FAB2(SCH_1):M_B_DQ(54)    I14 @BASEBOARD_FAB2_LIB.BASEBOARD_FAB2(SCH_1):PAGE46
   262 M_B_DQ<53> @BASEBOARD_FAB2_LIB.BASEBOARD_FAB2(SCH_1):M_B_DQ(53)    I14 @BASEBOARD_FAB2_LIB.BASEBOARD_FAB2(SCH_1):PAGE46
   117 M_B_DQ<52> @BASEBOARD_FAB2_LIB.BASEBOARD_FAB2(SCH_1):M_B_DQ(52)    I14 @BASEBOARD_FAB2_LIB.BASEBOARD_FAB2(SCH_1):PAGE46
   271 M_B_DQ<51> @BASEBOARD_FAB2_LIB.BASEBOARD_FAB2(SCH_1):M_B_DQ(51)    I14 @BASEBOARD_FAB2_LIB.BASEBOARD_FAB2(SCH_1):PAGE46
   126 M_B_DQ<50> @BASEBOARD_FAB2_LIB.BASEBOARD_FAB2(SCH_1):M_B_DQ(50)    I14 @BASEBOARD_FAB2_LIB.BASEBOARD_FAB2(SCH_1):PAGE46
   264 M_B_DQ<49> @BASEBOARD_FAB2_LIB.BASEBOARD_FAB2(SCH_1):M_B_DQ(49)    I14 @BASEBOARD_FAB2_LIB.BASEBOARD_FAB2(SCH_1):PAGE46
   119 M_B_DQ<48> @BASEBOARD_FAB2_LIB.BASEBOARD_FAB2(SCH_1):M_B_DQ(48)    I14 @BASEBOARD_FAB2_LIB.BASEBOARD_FAB2(SCH_1):PAGE46
   258 M_B_DQ<47> @BASEBOARD_FAB2_LIB.BASEBOARD_FAB2(SCH_1):M_B_DQ(47)    I14 @BASEBOARD_FAB2_LIB.BASEBOARD_FAB2(SCH_1):PAGE46
   113 M_B_DQ<46> @BASEBOARD_FAB2_LIB.BASEBOARD_FAB2(SCH_1):M_B_DQ(46)    I14 @BASEBOARD_FAB2_LIB.BASEBOARD_FAB2(SCH_1):PAGE46
   251 M_B_DQ<45> @BASEBOARD_FAB2_LIB.BASEBOARD_FAB2(SCH_1):M_B_DQ(45)    I14 @BASEBOARD_FAB2_LIB.BASEBOARD_FAB2(SCH_1):PAGE46
   106 M_B_DQ<44> @BASEBOARD_FAB2_LIB.BASEBOARD_FAB2(SCH_1):M_B_DQ(44)    I14 @BASEBOARD_FAB2_LIB.BASEBOARD_FAB2(SCH_1):PAGE46
   260 M_B_DQ<43> @BASEBOARD_FAB2_LIB.BASEBOARD_FAB2(SCH_1):M_B_DQ(43)    I14 @BASEBOARD_FAB2_LIB.BASEBOARD_FAB2(SCH_1):PAGE46
   115 M_B_DQ<42> @BASEBOARD_FAB2_LIB.BASEBOARD_FAB2(SCH_1):M_B_DQ(42)    I14 @BASEBOARD_FAB2_LIB.BASEBOARD_FAB2(SCH_1):PAGE46
   253 M_B_DQ<41> @BASEBOARD_FAB2_LIB.BASEBOARD_FAB2(SCH_1):M_B_DQ(41)    I14 @BASEBOARD_FAB2_LIB.BASEBOARD_FAB2(SCH_1):PAGE46
   108 M_B_DQ<40> @BASEBOARD_FAB2_LIB.BASEBOARD_FAB2(SCH_1):M_B_DQ(40)    I14 @BASEBOARD_FAB2_LIB.BASEBOARD_FAB2(SCH_1):PAGE46
   247 M_B_DQ<39> @BASEBOARD_FAB2_LIB.BASEBOARD_FAB2(SCH_1):M_B_DQ(39)    I14 @BASEBOARD_FAB2_LIB.BASEBOARD_FAB2(SCH_1):PAGE46
   102 M_B_DQ<38> @BASEBOARD_FAB2_LIB.BASEBOARD_FAB2(SCH_1):M_B_DQ(38)    I14 @BASEBOARD_FAB2_LIB.BASEBOARD_FAB2(SCH_1):PAGE46
   240 M_B_DQ<37> @BASEBOARD_FAB2_LIB.BASEBOARD_FAB2(SCH_1):M_B_DQ(37)    I14 @BASEBOARD_FAB2_LIB.BASEBOARD_FAB2(SCH_1):PAGE46
    95 M_B_DQ<36> @BASEBOARD_FAB2_LIB.BASEBOARD_FAB2(SCH_1):M_B_DQ(36)    I14 @BASEBOARD_FAB2_LIB.BASEBOARD_FAB2(SCH_1):PAGE46
   249 M_B_DQ<35> @BASEBOARD_FAB2_LIB.BASEBOARD_FAB2(SCH_1):M_B_DQ(35)    I14 @BASEBOARD_FAB2_LIB.BASEBOARD_FAB2(SCH_1):PAGE46
   104 M_B_DQ<34> @BASEBOARD_FAB2_LIB.BASEBOARD_FAB2(SCH_1):M_B_DQ(34)    I14 @BASEBOARD_FAB2_LIB.BASEBOARD_FAB2(SCH_1):PAGE46
   242 M_B_DQ<33> @BASEBOARD_FAB2_LIB.BASEBOARD_FAB2(SCH_1):M_B_DQ(33)    I14 @BASEBOARD_FAB2_LIB.BASEBOARD_FAB2(SCH_1):PAGE46
    97 M_B_DQ<32> @BASEBOARD_FAB2_LIB.BASEBOARD_FAB2(SCH_1):M_B_DQ(32)    I14 @BASEBOARD_FAB2_LIB.BASEBOARD_FAB2(SCH_1):PAGE46
   188 M_B_DQ<31> @BASEBOARD_FAB2_LIB.BASEBOARD_FAB2(SCH_1):M_B_DQ(31)    I14 @BASEBOARD_FAB2_LIB.BASEBOARD_FAB2(SCH_1):PAGE46
    43 M_B_DQ<30> @BASEBOARD_FAB2_LIB.BASEBOARD_FAB2(SCH_1):M_B_DQ(30)    I14 @BASEBOARD_FAB2_LIB.BASEBOARD_FAB2(SCH_1):PAGE46
   181 M_B_DQ<29> @BASEBOARD_FAB2_LIB.BASEBOARD_FAB2(SCH_1):M_B_DQ(29)    I14 @BASEBOARD_FAB2_LIB.BASEBOARD_FAB2(SCH_1):PAGE46
    36 M_B_DQ<28> @BASEBOARD_FAB2_LIB.BASEBOARD_FAB2(SCH_1):M_B_DQ(28)    I14 @BASEBOARD_FAB2_LIB.BASEBOARD_FAB2(SCH_1):PAGE46
   190 M_B_DQ<27> @BASEBOARD_FAB2_LIB.BASEBOARD_FAB2(SCH_1):M_B_DQ(27)    I14 @BASEBOARD_FAB2_LIB.BASEBOARD_FAB2(SCH_1):PAGE46
    45 M_B_DQ<26> @BASEBOARD_FAB2_LIB.BASEBOARD_FAB2(SCH_1):M_B_DQ(26)    I14 @BASEBOARD_FAB2_LIB.BASEBOARD_FAB2(SCH_1):PAGE46
   183 M_B_DQ<25> @BASEBOARD_FAB2_LIB.BASEBOARD_FAB2(SCH_1):M_B_DQ(25)    I14 @BASEBOARD_FAB2_LIB.BASEBOARD_FAB2(SCH_1):PAGE46
    38 M_B_DQ<24> @BASEBOARD_FAB2_LIB.BASEBOARD_FAB2(SCH_1):M_B_DQ(24)    I14 @BASEBOARD_FAB2_LIB.BASEBOARD_FAB2(SCH_1):PAGE46
   177 M_B_DQ<23> @BASEBOARD_FAB2_LIB.BASEBOARD_FAB2(SCH_1):M_B_DQ(23)    I14 @BASEBOARD_FAB2_LIB.BASEBOARD_FAB2(SCH_1):PAGE46
    32 M_B_DQ<22> @BASEBOARD_FAB2_LIB.BASEBOARD_FAB2(SCH_1):M_B_DQ(22)    I14 @BASEBOARD_FAB2_LIB.BASEBOARD_FAB2(SCH_1):PAGE46
   170 M_B_DQ<21> @BASEBOARD_FAB2_LIB.BASEBOARD_FAB2(SCH_1):M_B_DQ(21)    I14 @BASEBOARD_FAB2_LIB.BASEBOARD_FAB2(SCH_1):PAGE46
    25 M_B_DQ<20> @BASEBOARD_FAB2_LIB.BASEBOARD_FAB2(SCH_1):M_B_DQ(20)    I14 @BASEBOARD_FAB2_LIB.BASEBOARD_FAB2(SCH_1):PAGE46
   179 M_B_DQ<19> @BASEBOARD_FAB2_LIB.BASEBOARD_FAB2(SCH_1):M_B_DQ(19)    I14 @BASEBOARD_FAB2_LIB.BASEBOARD_FAB2(SCH_1):PAGE46
    34 M_B_DQ<18> @BASEBOARD_FAB2_LIB.BASEBOARD_FAB2(SCH_1):M_B_DQ(18)    I14 @BASEBOARD_FAB2_LIB.BASEBOARD_FAB2(SCH_1):PAGE46
   172 M_B_DQ<17> @BASEBOARD_FAB2_LIB.BASEBOARD_FAB2(SCH_1):M_B_DQ(17)    I14 @BASEBOARD_FAB2_LIB.BASEBOARD_FAB2(SCH_1):PAGE46
    27 M_B_DQ<16> @BASEBOARD_FAB2_LIB.BASEBOARD_FAB2(SCH_1):M_B_DQ(16)    I14 @BASEBOARD_FAB2_LIB.BASEBOARD_FAB2(SCH_1):PAGE46
   166 M_B_DQ<15> @BASEBOARD_FAB2_LIB.BASEBOARD_FAB2(SCH_1):M_B_DQ(15)    I14 @BASEBOARD_FAB2_LIB.BASEBOARD_FAB2(SCH_1):PAGE46
    21 M_B_DQ<14> @BASEBOARD_FAB2_LIB.BASEBOARD_FAB2(SCH_1):M_B_DQ(14)    I14 @BASEBOARD_FAB2_LIB.BASEBOARD_FAB2(SCH_1):PAGE46
   159 M_B_DQ<13> @BASEBOARD_FAB2_LIB.BASEBOARD_FAB2(SCH_1):M_B_DQ(13)    I14 @BASEBOARD_FAB2_LIB.BASEBOARD_FAB2(SCH_1):PAGE46
    14 M_B_DQ<12> @BASEBOARD_FAB2_LIB.BASEBOARD_FAB2(SCH_1):M_B_DQ(12)    I14 @BASEBOARD_FAB2_LIB.BASEBOARD_FAB2(SCH_1):PAGE46
   168 M_B_DQ<11> @BASEBOARD_FAB2_LIB.BASEBOARD_FAB2(SCH_1):M_B_DQ(11)    I14 @BASEBOARD_FAB2_LIB.BASEBOARD_FAB2(SCH_1):PAGE46
    23 M_B_DQ<10> @BASEBOARD_FAB2_LIB.BASEBOARD_FAB2(SCH_1):M_B_DQ(10)    I14 @BASEBOARD_FAB2_LIB.BASEBOARD_FAB2(SCH_1):PAGE46
   161 M_B_DQ<9> @BASEBOARD_FAB2_LIB.BASEBOARD_FAB2(SCH_1):M_B_DQ(9)    I14 @BASEBOARD_FAB2_LIB.BASEBOARD_FAB2(SCH_1):PAGE46
    16 M_B_DQ<8> @BASEBOARD_FAB2_LIB.BASEBOARD_FAB2(SCH_1):M_B_DQ(8)    I14 @BASEBOARD_FAB2_LIB.BASEBOARD_FAB2(SCH_1):PAGE46
   155 M_B_DQ<7> @BASEBOARD_FAB2_LIB.BASEBOARD_FAB2(SCH_1):M_B_DQ(7)    I14 @BASEBOARD_FAB2_LIB.BASEBOARD_FAB2(SCH_1):PAGE46
    10 M_B_DQ<6> @BASEBOARD_FAB2_LIB.BASEBOARD_FAB2(SCH_1):M_B_DQ(6)    I14 @BASEBOARD_FAB2_LIB.BASEBOARD_FAB2(SCH_1):PAGE46
   148 M_B_DQ<5> @BASEBOARD_FAB2_LIB.BASEBOARD_FAB2(SCH_1):M_B_DQ(5)    I14 @BASEBOARD_FAB2_LIB.BASEBOARD_FAB2(SCH_1):PAGE46
     3 M_B_DQ<4> @BASEBOARD_FAB2_LIB.BASEBOARD_FAB2(SCH_1):M_B_DQ(4)    I14 @BASEBOARD_FAB2_LIB.BASEBOARD_FAB2(SCH_1):PAGE46
   157 M_B_DQ<3> @BASEBOARD_FAB2_LIB.BASEBOARD_FAB2(SCH_1):M_B_DQ(3)    I14 @BASEBOARD_FAB2_LIB.BASEBOARD_FAB2(SCH_1):PAGE46
    12 M_B_DQ<2> @BASEBOARD_FAB2_LIB.BASEBOARD_FAB2(SCH_1):M_B_DQ(2)    I14 @BASEBOARD_FAB2_LIB.BASEBOARD_FAB2(SCH_1):PAGE46
   150 M_B_DQ<1> @BASEBOARD_FAB2_LIB.BASEBOARD_FAB2(SCH_1):M_B_DQ(1)    I14 @BASEBOARD_FAB2_LIB.BASEBOARD_FAB2(SCH_1):PAGE46
     5 M_B_DQ<0> @BASEBOARD_FAB2_LIB.BASEBOARD_FAB2(SCH_1):M_B_DQ(0)    I14 @BASEBOARD_FAB2_LIB.BASEBOARD_FAB2(SCH_1):PAGE46
    78 FM_DIMM_EVENT_COD_N @BASEBOARD_FAB2_LIB.BASEBOARD_FAB2(SCH_1):FM_DIMM_EVENT_COD_N    I14 @BASEBOARD_FAB2_LIB.BASEBOARD_FAB2(SCH_1):PAGE46
    91 M_B_ODT<3> @BASEBOARD_FAB2_LIB.BASEBOARD_FAB2(SCH_1):M_B_ODT(3)    I14 @BASEBOARD_FAB2_LIB.BASEBOARD_FAB2(SCH_1):PAGE46
    87 M_B_ODT<2> @BASEBOARD_FAB2_LIB.BASEBOARD_FAB2(SCH_1):M_B_ODT(2)    I14 @BASEBOARD_FAB2_LIB.BASEBOARD_FAB2(SCH_1):PAGE46
   222 M_B_PAR @BASEBOARD_FAB2_LIB.BASEBOARD_FAB2(SCH_1):M_B_PAR    I14 @BASEBOARD_FAB2_LIB.BASEBOARD_FAB2(SCH_1):PAGE46
    58 M_ABC_RST_N @BASEBOARD_FAB2_LIB.BASEBOARD_FAB2(SCH_1):M_ABC_RST_N    I14 @BASEBOARD_FAB2_LIB.BASEBOARD_FAB2(SCH_1):PAGE46
   144 TP_CH_B_DIMM_B1_RFU_2 @BASEBOARD_FAB2_LIB.BASEBOARD_FAB2(SCH_1):TP_CH_B_DIMM_B1_RFU_2    I14 @BASEBOARD_FAB2_LIB.BASEBOARD_FAB2(SCH_1):PAGE46
   227 TP_CH_B_DIMM_B1_RFU_1 @BASEBOARD_FAB2_LIB.BASEBOARD_FAB2(SCH_1):TP_CH_B_DIMM_B1_RFU_1    I14 @BASEBOARD_FAB2_LIB.BASEBOARD_FAB2(SCH_1):PAGE46
   205 TP_CH_B_DIMM_B1_RFU_0 @BASEBOARD_FAB2_LIB.BASEBOARD_FAB2(SCH_1):TP_CH_B_DIMM_B1_RFU_0    I14 @BASEBOARD_FAB2_LIB.BASEBOARD_FAB2(SCH_1):PAGE46
    84 M_B_CS_N<4> @BASEBOARD_FAB2_LIB.BASEBOARD_FAB2(SCH_1):M_B_CS_N(4)    I14 @BASEBOARD_FAB2_LIB.BASEBOARD_FAB2(SCH_1):PAGE46
    89 M_B_CS_N<5> @BASEBOARD_FAB2_LIB.BASEBOARD_FAB2(SCH_1):M_B_CS_N(5)    I14 @BASEBOARD_FAB2_LIB.BASEBOARD_FAB2(SCH_1):PAGE46
    93 M_B_CS_N<6> @BASEBOARD_FAB2_LIB.BASEBOARD_FAB2(SCH_1):M_B_CS_N(6)    I14 @BASEBOARD_FAB2_LIB.BASEBOARD_FAB2(SCH_1):PAGE46
   237 M_B_CS_N<7> @BASEBOARD_FAB2_LIB.BASEBOARD_FAB2(SCH_1):M_B_CS_N(7)    I14 @BASEBOARD_FAB2_LIB.BASEBOARD_FAB2(SCH_1):PAGE46
   238    GND @BASEBOARD_FAB2_LIB.BASEBOARD_FAB2(SCH_1):GND    I14 @BASEBOARD_FAB2_LIB.BASEBOARD_FAB2(SCH_1):PAGE46
   140 PVPP_ABC @BASEBOARD_FAB2_LIB.BASEBOARD_FAB2(SCH_1):PVPP_ABC    I14 @BASEBOARD_FAB2_LIB.BASEBOARD_FAB2(SCH_1):PAGE46
   139 PVPP_ABC @BASEBOARD_FAB2_LIB.BASEBOARD_FAB2(SCH_1):PVPP_ABC    I14 @BASEBOARD_FAB2_LIB.BASEBOARD_FAB2(SCH_1):PAGE46
   230 FM_ADR_COMPLETE_ABC_N @BASEBOARD_FAB2_LIB.BASEBOARD_FAB2(SCH_1):FM_ADR_COMPLETE_ABC_N    I14 @BASEBOARD_FAB2_LIB.BASEBOARD_FAB2(SCH_1):PAGE46
   141 SMB_DDR_ABC_VPP_SCL @BASEBOARD_FAB2_LIB.BASEBOARD_FAB2(SCH_1):SMB_DDR_ABC_VPP_SCL    I14 @BASEBOARD_FAB2_LIB.BASEBOARD_FAB2(SCH_1):PAGE46
   285 SMB_DDR_ABC_VPP_SDA @BASEBOARD_FAB2_LIB.BASEBOARD_FAB2(SCH_1):SMB_DDR_ABC_VPP_SDA    I14 @BASEBOARD_FAB2_LIB.BASEBOARD_FAB2(SCH_1):PAGE46
   284 PVPP_ABC @BASEBOARD_FAB2_LIB.BASEBOARD_FAB2(SCH_1):PVPP_ABC    I14 @BASEBOARD_FAB2_LIB.BASEBOARD_FAB2(SCH_1):PAGE46
   146 M_B_VREF @BASEBOARD_FAB2_LIB.BASEBOARD_FAB2(SCH_1):M_B_VREF    I14 @BASEBOARD_FAB2_LIB.BASEBOARD_FAB2(SCH_1):PAGE46
   152 M_B_DQS_DN<0> @BASEBOARD_FAB2_LIB.BASEBOARD_FAB2(SCH_1):M_B_DQS_DN(0)   I112 @BASEBOARD_FAB2_LIB.BASEBOARD_FAB2(SCH_1):PAGE46
   153 M_B_DQS_DP<0> @BASEBOARD_FAB2_LIB.BASEBOARD_FAB2(SCH_1):M_B_DQS_DP(0)   I112 @BASEBOARD_FAB2_LIB.BASEBOARD_FAB2(SCH_1):PAGE46
    19 M_B_DQS_DN<10> @BASEBOARD_FAB2_LIB.BASEBOARD_FAB2(SCH_1):M_B_DQS_DN(10)   I112 @BASEBOARD_FAB2_LIB.BASEBOARD_FAB2(SCH_1):PAGE46
    18 M_B_DQS_DP<10> @BASEBOARD_FAB2_LIB.BASEBOARD_FAB2(SCH_1):M_B_DQS_DP(10)   I112 @BASEBOARD_FAB2_LIB.BASEBOARD_FAB2(SCH_1):PAGE46
    30 M_B_DQS_DN<11> @BASEBOARD_FAB2_LIB.BASEBOARD_FAB2(SCH_1):M_B_DQS_DN(11)   I112 @BASEBOARD_FAB2_LIB.BASEBOARD_FAB2(SCH_1):PAGE46
    29 M_B_DQS_DP<11> @BASEBOARD_FAB2_LIB.BASEBOARD_FAB2(SCH_1):M_B_DQS_DP(11)   I112 @BASEBOARD_FAB2_LIB.BASEBOARD_FAB2(SCH_1):PAGE46
    41 M_B_DQS_DN<12> @BASEBOARD_FAB2_LIB.BASEBOARD_FAB2(SCH_1):M_B_DQS_DN(12)   I112 @BASEBOARD_FAB2_LIB.BASEBOARD_FAB2(SCH_1):PAGE46
    40 M_B_DQS_DP<12> @BASEBOARD_FAB2_LIB.BASEBOARD_FAB2(SCH_1):M_B_DQS_DP(12)   I112 @BASEBOARD_FAB2_LIB.BASEBOARD_FAB2(SCH_1):PAGE46
   100 M_B_DQS_DN<13> @BASEBOARD_FAB2_LIB.BASEBOARD_FAB2(SCH_1):M_B_DQS_DN(13)   I112 @BASEBOARD_FAB2_LIB.BASEBOARD_FAB2(SCH_1):PAGE46
    99 M_B_DQS_DP<13> @BASEBOARD_FAB2_LIB.BASEBOARD_FAB2(SCH_1):M_B_DQS_DP(13)   I112 @BASEBOARD_FAB2_LIB.BASEBOARD_FAB2(SCH_1):PAGE46
   111 M_B_DQS_DN<14> @BASEBOARD_FAB2_LIB.BASEBOARD_FAB2(SCH_1):M_B_DQS_DN(14)   I112 @BASEBOARD_FAB2_LIB.BASEBOARD_FAB2(SCH_1):PAGE46
   110 M_B_DQS_DP<14> @BASEBOARD_FAB2_LIB.BASEBOARD_FAB2(SCH_1):M_B_DQS_DP(14)   I112 @BASEBOARD_FAB2_LIB.BASEBOARD_FAB2(SCH_1):PAGE46
   122 M_B_DQS_DN<15> @BASEBOARD_FAB2_LIB.BASEBOARD_FAB2(SCH_1):M_B_DQS_DN(15)   I112 @BASEBOARD_FAB2_LIB.BASEBOARD_FAB2(SCH_1):PAGE46
   121 M_B_DQS_DP<15> @BASEBOARD_FAB2_LIB.BASEBOARD_FAB2(SCH_1):M_B_DQS_DP(15)   I112 @BASEBOARD_FAB2_LIB.BASEBOARD_FAB2(SCH_1):PAGE46
   133 M_B_DQS_DN<16> @BASEBOARD_FAB2_LIB.BASEBOARD_FAB2(SCH_1):M_B_DQS_DN(16)   I112 @BASEBOARD_FAB2_LIB.BASEBOARD_FAB2(SCH_1):PAGE46
   132 M_B_DQS_DP<16> @BASEBOARD_FAB2_LIB.BASEBOARD_FAB2(SCH_1):M_B_DQS_DP(16)   I112 @BASEBOARD_FAB2_LIB.BASEBOARD_FAB2(SCH_1):PAGE46
    52 M_B_DQS_DN<17> @BASEBOARD_FAB2_LIB.BASEBOARD_FAB2(SCH_1):M_B_DQS_DN(17)   I112 @BASEBOARD_FAB2_LIB.BASEBOARD_FAB2(SCH_1):PAGE46
    51 M_B_DQS_DP<17> @BASEBOARD_FAB2_LIB.BASEBOARD_FAB2(SCH_1):M_B_DQS_DP(17)   I112 @BASEBOARD_FAB2_LIB.BASEBOARD_FAB2(SCH_1):PAGE46
   163 M_B_DQS_DN<1> @BASEBOARD_FAB2_LIB.BASEBOARD_FAB2(SCH_1):M_B_DQS_DN(1)   I112 @BASEBOARD_FAB2_LIB.BASEBOARD_FAB2(SCH_1):PAGE46
   164 M_B_DQS_DP<1> @BASEBOARD_FAB2_LIB.BASEBOARD_FAB2(SCH_1):M_B_DQS_DP(1)   I112 @BASEBOARD_FAB2_LIB.BASEBOARD_FAB2(SCH_1):PAGE46
   174 M_B_DQS_DN<2> @BASEBOARD_FAB2_LIB.BASEBOARD_FAB2(SCH_1):M_B_DQS_DN(2)   I112 @BASEBOARD_FAB2_LIB.BASEBOARD_FAB2(SCH_1):PAGE46
   175 M_B_DQS_DP<2> @BASEBOARD_FAB2_LIB.BASEBOARD_FAB2(SCH_1):M_B_DQS_DP(2)   I112 @BASEBOARD_FAB2_LIB.BASEBOARD_FAB2(SCH_1):PAGE46
   185 M_B_DQS_DN<3> @BASEBOARD_FAB2_LIB.BASEBOARD_FAB2(SCH_1):M_B_DQS_DN(3)   I112 @BASEBOARD_FAB2_LIB.BASEBOARD_FAB2(SCH_1):PAGE46
   186 M_B_DQS_DP<3> @BASEBOARD_FAB2_LIB.BASEBOARD_FAB2(SCH_1):M_B_DQS_DP(3)   I112 @BASEBOARD_FAB2_LIB.BASEBOARD_FAB2(SCH_1):PAGE46
   244 M_B_DQS_DN<4> @BASEBOARD_FAB2_LIB.BASEBOARD_FAB2(SCH_1):M_B_DQS_DN(4)   I112 @BASEBOARD_FAB2_LIB.BASEBOARD_FAB2(SCH_1):PAGE46
   245 M_B_DQS_DP<4> @BASEBOARD_FAB2_LIB.BASEBOARD_FAB2(SCH_1):M_B_DQS_DP(4)   I112 @BASEBOARD_FAB2_LIB.BASEBOARD_FAB2(SCH_1):PAGE46
   255 M_B_DQS_DN<5> @BASEBOARD_FAB2_LIB.BASEBOARD_FAB2(SCH_1):M_B_DQS_DN(5)   I112 @BASEBOARD_FAB2_LIB.BASEBOARD_FAB2(SCH_1):PAGE46
   256 M_B_DQS_DP<5> @BASEBOARD_FAB2_LIB.BASEBOARD_FAB2(SCH_1):M_B_DQS_DP(5)   I112 @BASEBOARD_FAB2_LIB.BASEBOARD_FAB2(SCH_1):PAGE46
   266 M_B_DQS_DN<6> @BASEBOARD_FAB2_LIB.BASEBOARD_FAB2(SCH_1):M_B_DQS_DN(6)   I112 @BASEBOARD_FAB2_LIB.BASEBOARD_FAB2(SCH_1):PAGE46
   267 M_B_DQS_DP<6> @BASEBOARD_FAB2_LIB.BASEBOARD_FAB2(SCH_1):M_B_DQS_DP(6)   I112 @BASEBOARD_FAB2_LIB.BASEBOARD_FAB2(SCH_1):PAGE46
   277 M_B_DQS_DN<7> @BASEBOARD_FAB2_LIB.BASEBOARD_FAB2(SCH_1):M_B_DQS_DN(7)   I112 @BASEBOARD_FAB2_LIB.BASEBOARD_FAB2(SCH_1):PAGE46
   278 M_B_DQS_DP<7> @BASEBOARD_FAB2_LIB.BASEBOARD_FAB2(SCH_1):M_B_DQS_DP(7)   I112 @BASEBOARD_FAB2_LIB.BASEBOARD_FAB2(SCH_1):PAGE46
   196 M_B_DQS_DN<8> @BASEBOARD_FAB2_LIB.BASEBOARD_FAB2(SCH_1):M_B_DQS_DN(8)   I112 @BASEBOARD_FAB2_LIB.BASEBOARD_FAB2(SCH_1):PAGE46
   197 M_B_DQS_DP<8> @BASEBOARD_FAB2_LIB.BASEBOARD_FAB2(SCH_1):M_B_DQS_DP(8)   I112 @BASEBOARD_FAB2_LIB.BASEBOARD_FAB2(SCH_1):PAGE46
     8 M_B_DQS_DN<9> @BASEBOARD_FAB2_LIB.BASEBOARD_FAB2(SCH_1):M_B_DQS_DN(9)   I112 @BASEBOARD_FAB2_LIB.BASEBOARD_FAB2(SCH_1):PAGE46
     7 M_B_DQS_DP<9> @BASEBOARD_FAB2_LIB.BASEBOARD_FAB2(SCH_1):M_B_DQS_DP(9)   I112 @BASEBOARD_FAB2_LIB.BASEBOARD_FAB2(SCH_1):PAGE46
     2    GND @BASEBOARD_FAB2_LIB.BASEBOARD_FAB2(SCH_1):GND   I138 @BASEBOARD_FAB2_LIB.BASEBOARD_FAB2(SCH_1):PAGE46
     4    GND @BASEBOARD_FAB2_LIB.BASEBOARD_FAB2(SCH_1):GND   I138 @BASEBOARD_FAB2_LIB.BASEBOARD_FAB2(SCH_1):PAGE46
     6    GND @BASEBOARD_FAB2_LIB.BASEBOARD_FAB2(SCH_1):GND   I138 @BASEBOARD_FAB2_LIB.BASEBOARD_FAB2(SCH_1):PAGE46
     9    GND @BASEBOARD_FAB2_LIB.BASEBOARD_FAB2(SCH_1):GND   I138 @BASEBOARD_FAB2_LIB.BASEBOARD_FAB2(SCH_1):PAGE46
    11    GND @BASEBOARD_FAB2_LIB.BASEBOARD_FAB2(SCH_1):GND   I138 @BASEBOARD_FAB2_LIB.BASEBOARD_FAB2(SCH_1):PAGE46
    13    GND @BASEBOARD_FAB2_LIB.BASEBOARD_FAB2(SCH_1):GND   I138 @BASEBOARD_FAB2_LIB.BASEBOARD_FAB2(SCH_1):PAGE46
    15    GND @BASEBOARD_FAB2_LIB.BASEBOARD_FAB2(SCH_1):GND   I138 @BASEBOARD_FAB2_LIB.BASEBOARD_FAB2(SCH_1):PAGE46
    17    GND @BASEBOARD_FAB2_LIB.BASEBOARD_FAB2(SCH_1):GND   I138 @BASEBOARD_FAB2_LIB.BASEBOARD_FAB2(SCH_1):PAGE46
    20    GND @BASEBOARD_FAB2_LIB.BASEBOARD_FAB2(SCH_1):GND   I138 @BASEBOARD_FAB2_LIB.BASEBOARD_FAB2(SCH_1):PAGE46
    22    GND @BASEBOARD_FAB2_LIB.BASEBOARD_FAB2(SCH_1):GND   I138 @BASEBOARD_FAB2_LIB.BASEBOARD_FAB2(SCH_1):PAGE46
    24    GND @BASEBOARD_FAB2_LIB.BASEBOARD_FAB2(SCH_1):GND   I138 @BASEBOARD_FAB2_LIB.BASEBOARD_FAB2(SCH_1):PAGE46
    26    GND @BASEBOARD_FAB2_LIB.BASEBOARD_FAB2(SCH_1):GND   I138 @BASEBOARD_FAB2_LIB.BASEBOARD_FAB2(SCH_1):PAGE46
    28    GND @BASEBOARD_FAB2_LIB.BASEBOARD_FAB2(SCH_1):GND   I138 @BASEBOARD_FAB2_LIB.BASEBOARD_FAB2(SCH_1):PAGE46
    31    GND @BASEBOARD_FAB2_LIB.BASEBOARD_FAB2(SCH_1):GND   I138 @BASEBOARD_FAB2_LIB.BASEBOARD_FAB2(SCH_1):PAGE46
    33    GND @BASEBOARD_FAB2_LIB.BASEBOARD_FAB2(SCH_1):GND   I138 @BASEBOARD_FAB2_LIB.BASEBOARD_FAB2(SCH_1):PAGE46
    35    GND @BASEBOARD_FAB2_LIB.BASEBOARD_FAB2(SCH_1):GND   I138 @BASEBOARD_FAB2_LIB.BASEBOARD_FAB2(SCH_1):PAGE46
    37    GND @BASEBOARD_FAB2_LIB.BASEBOARD_FAB2(SCH_1):GND   I138 @BASEBOARD_FAB2_LIB.BASEBOARD_FAB2(SCH_1):PAGE46
    39    GND @BASEBOARD_FAB2_LIB.BASEBOARD_FAB2(SCH_1):GND   I138 @BASEBOARD_FAB2_LIB.BASEBOARD_FAB2(SCH_1):PAGE46
    42    GND @BASEBOARD_FAB2_LIB.BASEBOARD_FAB2(SCH_1):GND   I138 @BASEBOARD_FAB2_LIB.BASEBOARD_FAB2(SCH_1):PAGE46
    44    GND @BASEBOARD_FAB2_LIB.BASEBOARD_FAB2(SCH_1):GND   I138 @BASEBOARD_FAB2_LIB.BASEBOARD_FAB2(SCH_1):PAGE46
    46    GND @BASEBOARD_FAB2_LIB.BASEBOARD_FAB2(SCH_1):GND   I138 @BASEBOARD_FAB2_LIB.BASEBOARD_FAB2(SCH_1):PAGE46
    48    GND @BASEBOARD_FAB2_LIB.BASEBOARD_FAB2(SCH_1):GND   I138 @BASEBOARD_FAB2_LIB.BASEBOARD_FAB2(SCH_1):PAGE46
    50    GND @BASEBOARD_FAB2_LIB.BASEBOARD_FAB2(SCH_1):GND   I138 @BASEBOARD_FAB2_LIB.BASEBOARD_FAB2(SCH_1):PAGE46
    53    GND @BASEBOARD_FAB2_LIB.BASEBOARD_FAB2(SCH_1):GND   I138 @BASEBOARD_FAB2_LIB.BASEBOARD_FAB2(SCH_1):PAGE46
    55    GND @BASEBOARD_FAB2_LIB.BASEBOARD_FAB2(SCH_1):GND   I138 @BASEBOARD_FAB2_LIB.BASEBOARD_FAB2(SCH_1):PAGE46
    57    GND @BASEBOARD_FAB2_LIB.BASEBOARD_FAB2(SCH_1):GND   I138 @BASEBOARD_FAB2_LIB.BASEBOARD_FAB2(SCH_1):PAGE46
    94    GND @BASEBOARD_FAB2_LIB.BASEBOARD_FAB2(SCH_1):GND   I138 @BASEBOARD_FAB2_LIB.BASEBOARD_FAB2(SCH_1):PAGE46
    96    GND @BASEBOARD_FAB2_LIB.BASEBOARD_FAB2(SCH_1):GND   I138 @BASEBOARD_FAB2_LIB.BASEBOARD_FAB2(SCH_1):PAGE46
    98    GND @BASEBOARD_FAB2_LIB.BASEBOARD_FAB2(SCH_1):GND   I138 @BASEBOARD_FAB2_LIB.BASEBOARD_FAB2(SCH_1):PAGE46
   101    GND @BASEBOARD_FAB2_LIB.BASEBOARD_FAB2(SCH_1):GND   I138 @BASEBOARD_FAB2_LIB.BASEBOARD_FAB2(SCH_1):PAGE46
   103    GND @BASEBOARD_FAB2_LIB.BASEBOARD_FAB2(SCH_1):GND   I138 @BASEBOARD_FAB2_LIB.BASEBOARD_FAB2(SCH_1):PAGE46
   105    GND @BASEBOARD_FAB2_LIB.BASEBOARD_FAB2(SCH_1):GND   I138 @BASEBOARD_FAB2_LIB.BASEBOARD_FAB2(SCH_1):PAGE46
   107    GND @BASEBOARD_FAB2_LIB.BASEBOARD_FAB2(SCH_1):GND   I138 @BASEBOARD_FAB2_LIB.BASEBOARD_FAB2(SCH_1):PAGE46
   109    GND @BASEBOARD_FAB2_LIB.BASEBOARD_FAB2(SCH_1):GND   I138 @BASEBOARD_FAB2_LIB.BASEBOARD_FAB2(SCH_1):PAGE46
   112    GND @BASEBOARD_FAB2_LIB.BASEBOARD_FAB2(SCH_1):GND   I138 @BASEBOARD_FAB2_LIB.BASEBOARD_FAB2(SCH_1):PAGE46
   114    GND @BASEBOARD_FAB2_LIB.BASEBOARD_FAB2(SCH_1):GND   I138 @BASEBOARD_FAB2_LIB.BASEBOARD_FAB2(SCH_1):PAGE46
   116    GND @BASEBOARD_FAB2_LIB.BASEBOARD_FAB2(SCH_1):GND   I138 @BASEBOARD_FAB2_LIB.BASEBOARD_FAB2(SCH_1):PAGE46
   118    GND @BASEBOARD_FAB2_LIB.BASEBOARD_FAB2(SCH_1):GND   I138 @BASEBOARD_FAB2_LIB.BASEBOARD_FAB2(SCH_1):PAGE46
   120    GND @BASEBOARD_FAB2_LIB.BASEBOARD_FAB2(SCH_1):GND   I138 @BASEBOARD_FAB2_LIB.BASEBOARD_FAB2(SCH_1):PAGE46
   123    GND @BASEBOARD_FAB2_LIB.BASEBOARD_FAB2(SCH_1):GND   I138 @BASEBOARD_FAB2_LIB.BASEBOARD_FAB2(SCH_1):PAGE46
   125    GND @BASEBOARD_FAB2_LIB.BASEBOARD_FAB2(SCH_1):GND   I138 @BASEBOARD_FAB2_LIB.BASEBOARD_FAB2(SCH_1):PAGE46
   127    GND @BASEBOARD_FAB2_LIB.BASEBOARD_FAB2(SCH_1):GND   I138 @BASEBOARD_FAB2_LIB.BASEBOARD_FAB2(SCH_1):PAGE46
   129    GND @BASEBOARD_FAB2_LIB.BASEBOARD_FAB2(SCH_1):GND   I138 @BASEBOARD_FAB2_LIB.BASEBOARD_FAB2(SCH_1):PAGE46
   131    GND @BASEBOARD_FAB2_LIB.BASEBOARD_FAB2(SCH_1):GND   I138 @BASEBOARD_FAB2_LIB.BASEBOARD_FAB2(SCH_1):PAGE46
   134    GND @BASEBOARD_FAB2_LIB.BASEBOARD_FAB2(SCH_1):GND   I138 @BASEBOARD_FAB2_LIB.BASEBOARD_FAB2(SCH_1):PAGE46
   136    GND @BASEBOARD_FAB2_LIB.BASEBOARD_FAB2(SCH_1):GND   I138 @BASEBOARD_FAB2_LIB.BASEBOARD_FAB2(SCH_1):PAGE46
   138    GND @BASEBOARD_FAB2_LIB.BASEBOARD_FAB2(SCH_1):GND   I138 @BASEBOARD_FAB2_LIB.BASEBOARD_FAB2(SCH_1):PAGE46
   147    GND @BASEBOARD_FAB2_LIB.BASEBOARD_FAB2(SCH_1):GND   I138 @BASEBOARD_FAB2_LIB.BASEBOARD_FAB2(SCH_1):PAGE46
   149    GND @BASEBOARD_FAB2_LIB.BASEBOARD_FAB2(SCH_1):GND   I138 @BASEBOARD_FAB2_LIB.BASEBOARD_FAB2(SCH_1):PAGE46
   151    GND @BASEBOARD_FAB2_LIB.BASEBOARD_FAB2(SCH_1):GND   I138 @BASEBOARD_FAB2_LIB.BASEBOARD_FAB2(SCH_1):PAGE46
   154    GND @BASEBOARD_FAB2_LIB.BASEBOARD_FAB2(SCH_1):GND   I138 @BASEBOARD_FAB2_LIB.BASEBOARD_FAB2(SCH_1):PAGE46
   156    GND @BASEBOARD_FAB2_LIB.BASEBOARD_FAB2(SCH_1):GND   I138 @BASEBOARD_FAB2_LIB.BASEBOARD_FAB2(SCH_1):PAGE46
   158    GND @BASEBOARD_FAB2_LIB.BASEBOARD_FAB2(SCH_1):GND   I138 @BASEBOARD_FAB2_LIB.BASEBOARD_FAB2(SCH_1):PAGE46
   160    GND @BASEBOARD_FAB2_LIB.BASEBOARD_FAB2(SCH_1):GND   I138 @BASEBOARD_FAB2_LIB.BASEBOARD_FAB2(SCH_1):PAGE46
   162    GND @BASEBOARD_FAB2_LIB.BASEBOARD_FAB2(SCH_1):GND   I138 @BASEBOARD_FAB2_LIB.BASEBOARD_FAB2(SCH_1):PAGE46
   165    GND @BASEBOARD_FAB2_LIB.BASEBOARD_FAB2(SCH_1):GND   I138 @BASEBOARD_FAB2_LIB.BASEBOARD_FAB2(SCH_1):PAGE46
   167    GND @BASEBOARD_FAB2_LIB.BASEBOARD_FAB2(SCH_1):GND   I138 @BASEBOARD_FAB2_LIB.BASEBOARD_FAB2(SCH_1):PAGE46
   169    GND @BASEBOARD_FAB2_LIB.BASEBOARD_FAB2(SCH_1):GND   I138 @BASEBOARD_FAB2_LIB.BASEBOARD_FAB2(SCH_1):PAGE46
   171    GND @BASEBOARD_FAB2_LIB.BASEBOARD_FAB2(SCH_1):GND   I138 @BASEBOARD_FAB2_LIB.BASEBOARD_FAB2(SCH_1):PAGE46
   173    GND @BASEBOARD_FAB2_LIB.BASEBOARD_FAB2(SCH_1):GND   I138 @BASEBOARD_FAB2_LIB.BASEBOARD_FAB2(SCH_1):PAGE46
   176    GND @BASEBOARD_FAB2_LIB.BASEBOARD_FAB2(SCH_1):GND   I138 @BASEBOARD_FAB2_LIB.BASEBOARD_FAB2(SCH_1):PAGE46
   178    GND @BASEBOARD_FAB2_LIB.BASEBOARD_FAB2(SCH_1):GND   I138 @BASEBOARD_FAB2_LIB.BASEBOARD_FAB2(SCH_1):PAGE46
   180    GND @BASEBOARD_FAB2_LIB.BASEBOARD_FAB2(SCH_1):GND   I138 @BASEBOARD_FAB2_LIB.BASEBOARD_FAB2(SCH_1):PAGE46
   182    GND @BASEBOARD_FAB2_LIB.BASEBOARD_FAB2(SCH_1):GND   I138 @BASEBOARD_FAB2_LIB.BASEBOARD_FAB2(SCH_1):PAGE46
   184    GND @BASEBOARD_FAB2_LIB.BASEBOARD_FAB2(SCH_1):GND   I138 @BASEBOARD_FAB2_LIB.BASEBOARD_FAB2(SCH_1):PAGE46
   187    GND @BASEBOARD_FAB2_LIB.BASEBOARD_FAB2(SCH_1):GND   I138 @BASEBOARD_FAB2_LIB.BASEBOARD_FAB2(SCH_1):PAGE46
   189    GND @BASEBOARD_FAB2_LIB.BASEBOARD_FAB2(SCH_1):GND   I138 @BASEBOARD_FAB2_LIB.BASEBOARD_FAB2(SCH_1):PAGE46
   191    GND @BASEBOARD_FAB2_LIB.BASEBOARD_FAB2(SCH_1):GND   I138 @BASEBOARD_FAB2_LIB.BASEBOARD_FAB2(SCH_1):PAGE46
   193    GND @BASEBOARD_FAB2_LIB.BASEBOARD_FAB2(SCH_1):GND   I138 @BASEBOARD_FAB2_LIB.BASEBOARD_FAB2(SCH_1):PAGE46
   195    GND @BASEBOARD_FAB2_LIB.BASEBOARD_FAB2(SCH_1):GND   I138 @BASEBOARD_FAB2_LIB.BASEBOARD_FAB2(SCH_1):PAGE46
   198    GND @BASEBOARD_FAB2_LIB.BASEBOARD_FAB2(SCH_1):GND   I138 @BASEBOARD_FAB2_LIB.BASEBOARD_FAB2(SCH_1):PAGE46
   200    GND @BASEBOARD_FAB2_LIB.BASEBOARD_FAB2(SCH_1):GND   I138 @BASEBOARD_FAB2_LIB.BASEBOARD_FAB2(SCH_1):PAGE46
   202    GND @BASEBOARD_FAB2_LIB.BASEBOARD_FAB2(SCH_1):GND   I138 @BASEBOARD_FAB2_LIB.BASEBOARD_FAB2(SCH_1):PAGE46
   239    GND @BASEBOARD_FAB2_LIB.BASEBOARD_FAB2(SCH_1):GND   I138 @BASEBOARD_FAB2_LIB.BASEBOARD_FAB2(SCH_1):PAGE46
   241    GND @BASEBOARD_FAB2_LIB.BASEBOARD_FAB2(SCH_1):GND   I138 @BASEBOARD_FAB2_LIB.BASEBOARD_FAB2(SCH_1):PAGE46
   243    GND @BASEBOARD_FAB2_LIB.BASEBOARD_FAB2(SCH_1):GND   I138 @BASEBOARD_FAB2_LIB.BASEBOARD_FAB2(SCH_1):PAGE46
   246    GND @BASEBOARD_FAB2_LIB.BASEBOARD_FAB2(SCH_1):GND   I138 @BASEBOARD_FAB2_LIB.BASEBOARD_FAB2(SCH_1):PAGE46
   248    GND @BASEBOARD_FAB2_LIB.BASEBOARD_FAB2(SCH_1):GND   I138 @BASEBOARD_FAB2_LIB.BASEBOARD_FAB2(SCH_1):PAGE46
   250    GND @BASEBOARD_FAB2_LIB.BASEBOARD_FAB2(SCH_1):GND   I138 @BASEBOARD_FAB2_LIB.BASEBOARD_FAB2(SCH_1):PAGE46
   252    GND @BASEBOARD_FAB2_LIB.BASEBOARD_FAB2(SCH_1):GND   I138 @BASEBOARD_FAB2_LIB.BASEBOARD_FAB2(SCH_1):PAGE46
   254    GND @BASEBOARD_FAB2_LIB.BASEBOARD_FAB2(SCH_1):GND   I138 @BASEBOARD_FAB2_LIB.BASEBOARD_FAB2(SCH_1):PAGE46
   257    GND @BASEBOARD_FAB2_LIB.BASEBOARD_FAB2(SCH_1):GND   I138 @BASEBOARD_FAB2_LIB.BASEBOARD_FAB2(SCH_1):PAGE46
   259    GND @BASEBOARD_FAB2_LIB.BASEBOARD_FAB2(SCH_1):GND   I138 @BASEBOARD_FAB2_LIB.BASEBOARD_FAB2(SCH_1):PAGE46
   261    GND @BASEBOARD_FAB2_LIB.BASEBOARD_FAB2(SCH_1):GND   I138 @BASEBOARD_FAB2_LIB.BASEBOARD_FAB2(SCH_1):PAGE46
   263    GND @BASEBOARD_FAB2_LIB.BASEBOARD_FAB2(SCH_1):GND   I138 @BASEBOARD_FAB2_LIB.BASEBOARD_FAB2(SCH_1):PAGE46
   265    GND @BASEBOARD_FAB2_LIB.BASEBOARD_FAB2(SCH_1):GND   I138 @BASEBOARD_FAB2_LIB.BASEBOARD_FAB2(SCH_1):PAGE46
   268    GND @BASEBOARD_FAB2_LIB.BASEBOARD_FAB2(SCH_1):GND   I138 @BASEBOARD_FAB2_LIB.BASEBOARD_FAB2(SCH_1):PAGE46
   270    GND @BASEBOARD_FAB2_LIB.BASEBOARD_FAB2(SCH_1):GND   I138 @BASEBOARD_FAB2_LIB.BASEBOARD_FAB2(SCH_1):PAGE46
   272    GND @BASEBOARD_FAB2_LIB.BASEBOARD_FAB2(SCH_1):GND   I138 @BASEBOARD_FAB2_LIB.BASEBOARD_FAB2(SCH_1):PAGE46
   274    GND @BASEBOARD_FAB2_LIB.BASEBOARD_FAB2(SCH_1):GND   I138 @BASEBOARD_FAB2_LIB.BASEBOARD_FAB2(SCH_1):PAGE46
   276    GND @BASEBOARD_FAB2_LIB.BASEBOARD_FAB2(SCH_1):GND   I138 @BASEBOARD_FAB2_LIB.BASEBOARD_FAB2(SCH_1):PAGE46
   279    GND @BASEBOARD_FAB2_LIB.BASEBOARD_FAB2(SCH_1):GND   I138 @BASEBOARD_FAB2_LIB.BASEBOARD_FAB2(SCH_1):PAGE46
   281    GND @BASEBOARD_FAB2_LIB.BASEBOARD_FAB2(SCH_1):GND   I138 @BASEBOARD_FAB2_LIB.BASEBOARD_FAB2(SCH_1):PAGE46
   283    GND @BASEBOARD_FAB2_LIB.BASEBOARD_FAB2(SCH_1):GND   I138 @BASEBOARD_FAB2_LIB.BASEBOARD_FAB2(SCH_1):PAGE46
     1 P12V_NVDIMM_ABC @BASEBOARD_FAB2_LIB.BASEBOARD_FAB2(SCH_1):P12V_NVDIMM_ABC    I67 @BASEBOARD_FAB2_LIB.BASEBOARD_FAB2(SCH_1):PAGE46
   145 P12V_NVDIMM_ABC @BASEBOARD_FAB2_LIB.BASEBOARD_FAB2(SCH_1):P12V_NVDIMM_ABC    I67 @BASEBOARD_FAB2_LIB.BASEBOARD_FAB2(SCH_1):PAGE46
    59 PVDDQ_ABC @BASEBOARD_FAB2_LIB.BASEBOARD_FAB2(SCH_1):PVDDQ_ABC    I67 @BASEBOARD_FAB2_LIB.BASEBOARD_FAB2(SCH_1):PAGE46
    61 PVDDQ_ABC @BASEBOARD_FAB2_LIB.BASEBOARD_FAB2(SCH_1):PVDDQ_ABC    I67 @BASEBOARD_FAB2_LIB.BASEBOARD_FAB2(SCH_1):PAGE46
    64 PVDDQ_ABC @BASEBOARD_FAB2_LIB.BASEBOARD_FAB2(SCH_1):PVDDQ_ABC    I67 @BASEBOARD_FAB2_LIB.BASEBOARD_FAB2(SCH_1):PAGE46
    67 PVDDQ_ABC @BASEBOARD_FAB2_LIB.BASEBOARD_FAB2(SCH_1):PVDDQ_ABC    I67 @BASEBOARD_FAB2_LIB.BASEBOARD_FAB2(SCH_1):PAGE46
    70 PVDDQ_ABC @BASEBOARD_FAB2_LIB.BASEBOARD_FAB2(SCH_1):PVDDQ_ABC    I67 @BASEBOARD_FAB2_LIB.BASEBOARD_FAB2(SCH_1):PAGE46
    73 PVDDQ_ABC @BASEBOARD_FAB2_LIB.BASEBOARD_FAB2(SCH_1):PVDDQ_ABC    I67 @BASEBOARD_FAB2_LIB.BASEBOARD_FAB2(SCH_1):PAGE46
    76 PVDDQ_ABC @BASEBOARD_FAB2_LIB.BASEBOARD_FAB2(SCH_1):PVDDQ_ABC    I67 @BASEBOARD_FAB2_LIB.BASEBOARD_FAB2(SCH_1):PAGE46
    80 PVDDQ_ABC @BASEBOARD_FAB2_LIB.BASEBOARD_FAB2(SCH_1):PVDDQ_ABC    I67 @BASEBOARD_FAB2_LIB.BASEBOARD_FAB2(SCH_1):PAGE46
    83 PVDDQ_ABC @BASEBOARD_FAB2_LIB.BASEBOARD_FAB2(SCH_1):PVDDQ_ABC    I67 @BASEBOARD_FAB2_LIB.BASEBOARD_FAB2(SCH_1):PAGE46
    85 PVDDQ_ABC @BASEBOARD_FAB2_LIB.BASEBOARD_FAB2(SCH_1):PVDDQ_ABC    I67 @BASEBOARD_FAB2_LIB.BASEBOARD_FAB2(SCH_1):PAGE46
    88 PVDDQ_ABC @BASEBOARD_FAB2_LIB.BASEBOARD_FAB2(SCH_1):PVDDQ_ABC    I67 @BASEBOARD_FAB2_LIB.BASEBOARD_FAB2(SCH_1):PAGE46
    90 PVDDQ_ABC @BASEBOARD_FAB2_LIB.BASEBOARD_FAB2(SCH_1):PVDDQ_ABC    I67 @BASEBOARD_FAB2_LIB.BASEBOARD_FAB2(SCH_1):PAGE46
    92 PVDDQ_ABC @BASEBOARD_FAB2_LIB.BASEBOARD_FAB2(SCH_1):PVDDQ_ABC    I67 @BASEBOARD_FAB2_LIB.BASEBOARD_FAB2(SCH_1):PAGE46
   204 PVDDQ_ABC @BASEBOARD_FAB2_LIB.BASEBOARD_FAB2(SCH_1):PVDDQ_ABC    I67 @BASEBOARD_FAB2_LIB.BASEBOARD_FAB2(SCH_1):PAGE46
   206 PVDDQ_ABC @BASEBOARD_FAB2_LIB.BASEBOARD_FAB2(SCH_1):PVDDQ_ABC    I67 @BASEBOARD_FAB2_LIB.BASEBOARD_FAB2(SCH_1):PAGE46
   209 PVDDQ_ABC @BASEBOARD_FAB2_LIB.BASEBOARD_FAB2(SCH_1):PVDDQ_ABC    I67 @BASEBOARD_FAB2_LIB.BASEBOARD_FAB2(SCH_1):PAGE46
   212 PVDDQ_ABC @BASEBOARD_FAB2_LIB.BASEBOARD_FAB2(SCH_1):PVDDQ_ABC    I67 @BASEBOARD_FAB2_LIB.BASEBOARD_FAB2(SCH_1):PAGE46
   215 PVDDQ_ABC @BASEBOARD_FAB2_LIB.BASEBOARD_FAB2(SCH_1):PVDDQ_ABC    I67 @BASEBOARD_FAB2_LIB.BASEBOARD_FAB2(SCH_1):PAGE46
   217 PVDDQ_ABC @BASEBOARD_FAB2_LIB.BASEBOARD_FAB2(SCH_1):PVDDQ_ABC    I67 @BASEBOARD_FAB2_LIB.BASEBOARD_FAB2(SCH_1):PAGE46
   220 PVDDQ_ABC @BASEBOARD_FAB2_LIB.BASEBOARD_FAB2(SCH_1):PVDDQ_ABC    I67 @BASEBOARD_FAB2_LIB.BASEBOARD_FAB2(SCH_1):PAGE46
   223 PVDDQ_ABC @BASEBOARD_FAB2_LIB.BASEBOARD_FAB2(SCH_1):PVDDQ_ABC    I67 @BASEBOARD_FAB2_LIB.BASEBOARD_FAB2(SCH_1):PAGE46
   226 PVDDQ_ABC @BASEBOARD_FAB2_LIB.BASEBOARD_FAB2(SCH_1):PVDDQ_ABC    I67 @BASEBOARD_FAB2_LIB.BASEBOARD_FAB2(SCH_1):PAGE46
   229 PVDDQ_ABC @BASEBOARD_FAB2_LIB.BASEBOARD_FAB2(SCH_1):PVDDQ_ABC    I67 @BASEBOARD_FAB2_LIB.BASEBOARD_FAB2(SCH_1):PAGE46
   231 PVDDQ_ABC @BASEBOARD_FAB2_LIB.BASEBOARD_FAB2(SCH_1):PVDDQ_ABC    I67 @BASEBOARD_FAB2_LIB.BASEBOARD_FAB2(SCH_1):PAGE46
   233 PVDDQ_ABC @BASEBOARD_FAB2_LIB.BASEBOARD_FAB2(SCH_1):PVDDQ_ABC    I67 @BASEBOARD_FAB2_LIB.BASEBOARD_FAB2(SCH_1):PAGE46
   236 PVDDQ_ABC @BASEBOARD_FAB2_LIB.BASEBOARD_FAB2(SCH_1):PVDDQ_ABC    I67 @BASEBOARD_FAB2_LIB.BASEBOARD_FAB2(SCH_1):PAGE46
   142 PVPP_ABC @BASEBOARD_FAB2_LIB.BASEBOARD_FAB2(SCH_1):PVPP_ABC    I67 @BASEBOARD_FAB2_LIB.BASEBOARD_FAB2(SCH_1):PAGE46
   143 PVPP_ABC @BASEBOARD_FAB2_LIB.BASEBOARD_FAB2(SCH_1):PVPP_ABC    I67 @BASEBOARD_FAB2_LIB.BASEBOARD_FAB2(SCH_1):PAGE46
   288 PVPP_ABC @BASEBOARD_FAB2_LIB.BASEBOARD_FAB2(SCH_1):PVPP_ABC    I67 @BASEBOARD_FAB2_LIB.BASEBOARD_FAB2(SCH_1):PAGE46
   286 PVPP_ABC @BASEBOARD_FAB2_LIB.BASEBOARD_FAB2(SCH_1):PVPP_ABC    I67 @BASEBOARD_FAB2_LIB.BASEBOARD_FAB2(SCH_1):PAGE46
   287 PVPP_ABC @BASEBOARD_FAB2_LIB.BASEBOARD_FAB2(SCH_1):PVPP_ABC    I67 @BASEBOARD_FAB2_LIB.BASEBOARD_FAB2(SCH_1):PAGE46
    77 PVTT_ABC @BASEBOARD_FAB2_LIB.BASEBOARD_FAB2(SCH_1):PVTT_ABC    I67 @BASEBOARD_FAB2_LIB.BASEBOARD_FAB2(SCH_1):PAGE46
   221 PVTT_ABC @BASEBOARD_FAB2_LIB.BASEBOARD_FAB2(SCH_1):PVTT_ABC    I67 @BASEBOARD_FAB2_LIB.BASEBOARD_FAB2(SCH_1):PAGE46

J6U2 SCONN288_H44441003_PIP-SCONN,HA
    79 M_C_MA<0> @BASEBOARD_FAB2_LIB.BASEBOARD_FAB2(SCH_1):M_C_MA(0)   I111 @BASEBOARD_FAB2_LIB.BASEBOARD_FAB2(SCH_1):PAGE48
    72 M_C_MA<1> @BASEBOARD_FAB2_LIB.BASEBOARD_FAB2(SCH_1):M_C_MA(1)   I111 @BASEBOARD_FAB2_LIB.BASEBOARD_FAB2(SCH_1):PAGE48
   225 M_C_MA<10> @BASEBOARD_FAB2_LIB.BASEBOARD_FAB2(SCH_1):M_C_MA(10)   I111 @BASEBOARD_FAB2_LIB.BASEBOARD_FAB2(SCH_1):PAGE48
   210 M_C_MA<11> @BASEBOARD_FAB2_LIB.BASEBOARD_FAB2(SCH_1):M_C_MA(11)   I111 @BASEBOARD_FAB2_LIB.BASEBOARD_FAB2(SCH_1):PAGE48
    65 M_C_MA<12> @BASEBOARD_FAB2_LIB.BASEBOARD_FAB2(SCH_1):M_C_MA(12)   I111 @BASEBOARD_FAB2_LIB.BASEBOARD_FAB2(SCH_1):PAGE48
   232 M_C_MA<13> @BASEBOARD_FAB2_LIB.BASEBOARD_FAB2(SCH_1):M_C_MA(13)   I111 @BASEBOARD_FAB2_LIB.BASEBOARD_FAB2(SCH_1):PAGE48
   228 M_C_MA<14> @BASEBOARD_FAB2_LIB.BASEBOARD_FAB2(SCH_1):M_C_MA(14)   I111 @BASEBOARD_FAB2_LIB.BASEBOARD_FAB2(SCH_1):PAGE48
    86 M_C_MA<15> @BASEBOARD_FAB2_LIB.BASEBOARD_FAB2(SCH_1):M_C_MA(15)   I111 @BASEBOARD_FAB2_LIB.BASEBOARD_FAB2(SCH_1):PAGE48
    82 M_C_MA<16> @BASEBOARD_FAB2_LIB.BASEBOARD_FAB2(SCH_1):M_C_MA(16)   I111 @BASEBOARD_FAB2_LIB.BASEBOARD_FAB2(SCH_1):PAGE48
   234 M_C_MA<17> @BASEBOARD_FAB2_LIB.BASEBOARD_FAB2(SCH_1):M_C_MA(17)   I111 @BASEBOARD_FAB2_LIB.BASEBOARD_FAB2(SCH_1):PAGE48
   216 M_C_MA<2> @BASEBOARD_FAB2_LIB.BASEBOARD_FAB2(SCH_1):M_C_MA(2)   I111 @BASEBOARD_FAB2_LIB.BASEBOARD_FAB2(SCH_1):PAGE48
    71 M_C_MA<3> @BASEBOARD_FAB2_LIB.BASEBOARD_FAB2(SCH_1):M_C_MA(3)   I111 @BASEBOARD_FAB2_LIB.BASEBOARD_FAB2(SCH_1):PAGE48
   214 M_C_MA<4> @BASEBOARD_FAB2_LIB.BASEBOARD_FAB2(SCH_1):M_C_MA(4)   I111 @BASEBOARD_FAB2_LIB.BASEBOARD_FAB2(SCH_1):PAGE48
   213 M_C_MA<5> @BASEBOARD_FAB2_LIB.BASEBOARD_FAB2(SCH_1):M_C_MA(5)   I111 @BASEBOARD_FAB2_LIB.BASEBOARD_FAB2(SCH_1):PAGE48
    69 M_C_MA<6> @BASEBOARD_FAB2_LIB.BASEBOARD_FAB2(SCH_1):M_C_MA(6)   I111 @BASEBOARD_FAB2_LIB.BASEBOARD_FAB2(SCH_1):PAGE48
   211 M_C_MA<7> @BASEBOARD_FAB2_LIB.BASEBOARD_FAB2(SCH_1):M_C_MA(7)   I111 @BASEBOARD_FAB2_LIB.BASEBOARD_FAB2(SCH_1):PAGE48
    68 M_C_MA<8> @BASEBOARD_FAB2_LIB.BASEBOARD_FAB2(SCH_1):M_C_MA(8)   I111 @BASEBOARD_FAB2_LIB.BASEBOARD_FAB2(SCH_1):PAGE48
    66 M_C_MA<9> @BASEBOARD_FAB2_LIB.BASEBOARD_FAB2(SCH_1):M_C_MA(9)   I111 @BASEBOARD_FAB2_LIB.BASEBOARD_FAB2(SCH_1):PAGE48
    62 M_C_ACT_N @BASEBOARD_FAB2_LIB.BASEBOARD_FAB2(SCH_1):M_C_ACT_N   I111 @BASEBOARD_FAB2_LIB.BASEBOARD_FAB2(SCH_1):PAGE48
   208 M_C_ALERT_N @BASEBOARD_FAB2_LIB.BASEBOARD_FAB2(SCH_1):M_C_ALERT_N   I111 @BASEBOARD_FAB2_LIB.BASEBOARD_FAB2(SCH_1):PAGE48
   224 M_C_BA<1> @BASEBOARD_FAB2_LIB.BASEBOARD_FAB2(SCH_1):M_C_BA(1)   I111 @BASEBOARD_FAB2_LIB.BASEBOARD_FAB2(SCH_1):PAGE48
    81 M_C_BA<0> @BASEBOARD_FAB2_LIB.BASEBOARD_FAB2(SCH_1):M_C_BA(0)   I111 @BASEBOARD_FAB2_LIB.BASEBOARD_FAB2(SCH_1):PAGE48
   207 M_C_BG<1> @BASEBOARD_FAB2_LIB.BASEBOARD_FAB2(SCH_1):M_C_BG(1)   I111 @BASEBOARD_FAB2_LIB.BASEBOARD_FAB2(SCH_1):PAGE48
    63 M_C_BG<0> @BASEBOARD_FAB2_LIB.BASEBOARD_FAB2(SCH_1):M_C_BG(0)   I111 @BASEBOARD_FAB2_LIB.BASEBOARD_FAB2(SCH_1):PAGE48
   235 M_C_C<2> @BASEBOARD_FAB2_LIB.BASEBOARD_FAB2(SCH_1):M_C_C(2)   I111 @BASEBOARD_FAB2_LIB.BASEBOARD_FAB2(SCH_1):PAGE48
   199 M_C_ECC<7> @BASEBOARD_FAB2_LIB.BASEBOARD_FAB2(SCH_1):M_C_ECC(7)   I111 @BASEBOARD_FAB2_LIB.BASEBOARD_FAB2(SCH_1):PAGE48
    54 M_C_ECC<6> @BASEBOARD_FAB2_LIB.BASEBOARD_FAB2(SCH_1):M_C_ECC(6)   I111 @BASEBOARD_FAB2_LIB.BASEBOARD_FAB2(SCH_1):PAGE48
   192 M_C_ECC<5> @BASEBOARD_FAB2_LIB.BASEBOARD_FAB2(SCH_1):M_C_ECC(5)   I111 @BASEBOARD_FAB2_LIB.BASEBOARD_FAB2(SCH_1):PAGE48
    47 M_C_ECC<4> @BASEBOARD_FAB2_LIB.BASEBOARD_FAB2(SCH_1):M_C_ECC(4)   I111 @BASEBOARD_FAB2_LIB.BASEBOARD_FAB2(SCH_1):PAGE48
   201 M_C_ECC<3> @BASEBOARD_FAB2_LIB.BASEBOARD_FAB2(SCH_1):M_C_ECC(3)   I111 @BASEBOARD_FAB2_LIB.BASEBOARD_FAB2(SCH_1):PAGE48
    56 M_C_ECC<2> @BASEBOARD_FAB2_LIB.BASEBOARD_FAB2(SCH_1):M_C_ECC(2)   I111 @BASEBOARD_FAB2_LIB.BASEBOARD_FAB2(SCH_1):PAGE48
   194 M_C_ECC<1> @BASEBOARD_FAB2_LIB.BASEBOARD_FAB2(SCH_1):M_C_ECC(1)   I111 @BASEBOARD_FAB2_LIB.BASEBOARD_FAB2(SCH_1):PAGE48
    49 M_C_ECC<0> @BASEBOARD_FAB2_LIB.BASEBOARD_FAB2(SCH_1):M_C_ECC(0)   I111 @BASEBOARD_FAB2_LIB.BASEBOARD_FAB2(SCH_1):PAGE48
    75 M_C_CLK_DN<2> @BASEBOARD_FAB2_LIB.BASEBOARD_FAB2(SCH_1):M_C_CLK_DN(2)   I111 @BASEBOARD_FAB2_LIB.BASEBOARD_FAB2(SCH_1):PAGE48
    74 M_C_CLK_DP<2> @BASEBOARD_FAB2_LIB.BASEBOARD_FAB2(SCH_1):M_C_CLK_DP(2)   I111 @BASEBOARD_FAB2_LIB.BASEBOARD_FAB2(SCH_1):PAGE48
   219 M_C_CLK_DN<3> @BASEBOARD_FAB2_LIB.BASEBOARD_FAB2(SCH_1):M_C_CLK_DN(3)   I111 @BASEBOARD_FAB2_LIB.BASEBOARD_FAB2(SCH_1):PAGE48
   218 M_C_CLK_DP<3> @BASEBOARD_FAB2_LIB.BASEBOARD_FAB2(SCH_1):M_C_CLK_DP(3)   I111 @BASEBOARD_FAB2_LIB.BASEBOARD_FAB2(SCH_1):PAGE48
   203 M_C_CKE<3> @BASEBOARD_FAB2_LIB.BASEBOARD_FAB2(SCH_1):M_C_CKE(3)   I111 @BASEBOARD_FAB2_LIB.BASEBOARD_FAB2(SCH_1):PAGE48
    60 M_C_CKE<2> @BASEBOARD_FAB2_LIB.BASEBOARD_FAB2(SCH_1):M_C_CKE(2)   I111 @BASEBOARD_FAB2_LIB.BASEBOARD_FAB2(SCH_1):PAGE48
   280 M_C_DQ<63> @BASEBOARD_FAB2_LIB.BASEBOARD_FAB2(SCH_1):M_C_DQ(63)   I111 @BASEBOARD_FAB2_LIB.BASEBOARD_FAB2(SCH_1):PAGE48
   135 M_C_DQ<62> @BASEBOARD_FAB2_LIB.BASEBOARD_FAB2(SCH_1):M_C_DQ(62)   I111 @BASEBOARD_FAB2_LIB.BASEBOARD_FAB2(SCH_1):PAGE48
   273 M_C_DQ<61> @BASEBOARD_FAB2_LIB.BASEBOARD_FAB2(SCH_1):M_C_DQ(61)   I111 @BASEBOARD_FAB2_LIB.BASEBOARD_FAB2(SCH_1):PAGE48
   128 M_C_DQ<60> @BASEBOARD_FAB2_LIB.BASEBOARD_FAB2(SCH_1):M_C_DQ(60)   I111 @BASEBOARD_FAB2_LIB.BASEBOARD_FAB2(SCH_1):PAGE48
   282 M_C_DQ<59> @BASEBOARD_FAB2_LIB.BASEBOARD_FAB2(SCH_1):M_C_DQ(59)   I111 @BASEBOARD_FAB2_LIB.BASEBOARD_FAB2(SCH_1):PAGE48
   137 M_C_DQ<58> @BASEBOARD_FAB2_LIB.BASEBOARD_FAB2(SCH_1):M_C_DQ(58)   I111 @BASEBOARD_FAB2_LIB.BASEBOARD_FAB2(SCH_1):PAGE48
   275 M_C_DQ<57> @BASEBOARD_FAB2_LIB.BASEBOARD_FAB2(SCH_1):M_C_DQ(57)   I111 @BASEBOARD_FAB2_LIB.BASEBOARD_FAB2(SCH_1):PAGE48
   130 M_C_DQ<56> @BASEBOARD_FAB2_LIB.BASEBOARD_FAB2(SCH_1):M_C_DQ(56)   I111 @BASEBOARD_FAB2_LIB.BASEBOARD_FAB2(SCH_1):PAGE48
   269 M_C_DQ<55> @BASEBOARD_FAB2_LIB.BASEBOARD_FAB2(SCH_1):M_C_DQ(55)   I111 @BASEBOARD_FAB2_LIB.BASEBOARD_FAB2(SCH_1):PAGE48
   124 M_C_DQ<54> @BASEBOARD_FAB2_LIB.BASEBOARD_FAB2(SCH_1):M_C_DQ(54)   I111 @BASEBOARD_FAB2_LIB.BASEBOARD_FAB2(SCH_1):PAGE48
   262 M_C_DQ<53> @BASEBOARD_FAB2_LIB.BASEBOARD_FAB2(SCH_1):M_C_DQ(53)   I111 @BASEBOARD_FAB2_LIB.BASEBOARD_FAB2(SCH_1):PAGE48
   117 M_C_DQ<52> @BASEBOARD_FAB2_LIB.BASEBOARD_FAB2(SCH_1):M_C_DQ(52)   I111 @BASEBOARD_FAB2_LIB.BASEBOARD_FAB2(SCH_1):PAGE48
   271 M_C_DQ<51> @BASEBOARD_FAB2_LIB.BASEBOARD_FAB2(SCH_1):M_C_DQ(51)   I111 @BASEBOARD_FAB2_LIB.BASEBOARD_FAB2(SCH_1):PAGE48
   126 M_C_DQ<50> @BASEBOARD_FAB2_LIB.BASEBOARD_FAB2(SCH_1):M_C_DQ(50)   I111 @BASEBOARD_FAB2_LIB.BASEBOARD_FAB2(SCH_1):PAGE48
   264 M_C_DQ<49> @BASEBOARD_FAB2_LIB.BASEBOARD_FAB2(SCH_1):M_C_DQ(49)   I111 @BASEBOARD_FAB2_LIB.BASEBOARD_FAB2(SCH_1):PAGE48
   119 M_C_DQ<48> @BASEBOARD_FAB2_LIB.BASEBOARD_FAB2(SCH_1):M_C_DQ(48)   I111 @BASEBOARD_FAB2_LIB.BASEBOARD_FAB2(SCH_1):PAGE48
   258 M_C_DQ<47> @BASEBOARD_FAB2_LIB.BASEBOARD_FAB2(SCH_1):M_C_DQ(47)   I111 @BASEBOARD_FAB2_LIB.BASEBOARD_FAB2(SCH_1):PAGE48
   113 M_C_DQ<46> @BASEBOARD_FAB2_LIB.BASEBOARD_FAB2(SCH_1):M_C_DQ(46)   I111 @BASEBOARD_FAB2_LIB.BASEBOARD_FAB2(SCH_1):PAGE48
   251 M_C_DQ<45> @BASEBOARD_FAB2_LIB.BASEBOARD_FAB2(SCH_1):M_C_DQ(45)   I111 @BASEBOARD_FAB2_LIB.BASEBOARD_FAB2(SCH_1):PAGE48
   106 M_C_DQ<44> @BASEBOARD_FAB2_LIB.BASEBOARD_FAB2(SCH_1):M_C_DQ(44)   I111 @BASEBOARD_FAB2_LIB.BASEBOARD_FAB2(SCH_1):PAGE48
   260 M_C_DQ<43> @BASEBOARD_FAB2_LIB.BASEBOARD_FAB2(SCH_1):M_C_DQ(43)   I111 @BASEBOARD_FAB2_LIB.BASEBOARD_FAB2(SCH_1):PAGE48
   115 M_C_DQ<42> @BASEBOARD_FAB2_LIB.BASEBOARD_FAB2(SCH_1):M_C_DQ(42)   I111 @BASEBOARD_FAB2_LIB.BASEBOARD_FAB2(SCH_1):PAGE48
   253 M_C_DQ<41> @BASEBOARD_FAB2_LIB.BASEBOARD_FAB2(SCH_1):M_C_DQ(41)   I111 @BASEBOARD_FAB2_LIB.BASEBOARD_FAB2(SCH_1):PAGE48
   108 M_C_DQ<40> @BASEBOARD_FAB2_LIB.BASEBOARD_FAB2(SCH_1):M_C_DQ(40)   I111 @BASEBOARD_FAB2_LIB.BASEBOARD_FAB2(SCH_1):PAGE48
   247 M_C_DQ<39> @BASEBOARD_FAB2_LIB.BASEBOARD_FAB2(SCH_1):M_C_DQ(39)   I111 @BASEBOARD_FAB2_LIB.BASEBOARD_FAB2(SCH_1):PAGE48
   102 M_C_DQ<38> @BASEBOARD_FAB2_LIB.BASEBOARD_FAB2(SCH_1):M_C_DQ(38)   I111 @BASEBOARD_FAB2_LIB.BASEBOARD_FAB2(SCH_1):PAGE48
   240 M_C_DQ<37> @BASEBOARD_FAB2_LIB.BASEBOARD_FAB2(SCH_1):M_C_DQ(37)   I111 @BASEBOARD_FAB2_LIB.BASEBOARD_FAB2(SCH_1):PAGE48
    95 M_C_DQ<36> @BASEBOARD_FAB2_LIB.BASEBOARD_FAB2(SCH_1):M_C_DQ(36)   I111 @BASEBOARD_FAB2_LIB.BASEBOARD_FAB2(SCH_1):PAGE48
   249 M_C_DQ<35> @BASEBOARD_FAB2_LIB.BASEBOARD_FAB2(SCH_1):M_C_DQ(35)   I111 @BASEBOARD_FAB2_LIB.BASEBOARD_FAB2(SCH_1):PAGE48
   104 M_C_DQ<34> @BASEBOARD_FAB2_LIB.BASEBOARD_FAB2(SCH_1):M_C_DQ(34)   I111 @BASEBOARD_FAB2_LIB.BASEBOARD_FAB2(SCH_1):PAGE48
   242 M_C_DQ<33> @BASEBOARD_FAB2_LIB.BASEBOARD_FAB2(SCH_1):M_C_DQ(33)   I111 @BASEBOARD_FAB2_LIB.BASEBOARD_FAB2(SCH_1):PAGE48
    97 M_C_DQ<32> @BASEBOARD_FAB2_LIB.BASEBOARD_FAB2(SCH_1):M_C_DQ(32)   I111 @BASEBOARD_FAB2_LIB.BASEBOARD_FAB2(SCH_1):PAGE48
   188 M_C_DQ<31> @BASEBOARD_FAB2_LIB.BASEBOARD_FAB2(SCH_1):M_C_DQ(31)   I111 @BASEBOARD_FAB2_LIB.BASEBOARD_FAB2(SCH_1):PAGE48
    43 M_C_DQ<30> @BASEBOARD_FAB2_LIB.BASEBOARD_FAB2(SCH_1):M_C_DQ(30)   I111 @BASEBOARD_FAB2_LIB.BASEBOARD_FAB2(SCH_1):PAGE48
   181 M_C_DQ<29> @BASEBOARD_FAB2_LIB.BASEBOARD_FAB2(SCH_1):M_C_DQ(29)   I111 @BASEBOARD_FAB2_LIB.BASEBOARD_FAB2(SCH_1):PAGE48
    36 M_C_DQ<28> @BASEBOARD_FAB2_LIB.BASEBOARD_FAB2(SCH_1):M_C_DQ(28)   I111 @BASEBOARD_FAB2_LIB.BASEBOARD_FAB2(SCH_1):PAGE48
   190 M_C_DQ<27> @BASEBOARD_FAB2_LIB.BASEBOARD_FAB2(SCH_1):M_C_DQ(27)   I111 @BASEBOARD_FAB2_LIB.BASEBOARD_FAB2(SCH_1):PAGE48
    45 M_C_DQ<26> @BASEBOARD_FAB2_LIB.BASEBOARD_FAB2(SCH_1):M_C_DQ(26)   I111 @BASEBOARD_FAB2_LIB.BASEBOARD_FAB2(SCH_1):PAGE48
   183 M_C_DQ<25> @BASEBOARD_FAB2_LIB.BASEBOARD_FAB2(SCH_1):M_C_DQ(25)   I111 @BASEBOARD_FAB2_LIB.BASEBOARD_FAB2(SCH_1):PAGE48
    38 M_C_DQ<24> @BASEBOARD_FAB2_LIB.BASEBOARD_FAB2(SCH_1):M_C_DQ(24)   I111 @BASEBOARD_FAB2_LIB.BASEBOARD_FAB2(SCH_1):PAGE48
   177 M_C_DQ<23> @BASEBOARD_FAB2_LIB.BASEBOARD_FAB2(SCH_1):M_C_DQ(23)   I111 @BASEBOARD_FAB2_LIB.BASEBOARD_FAB2(SCH_1):PAGE48
    32 M_C_DQ<22> @BASEBOARD_FAB2_LIB.BASEBOARD_FAB2(SCH_1):M_C_DQ(22)   I111 @BASEBOARD_FAB2_LIB.BASEBOARD_FAB2(SCH_1):PAGE48
   170 M_C_DQ<21> @BASEBOARD_FAB2_LIB.BASEBOARD_FAB2(SCH_1):M_C_DQ(21)   I111 @BASEBOARD_FAB2_LIB.BASEBOARD_FAB2(SCH_1):PAGE48
    25 M_C_DQ<20> @BASEBOARD_FAB2_LIB.BASEBOARD_FAB2(SCH_1):M_C_DQ(20)   I111 @BASEBOARD_FAB2_LIB.BASEBOARD_FAB2(SCH_1):PAGE48
   179 M_C_DQ<19> @BASEBOARD_FAB2_LIB.BASEBOARD_FAB2(SCH_1):M_C_DQ(19)   I111 @BASEBOARD_FAB2_LIB.BASEBOARD_FAB2(SCH_1):PAGE48
    34 M_C_DQ<18> @BASEBOARD_FAB2_LIB.BASEBOARD_FAB2(SCH_1):M_C_DQ(18)   I111 @BASEBOARD_FAB2_LIB.BASEBOARD_FAB2(SCH_1):PAGE48
   172 M_C_DQ<17> @BASEBOARD_FAB2_LIB.BASEBOARD_FAB2(SCH_1):M_C_DQ(17)   I111 @BASEBOARD_FAB2_LIB.BASEBOARD_FAB2(SCH_1):PAGE48
    27 M_C_DQ<16> @BASEBOARD_FAB2_LIB.BASEBOARD_FAB2(SCH_1):M_C_DQ(16)   I111 @BASEBOARD_FAB2_LIB.BASEBOARD_FAB2(SCH_1):PAGE48
   166 M_C_DQ<15> @BASEBOARD_FAB2_LIB.BASEBOARD_FAB2(SCH_1):M_C_DQ(15)   I111 @BASEBOARD_FAB2_LIB.BASEBOARD_FAB2(SCH_1):PAGE48
    21 M_C_DQ<14> @BASEBOARD_FAB2_LIB.BASEBOARD_FAB2(SCH_1):M_C_DQ(14)   I111 @BASEBOARD_FAB2_LIB.BASEBOARD_FAB2(SCH_1):PAGE48
   159 M_C_DQ<13> @BASEBOARD_FAB2_LIB.BASEBOARD_FAB2(SCH_1):M_C_DQ(13)   I111 @BASEBOARD_FAB2_LIB.BASEBOARD_FAB2(SCH_1):PAGE48
    14 M_C_DQ<12> @BASEBOARD_FAB2_LIB.BASEBOARD_FAB2(SCH_1):M_C_DQ(12)   I111 @BASEBOARD_FAB2_LIB.BASEBOARD_FAB2(SCH_1):PAGE48
   168 M_C_DQ<11> @BASEBOARD_FAB2_LIB.BASEBOARD_FAB2(SCH_1):M_C_DQ(11)   I111 @BASEBOARD_FAB2_LIB.BASEBOARD_FAB2(SCH_1):PAGE48
    23 M_C_DQ<10> @BASEBOARD_FAB2_LIB.BASEBOARD_FAB2(SCH_1):M_C_DQ(10)   I111 @BASEBOARD_FAB2_LIB.BASEBOARD_FAB2(SCH_1):PAGE48
   161 M_C_DQ<9> @BASEBOARD_FAB2_LIB.BASEBOARD_FAB2(SCH_1):M_C_DQ(9)   I111 @BASEBOARD_FAB2_LIB.BASEBOARD_FAB2(SCH_1):PAGE48
    16 M_C_DQ<8> @BASEBOARD_FAB2_LIB.BASEBOARD_FAB2(SCH_1):M_C_DQ(8)   I111 @BASEBOARD_FAB2_LIB.BASEBOARD_FAB2(SCH_1):PAGE48
   155 M_C_DQ<7> @BASEBOARD_FAB2_LIB.BASEBOARD_FAB2(SCH_1):M_C_DQ(7)   I111 @BASEBOARD_FAB2_LIB.BASEBOARD_FAB2(SCH_1):PAGE48
    10 M_C_DQ<6> @BASEBOARD_FAB2_LIB.BASEBOARD_FAB2(SCH_1):M_C_DQ(6)   I111 @BASEBOARD_FAB2_LIB.BASEBOARD_FAB2(SCH_1):PAGE48
   148 M_C_DQ<5> @BASEBOARD_FAB2_LIB.BASEBOARD_FAB2(SCH_1):M_C_DQ(5)   I111 @BASEBOARD_FAB2_LIB.BASEBOARD_FAB2(SCH_1):PAGE48
     3 M_C_DQ<4> @BASEBOARD_FAB2_LIB.BASEBOARD_FAB2(SCH_1):M_C_DQ(4)   I111 @BASEBOARD_FAB2_LIB.BASEBOARD_FAB2(SCH_1):PAGE48
   157 M_C_DQ<3> @BASEBOARD_FAB2_LIB.BASEBOARD_FAB2(SCH_1):M_C_DQ(3)   I111 @BASEBOARD_FAB2_LIB.BASEBOARD_FAB2(SCH_1):PAGE48
    12 M_C_DQ<2> @BASEBOARD_FAB2_LIB.BASEBOARD_FAB2(SCH_1):M_C_DQ(2)   I111 @BASEBOARD_FAB2_LIB.BASEBOARD_FAB2(SCH_1):PAGE48
   150 M_C_DQ<1> @BASEBOARD_FAB2_LIB.BASEBOARD_FAB2(SCH_1):M_C_DQ(1)   I111 @BASEBOARD_FAB2_LIB.BASEBOARD_FAB2(SCH_1):PAGE48
     5 M_C_DQ<0> @BASEBOARD_FAB2_LIB.BASEBOARD_FAB2(SCH_1):M_C_DQ(0)   I111 @BASEBOARD_FAB2_LIB.BASEBOARD_FAB2(SCH_1):PAGE48
    78 FM_DIMM_EVENT_COD_N @BASEBOARD_FAB2_LIB.BASEBOARD_FAB2(SCH_1):FM_DIMM_EVENT_COD_N   I111 @BASEBOARD_FAB2_LIB.BASEBOARD_FAB2(SCH_1):PAGE48
    91 M_C_ODT<3> @BASEBOARD_FAB2_LIB.BASEBOARD_FAB2(SCH_1):M_C_ODT(3)   I111 @BASEBOARD_FAB2_LIB.BASEBOARD_FAB2(SCH_1):PAGE48
    87 M_C_ODT<2> @BASEBOARD_FAB2_LIB.BASEBOARD_FAB2(SCH_1):M_C_ODT(2)   I111 @BASEBOARD_FAB2_LIB.BASEBOARD_FAB2(SCH_1):PAGE48
   222 M_C_PAR @BASEBOARD_FAB2_LIB.BASEBOARD_FAB2(SCH_1):M_C_PAR   I111 @BASEBOARD_FAB2_LIB.BASEBOARD_FAB2(SCH_1):PAGE48
    58 M_ABC_RST_N @BASEBOARD_FAB2_LIB.BASEBOARD_FAB2(SCH_1):M_ABC_RST_N   I111 @BASEBOARD_FAB2_LIB.BASEBOARD_FAB2(SCH_1):PAGE48
   144 TP_CH_C_DIMM_C1_RFU_2 @BASEBOARD_FAB2_LIB.BASEBOARD_FAB2(SCH_1):TP_CH_C_DIMM_C1_RFU_2   I111 @BASEBOARD_FAB2_LIB.BASEBOARD_FAB2(SCH_1):PAGE48
   227 TP_CH_C_DIMM_C1_RFU_1 @BASEBOARD_FAB2_LIB.BASEBOARD_FAB2(SCH_1):TP_CH_C_DIMM_C1_RFU_1   I111 @BASEBOARD_FAB2_LIB.BASEBOARD_FAB2(SCH_1):PAGE48
   205 TP_CH_C_DIMM_C1_RFU_0 @BASEBOARD_FAB2_LIB.BASEBOARD_FAB2(SCH_1):TP_CH_C_DIMM_C1_RFU_0   I111 @BASEBOARD_FAB2_LIB.BASEBOARD_FAB2(SCH_1):PAGE48
    84 M_C_CS_N<4> @BASEBOARD_FAB2_LIB.BASEBOARD_FAB2(SCH_1):M_C_CS_N(4)   I111 @BASEBOARD_FAB2_LIB.BASEBOARD_FAB2(SCH_1):PAGE48
    89 M_C_CS_N<5> @BASEBOARD_FAB2_LIB.BASEBOARD_FAB2(SCH_1):M_C_CS_N(5)   I111 @BASEBOARD_FAB2_LIB.BASEBOARD_FAB2(SCH_1):PAGE48
    93 M_C_CS_N<6> @BASEBOARD_FAB2_LIB.BASEBOARD_FAB2(SCH_1):M_C_CS_N(6)   I111 @BASEBOARD_FAB2_LIB.BASEBOARD_FAB2(SCH_1):PAGE48
   237 M_C_CS_N<7> @BASEBOARD_FAB2_LIB.BASEBOARD_FAB2(SCH_1):M_C_CS_N(7)   I111 @BASEBOARD_FAB2_LIB.BASEBOARD_FAB2(SCH_1):PAGE48
   238 PVPP_ABC @BASEBOARD_FAB2_LIB.BASEBOARD_FAB2(SCH_1):PVPP_ABC   I111 @BASEBOARD_FAB2_LIB.BASEBOARD_FAB2(SCH_1):PAGE48
   140    GND @BASEBOARD_FAB2_LIB.BASEBOARD_FAB2(SCH_1):GND   I111 @BASEBOARD_FAB2_LIB.BASEBOARD_FAB2(SCH_1):PAGE48
   139 PVPP_ABC @BASEBOARD_FAB2_LIB.BASEBOARD_FAB2(SCH_1):PVPP_ABC   I111 @BASEBOARD_FAB2_LIB.BASEBOARD_FAB2(SCH_1):PAGE48
   230 FM_ADR_COMPLETE_ABC_N @BASEBOARD_FAB2_LIB.BASEBOARD_FAB2(SCH_1):FM_ADR_COMPLETE_ABC_N   I111 @BASEBOARD_FAB2_LIB.BASEBOARD_FAB2(SCH_1):PAGE48
   141 SMB_DDR_ABC_VPP_SCL @BASEBOARD_FAB2_LIB.BASEBOARD_FAB2(SCH_1):SMB_DDR_ABC_VPP_SCL   I111 @BASEBOARD_FAB2_LIB.BASEBOARD_FAB2(SCH_1):PAGE48
   285 SMB_DDR_ABC_VPP_SDA @BASEBOARD_FAB2_LIB.BASEBOARD_FAB2(SCH_1):SMB_DDR_ABC_VPP_SDA   I111 @BASEBOARD_FAB2_LIB.BASEBOARD_FAB2(SCH_1):PAGE48
   284 PVPP_ABC @BASEBOARD_FAB2_LIB.BASEBOARD_FAB2(SCH_1):PVPP_ABC   I111 @BASEBOARD_FAB2_LIB.BASEBOARD_FAB2(SCH_1):PAGE48
   146 M_C_VREF @BASEBOARD_FAB2_LIB.BASEBOARD_FAB2(SCH_1):M_C_VREF   I111 @BASEBOARD_FAB2_LIB.BASEBOARD_FAB2(SCH_1):PAGE48
   152 M_C_DQS_DN<0> @BASEBOARD_FAB2_LIB.BASEBOARD_FAB2(SCH_1):M_C_DQS_DN(0)    I61 @BASEBOARD_FAB2_LIB.BASEBOARD_FAB2(SCH_1):PAGE48
   153 M_C_DQS_DP<0> @BASEBOARD_FAB2_LIB.BASEBOARD_FAB2(SCH_1):M_C_DQS_DP(0)    I61 @BASEBOARD_FAB2_LIB.BASEBOARD_FAB2(SCH_1):PAGE48
    19 M_C_DQS_DN<10> @BASEBOARD_FAB2_LIB.BASEBOARD_FAB2(SCH_1):M_C_DQS_DN(10)    I61 @BASEBOARD_FAB2_LIB.BASEBOARD_FAB2(SCH_1):PAGE48
    18 M_C_DQS_DP<10> @BASEBOARD_FAB2_LIB.BASEBOARD_FAB2(SCH_1):M_C_DQS_DP(10)    I61 @BASEBOARD_FAB2_LIB.BASEBOARD_FAB2(SCH_1):PAGE48
    30 M_C_DQS_DN<11> @BASEBOARD_FAB2_LIB.BASEBOARD_FAB2(SCH_1):M_C_DQS_DN(11)    I61 @BASEBOARD_FAB2_LIB.BASEBOARD_FAB2(SCH_1):PAGE48
    29 M_C_DQS_DP<11> @BASEBOARD_FAB2_LIB.BASEBOARD_FAB2(SCH_1):M_C_DQS_DP(11)    I61 @BASEBOARD_FAB2_LIB.BASEBOARD_FAB2(SCH_1):PAGE48
    41 M_C_DQS_DN<12> @BASEBOARD_FAB2_LIB.BASEBOARD_FAB2(SCH_1):M_C_DQS_DN(12)    I61 @BASEBOARD_FAB2_LIB.BASEBOARD_FAB2(SCH_1):PAGE48
    40 M_C_DQS_DP<12> @BASEBOARD_FAB2_LIB.BASEBOARD_FAB2(SCH_1):M_C_DQS_DP(12)    I61 @BASEBOARD_FAB2_LIB.BASEBOARD_FAB2(SCH_1):PAGE48
   100 M_C_DQS_DN<13> @BASEBOARD_FAB2_LIB.BASEBOARD_FAB2(SCH_1):M_C_DQS_DN(13)    I61 @BASEBOARD_FAB2_LIB.BASEBOARD_FAB2(SCH_1):PAGE48
    99 M_C_DQS_DP<13> @BASEBOARD_FAB2_LIB.BASEBOARD_FAB2(SCH_1):M_C_DQS_DP(13)    I61 @BASEBOARD_FAB2_LIB.BASEBOARD_FAB2(SCH_1):PAGE48
   111 M_C_DQS_DN<14> @BASEBOARD_FAB2_LIB.BASEBOARD_FAB2(SCH_1):M_C_DQS_DN(14)    I61 @BASEBOARD_FAB2_LIB.BASEBOARD_FAB2(SCH_1):PAGE48
   110 M_C_DQS_DP<14> @BASEBOARD_FAB2_LIB.BASEBOARD_FAB2(SCH_1):M_C_DQS_DP(14)    I61 @BASEBOARD_FAB2_LIB.BASEBOARD_FAB2(SCH_1):PAGE48
   122 M_C_DQS_DN<15> @BASEBOARD_FAB2_LIB.BASEBOARD_FAB2(SCH_1):M_C_DQS_DN(15)    I61 @BASEBOARD_FAB2_LIB.BASEBOARD_FAB2(SCH_1):PAGE48
   121 M_C_DQS_DP<15> @BASEBOARD_FAB2_LIB.BASEBOARD_FAB2(SCH_1):M_C_DQS_DP(15)    I61 @BASEBOARD_FAB2_LIB.BASEBOARD_FAB2(SCH_1):PAGE48
   133 M_C_DQS_DN<16> @BASEBOARD_FAB2_LIB.BASEBOARD_FAB2(SCH_1):M_C_DQS_DN(16)    I61 @BASEBOARD_FAB2_LIB.BASEBOARD_FAB2(SCH_1):PAGE48
   132 M_C_DQS_DP<16> @BASEBOARD_FAB2_LIB.BASEBOARD_FAB2(SCH_1):M_C_DQS_DP(16)    I61 @BASEBOARD_FAB2_LIB.BASEBOARD_FAB2(SCH_1):PAGE48
    52 M_C_DQS_DN<17> @BASEBOARD_FAB2_LIB.BASEBOARD_FAB2(SCH_1):M_C_DQS_DN(17)    I61 @BASEBOARD_FAB2_LIB.BASEBOARD_FAB2(SCH_1):PAGE48
    51 M_C_DQS_DP<17> @BASEBOARD_FAB2_LIB.BASEBOARD_FAB2(SCH_1):M_C_DQS_DP(17)    I61 @BASEBOARD_FAB2_LIB.BASEBOARD_FAB2(SCH_1):PAGE48
   163 M_C_DQS_DN<1> @BASEBOARD_FAB2_LIB.BASEBOARD_FAB2(SCH_1):M_C_DQS_DN(1)    I61 @BASEBOARD_FAB2_LIB.BASEBOARD_FAB2(SCH_1):PAGE48
   164 M_C_DQS_DP<1> @BASEBOARD_FAB2_LIB.BASEBOARD_FAB2(SCH_1):M_C_DQS_DP(1)    I61 @BASEBOARD_FAB2_LIB.BASEBOARD_FAB2(SCH_1):PAGE48
   174 M_C_DQS_DN<2> @BASEBOARD_FAB2_LIB.BASEBOARD_FAB2(SCH_1):M_C_DQS_DN(2)    I61 @BASEBOARD_FAB2_LIB.BASEBOARD_FAB2(SCH_1):PAGE48
   175 M_C_DQS_DP<2> @BASEBOARD_FAB2_LIB.BASEBOARD_FAB2(SCH_1):M_C_DQS_DP(2)    I61 @BASEBOARD_FAB2_LIB.BASEBOARD_FAB2(SCH_1):PAGE48
   185 M_C_DQS_DN<3> @BASEBOARD_FAB2_LIB.BASEBOARD_FAB2(SCH_1):M_C_DQS_DN(3)    I61 @BASEBOARD_FAB2_LIB.BASEBOARD_FAB2(SCH_1):PAGE48
   186 M_C_DQS_DP<3> @BASEBOARD_FAB2_LIB.BASEBOARD_FAB2(SCH_1):M_C_DQS_DP(3)    I61 @BASEBOARD_FAB2_LIB.BASEBOARD_FAB2(SCH_1):PAGE48
   244 M_C_DQS_DN<4> @BASEBOARD_FAB2_LIB.BASEBOARD_FAB2(SCH_1):M_C_DQS_DN(4)    I61 @BASEBOARD_FAB2_LIB.BASEBOARD_FAB2(SCH_1):PAGE48
   245 M_C_DQS_DP<4> @BASEBOARD_FAB2_LIB.BASEBOARD_FAB2(SCH_1):M_C_DQS_DP(4)    I61 @BASEBOARD_FAB2_LIB.BASEBOARD_FAB2(SCH_1):PAGE48
   255 M_C_DQS_DN<5> @BASEBOARD_FAB2_LIB.BASEBOARD_FAB2(SCH_1):M_C_DQS_DN(5)    I61 @BASEBOARD_FAB2_LIB.BASEBOARD_FAB2(SCH_1):PAGE48
   256 M_C_DQS_DP<5> @BASEBOARD_FAB2_LIB.BASEBOARD_FAB2(SCH_1):M_C_DQS_DP(5)    I61 @BASEBOARD_FAB2_LIB.BASEBOARD_FAB2(SCH_1):PAGE48
   266 M_C_DQS_DN<6> @BASEBOARD_FAB2_LIB.BASEBOARD_FAB2(SCH_1):M_C_DQS_DN(6)    I61 @BASEBOARD_FAB2_LIB.BASEBOARD_FAB2(SCH_1):PAGE48
   267 M_C_DQS_DP<6> @BASEBOARD_FAB2_LIB.BASEBOARD_FAB2(SCH_1):M_C_DQS_DP(6)    I61 @BASEBOARD_FAB2_LIB.BASEBOARD_FAB2(SCH_1):PAGE48
   277 M_C_DQS_DN<7> @BASEBOARD_FAB2_LIB.BASEBOARD_FAB2(SCH_1):M_C_DQS_DN(7)    I61 @BASEBOARD_FAB2_LIB.BASEBOARD_FAB2(SCH_1):PAGE48
   278 M_C_DQS_DP<7> @BASEBOARD_FAB2_LIB.BASEBOARD_FAB2(SCH_1):M_C_DQS_DP(7)    I61 @BASEBOARD_FAB2_LIB.BASEBOARD_FAB2(SCH_1):PAGE48
   196 M_C_DQS_DN<8> @BASEBOARD_FAB2_LIB.BASEBOARD_FAB2(SCH_1):M_C_DQS_DN(8)    I61 @BASEBOARD_FAB2_LIB.BASEBOARD_FAB2(SCH_1):PAGE48
   197 M_C_DQS_DP<8> @BASEBOARD_FAB2_LIB.BASEBOARD_FAB2(SCH_1):M_C_DQS_DP(8)    I61 @BASEBOARD_FAB2_LIB.BASEBOARD_FAB2(SCH_1):PAGE48
     8 M_C_DQS_DN<9> @BASEBOARD_FAB2_LIB.BASEBOARD_FAB2(SCH_1):M_C_DQS_DN(9)    I61 @BASEBOARD_FAB2_LIB.BASEBOARD_FAB2(SCH_1):PAGE48
     7 M_C_DQS_DP<9> @BASEBOARD_FAB2_LIB.BASEBOARD_FAB2(SCH_1):M_C_DQS_DP(9)    I61 @BASEBOARD_FAB2_LIB.BASEBOARD_FAB2(SCH_1):PAGE48
     2    GND @BASEBOARD_FAB2_LIB.BASEBOARD_FAB2(SCH_1):GND    I43 @BASEBOARD_FAB2_LIB.BASEBOARD_FAB2(SCH_1):PAGE48
     4    GND @BASEBOARD_FAB2_LIB.BASEBOARD_FAB2(SCH_1):GND    I43 @BASEBOARD_FAB2_LIB.BASEBOARD_FAB2(SCH_1):PAGE48
     6    GND @BASEBOARD_FAB2_LIB.BASEBOARD_FAB2(SCH_1):GND    I43 @BASEBOARD_FAB2_LIB.BASEBOARD_FAB2(SCH_1):PAGE48
     9    GND @BASEBOARD_FAB2_LIB.BASEBOARD_FAB2(SCH_1):GND    I43 @BASEBOARD_FAB2_LIB.BASEBOARD_FAB2(SCH_1):PAGE48
    11    GND @BASEBOARD_FAB2_LIB.BASEBOARD_FAB2(SCH_1):GND    I43 @BASEBOARD_FAB2_LIB.BASEBOARD_FAB2(SCH_1):PAGE48
    13    GND @BASEBOARD_FAB2_LIB.BASEBOARD_FAB2(SCH_1):GND    I43 @BASEBOARD_FAB2_LIB.BASEBOARD_FAB2(SCH_1):PAGE48
    15    GND @BASEBOARD_FAB2_LIB.BASEBOARD_FAB2(SCH_1):GND    I43 @BASEBOARD_FAB2_LIB.BASEBOARD_FAB2(SCH_1):PAGE48
    17    GND @BASEBOARD_FAB2_LIB.BASEBOARD_FAB2(SCH_1):GND    I43 @BASEBOARD_FAB2_LIB.BASEBOARD_FAB2(SCH_1):PAGE48
    20    GND @BASEBOARD_FAB2_LIB.BASEBOARD_FAB2(SCH_1):GND    I43 @BASEBOARD_FAB2_LIB.BASEBOARD_FAB2(SCH_1):PAGE48
    22    GND @BASEBOARD_FAB2_LIB.BASEBOARD_FAB2(SCH_1):GND    I43 @BASEBOARD_FAB2_LIB.BASEBOARD_FAB2(SCH_1):PAGE48
    24    GND @BASEBOARD_FAB2_LIB.BASEBOARD_FAB2(SCH_1):GND    I43 @BASEBOARD_FAB2_LIB.BASEBOARD_FAB2(SCH_1):PAGE48
    26    GND @BASEBOARD_FAB2_LIB.BASEBOARD_FAB2(SCH_1):GND    I43 @BASEBOARD_FAB2_LIB.BASEBOARD_FAB2(SCH_1):PAGE48
    28    GND @BASEBOARD_FAB2_LIB.BASEBOARD_FAB2(SCH_1):GND    I43 @BASEBOARD_FAB2_LIB.BASEBOARD_FAB2(SCH_1):PAGE48
    31    GND @BASEBOARD_FAB2_LIB.BASEBOARD_FAB2(SCH_1):GND    I43 @BASEBOARD_FAB2_LIB.BASEBOARD_FAB2(SCH_1):PAGE48
    33    GND @BASEBOARD_FAB2_LIB.BASEBOARD_FAB2(SCH_1):GND    I43 @BASEBOARD_FAB2_LIB.BASEBOARD_FAB2(SCH_1):PAGE48
    35    GND @BASEBOARD_FAB2_LIB.BASEBOARD_FAB2(SCH_1):GND    I43 @BASEBOARD_FAB2_LIB.BASEBOARD_FAB2(SCH_1):PAGE48
    37    GND @BASEBOARD_FAB2_LIB.BASEBOARD_FAB2(SCH_1):GND    I43 @BASEBOARD_FAB2_LIB.BASEBOARD_FAB2(SCH_1):PAGE48
    39    GND @BASEBOARD_FAB2_LIB.BASEBOARD_FAB2(SCH_1):GND    I43 @BASEBOARD_FAB2_LIB.BASEBOARD_FAB2(SCH_1):PAGE48
    42    GND @BASEBOARD_FAB2_LIB.BASEBOARD_FAB2(SCH_1):GND    I43 @BASEBOARD_FAB2_LIB.BASEBOARD_FAB2(SCH_1):PAGE48
    44    GND @BASEBOARD_FAB2_LIB.BASEBOARD_FAB2(SCH_1):GND    I43 @BASEBOARD_FAB2_LIB.BASEBOARD_FAB2(SCH_1):PAGE48
    46    GND @BASEBOARD_FAB2_LIB.BASEBOARD_FAB2(SCH_1):GND    I43 @BASEBOARD_FAB2_LIB.BASEBOARD_FAB2(SCH_1):PAGE48
    48    GND @BASEBOARD_FAB2_LIB.BASEBOARD_FAB2(SCH_1):GND    I43 @BASEBOARD_FAB2_LIB.BASEBOARD_FAB2(SCH_1):PAGE48
    50    GND @BASEBOARD_FAB2_LIB.BASEBOARD_FAB2(SCH_1):GND    I43 @BASEBOARD_FAB2_LIB.BASEBOARD_FAB2(SCH_1):PAGE48
    53    GND @BASEBOARD_FAB2_LIB.BASEBOARD_FAB2(SCH_1):GND    I43 @BASEBOARD_FAB2_LIB.BASEBOARD_FAB2(SCH_1):PAGE48
    55    GND @BASEBOARD_FAB2_LIB.BASEBOARD_FAB2(SCH_1):GND    I43 @BASEBOARD_FAB2_LIB.BASEBOARD_FAB2(SCH_1):PAGE48
    57    GND @BASEBOARD_FAB2_LIB.BASEBOARD_FAB2(SCH_1):GND    I43 @BASEBOARD_FAB2_LIB.BASEBOARD_FAB2(SCH_1):PAGE48
    94    GND @BASEBOARD_FAB2_LIB.BASEBOARD_FAB2(SCH_1):GND    I43 @BASEBOARD_FAB2_LIB.BASEBOARD_FAB2(SCH_1):PAGE48
    96    GND @BASEBOARD_FAB2_LIB.BASEBOARD_FAB2(SCH_1):GND    I43 @BASEBOARD_FAB2_LIB.BASEBOARD_FAB2(SCH_1):PAGE48
    98    GND @BASEBOARD_FAB2_LIB.BASEBOARD_FAB2(SCH_1):GND    I43 @BASEBOARD_FAB2_LIB.BASEBOARD_FAB2(SCH_1):PAGE48
   101    GND @BASEBOARD_FAB2_LIB.BASEBOARD_FAB2(SCH_1):GND    I43 @BASEBOARD_FAB2_LIB.BASEBOARD_FAB2(SCH_1):PAGE48
   103    GND @BASEBOARD_FAB2_LIB.BASEBOARD_FAB2(SCH_1):GND    I43 @BASEBOARD_FAB2_LIB.BASEBOARD_FAB2(SCH_1):PAGE48
   105    GND @BASEBOARD_FAB2_LIB.BASEBOARD_FAB2(SCH_1):GND    I43 @BASEBOARD_FAB2_LIB.BASEBOARD_FAB2(SCH_1):PAGE48
   107    GND @BASEBOARD_FAB2_LIB.BASEBOARD_FAB2(SCH_1):GND    I43 @BASEBOARD_FAB2_LIB.BASEBOARD_FAB2(SCH_1):PAGE48
   109    GND @BASEBOARD_FAB2_LIB.BASEBOARD_FAB2(SCH_1):GND    I43 @BASEBOARD_FAB2_LIB.BASEBOARD_FAB2(SCH_1):PAGE48
   112    GND @BASEBOARD_FAB2_LIB.BASEBOARD_FAB2(SCH_1):GND    I43 @BASEBOARD_FAB2_LIB.BASEBOARD_FAB2(SCH_1):PAGE48
   114    GND @BASEBOARD_FAB2_LIB.BASEBOARD_FAB2(SCH_1):GND    I43 @BASEBOARD_FAB2_LIB.BASEBOARD_FAB2(SCH_1):PAGE48
   116    GND @BASEBOARD_FAB2_LIB.BASEBOARD_FAB2(SCH_1):GND    I43 @BASEBOARD_FAB2_LIB.BASEBOARD_FAB2(SCH_1):PAGE48
   118    GND @BASEBOARD_FAB2_LIB.BASEBOARD_FAB2(SCH_1):GND    I43 @BASEBOARD_FAB2_LIB.BASEBOARD_FAB2(SCH_1):PAGE48
   120    GND @BASEBOARD_FAB2_LIB.BASEBOARD_FAB2(SCH_1):GND    I43 @BASEBOARD_FAB2_LIB.BASEBOARD_FAB2(SCH_1):PAGE48
   123    GND @BASEBOARD_FAB2_LIB.BASEBOARD_FAB2(SCH_1):GND    I43 @BASEBOARD_FAB2_LIB.BASEBOARD_FAB2(SCH_1):PAGE48
   125    GND @BASEBOARD_FAB2_LIB.BASEBOARD_FAB2(SCH_1):GND    I43 @BASEBOARD_FAB2_LIB.BASEBOARD_FAB2(SCH_1):PAGE48
   127    GND @BASEBOARD_FAB2_LIB.BASEBOARD_FAB2(SCH_1):GND    I43 @BASEBOARD_FAB2_LIB.BASEBOARD_FAB2(SCH_1):PAGE48
   129    GND @BASEBOARD_FAB2_LIB.BASEBOARD_FAB2(SCH_1):GND    I43 @BASEBOARD_FAB2_LIB.BASEBOARD_FAB2(SCH_1):PAGE48
   131    GND @BASEBOARD_FAB2_LIB.BASEBOARD_FAB2(SCH_1):GND    I43 @BASEBOARD_FAB2_LIB.BASEBOARD_FAB2(SCH_1):PAGE48
   134    GND @BASEBOARD_FAB2_LIB.BASEBOARD_FAB2(SCH_1):GND    I43 @BASEBOARD_FAB2_LIB.BASEBOARD_FAB2(SCH_1):PAGE48
   136    GND @BASEBOARD_FAB2_LIB.BASEBOARD_FAB2(SCH_1):GND    I43 @BASEBOARD_FAB2_LIB.BASEBOARD_FAB2(SCH_1):PAGE48
   138    GND @BASEBOARD_FAB2_LIB.BASEBOARD_FAB2(SCH_1):GND    I43 @BASEBOARD_FAB2_LIB.BASEBOARD_FAB2(SCH_1):PAGE48
   147    GND @BASEBOARD_FAB2_LIB.BASEBOARD_FAB2(SCH_1):GND    I43 @BASEBOARD_FAB2_LIB.BASEBOARD_FAB2(SCH_1):PAGE48
   149    GND @BASEBOARD_FAB2_LIB.BASEBOARD_FAB2(SCH_1):GND    I43 @BASEBOARD_FAB2_LIB.BASEBOARD_FAB2(SCH_1):PAGE48
   151    GND @BASEBOARD_FAB2_LIB.BASEBOARD_FAB2(SCH_1):GND    I43 @BASEBOARD_FAB2_LIB.BASEBOARD_FAB2(SCH_1):PAGE48
   154    GND @BASEBOARD_FAB2_LIB.BASEBOARD_FAB2(SCH_1):GND    I43 @BASEBOARD_FAB2_LIB.BASEBOARD_FAB2(SCH_1):PAGE48
   156    GND @BASEBOARD_FAB2_LIB.BASEBOARD_FAB2(SCH_1):GND    I43 @BASEBOARD_FAB2_LIB.BASEBOARD_FAB2(SCH_1):PAGE48
   158    GND @BASEBOARD_FAB2_LIB.BASEBOARD_FAB2(SCH_1):GND    I43 @BASEBOARD_FAB2_LIB.BASEBOARD_FAB2(SCH_1):PAGE48
   160    GND @BASEBOARD_FAB2_LIB.BASEBOARD_FAB2(SCH_1):GND    I43 @BASEBOARD_FAB2_LIB.BASEBOARD_FAB2(SCH_1):PAGE48
   162    GND @BASEBOARD_FAB2_LIB.BASEBOARD_FAB2(SCH_1):GND    I43 @BASEBOARD_FAB2_LIB.BASEBOARD_FAB2(SCH_1):PAGE48
   165    GND @BASEBOARD_FAB2_LIB.BASEBOARD_FAB2(SCH_1):GND    I43 @BASEBOARD_FAB2_LIB.BASEBOARD_FAB2(SCH_1):PAGE48
   167    GND @BASEBOARD_FAB2_LIB.BASEBOARD_FAB2(SCH_1):GND    I43 @BASEBOARD_FAB2_LIB.BASEBOARD_FAB2(SCH_1):PAGE48
   169    GND @BASEBOARD_FAB2_LIB.BASEBOARD_FAB2(SCH_1):GND    I43 @BASEBOARD_FAB2_LIB.BASEBOARD_FAB2(SCH_1):PAGE48
   171    GND @BASEBOARD_FAB2_LIB.BASEBOARD_FAB2(SCH_1):GND    I43 @BASEBOARD_FAB2_LIB.BASEBOARD_FAB2(SCH_1):PAGE48
   173    GND @BASEBOARD_FAB2_LIB.BASEBOARD_FAB2(SCH_1):GND    I43 @BASEBOARD_FAB2_LIB.BASEBOARD_FAB2(SCH_1):PAGE48
   176    GND @BASEBOARD_FAB2_LIB.BASEBOARD_FAB2(SCH_1):GND    I43 @BASEBOARD_FAB2_LIB.BASEBOARD_FAB2(SCH_1):PAGE48
   178    GND @BASEBOARD_FAB2_LIB.BASEBOARD_FAB2(SCH_1):GND    I43 @BASEBOARD_FAB2_LIB.BASEBOARD_FAB2(SCH_1):PAGE48
   180    GND @BASEBOARD_FAB2_LIB.BASEBOARD_FAB2(SCH_1):GND    I43 @BASEBOARD_FAB2_LIB.BASEBOARD_FAB2(SCH_1):PAGE48
   182    GND @BASEBOARD_FAB2_LIB.BASEBOARD_FAB2(SCH_1):GND    I43 @BASEBOARD_FAB2_LIB.BASEBOARD_FAB2(SCH_1):PAGE48
   184    GND @BASEBOARD_FAB2_LIB.BASEBOARD_FAB2(SCH_1):GND    I43 @BASEBOARD_FAB2_LIB.BASEBOARD_FAB2(SCH_1):PAGE48
   187    GND @BASEBOARD_FAB2_LIB.BASEBOARD_FAB2(SCH_1):GND    I43 @BASEBOARD_FAB2_LIB.BASEBOARD_FAB2(SCH_1):PAGE48
   189    GND @BASEBOARD_FAB2_LIB.BASEBOARD_FAB2(SCH_1):GND    I43 @BASEBOARD_FAB2_LIB.BASEBOARD_FAB2(SCH_1):PAGE48
   191    GND @BASEBOARD_FAB2_LIB.BASEBOARD_FAB2(SCH_1):GND    I43 @BASEBOARD_FAB2_LIB.BASEBOARD_FAB2(SCH_1):PAGE48
   193    GND @BASEBOARD_FAB2_LIB.BASEBOARD_FAB2(SCH_1):GND    I43 @BASEBOARD_FAB2_LIB.BASEBOARD_FAB2(SCH_1):PAGE48
   195    GND @BASEBOARD_FAB2_LIB.BASEBOARD_FAB2(SCH_1):GND    I43 @BASEBOARD_FAB2_LIB.BASEBOARD_FAB2(SCH_1):PAGE48
   198    GND @BASEBOARD_FAB2_LIB.BASEBOARD_FAB2(SCH_1):GND    I43 @BASEBOARD_FAB2_LIB.BASEBOARD_FAB2(SCH_1):PAGE48
   200    GND @BASEBOARD_FAB2_LIB.BASEBOARD_FAB2(SCH_1):GND    I43 @BASEBOARD_FAB2_LIB.BASEBOARD_FAB2(SCH_1):PAGE48
   202    GND @BASEBOARD_FAB2_LIB.BASEBOARD_FAB2(SCH_1):GND    I43 @BASEBOARD_FAB2_LIB.BASEBOARD_FAB2(SCH_1):PAGE48
   239    GND @BASEBOARD_FAB2_LIB.BASEBOARD_FAB2(SCH_1):GND    I43 @BASEBOARD_FAB2_LIB.BASEBOARD_FAB2(SCH_1):PAGE48
   241    GND @BASEBOARD_FAB2_LIB.BASEBOARD_FAB2(SCH_1):GND    I43 @BASEBOARD_FAB2_LIB.BASEBOARD_FAB2(SCH_1):PAGE48
   243    GND @BASEBOARD_FAB2_LIB.BASEBOARD_FAB2(SCH_1):GND    I43 @BASEBOARD_FAB2_LIB.BASEBOARD_FAB2(SCH_1):PAGE48
   246    GND @BASEBOARD_FAB2_LIB.BASEBOARD_FAB2(SCH_1):GND    I43 @BASEBOARD_FAB2_LIB.BASEBOARD_FAB2(SCH_1):PAGE48
   248    GND @BASEBOARD_FAB2_LIB.BASEBOARD_FAB2(SCH_1):GND    I43 @BASEBOARD_FAB2_LIB.BASEBOARD_FAB2(SCH_1):PAGE48
   250    GND @BASEBOARD_FAB2_LIB.BASEBOARD_FAB2(SCH_1):GND    I43 @BASEBOARD_FAB2_LIB.BASEBOARD_FAB2(SCH_1):PAGE48
   252    GND @BASEBOARD_FAB2_LIB.BASEBOARD_FAB2(SCH_1):GND    I43 @BASEBOARD_FAB2_LIB.BASEBOARD_FAB2(SCH_1):PAGE48
   254    GND @BASEBOARD_FAB2_LIB.BASEBOARD_FAB2(SCH_1):GND    I43 @BASEBOARD_FAB2_LIB.BASEBOARD_FAB2(SCH_1):PAGE48
   257    GND @BASEBOARD_FAB2_LIB.BASEBOARD_FAB2(SCH_1):GND    I43 @BASEBOARD_FAB2_LIB.BASEBOARD_FAB2(SCH_1):PAGE48
   259    GND @BASEBOARD_FAB2_LIB.BASEBOARD_FAB2(SCH_1):GND    I43 @BASEBOARD_FAB2_LIB.BASEBOARD_FAB2(SCH_1):PAGE48
   261    GND @BASEBOARD_FAB2_LIB.BASEBOARD_FAB2(SCH_1):GND    I43 @BASEBOARD_FAB2_LIB.BASEBOARD_FAB2(SCH_1):PAGE48
   263    GND @BASEBOARD_FAB2_LIB.BASEBOARD_FAB2(SCH_1):GND    I43 @BASEBOARD_FAB2_LIB.BASEBOARD_FAB2(SCH_1):PAGE48
   265    GND @BASEBOARD_FAB2_LIB.BASEBOARD_FAB2(SCH_1):GND    I43 @BASEBOARD_FAB2_LIB.BASEBOARD_FAB2(SCH_1):PAGE48
   268    GND @BASEBOARD_FAB2_LIB.BASEBOARD_FAB2(SCH_1):GND    I43 @BASEBOARD_FAB2_LIB.BASEBOARD_FAB2(SCH_1):PAGE48
   270    GND @BASEBOARD_FAB2_LIB.BASEBOARD_FAB2(SCH_1):GND    I43 @BASEBOARD_FAB2_LIB.BASEBOARD_FAB2(SCH_1):PAGE48
   272    GND @BASEBOARD_FAB2_LIB.BASEBOARD_FAB2(SCH_1):GND    I43 @BASEBOARD_FAB2_LIB.BASEBOARD_FAB2(SCH_1):PAGE48
   274    GND @BASEBOARD_FAB2_LIB.BASEBOARD_FAB2(SCH_1):GND    I43 @BASEBOARD_FAB2_LIB.BASEBOARD_FAB2(SCH_1):PAGE48
   276    GND @BASEBOARD_FAB2_LIB.BASEBOARD_FAB2(SCH_1):GND    I43 @BASEBOARD_FAB2_LIB.BASEBOARD_FAB2(SCH_1):PAGE48
   279    GND @BASEBOARD_FAB2_LIB.BASEBOARD_FAB2(SCH_1):GND    I43 @BASEBOARD_FAB2_LIB.BASEBOARD_FAB2(SCH_1):PAGE48
   281    GND @BASEBOARD_FAB2_LIB.BASEBOARD_FAB2(SCH_1):GND    I43 @BASEBOARD_FAB2_LIB.BASEBOARD_FAB2(SCH_1):PAGE48
   283    GND @BASEBOARD_FAB2_LIB.BASEBOARD_FAB2(SCH_1):GND    I43 @BASEBOARD_FAB2_LIB.BASEBOARD_FAB2(SCH_1):PAGE48
     1 P12V_NVDIMM_ABC @BASEBOARD_FAB2_LIB.BASEBOARD_FAB2(SCH_1):P12V_NVDIMM_ABC   I171 @BASEBOARD_FAB2_LIB.BASEBOARD_FAB2(SCH_1):PAGE48
   145 P12V_NVDIMM_ABC @BASEBOARD_FAB2_LIB.BASEBOARD_FAB2(SCH_1):P12V_NVDIMM_ABC   I171 @BASEBOARD_FAB2_LIB.BASEBOARD_FAB2(SCH_1):PAGE48
    59 PVDDQ_ABC @BASEBOARD_FAB2_LIB.BASEBOARD_FAB2(SCH_1):PVDDQ_ABC   I171 @BASEBOARD_FAB2_LIB.BASEBOARD_FAB2(SCH_1):PAGE48
    61 PVDDQ_ABC @BASEBOARD_FAB2_LIB.BASEBOARD_FAB2(SCH_1):PVDDQ_ABC   I171 @BASEBOARD_FAB2_LIB.BASEBOARD_FAB2(SCH_1):PAGE48
    64 PVDDQ_ABC @BASEBOARD_FAB2_LIB.BASEBOARD_FAB2(SCH_1):PVDDQ_ABC   I171 @BASEBOARD_FAB2_LIB.BASEBOARD_FAB2(SCH_1):PAGE48
    67 PVDDQ_ABC @BASEBOARD_FAB2_LIB.BASEBOARD_FAB2(SCH_1):PVDDQ_ABC   I171 @BASEBOARD_FAB2_LIB.BASEBOARD_FAB2(SCH_1):PAGE48
    70 PVDDQ_ABC @BASEBOARD_FAB2_LIB.BASEBOARD_FAB2(SCH_1):PVDDQ_ABC   I171 @BASEBOARD_FAB2_LIB.BASEBOARD_FAB2(SCH_1):PAGE48
    73 PVDDQ_ABC @BASEBOARD_FAB2_LIB.BASEBOARD_FAB2(SCH_1):PVDDQ_ABC   I171 @BASEBOARD_FAB2_LIB.BASEBOARD_FAB2(SCH_1):PAGE48
    76 PVDDQ_ABC @BASEBOARD_FAB2_LIB.BASEBOARD_FAB2(SCH_1):PVDDQ_ABC   I171 @BASEBOARD_FAB2_LIB.BASEBOARD_FAB2(SCH_1):PAGE48
    80 PVDDQ_ABC @BASEBOARD_FAB2_LIB.BASEBOARD_FAB2(SCH_1):PVDDQ_ABC   I171 @BASEBOARD_FAB2_LIB.BASEBOARD_FAB2(SCH_1):PAGE48
    83 PVDDQ_ABC @BASEBOARD_FAB2_LIB.BASEBOARD_FAB2(SCH_1):PVDDQ_ABC   I171 @BASEBOARD_FAB2_LIB.BASEBOARD_FAB2(SCH_1):PAGE48
    85 PVDDQ_ABC @BASEBOARD_FAB2_LIB.BASEBOARD_FAB2(SCH_1):PVDDQ_ABC   I171 @BASEBOARD_FAB2_LIB.BASEBOARD_FAB2(SCH_1):PAGE48
    88 PVDDQ_ABC @BASEBOARD_FAB2_LIB.BASEBOARD_FAB2(SCH_1):PVDDQ_ABC   I171 @BASEBOARD_FAB2_LIB.BASEBOARD_FAB2(SCH_1):PAGE48
    90 PVDDQ_ABC @BASEBOARD_FAB2_LIB.BASEBOARD_FAB2(SCH_1):PVDDQ_ABC   I171 @BASEBOARD_FAB2_LIB.BASEBOARD_FAB2(SCH_1):PAGE48
    92 PVDDQ_ABC @BASEBOARD_FAB2_LIB.BASEBOARD_FAB2(SCH_1):PVDDQ_ABC   I171 @BASEBOARD_FAB2_LIB.BASEBOARD_FAB2(SCH_1):PAGE48
   204 PVDDQ_ABC @BASEBOARD_FAB2_LIB.BASEBOARD_FAB2(SCH_1):PVDDQ_ABC   I171 @BASEBOARD_FAB2_LIB.BASEBOARD_FAB2(SCH_1):PAGE48
   206 PVDDQ_ABC @BASEBOARD_FAB2_LIB.BASEBOARD_FAB2(SCH_1):PVDDQ_ABC   I171 @BASEBOARD_FAB2_LIB.BASEBOARD_FAB2(SCH_1):PAGE48
   209 PVDDQ_ABC @BASEBOARD_FAB2_LIB.BASEBOARD_FAB2(SCH_1):PVDDQ_ABC   I171 @BASEBOARD_FAB2_LIB.BASEBOARD_FAB2(SCH_1):PAGE48
   212 PVDDQ_ABC @BASEBOARD_FAB2_LIB.BASEBOARD_FAB2(SCH_1):PVDDQ_ABC   I171 @BASEBOARD_FAB2_LIB.BASEBOARD_FAB2(SCH_1):PAGE48
   215 PVDDQ_ABC @BASEBOARD_FAB2_LIB.BASEBOARD_FAB2(SCH_1):PVDDQ_ABC   I171 @BASEBOARD_FAB2_LIB.BASEBOARD_FAB2(SCH_1):PAGE48
   217 PVDDQ_ABC @BASEBOARD_FAB2_LIB.BASEBOARD_FAB2(SCH_1):PVDDQ_ABC   I171 @BASEBOARD_FAB2_LIB.BASEBOARD_FAB2(SCH_1):PAGE48
   220 PVDDQ_ABC @BASEBOARD_FAB2_LIB.BASEBOARD_FAB2(SCH_1):PVDDQ_ABC   I171 @BASEBOARD_FAB2_LIB.BASEBOARD_FAB2(SCH_1):PAGE48
   223 PVDDQ_ABC @BASEBOARD_FAB2_LIB.BASEBOARD_FAB2(SCH_1):PVDDQ_ABC   I171 @BASEBOARD_FAB2_LIB.BASEBOARD_FAB2(SCH_1):PAGE48
   226 PVDDQ_ABC @BASEBOARD_FAB2_LIB.BASEBOARD_FAB2(SCH_1):PVDDQ_ABC   I171 @BASEBOARD_FAB2_LIB.BASEBOARD_FAB2(SCH_1):PAGE48
   229 PVDDQ_ABC @BASEBOARD_FAB2_LIB.BASEBOARD_FAB2(SCH_1):PVDDQ_ABC   I171 @BASEBOARD_FAB2_LIB.BASEBOARD_FAB2(SCH_1):PAGE48
   231 PVDDQ_ABC @BASEBOARD_FAB2_LIB.BASEBOARD_FAB2(SCH_1):PVDDQ_ABC   I171 @BASEBOARD_FAB2_LIB.BASEBOARD_FAB2(SCH_1):PAGE48
   233 PVDDQ_ABC @BASEBOARD_FAB2_LIB.BASEBOARD_FAB2(SCH_1):PVDDQ_ABC   I171 @BASEBOARD_FAB2_LIB.BASEBOARD_FAB2(SCH_1):PAGE48
   236 PVDDQ_ABC @BASEBOARD_FAB2_LIB.BASEBOARD_FAB2(SCH_1):PVDDQ_ABC   I171 @BASEBOARD_FAB2_LIB.BASEBOARD_FAB2(SCH_1):PAGE48
   142 PVPP_ABC @BASEBOARD_FAB2_LIB.BASEBOARD_FAB2(SCH_1):PVPP_ABC   I171 @BASEBOARD_FAB2_LIB.BASEBOARD_FAB2(SCH_1):PAGE48
   143 PVPP_ABC @BASEBOARD_FAB2_LIB.BASEBOARD_FAB2(SCH_1):PVPP_ABC   I171 @BASEBOARD_FAB2_LIB.BASEBOARD_FAB2(SCH_1):PAGE48
   288 PVPP_ABC @BASEBOARD_FAB2_LIB.BASEBOARD_FAB2(SCH_1):PVPP_ABC   I171 @BASEBOARD_FAB2_LIB.BASEBOARD_FAB2(SCH_1):PAGE48
   286 PVPP_ABC @BASEBOARD_FAB2_LIB.BASEBOARD_FAB2(SCH_1):PVPP_ABC   I171 @BASEBOARD_FAB2_LIB.BASEBOARD_FAB2(SCH_1):PAGE48
   287 PVPP_ABC @BASEBOARD_FAB2_LIB.BASEBOARD_FAB2(SCH_1):PVPP_ABC   I171 @BASEBOARD_FAB2_LIB.BASEBOARD_FAB2(SCH_1):PAGE48
    77 PVTT_ABC @BASEBOARD_FAB2_LIB.BASEBOARD_FAB2(SCH_1):PVTT_ABC   I171 @BASEBOARD_FAB2_LIB.BASEBOARD_FAB2(SCH_1):PAGE48
   221 PVTT_ABC @BASEBOARD_FAB2_LIB.BASEBOARD_FAB2(SCH_1):PVTT_ABC   I171 @BASEBOARD_FAB2_LIB.BASEBOARD_FAB2(SCH_1):PAGE48

J7G2 CONN8_C77962004_PIP-CONN,C7796A
     1 P3V3_STBY_PLD_D @BASEBOARD_FAB2_LIB.BASEBOARD_FAB2(SCH_1):P3V3_STBY_PLD_D    I47 @BASEBOARD_FAB2_LIB.BASEBOARD_FAB2(SCH_1):PAGE189
     2 JTAG_TDO_R @BASEBOARD_FAB2_LIB.BASEBOARD_FAB2(SCH_1):JTAG_TDO_R    I47 @BASEBOARD_FAB2_LIB.BASEBOARD_FAB2(SCH_1):PAGE189
     3 JTAG_TDI_R @BASEBOARD_FAB2_LIB.BASEBOARD_FAB2(SCH_1):JTAG_TDI_R    I47 @BASEBOARD_FAB2_LIB.BASEBOARD_FAB2(SCH_1):PAGE189
     4 JTAG_TRST_N @BASEBOARD_FAB2_LIB.BASEBOARD_FAB2(SCH_1):JTAG_TRST_N    I47 @BASEBOARD_FAB2_LIB.BASEBOARD_FAB2(SCH_1):PAGE189
     5 PWRGD_P3V3_STBY @BASEBOARD_FAB2_LIB.BASEBOARD_FAB2(SCH_1):PWRGD_P3V3_STBY    I47 @BASEBOARD_FAB2_LIB.BASEBOARD_FAB2(SCH_1):PAGE189
     6 JTAG_TMS_R @BASEBOARD_FAB2_LIB.BASEBOARD_FAB2(SCH_1):JTAG_TMS_R    I47 @BASEBOARD_FAB2_LIB.BASEBOARD_FAB2(SCH_1):PAGE189
     7    GND @BASEBOARD_FAB2_LIB.BASEBOARD_FAB2(SCH_1):GND    I47 @BASEBOARD_FAB2_LIB.BASEBOARD_FAB2(SCH_1):PAGE189
     8 JTAG_TCK_R @BASEBOARD_FAB2_LIB.BASEBOARD_FAB2(SCH_1):JTAG_TCK_R    I47 @BASEBOARD_FAB2_LIB.BASEBOARD_FAB2(SCH_1):PAGE189

J7G3 CONN12_C73564003_PIP-CONN,C735A
     1 TP_ME_RCVR_BOOT @BASEBOARD_FAB2_LIB.BASEBOARD_FAB2(SCH_1):TP_ME_RCVR_BOOT   I174 @BASEBOARD_FAB2_LIB.BASEBOARD_FAB2(SCH_1):PAGE136
    10 FM_BIOS_TOP_SWAP @BASEBOARD_FAB2_LIB.BASEBOARD_FAB2(SCH_1):FM_BIOS_TOP_SWAP   I174 @BASEBOARD_FAB2_LIB.BASEBOARD_FAB2(SCH_1):PAGE136
    11 PD_PASSWORD_CLEAR @BASEBOARD_FAB2_LIB.BASEBOARD_FAB2(SCH_1):PD_PASSWORD_CLEAR   I174 @BASEBOARD_FAB2_LIB.BASEBOARD_FAB2(SCH_1):PAGE136
    12 PU_BIOS_RECOVER_BOOT @BASEBOARD_FAB2_LIB.BASEBOARD_FAB2(SCH_1):PU_BIOS_RECOVER_BOOT   I174 @BASEBOARD_FAB2_LIB.BASEBOARD_FAB2(SCH_1):PAGE136
     2 TP_BIOS_USB_RECOVERY @BASEBOARD_FAB2_LIB.BASEBOARD_FAB2(SCH_1):TP_BIOS_USB_RECOVERY   I174 @BASEBOARD_FAB2_LIB.BASEBOARD_FAB2(SCH_1):PAGE136
     3 FM_ME_RECOVER_N @BASEBOARD_FAB2_LIB.BASEBOARD_FAB2(SCH_1):FM_ME_RECOVER_N   I174 @BASEBOARD_FAB2_LIB.BASEBOARD_FAB2(SCH_1):PAGE136
     4 FM_BIOS_USB_RECOVERY @BASEBOARD_FAB2_LIB.BASEBOARD_FAB2(SCH_1):FM_BIOS_USB_RECOVERY   I174 @BASEBOARD_FAB2_LIB.BASEBOARD_FAB2(SCH_1):PAGE136
     5 PD_ME_RCVR_N @BASEBOARD_FAB2_LIB.BASEBOARD_FAB2(SCH_1):PD_ME_RCVR_N   I174 @BASEBOARD_FAB2_LIB.BASEBOARD_FAB2(SCH_1):PAGE136
     6 PU_BIOS_USB_RECOVERY @BASEBOARD_FAB2_LIB.BASEBOARD_FAB2(SCH_1):PU_BIOS_USB_RECOVERY   I174 @BASEBOARD_FAB2_LIB.BASEBOARD_FAB2(SCH_1):PAGE136
     7 TP_PASSWORD_CLEAR @BASEBOARD_FAB2_LIB.BASEBOARD_FAB2(SCH_1):TP_PASSWORD_CLEAR   I174 @BASEBOARD_FAB2_LIB.BASEBOARD_FAB2(SCH_1):PAGE136
     8 TP_BIOS_RECOVER_BOOT @BASEBOARD_FAB2_LIB.BASEBOARD_FAB2(SCH_1):TP_BIOS_RECOVER_BOOT   I174 @BASEBOARD_FAB2_LIB.BASEBOARD_FAB2(SCH_1):PAGE136
     9 FM_PASSWORD_CLEAR_N @BASEBOARD_FAB2_LIB.BASEBOARD_FAB2(SCH_1):FM_PASSWORD_CLEAR_N   I174 @BASEBOARD_FAB2_LIB.BASEBOARD_FAB2(SCH_1):PAGE136

J8A1 CONN72_G97614002_A_CP-CONN,G97A
   1A3    GND @BASEBOARD_FAB2_LIB.BASEBOARD_FAB2(SCH_1):GND   I163 @BASEBOARD_FAB2_LIB.BASEBOARD_FAB2(SCH_1):PAGE173
   1A6    GND @BASEBOARD_FAB2_LIB.BASEBOARD_FAB2(SCH_1):GND   I163 @BASEBOARD_FAB2_LIB.BASEBOARD_FAB2(SCH_1):PAGE173
   1A9    GND @BASEBOARD_FAB2_LIB.BASEBOARD_FAB2(SCH_1):GND   I163 @BASEBOARD_FAB2_LIB.BASEBOARD_FAB2(SCH_1):PAGE173
   1B3    GND @BASEBOARD_FAB2_LIB.BASEBOARD_FAB2(SCH_1):GND   I163 @BASEBOARD_FAB2_LIB.BASEBOARD_FAB2(SCH_1):PAGE173
   1B6    GND @BASEBOARD_FAB2_LIB.BASEBOARD_FAB2(SCH_1):GND   I163 @BASEBOARD_FAB2_LIB.BASEBOARD_FAB2(SCH_1):PAGE173
   1B9    GND @BASEBOARD_FAB2_LIB.BASEBOARD_FAB2(SCH_1):GND   I163 @BASEBOARD_FAB2_LIB.BASEBOARD_FAB2(SCH_1):PAGE173
   1C3    GND @BASEBOARD_FAB2_LIB.BASEBOARD_FAB2(SCH_1):GND   I163 @BASEBOARD_FAB2_LIB.BASEBOARD_FAB2(SCH_1):PAGE173
   1C6    GND @BASEBOARD_FAB2_LIB.BASEBOARD_FAB2(SCH_1):GND   I163 @BASEBOARD_FAB2_LIB.BASEBOARD_FAB2(SCH_1):PAGE173
   1C9    GND @BASEBOARD_FAB2_LIB.BASEBOARD_FAB2(SCH_1):GND   I163 @BASEBOARD_FAB2_LIB.BASEBOARD_FAB2(SCH_1):PAGE173
   1D3    GND @BASEBOARD_FAB2_LIB.BASEBOARD_FAB2(SCH_1):GND   I163 @BASEBOARD_FAB2_LIB.BASEBOARD_FAB2(SCH_1):PAGE173
   1D6    GND @BASEBOARD_FAB2_LIB.BASEBOARD_FAB2(SCH_1):GND   I163 @BASEBOARD_FAB2_LIB.BASEBOARD_FAB2(SCH_1):PAGE173
   1D9    GND @BASEBOARD_FAB2_LIB.BASEBOARD_FAB2(SCH_1):GND   I163 @BASEBOARD_FAB2_LIB.BASEBOARD_FAB2(SCH_1):PAGE173
   2A3    GND @BASEBOARD_FAB2_LIB.BASEBOARD_FAB2(SCH_1):GND   I163 @BASEBOARD_FAB2_LIB.BASEBOARD_FAB2(SCH_1):PAGE173
   2A6    GND @BASEBOARD_FAB2_LIB.BASEBOARD_FAB2(SCH_1):GND   I163 @BASEBOARD_FAB2_LIB.BASEBOARD_FAB2(SCH_1):PAGE173
   2A9    GND @BASEBOARD_FAB2_LIB.BASEBOARD_FAB2(SCH_1):GND   I163 @BASEBOARD_FAB2_LIB.BASEBOARD_FAB2(SCH_1):PAGE173
   2B3    GND @BASEBOARD_FAB2_LIB.BASEBOARD_FAB2(SCH_1):GND   I163 @BASEBOARD_FAB2_LIB.BASEBOARD_FAB2(SCH_1):PAGE173
   2B6    GND @BASEBOARD_FAB2_LIB.BASEBOARD_FAB2(SCH_1):GND   I163 @BASEBOARD_FAB2_LIB.BASEBOARD_FAB2(SCH_1):PAGE173
   2B9    GND @BASEBOARD_FAB2_LIB.BASEBOARD_FAB2(SCH_1):GND   I163 @BASEBOARD_FAB2_LIB.BASEBOARD_FAB2(SCH_1):PAGE173
   2C3    GND @BASEBOARD_FAB2_LIB.BASEBOARD_FAB2(SCH_1):GND   I163 @BASEBOARD_FAB2_LIB.BASEBOARD_FAB2(SCH_1):PAGE173
   2C6    GND @BASEBOARD_FAB2_LIB.BASEBOARD_FAB2(SCH_1):GND   I163 @BASEBOARD_FAB2_LIB.BASEBOARD_FAB2(SCH_1):PAGE173
   2C9    GND @BASEBOARD_FAB2_LIB.BASEBOARD_FAB2(SCH_1):GND   I163 @BASEBOARD_FAB2_LIB.BASEBOARD_FAB2(SCH_1):PAGE173
   2D3    GND @BASEBOARD_FAB2_LIB.BASEBOARD_FAB2(SCH_1):GND   I163 @BASEBOARD_FAB2_LIB.BASEBOARD_FAB2(SCH_1):PAGE173
   2D6    GND @BASEBOARD_FAB2_LIB.BASEBOARD_FAB2(SCH_1):GND   I163 @BASEBOARD_FAB2_LIB.BASEBOARD_FAB2(SCH_1):PAGE173
   2D9    GND @BASEBOARD_FAB2_LIB.BASEBOARD_FAB2(SCH_1):GND   I163 @BASEBOARD_FAB2_LIB.BASEBOARD_FAB2(SCH_1):PAGE173
   1B5 SATA6G_P0_RX_C_DN @BASEBOARD_FAB2_LIB.BASEBOARD_FAB2(SCH_1):SATA6G_P0_RX_C_DN   I163 @BASEBOARD_FAB2_LIB.BASEBOARD_FAB2(SCH_1):PAGE173
   1B4 SATA6G_P0_RX_C_DP @BASEBOARD_FAB2_LIB.BASEBOARD_FAB2(SCH_1):SATA6G_P0_RX_C_DP   I163 @BASEBOARD_FAB2_LIB.BASEBOARD_FAB2(SCH_1):PAGE173
   1A5 SATA6G_P1_RX_C_DN @BASEBOARD_FAB2_LIB.BASEBOARD_FAB2(SCH_1):SATA6G_P1_RX_C_DN   I163 @BASEBOARD_FAB2_LIB.BASEBOARD_FAB2(SCH_1):PAGE173
   1A4 SATA6G_P1_RX_C_DP @BASEBOARD_FAB2_LIB.BASEBOARD_FAB2(SCH_1):SATA6G_P1_RX_C_DP   I163 @BASEBOARD_FAB2_LIB.BASEBOARD_FAB2(SCH_1):PAGE173
   1B8 SATA6G_P2_RX_C_DN @BASEBOARD_FAB2_LIB.BASEBOARD_FAB2(SCH_1):SATA6G_P2_RX_C_DN   I163 @BASEBOARD_FAB2_LIB.BASEBOARD_FAB2(SCH_1):PAGE173
   1B7 SATA6G_P2_RX_C_DP @BASEBOARD_FAB2_LIB.BASEBOARD_FAB2(SCH_1):SATA6G_P2_RX_C_DP   I163 @BASEBOARD_FAB2_LIB.BASEBOARD_FAB2(SCH_1):PAGE173
   1A8 SATA6G_P3_RX_C_DN @BASEBOARD_FAB2_LIB.BASEBOARD_FAB2(SCH_1):SATA6G_P3_RX_C_DN   I163 @BASEBOARD_FAB2_LIB.BASEBOARD_FAB2(SCH_1):PAGE173
   1A7 SATA6G_P3_RX_C_DP @BASEBOARD_FAB2_LIB.BASEBOARD_FAB2(SCH_1):SATA6G_P3_RX_C_DP   I163 @BASEBOARD_FAB2_LIB.BASEBOARD_FAB2(SCH_1):PAGE173
   2B5 SATA6G_P4_RX_C_DN @BASEBOARD_FAB2_LIB.BASEBOARD_FAB2(SCH_1):SATA6G_P4_RX_C_DN   I163 @BASEBOARD_FAB2_LIB.BASEBOARD_FAB2(SCH_1):PAGE173
   2B4 SATA6G_P4_RX_C_DP @BASEBOARD_FAB2_LIB.BASEBOARD_FAB2(SCH_1):SATA6G_P4_RX_C_DP   I163 @BASEBOARD_FAB2_LIB.BASEBOARD_FAB2(SCH_1):PAGE173
   2A5 SATA6G_P5_RX_C_DN @BASEBOARD_FAB2_LIB.BASEBOARD_FAB2(SCH_1):SATA6G_P5_RX_C_DN   I163 @BASEBOARD_FAB2_LIB.BASEBOARD_FAB2(SCH_1):PAGE173
   2A4 SATA6G_P5_RX_C_DP @BASEBOARD_FAB2_LIB.BASEBOARD_FAB2(SCH_1):SATA6G_P5_RX_C_DP   I163 @BASEBOARD_FAB2_LIB.BASEBOARD_FAB2(SCH_1):PAGE173
   2B8 SATA6G_P6_RX_C_DN @BASEBOARD_FAB2_LIB.BASEBOARD_FAB2(SCH_1):SATA6G_P6_RX_C_DN   I163 @BASEBOARD_FAB2_LIB.BASEBOARD_FAB2(SCH_1):PAGE173
   2B7 SATA6G_P6_RX_C_DP @BASEBOARD_FAB2_LIB.BASEBOARD_FAB2(SCH_1):SATA6G_P6_RX_C_DP   I163 @BASEBOARD_FAB2_LIB.BASEBOARD_FAB2(SCH_1):PAGE173
   2A8 SATA6G_P7_RX_C_DN @BASEBOARD_FAB2_LIB.BASEBOARD_FAB2(SCH_1):SATA6G_P7_RX_C_DN   I163 @BASEBOARD_FAB2_LIB.BASEBOARD_FAB2(SCH_1):PAGE173
   2A7 SATA6G_P7_RX_C_DP @BASEBOARD_FAB2_LIB.BASEBOARD_FAB2(SCH_1):SATA6G_P7_RX_C_DP   I163 @BASEBOARD_FAB2_LIB.BASEBOARD_FAB2(SCH_1):PAGE173
   1A2 SGPIO_PCH_SATA_CLOCK_R @BASEBOARD_FAB2_LIB.BASEBOARD_FAB2(SCH_1):SGPIO_PCH_SATA_CLOCK_R   I163 @BASEBOARD_FAB2_LIB.BASEBOARD_FAB2(SCH_1):PAGE173
   1B2 SGPIO_PCH_SATA_LOAD_R @BASEBOARD_FAB2_LIB.BASEBOARD_FAB2(SCH_1):SGPIO_PCH_SATA_LOAD_R   I163 @BASEBOARD_FAB2_LIB.BASEBOARD_FAB2(SCH_1):PAGE173
   1C2    GND @BASEBOARD_FAB2_LIB.BASEBOARD_FAB2(SCH_1):GND   I163 @BASEBOARD_FAB2_LIB.BASEBOARD_FAB2(SCH_1):PAGE173
   1B1    GND @BASEBOARD_FAB2_LIB.BASEBOARD_FAB2(SCH_1):GND   I163 @BASEBOARD_FAB2_LIB.BASEBOARD_FAB2(SCH_1):PAGE173
   1C1 SGPIO_PCH_SATA_DOUT0_R @BASEBOARD_FAB2_LIB.BASEBOARD_FAB2(SCH_1):SGPIO_PCH_SATA_DOUT0_R   I163 @BASEBOARD_FAB2_LIB.BASEBOARD_FAB2(SCH_1):PAGE173
   1D1 PU_DATAIN1_SATA_0_R @BASEBOARD_FAB2_LIB.BASEBOARD_FAB2(SCH_1):PU_DATAIN1_SATA_0_R   I163 @BASEBOARD_FAB2_LIB.BASEBOARD_FAB2(SCH_1):PAGE173
   1D2 PD_SATA0_CONTROLLER_TYPE_R @BASEBOARD_FAB2_LIB.BASEBOARD_FAB2(SCH_1):PD_SATA0_CONTROLLER_TYPE_R   I163 @BASEBOARD_FAB2_LIB.BASEBOARD_FAB2(SCH_1):PAGE173
   1A1 TP_FM_QAT_CBL_PRSNT0_R_N @BASEBOARD_FAB2_LIB.BASEBOARD_FAB2(SCH_1):TP_FM_QAT_CBL_PRSNT0_R_N   I163 @BASEBOARD_FAB2_LIB.BASEBOARD_FAB2(SCH_1):PAGE173
   2A2 TP_SGPIO_SATA_CLOCK1_R @BASEBOARD_FAB2_LIB.BASEBOARD_FAB2(SCH_1):TP_SGPIO_SATA_CLOCK1_R   I163 @BASEBOARD_FAB2_LIB.BASEBOARD_FAB2(SCH_1):PAGE173
   2B2 TP_SGPIO_SATA_LOAD1_R @BASEBOARD_FAB2_LIB.BASEBOARD_FAB2(SCH_1):TP_SGPIO_SATA_LOAD1_R   I163 @BASEBOARD_FAB2_LIB.BASEBOARD_FAB2(SCH_1):PAGE173
   2C2    GND @BASEBOARD_FAB2_LIB.BASEBOARD_FAB2(SCH_1):GND   I163 @BASEBOARD_FAB2_LIB.BASEBOARD_FAB2(SCH_1):PAGE173
   2B1    GND @BASEBOARD_FAB2_LIB.BASEBOARD_FAB2(SCH_1):GND   I163 @BASEBOARD_FAB2_LIB.BASEBOARD_FAB2(SCH_1):PAGE173
   2C1 TP_SGPIO_SATA_DATA1_R @BASEBOARD_FAB2_LIB.BASEBOARD_FAB2(SCH_1):TP_SGPIO_SATA_DATA1_R   I163 @BASEBOARD_FAB2_LIB.BASEBOARD_FAB2(SCH_1):PAGE173
   2D1 PU_DATAIN1_SATA_1_R @BASEBOARD_FAB2_LIB.BASEBOARD_FAB2(SCH_1):PU_DATAIN1_SATA_1_R   I163 @BASEBOARD_FAB2_LIB.BASEBOARD_FAB2(SCH_1):PAGE173
   2D2 PD_SATA1_CONTROLLER_TYPE_R @BASEBOARD_FAB2_LIB.BASEBOARD_FAB2(SCH_1):PD_SATA1_CONTROLLER_TYPE_R   I163 @BASEBOARD_FAB2_LIB.BASEBOARD_FAB2(SCH_1):PAGE173
   2A1 TP_FM_QAT_CBL_PRSNT1_N_R @BASEBOARD_FAB2_LIB.BASEBOARD_FAB2(SCH_1):TP_FM_QAT_CBL_PRSNT1_N_R   I163 @BASEBOARD_FAB2_LIB.BASEBOARD_FAB2(SCH_1):PAGE173
   1D5 SATA6G_P0_TX_C_DN @BASEBOARD_FAB2_LIB.BASEBOARD_FAB2(SCH_1):SATA6G_P0_TX_C_DN   I163 @BASEBOARD_FAB2_LIB.BASEBOARD_FAB2(SCH_1):PAGE173
   1D4 SATA6G_P0_TX_C_DP @BASEBOARD_FAB2_LIB.BASEBOARD_FAB2(SCH_1):SATA6G_P0_TX_C_DP   I163 @BASEBOARD_FAB2_LIB.BASEBOARD_FAB2(SCH_1):PAGE173
   1C5 SATA6G_P1_TX_C_DN @BASEBOARD_FAB2_LIB.BASEBOARD_FAB2(SCH_1):SATA6G_P1_TX_C_DN   I163 @BASEBOARD_FAB2_LIB.BASEBOARD_FAB2(SCH_1):PAGE173
   1C4 SATA6G_P1_TX_C_DP @BASEBOARD_FAB2_LIB.BASEBOARD_FAB2(SCH_1):SATA6G_P1_TX_C_DP   I163 @BASEBOARD_FAB2_LIB.BASEBOARD_FAB2(SCH_1):PAGE173
   1D8 SATA6G_P2_TX_C_DN @BASEBOARD_FAB2_LIB.BASEBOARD_FAB2(SCH_1):SATA6G_P2_TX_C_DN   I163 @BASEBOARD_FAB2_LIB.BASEBOARD_FAB2(SCH_1):PAGE173
   1D7 SATA6G_P2_TX_C_DP @BASEBOARD_FAB2_LIB.BASEBOARD_FAB2(SCH_1):SATA6G_P2_TX_C_DP   I163 @BASEBOARD_FAB2_LIB.BASEBOARD_FAB2(SCH_1):PAGE173
   1C8 SATA6G_P3_TX_C_DN @BASEBOARD_FAB2_LIB.BASEBOARD_FAB2(SCH_1):SATA6G_P3_TX_C_DN   I163 @BASEBOARD_FAB2_LIB.BASEBOARD_FAB2(SCH_1):PAGE173
   1C7 SATA6G_P3_TX_C_DP @BASEBOARD_FAB2_LIB.BASEBOARD_FAB2(SCH_1):SATA6G_P3_TX_C_DP   I163 @BASEBOARD_FAB2_LIB.BASEBOARD_FAB2(SCH_1):PAGE173
   2D5 SATA6G_P4_TX_C_DN @BASEBOARD_FAB2_LIB.BASEBOARD_FAB2(SCH_1):SATA6G_P4_TX_C_DN   I163 @BASEBOARD_FAB2_LIB.BASEBOARD_FAB2(SCH_1):PAGE173
   2D4 SATA6G_P4_TX_C_DP @BASEBOARD_FAB2_LIB.BASEBOARD_FAB2(SCH_1):SATA6G_P4_TX_C_DP   I163 @BASEBOARD_FAB2_LIB.BASEBOARD_FAB2(SCH_1):PAGE173
   2C5 SATA6G_P5_TX_C_DN @BASEBOARD_FAB2_LIB.BASEBOARD_FAB2(SCH_1):SATA6G_P5_TX_C_DN   I163 @BASEBOARD_FAB2_LIB.BASEBOARD_FAB2(SCH_1):PAGE173
   2C4 SATA6G_P5_TX_C_DP @BASEBOARD_FAB2_LIB.BASEBOARD_FAB2(SCH_1):SATA6G_P5_TX_C_DP   I163 @BASEBOARD_FAB2_LIB.BASEBOARD_FAB2(SCH_1):PAGE173
   2D8 SATA6G_P6_TX_C_DN @BASEBOARD_FAB2_LIB.BASEBOARD_FAB2(SCH_1):SATA6G_P6_TX_C_DN   I163 @BASEBOARD_FAB2_LIB.BASEBOARD_FAB2(SCH_1):PAGE173
   2D7 SATA6G_P6_TX_C_DP @BASEBOARD_FAB2_LIB.BASEBOARD_FAB2(SCH_1):SATA6G_P6_TX_C_DP   I163 @BASEBOARD_FAB2_LIB.BASEBOARD_FAB2(SCH_1):PAGE173
   2C8 SATA6G_P7_TX_C_DN @BASEBOARD_FAB2_LIB.BASEBOARD_FAB2(SCH_1):SATA6G_P7_TX_C_DN   I163 @BASEBOARD_FAB2_LIB.BASEBOARD_FAB2(SCH_1):PAGE173
   2C7 SATA6G_P7_TX_C_DP @BASEBOARD_FAB2_LIB.BASEBOARD_FAB2(SCH_1):SATA6G_P7_TX_C_DP   I163 @BASEBOARD_FAB2_LIB.BASEBOARD_FAB2(SCH_1):PAGE173

J8B1 SCONN24_H46321001_SM-SCONN,H46A
     1    GND @BASEBOARD_FAB2_LIB.BASEBOARD_FAB2(SCH_1):GND     I1 @BASEBOARD_FAB2_LIB.BASEBOARD_FAB2(SCH_1):PAGE91
    10 SMB_HFI1_CPU0_LVC2_SCL @BASEBOARD_FAB2_LIB.BASEBOARD_FAB2(SCH_1):SMB_HFI1_CPU0_LVC2_SCL     I1 @BASEBOARD_FAB2_LIB.BASEBOARD_FAB2(SCH_1):PAGE91
    11 FM_MODPRST_HFI1_CPU0_LVT2_N @BASEBOARD_FAB2_LIB.BASEBOARD_FAB2(SCH_1):FM_MODPRST_HFI1_CPU0_LVT2_N     I1 @BASEBOARD_FAB2_LIB.BASEBOARD_FAB2(SCH_1):PAGE91
    12 SMB_HFI1_CPU0_LVC2_SDA @BASEBOARD_FAB2_LIB.BASEBOARD_FAB2(SCH_1):SMB_HFI1_CPU0_LVC2_SDA     I1 @BASEBOARD_FAB2_LIB.BASEBOARD_FAB2(SCH_1):PAGE91
    13 LED_HFI1_CPU0_N @BASEBOARD_FAB2_LIB.BASEBOARD_FAB2(SCH_1):LED_HFI1_CPU0_N     I1 @BASEBOARD_FAB2_LIB.BASEBOARD_FAB2(SCH_1):PAGE91
    14 RST_HFI1_CPU0_LVT2_N @BASEBOARD_FAB2_LIB.BASEBOARD_FAB2(SCH_1):RST_HFI1_CPU0_LVT2_N     I1 @BASEBOARD_FAB2_LIB.BASEBOARD_FAB2(SCH_1):PAGE91
    15    GND @BASEBOARD_FAB2_LIB.BASEBOARD_FAB2(SCH_1):GND     I1 @BASEBOARD_FAB2_LIB.BASEBOARD_FAB2(SCH_1):PAGE91
    16 IRQ_HFI1_CPU0_LVT2_N @BASEBOARD_FAB2_LIB.BASEBOARD_FAB2(SCH_1):IRQ_HFI1_CPU0_LVT2_N     I1 @BASEBOARD_FAB2_LIB.BASEBOARD_FAB2(SCH_1):PAGE91
    17 TP_HFI_IO_CONN0_RSVD_17 @BASEBOARD_FAB2_LIB.BASEBOARD_FAB2(SCH_1):TP_HFI_IO_CONN0_RSVD_17     I1 @BASEBOARD_FAB2_LIB.BASEBOARD_FAB2(SCH_1):PAGE91
    18   P3V3 @BASEBOARD_FAB2_LIB.BASEBOARD_FAB2(SCH_1):P3V3     I1 @BASEBOARD_FAB2_LIB.BASEBOARD_FAB2(SCH_1):PAGE91
    19 PWRGD_PVPP_ABC @BASEBOARD_FAB2_LIB.BASEBOARD_FAB2(SCH_1):PWRGD_PVPP_ABC     I1 @BASEBOARD_FAB2_LIB.BASEBOARD_FAB2(SCH_1):PAGE91
     2 SMB_HFI0_CPU0_LVC2_SCL @BASEBOARD_FAB2_LIB.BASEBOARD_FAB2(SCH_1):SMB_HFI0_CPU0_LVC2_SCL     I1 @BASEBOARD_FAB2_LIB.BASEBOARD_FAB2(SCH_1):PAGE91
    20   P3V3 @BASEBOARD_FAB2_LIB.BASEBOARD_FAB2(SCH_1):P3V3     I1 @BASEBOARD_FAB2_LIB.BASEBOARD_FAB2(SCH_1):PAGE91
    21 PVPP_ABC @BASEBOARD_FAB2_LIB.BASEBOARD_FAB2(SCH_1):PVPP_ABC     I1 @BASEBOARD_FAB2_LIB.BASEBOARD_FAB2(SCH_1):PAGE91
    22 SMB_OCP_FRU_STBY_LVC3_SCL @BASEBOARD_FAB2_LIB.BASEBOARD_FAB2(SCH_1):SMB_OCP_FRU_STBY_LVC3_SCL     I1 @BASEBOARD_FAB2_LIB.BASEBOARD_FAB2(SCH_1):PAGE91
    23    GND @BASEBOARD_FAB2_LIB.BASEBOARD_FAB2(SCH_1):GND     I1 @BASEBOARD_FAB2_LIB.BASEBOARD_FAB2(SCH_1):PAGE91
    24 SMB_OCP_FRU_STBY_LVC3_SDA @BASEBOARD_FAB2_LIB.BASEBOARD_FAB2(SCH_1):SMB_OCP_FRU_STBY_LVC3_SDA     I1 @BASEBOARD_FAB2_LIB.BASEBOARD_FAB2(SCH_1):PAGE91
     3 FM_MODPRST_HFI0_CPU0_LVT2_N @BASEBOARD_FAB2_LIB.BASEBOARD_FAB2(SCH_1):FM_MODPRST_HFI0_CPU0_LVT2_N     I1 @BASEBOARD_FAB2_LIB.BASEBOARD_FAB2(SCH_1):PAGE91
     4 SMB_HFI0_CPU0_LVC2_SDA @BASEBOARD_FAB2_LIB.BASEBOARD_FAB2(SCH_1):SMB_HFI0_CPU0_LVC2_SDA     I1 @BASEBOARD_FAB2_LIB.BASEBOARD_FAB2(SCH_1):PAGE91
     5 LED_HFI0_CPU0_N @BASEBOARD_FAB2_LIB.BASEBOARD_FAB2(SCH_1):LED_HFI0_CPU0_N     I1 @BASEBOARD_FAB2_LIB.BASEBOARD_FAB2(SCH_1):PAGE91
     6 RST_HFI0_CPU0_LVT2_N @BASEBOARD_FAB2_LIB.BASEBOARD_FAB2(SCH_1):RST_HFI0_CPU0_LVT2_N     I1 @BASEBOARD_FAB2_LIB.BASEBOARD_FAB2(SCH_1):PAGE91
     7    GND @BASEBOARD_FAB2_LIB.BASEBOARD_FAB2(SCH_1):GND     I1 @BASEBOARD_FAB2_LIB.BASEBOARD_FAB2(SCH_1):PAGE91
     8 IRQ_HFI0_CPU0_LVT2_N @BASEBOARD_FAB2_LIB.BASEBOARD_FAB2(SCH_1):IRQ_HFI0_CPU0_LVT2_N     I1 @BASEBOARD_FAB2_LIB.BASEBOARD_FAB2(SCH_1):PAGE91
     9    GND @BASEBOARD_FAB2_LIB.BASEBOARD_FAB2(SCH_1):GND     I1 @BASEBOARD_FAB2_LIB.BASEBOARD_FAB2(SCH_1):PAGE91
   MP1    GND @BASEBOARD_FAB2_LIB.BASEBOARD_FAB2(SCH_1):GND     I1 @BASEBOARD_FAB2_LIB.BASEBOARD_FAB2(SCH_1):PAGE91
   MP2    GND @BASEBOARD_FAB2_LIB.BASEBOARD_FAB2(SCH_1):GND     I1 @BASEBOARD_FAB2_LIB.BASEBOARD_FAB2(SCH_1):PAGE91

J8C1 CONN3_C95678002_PIP-CONN,C9567A
     1 SMB_HOST_STBY_LVC3_SDA @BASEBOARD_FAB2_LIB.BASEBOARD_FAB2(SCH_1):SMB_HOST_STBY_LVC3_SDA   I285 @BASEBOARD_FAB2_LIB.BASEBOARD_FAB2(SCH_1):PAGE156
     2    GND @BASEBOARD_FAB2_LIB.BASEBOARD_FAB2(SCH_1):GND   I285 @BASEBOARD_FAB2_LIB.BASEBOARD_FAB2(SCH_1):PAGE156
     3 SMB_HOST_STBY_LVC3_SCL @BASEBOARD_FAB2_LIB.BASEBOARD_FAB2(SCH_1):SMB_HOST_STBY_LVC3_SCL   I285 @BASEBOARD_FAB2_LIB.BASEBOARD_FAB2(SCH_1):PAGE156

J8D4 PIN-CON3-27-GP_CONN-G7-PIN-CONA
     1 SMB_VR_STBY_LVC3_SDA @BASEBOARD_FAB2_LIB.BASEBOARD_FAB2(SCH_1):SMB_VR_STBY_LVC3_SDA   I191 @BASEBOARD_FAB2_LIB.BASEBOARD_FAB2(SCH_1):PAGE201
     2    GND @BASEBOARD_FAB2_LIB.BASEBOARD_FAB2(SCH_1):GND   I191 @BASEBOARD_FAB2_LIB.BASEBOARD_FAB2(SCH_1):PAGE201
     3 SMB_VR_STBY_LVC3_SCL @BASEBOARD_FAB2_LIB.BASEBOARD_FAB2(SCH_1):SMB_VR_STBY_LVC3_SCL   I191 @BASEBOARD_FAB2_LIB.BASEBOARD_FAB2(SCH_1):PAGE201

J8E1 SCONN11_H67026001_SM-CONN,H670A
     1 SPI_PCH_TPM_CLK_R @BASEBOARD_FAB2_LIB.BASEBOARD_FAB2(SCH_1):SPI_PCH_TPM_CLK_R    I87 @BASEBOARD_FAB2_LIB.BASEBOARD_FAB2(SCH_1):PAGE184
     2 RST_PLTRST_BUF_N @BASEBOARD_FAB2_LIB.BASEBOARD_FAB2(SCH_1):RST_PLTRST_BUF_N    I87 @BASEBOARD_FAB2_LIB.BASEBOARD_FAB2(SCH_1):PAGE184
     3 SPI_PCH_TPM_MOSI_R @BASEBOARD_FAB2_LIB.BASEBOARD_FAB2(SCH_1):SPI_PCH_TPM_MOSI_R    I87 @BASEBOARD_FAB2_LIB.BASEBOARD_FAB2(SCH_1):PAGE184
     4 SPI_PCH_TPM_MISO_R @BASEBOARD_FAB2_LIB.BASEBOARD_FAB2(SCH_1):SPI_PCH_TPM_MISO_R    I87 @BASEBOARD_FAB2_LIB.BASEBOARD_FAB2(SCH_1):PAGE184
     5 SPI_PCH_TPM_CS_R_N @BASEBOARD_FAB2_LIB.BASEBOARD_FAB2(SCH_1):SPI_PCH_TPM_CS_R_N    I87 @BASEBOARD_FAB2_LIB.BASEBOARD_FAB2(SCH_1):PAGE184
     6 SMB_SENSOR_STBY_LVC3_SDA @BASEBOARD_FAB2_LIB.BASEBOARD_FAB2(SCH_1):SMB_SENSOR_STBY_LVC3_SDA    I87 @BASEBOARD_FAB2_LIB.BASEBOARD_FAB2(SCH_1):PAGE184
     7 P3V3_STBY @BASEBOARD_FAB2_LIB.BASEBOARD_FAB2(SCH_1):P3V3_STBY    I87 @BASEBOARD_FAB2_LIB.BASEBOARD_FAB2(SCH_1):PAGE184
     8 FM_TPM_PRES_RST_N @BASEBOARD_FAB2_LIB.BASEBOARD_FAB2(SCH_1):FM_TPM_PRES_RST_N    I87 @BASEBOARD_FAB2_LIB.BASEBOARD_FAB2(SCH_1):PAGE184
     9 IRQ_SPI_TPM_N_R @BASEBOARD_FAB2_LIB.BASEBOARD_FAB2(SCH_1):IRQ_SPI_TPM_N_R    I87 @BASEBOARD_FAB2_LIB.BASEBOARD_FAB2(SCH_1):PAGE184
    10 SMB_SENSOR_STBY_LVC3_SCL @BASEBOARD_FAB2_LIB.BASEBOARD_FAB2(SCH_1):SMB_SENSOR_STBY_LVC3_SCL    I87 @BASEBOARD_FAB2_LIB.BASEBOARD_FAB2(SCH_1):PAGE184
    11    GND @BASEBOARD_FAB2_LIB.BASEBOARD_FAB2(SCH_1):GND    I87 @BASEBOARD_FAB2_LIB.BASEBOARD_FAB2(SCH_1):PAGE184
   MP1    GND @BASEBOARD_FAB2_LIB.BASEBOARD_FAB2(SCH_1):GND    I87 @BASEBOARD_FAB2_LIB.BASEBOARD_FAB2(SCH_1):PAGE184
   MP2    GND @BASEBOARD_FAB2_LIB.BASEBOARD_FAB2(SCH_1):GND    I87 @BASEBOARD_FAB2_LIB.BASEBOARD_FAB2(SCH_1):PAGE184

J8E3 SCONN80_E67482007_SM-CONN,E674A
     1 FM_MEZZB_PRSNT1_N @BASEBOARD_FAB2_LIB.BASEBOARD_FAB2(SCH_1):FM_MEZZB_PRSNT1_N   I119 @BASEBOARD_FAB2_LIB.BASEBOARD_FAB2(SCH_1):PAGE187
    10 P3E_OCP_CPU0_PE3_C_TXP<7> @BASEBOARD_FAB2_LIB.BASEBOARD_FAB2(SCH_1):P3E_OCP_CPU0_PE3_C_TXP(7)   I119 @BASEBOARD_FAB2_LIB.BASEBOARD_FAB2(SCH_1):PAGE187
    11    GND @BASEBOARD_FAB2_LIB.BASEBOARD_FAB2(SCH_1):GND   I119 @BASEBOARD_FAB2_LIB.BASEBOARD_FAB2(SCH_1):PAGE187
    12 P3E_OCP_CPU0_PE3_C_TXN<7> @BASEBOARD_FAB2_LIB.BASEBOARD_FAB2(SCH_1):P3E_OCP_CPU0_PE3_C_TXN(7)   I119 @BASEBOARD_FAB2_LIB.BASEBOARD_FAB2(SCH_1):PAGE187
    13 P3E_CPU0_PE3_OCP_RXN<6> @BASEBOARD_FAB2_LIB.BASEBOARD_FAB2(SCH_1):P3E_CPU0_PE3_OCP_RXN(6)   I119 @BASEBOARD_FAB2_LIB.BASEBOARD_FAB2(SCH_1):PAGE187
    14    GND @BASEBOARD_FAB2_LIB.BASEBOARD_FAB2(SCH_1):GND   I119 @BASEBOARD_FAB2_LIB.BASEBOARD_FAB2(SCH_1):PAGE187
    15 P3E_CPU0_PE3_OCP_RXP<6> @BASEBOARD_FAB2_LIB.BASEBOARD_FAB2(SCH_1):P3E_CPU0_PE3_OCP_RXP(6)   I119 @BASEBOARD_FAB2_LIB.BASEBOARD_FAB2(SCH_1):PAGE187
    16    GND @BASEBOARD_FAB2_LIB.BASEBOARD_FAB2(SCH_1):GND   I119 @BASEBOARD_FAB2_LIB.BASEBOARD_FAB2(SCH_1):PAGE187
    17    GND @BASEBOARD_FAB2_LIB.BASEBOARD_FAB2(SCH_1):GND   I119 @BASEBOARD_FAB2_LIB.BASEBOARD_FAB2(SCH_1):PAGE187
    18 P3E_OCP_CPU0_PE3_C_TXP<6> @BASEBOARD_FAB2_LIB.BASEBOARD_FAB2(SCH_1):P3E_OCP_CPU0_PE3_C_TXP(6)   I119 @BASEBOARD_FAB2_LIB.BASEBOARD_FAB2(SCH_1):PAGE187
    19    GND @BASEBOARD_FAB2_LIB.BASEBOARD_FAB2(SCH_1):GND   I119 @BASEBOARD_FAB2_LIB.BASEBOARD_FAB2(SCH_1):PAGE187
     2 P12V_STBY @BASEBOARD_FAB2_LIB.BASEBOARD_FAB2(SCH_1):P12V_STBY   I119 @BASEBOARD_FAB2_LIB.BASEBOARD_FAB2(SCH_1):PAGE187
    20 P3E_OCP_CPU0_PE3_C_TXN<6> @BASEBOARD_FAB2_LIB.BASEBOARD_FAB2(SCH_1):P3E_OCP_CPU0_PE3_C_TXN(6)   I119 @BASEBOARD_FAB2_LIB.BASEBOARD_FAB2(SCH_1):PAGE187
    21 P3E_CPU0_PE3_OCP_RXN<5> @BASEBOARD_FAB2_LIB.BASEBOARD_FAB2(SCH_1):P3E_CPU0_PE3_OCP_RXN(5)   I119 @BASEBOARD_FAB2_LIB.BASEBOARD_FAB2(SCH_1):PAGE187
    22    GND @BASEBOARD_FAB2_LIB.BASEBOARD_FAB2(SCH_1):GND   I119 @BASEBOARD_FAB2_LIB.BASEBOARD_FAB2(SCH_1):PAGE187
    23 P3E_CPU0_PE3_OCP_RXP<5> @BASEBOARD_FAB2_LIB.BASEBOARD_FAB2(SCH_1):P3E_CPU0_PE3_OCP_RXP(5)   I119 @BASEBOARD_FAB2_LIB.BASEBOARD_FAB2(SCH_1):PAGE187
    24    GND @BASEBOARD_FAB2_LIB.BASEBOARD_FAB2(SCH_1):GND   I119 @BASEBOARD_FAB2_LIB.BASEBOARD_FAB2(SCH_1):PAGE187
    25    GND @BASEBOARD_FAB2_LIB.BASEBOARD_FAB2(SCH_1):GND   I119 @BASEBOARD_FAB2_LIB.BASEBOARD_FAB2(SCH_1):PAGE187
    26 P3E_OCP_CPU0_PE3_C_TXP<5> @BASEBOARD_FAB2_LIB.BASEBOARD_FAB2(SCH_1):P3E_OCP_CPU0_PE3_C_TXP(5)   I119 @BASEBOARD_FAB2_LIB.BASEBOARD_FAB2(SCH_1):PAGE187
    27    GND @BASEBOARD_FAB2_LIB.BASEBOARD_FAB2(SCH_1):GND   I119 @BASEBOARD_FAB2_LIB.BASEBOARD_FAB2(SCH_1):PAGE187
    28 P3E_OCP_CPU0_PE3_C_TXN<5> @BASEBOARD_FAB2_LIB.BASEBOARD_FAB2(SCH_1):P3E_OCP_CPU0_PE3_C_TXN(5)   I119 @BASEBOARD_FAB2_LIB.BASEBOARD_FAB2(SCH_1):PAGE187
    29 P3E_CPU0_PE3_OCP_RXN<4> @BASEBOARD_FAB2_LIB.BASEBOARD_FAB2(SCH_1):P3E_CPU0_PE3_OCP_RXN(4)   I119 @BASEBOARD_FAB2_LIB.BASEBOARD_FAB2(SCH_1):PAGE187
     3    GND @BASEBOARD_FAB2_LIB.BASEBOARD_FAB2(SCH_1):GND   I119 @BASEBOARD_FAB2_LIB.BASEBOARD_FAB2(SCH_1):PAGE187
    30    GND @BASEBOARD_FAB2_LIB.BASEBOARD_FAB2(SCH_1):GND   I119 @BASEBOARD_FAB2_LIB.BASEBOARD_FAB2(SCH_1):PAGE187
    31 P3E_CPU0_PE3_OCP_RXP<4> @BASEBOARD_FAB2_LIB.BASEBOARD_FAB2(SCH_1):P3E_CPU0_PE3_OCP_RXP(4)   I119 @BASEBOARD_FAB2_LIB.BASEBOARD_FAB2(SCH_1):PAGE187
    32    GND @BASEBOARD_FAB2_LIB.BASEBOARD_FAB2(SCH_1):GND   I119 @BASEBOARD_FAB2_LIB.BASEBOARD_FAB2(SCH_1):PAGE187
    33    GND @BASEBOARD_FAB2_LIB.BASEBOARD_FAB2(SCH_1):GND   I119 @BASEBOARD_FAB2_LIB.BASEBOARD_FAB2(SCH_1):PAGE187
    34 P3E_OCP_CPU0_PE3_C_TXP<4> @BASEBOARD_FAB2_LIB.BASEBOARD_FAB2(SCH_1):P3E_OCP_CPU0_PE3_C_TXP(4)   I119 @BASEBOARD_FAB2_LIB.BASEBOARD_FAB2(SCH_1):PAGE187
    35    GND @BASEBOARD_FAB2_LIB.BASEBOARD_FAB2(SCH_1):GND   I119 @BASEBOARD_FAB2_LIB.BASEBOARD_FAB2(SCH_1):PAGE187
    36 P3E_OCP_CPU0_PE3_C_TXN<4> @BASEBOARD_FAB2_LIB.BASEBOARD_FAB2(SCH_1):P3E_OCP_CPU0_PE3_C_TXN(4)   I119 @BASEBOARD_FAB2_LIB.BASEBOARD_FAB2(SCH_1):PAGE187
    37 P3E_CPU0_PE3_OCP_RXP<3> @BASEBOARD_FAB2_LIB.BASEBOARD_FAB2(SCH_1):P3E_CPU0_PE3_OCP_RXP(3)   I119 @BASEBOARD_FAB2_LIB.BASEBOARD_FAB2(SCH_1):PAGE187
    38    GND @BASEBOARD_FAB2_LIB.BASEBOARD_FAB2(SCH_1):GND   I119 @BASEBOARD_FAB2_LIB.BASEBOARD_FAB2(SCH_1):PAGE187
    39 P3E_CPU0_PE3_OCP_RXN<3> @BASEBOARD_FAB2_LIB.BASEBOARD_FAB2(SCH_1):P3E_CPU0_PE3_OCP_RXN(3)   I119 @BASEBOARD_FAB2_LIB.BASEBOARD_FAB2(SCH_1):PAGE187
     4 P12V_STBY @BASEBOARD_FAB2_LIB.BASEBOARD_FAB2(SCH_1):P12V_STBY   I119 @BASEBOARD_FAB2_LIB.BASEBOARD_FAB2(SCH_1):PAGE187
    40    GND @BASEBOARD_FAB2_LIB.BASEBOARD_FAB2(SCH_1):GND   I119 @BASEBOARD_FAB2_LIB.BASEBOARD_FAB2(SCH_1):PAGE187
    41    GND @BASEBOARD_FAB2_LIB.BASEBOARD_FAB2(SCH_1):GND   I119 @BASEBOARD_FAB2_LIB.BASEBOARD_FAB2(SCH_1):PAGE187
    42 P3E_OCP_CPU0_PE3_C_TXP<3> @BASEBOARD_FAB2_LIB.BASEBOARD_FAB2(SCH_1):P3E_OCP_CPU0_PE3_C_TXP(3)   I119 @BASEBOARD_FAB2_LIB.BASEBOARD_FAB2(SCH_1):PAGE187
    43    GND @BASEBOARD_FAB2_LIB.BASEBOARD_FAB2(SCH_1):GND   I119 @BASEBOARD_FAB2_LIB.BASEBOARD_FAB2(SCH_1):PAGE187
    44 P3E_OCP_CPU0_PE3_C_TXN<3> @BASEBOARD_FAB2_LIB.BASEBOARD_FAB2(SCH_1):P3E_OCP_CPU0_PE3_C_TXN(3)   I119 @BASEBOARD_FAB2_LIB.BASEBOARD_FAB2(SCH_1):PAGE187
    45 P3E_CPU0_PE3_OCP_RXP<2> @BASEBOARD_FAB2_LIB.BASEBOARD_FAB2(SCH_1):P3E_CPU0_PE3_OCP_RXP(2)   I119 @BASEBOARD_FAB2_LIB.BASEBOARD_FAB2(SCH_1):PAGE187
    46    GND @BASEBOARD_FAB2_LIB.BASEBOARD_FAB2(SCH_1):GND   I119 @BASEBOARD_FAB2_LIB.BASEBOARD_FAB2(SCH_1):PAGE187
    47 P3E_CPU0_PE3_OCP_RXN<2> @BASEBOARD_FAB2_LIB.BASEBOARD_FAB2(SCH_1):P3E_CPU0_PE3_OCP_RXN(2)   I119 @BASEBOARD_FAB2_LIB.BASEBOARD_FAB2(SCH_1):PAGE187
    48    GND @BASEBOARD_FAB2_LIB.BASEBOARD_FAB2(SCH_1):GND   I119 @BASEBOARD_FAB2_LIB.BASEBOARD_FAB2(SCH_1):PAGE187
    49    GND @BASEBOARD_FAB2_LIB.BASEBOARD_FAB2(SCH_1):GND   I119 @BASEBOARD_FAB2_LIB.BASEBOARD_FAB2(SCH_1):PAGE187
     5 P3E_CPU0_PE3_OCP_RXP<7> @BASEBOARD_FAB2_LIB.BASEBOARD_FAB2(SCH_1):P3E_CPU0_PE3_OCP_RXP(7)   I119 @BASEBOARD_FAB2_LIB.BASEBOARD_FAB2(SCH_1):PAGE187
    50 P3E_OCP_CPU0_PE3_C_TXP<2> @BASEBOARD_FAB2_LIB.BASEBOARD_FAB2(SCH_1):P3E_OCP_CPU0_PE3_C_TXP(2)   I119 @BASEBOARD_FAB2_LIB.BASEBOARD_FAB2(SCH_1):PAGE187
    51    GND @BASEBOARD_FAB2_LIB.BASEBOARD_FAB2(SCH_1):GND   I119 @BASEBOARD_FAB2_LIB.BASEBOARD_FAB2(SCH_1):PAGE187
    52 P3E_OCP_CPU0_PE3_C_TXN<2> @BASEBOARD_FAB2_LIB.BASEBOARD_FAB2(SCH_1):P3E_OCP_CPU0_PE3_C_TXN(2)   I119 @BASEBOARD_FAB2_LIB.BASEBOARD_FAB2(SCH_1):PAGE187
    53 P3E_CPU0_PE3_OCP_RXP<1> @BASEBOARD_FAB2_LIB.BASEBOARD_FAB2(SCH_1):P3E_CPU0_PE3_OCP_RXP(1)   I119 @BASEBOARD_FAB2_LIB.BASEBOARD_FAB2(SCH_1):PAGE187
    54    GND @BASEBOARD_FAB2_LIB.BASEBOARD_FAB2(SCH_1):GND   I119 @BASEBOARD_FAB2_LIB.BASEBOARD_FAB2(SCH_1):PAGE187
    55 P3E_CPU0_PE3_OCP_RXN<1> @BASEBOARD_FAB2_LIB.BASEBOARD_FAB2(SCH_1):P3E_CPU0_PE3_OCP_RXN(1)   I119 @BASEBOARD_FAB2_LIB.BASEBOARD_FAB2(SCH_1):PAGE187
    56    GND @BASEBOARD_FAB2_LIB.BASEBOARD_FAB2(SCH_1):GND   I119 @BASEBOARD_FAB2_LIB.BASEBOARD_FAB2(SCH_1):PAGE187
    57    GND @BASEBOARD_FAB2_LIB.BASEBOARD_FAB2(SCH_1):GND   I119 @BASEBOARD_FAB2_LIB.BASEBOARD_FAB2(SCH_1):PAGE187
    58 P3E_OCP_CPU0_PE3_C_TXP<1> @BASEBOARD_FAB2_LIB.BASEBOARD_FAB2(SCH_1):P3E_OCP_CPU0_PE3_C_TXP(1)   I119 @BASEBOARD_FAB2_LIB.BASEBOARD_FAB2(SCH_1):PAGE187
    59    GND @BASEBOARD_FAB2_LIB.BASEBOARD_FAB2(SCH_1):GND   I119 @BASEBOARD_FAB2_LIB.BASEBOARD_FAB2(SCH_1):PAGE187
     6 TP_RSVD_B1 @BASEBOARD_FAB2_LIB.BASEBOARD_FAB2(SCH_1):TP_RSVD_B1   I119 @BASEBOARD_FAB2_LIB.BASEBOARD_FAB2(SCH_1):PAGE187
    60 P3E_OCP_CPU0_PE3_C_TXN<1> @BASEBOARD_FAB2_LIB.BASEBOARD_FAB2(SCH_1):P3E_OCP_CPU0_PE3_C_TXN(1)   I119 @BASEBOARD_FAB2_LIB.BASEBOARD_FAB2(SCH_1):PAGE187
    61 P3E_CPU0_PE3_OCP_RXP<0> @BASEBOARD_FAB2_LIB.BASEBOARD_FAB2(SCH_1):P3E_CPU0_PE3_OCP_RXP(0)   I119 @BASEBOARD_FAB2_LIB.BASEBOARD_FAB2(SCH_1):PAGE187
    62    GND @BASEBOARD_FAB2_LIB.BASEBOARD_FAB2(SCH_1):GND   I119 @BASEBOARD_FAB2_LIB.BASEBOARD_FAB2(SCH_1):PAGE187
    63 P3E_CPU0_PE3_OCP_RXN<0> @BASEBOARD_FAB2_LIB.BASEBOARD_FAB2(SCH_1):P3E_CPU0_PE3_OCP_RXN(0)   I119 @BASEBOARD_FAB2_LIB.BASEBOARD_FAB2(SCH_1):PAGE187
    64    GND @BASEBOARD_FAB2_LIB.BASEBOARD_FAB2(SCH_1):GND   I119 @BASEBOARD_FAB2_LIB.BASEBOARD_FAB2(SCH_1):PAGE187
    65    GND @BASEBOARD_FAB2_LIB.BASEBOARD_FAB2(SCH_1):GND   I119 @BASEBOARD_FAB2_LIB.BASEBOARD_FAB2(SCH_1):PAGE187
    66 P3E_OCP_CPU0_PE3_C_TXP<0> @BASEBOARD_FAB2_LIB.BASEBOARD_FAB2(SCH_1):P3E_OCP_CPU0_PE3_C_TXP(0)   I119 @BASEBOARD_FAB2_LIB.BASEBOARD_FAB2(SCH_1):PAGE187
    67    GND @BASEBOARD_FAB2_LIB.BASEBOARD_FAB2(SCH_1):GND   I119 @BASEBOARD_FAB2_LIB.BASEBOARD_FAB2(SCH_1):PAGE187
    68 P3E_OCP_CPU0_PE3_C_TXN<0> @BASEBOARD_FAB2_LIB.BASEBOARD_FAB2(SCH_1):P3E_OCP_CPU0_PE3_C_TXN(0)   I119 @BASEBOARD_FAB2_LIB.BASEBOARD_FAB2(SCH_1):PAGE187
    69 CLK_100M_MEZZ3_DP @BASEBOARD_FAB2_LIB.BASEBOARD_FAB2(SCH_1):CLK_100M_MEZZ3_DP   I119 @BASEBOARD_FAB2_LIB.BASEBOARD_FAB2(SCH_1):PAGE187
     7 P3E_CPU0_PE3_OCP_RXN<7> @BASEBOARD_FAB2_LIB.BASEBOARD_FAB2(SCH_1):P3E_CPU0_PE3_OCP_RXN(7)   I119 @BASEBOARD_FAB2_LIB.BASEBOARD_FAB2(SCH_1):PAGE187
    70    GND @BASEBOARD_FAB2_LIB.BASEBOARD_FAB2(SCH_1):GND   I119 @BASEBOARD_FAB2_LIB.BASEBOARD_FAB2(SCH_1):PAGE187
    71 CLK_100M_MEZZ3_DN @BASEBOARD_FAB2_LIB.BASEBOARD_FAB2(SCH_1):CLK_100M_MEZZ3_DN   I119 @BASEBOARD_FAB2_LIB.BASEBOARD_FAB2(SCH_1):PAGE187
    72    GND @BASEBOARD_FAB2_LIB.BASEBOARD_FAB2(SCH_1):GND   I119 @BASEBOARD_FAB2_LIB.BASEBOARD_FAB2(SCH_1):PAGE187
    73    GND @BASEBOARD_FAB2_LIB.BASEBOARD_FAB2(SCH_1):GND   I119 @BASEBOARD_FAB2_LIB.BASEBOARD_FAB2(SCH_1):PAGE187
    74 CLK_100M_MEZZ4_DP @BASEBOARD_FAB2_LIB.BASEBOARD_FAB2(SCH_1):CLK_100M_MEZZ4_DP   I119 @BASEBOARD_FAB2_LIB.BASEBOARD_FAB2(SCH_1):PAGE187
    75 RST_PCIE_CPU_DEV1_R_N @BASEBOARD_FAB2_LIB.BASEBOARD_FAB2(SCH_1):RST_PCIE_CPU_DEV1_R_N   I119 @BASEBOARD_FAB2_LIB.BASEBOARD_FAB2(SCH_1):PAGE187
    76 CLK_100M_MEZZ4_DN @BASEBOARD_FAB2_LIB.BASEBOARD_FAB2(SCH_1):CLK_100M_MEZZ4_DN   I119 @BASEBOARD_FAB2_LIB.BASEBOARD_FAB2(SCH_1):PAGE187
    77 RST_PCIE_CPU_DEV2_R_N @BASEBOARD_FAB2_LIB.BASEBOARD_FAB2(SCH_1):RST_PCIE_CPU_DEV2_R_N   I119 @BASEBOARD_FAB2_LIB.BASEBOARD_FAB2(SCH_1):PAGE187
    78    GND @BASEBOARD_FAB2_LIB.BASEBOARD_FAB2(SCH_1):GND   I119 @BASEBOARD_FAB2_LIB.BASEBOARD_FAB2(SCH_1):PAGE187
    79 RST_PCIE_CPU_DEV3_R_N @BASEBOARD_FAB2_LIB.BASEBOARD_FAB2(SCH_1):RST_PCIE_CPU_DEV3_R_N   I119 @BASEBOARD_FAB2_LIB.BASEBOARD_FAB2(SCH_1):PAGE187
     8    GND @BASEBOARD_FAB2_LIB.BASEBOARD_FAB2(SCH_1):GND   I119 @BASEBOARD_FAB2_LIB.BASEBOARD_FAB2(SCH_1):PAGE187
    80 FM_OCP_MEZZB_PRES_N @BASEBOARD_FAB2_LIB.BASEBOARD_FAB2(SCH_1):FM_OCP_MEZZB_PRES_N   I119 @BASEBOARD_FAB2_LIB.BASEBOARD_FAB2(SCH_1):PAGE187
     9    GND @BASEBOARD_FAB2_LIB.BASEBOARD_FAB2(SCH_1):GND   I119 @BASEBOARD_FAB2_LIB.BASEBOARD_FAB2(SCH_1):PAGE187

J8E4 SCONN64_H87568002_A_SMT-CONN,HA
     1 SMB_OCP_FRU_STBY_LVC3_SCL @BASEBOARD_FAB2_LIB.BASEBOARD_FAB2(SCH_1):SMB_OCP_FRU_STBY_LVC3_SCL    I27 @BASEBOARD_FAB2_LIB.BASEBOARD_FAB2(SCH_1):PAGE188
    10    GND @BASEBOARD_FAB2_LIB.BASEBOARD_FAB2(SCH_1):GND    I27 @BASEBOARD_FAB2_LIB.BASEBOARD_FAB2(SCH_1):PAGE188
    11     NC     NC    I27 @BASEBOARD_FAB2_LIB.BASEBOARD_FAB2(SCH_1):PAGE188
    12     NC     NC    I27 @BASEBOARD_FAB2_LIB.BASEBOARD_FAB2(SCH_1):PAGE188
    13    GND @BASEBOARD_FAB2_LIB.BASEBOARD_FAB2(SCH_1):GND    I27 @BASEBOARD_FAB2_LIB.BASEBOARD_FAB2(SCH_1):PAGE188
    14 LED_GBE_P2_0 @BASEBOARD_FAB2_LIB.BASEBOARD_FAB2(SCH_1):LED_GBE_P2_0    I27 @BASEBOARD_FAB2_LIB.BASEBOARD_FAB2(SCH_1):PAGE188
    15 LED_GBE_P2_1 @BASEBOARD_FAB2_LIB.BASEBOARD_FAB2(SCH_1):LED_GBE_P2_1    I27 @BASEBOARD_FAB2_LIB.BASEBOARD_FAB2(SCH_1):PAGE188
    16    GND @BASEBOARD_FAB2_LIB.BASEBOARD_FAB2(SCH_1):GND    I27 @BASEBOARD_FAB2_LIB.BASEBOARD_FAB2(SCH_1):PAGE188
    17     NC     NC    I27 @BASEBOARD_FAB2_LIB.BASEBOARD_FAB2(SCH_1):PAGE188
    18     NC     NC    I27 @BASEBOARD_FAB2_LIB.BASEBOARD_FAB2(SCH_1):PAGE188
    19    GND @BASEBOARD_FAB2_LIB.BASEBOARD_FAB2(SCH_1):GND    I27 @BASEBOARD_FAB2_LIB.BASEBOARD_FAB2(SCH_1):PAGE188
     2 SMB_OCP_FRU_STBY_LVC3_SDA @BASEBOARD_FAB2_LIB.BASEBOARD_FAB2(SCH_1):SMB_OCP_FRU_STBY_LVC3_SDA    I27 @BASEBOARD_FAB2_LIB.BASEBOARD_FAB2(SCH_1):PAGE188
    20 SMB_PCH_MEZZ_LOM0_SCL @BASEBOARD_FAB2_LIB.BASEBOARD_FAB2(SCH_1):SMB_PCH_MEZZ_LOM0_SCL    I27 @BASEBOARD_FAB2_LIB.BASEBOARD_FAB2(SCH_1):PAGE188
    21 SMB_PCH_MEZZ_LOM0_SDA @BASEBOARD_FAB2_LIB.BASEBOARD_FAB2(SCH_1):SMB_PCH_MEZZ_LOM0_SDA    I27 @BASEBOARD_FAB2_LIB.BASEBOARD_FAB2(SCH_1):PAGE188
    22    GND @BASEBOARD_FAB2_LIB.BASEBOARD_FAB2(SCH_1):GND    I27 @BASEBOARD_FAB2_LIB.BASEBOARD_FAB2(SCH_1):PAGE188
    23     NC     NC    I27 @BASEBOARD_FAB2_LIB.BASEBOARD_FAB2(SCH_1):PAGE188
    24     NC     NC    I27 @BASEBOARD_FAB2_LIB.BASEBOARD_FAB2(SCH_1):PAGE188
    25    GND @BASEBOARD_FAB2_LIB.BASEBOARD_FAB2(SCH_1):GND    I27 @BASEBOARD_FAB2_LIB.BASEBOARD_FAB2(SCH_1):PAGE188
    26 SMB_PCH_MEZZ_LOM1_SCL @BASEBOARD_FAB2_LIB.BASEBOARD_FAB2(SCH_1):SMB_PCH_MEZZ_LOM1_SCL    I27 @BASEBOARD_FAB2_LIB.BASEBOARD_FAB2(SCH_1):PAGE188
    27 SMB_PCH_MEZZ_LOM1_SDA @BASEBOARD_FAB2_LIB.BASEBOARD_FAB2(SCH_1):SMB_PCH_MEZZ_LOM1_SDA    I27 @BASEBOARD_FAB2_LIB.BASEBOARD_FAB2(SCH_1):PAGE188
    28    GND @BASEBOARD_FAB2_LIB.BASEBOARD_FAB2(SCH_1):GND    I27 @BASEBOARD_FAB2_LIB.BASEBOARD_FAB2(SCH_1):PAGE188
    29 SMB_PCH_MEZZ_LOM3_SCL @BASEBOARD_FAB2_LIB.BASEBOARD_FAB2(SCH_1):SMB_PCH_MEZZ_LOM3_SCL    I27 @BASEBOARD_FAB2_LIB.BASEBOARD_FAB2(SCH_1):PAGE188
     3 EXT_MDIO_I2C_SEL @BASEBOARD_FAB2_LIB.BASEBOARD_FAB2(SCH_1):EXT_MDIO_I2C_SEL    I27 @BASEBOARD_FAB2_LIB.BASEBOARD_FAB2(SCH_1):PAGE188
    30 SMB_PCH_MEZZ_LOM3_SDA @BASEBOARD_FAB2_LIB.BASEBOARD_FAB2(SCH_1):SMB_PCH_MEZZ_LOM3_SDA    I27 @BASEBOARD_FAB2_LIB.BASEBOARD_FAB2(SCH_1):PAGE188
    31 FM_GBE2_LVC3_MOD_ABS @BASEBOARD_FAB2_LIB.BASEBOARD_FAB2(SCH_1):FM_GBE2_LVC3_MOD_ABS    I27 @BASEBOARD_FAB2_LIB.BASEBOARD_FAB2(SCH_1):PAGE188
    32 FM_GBE3_LVC3_MOD_ABS @BASEBOARD_FAB2_LIB.BASEBOARD_FAB2(SCH_1):FM_GBE3_LVC3_MOD_ABS    I27 @BASEBOARD_FAB2_LIB.BASEBOARD_FAB2(SCH_1):PAGE188
    33 P12V_STBY @BASEBOARD_FAB2_LIB.BASEBOARD_FAB2(SCH_1):P12V_STBY    I27 @BASEBOARD_FAB2_LIB.BASEBOARD_FAB2(SCH_1):PAGE188
    34 P12V_STBY @BASEBOARD_FAB2_LIB.BASEBOARD_FAB2(SCH_1):P12V_STBY    I27 @BASEBOARD_FAB2_LIB.BASEBOARD_FAB2(SCH_1):PAGE188
    35 P12V_STBY @BASEBOARD_FAB2_LIB.BASEBOARD_FAB2(SCH_1):P12V_STBY    I27 @BASEBOARD_FAB2_LIB.BASEBOARD_FAB2(SCH_1):PAGE188
    36 TP_RSVD<0> @BASEBOARD_FAB2_LIB.BASEBOARD_FAB2(SCH_1):TP_RSVD(0)    I27 @BASEBOARD_FAB2_LIB.BASEBOARD_FAB2(SCH_1):PAGE188
    37 FM_GBE0_LVC3_MOD_ABS @BASEBOARD_FAB2_LIB.BASEBOARD_FAB2(SCH_1):FM_GBE0_LVC3_MOD_ABS    I27 @BASEBOARD_FAB2_LIB.BASEBOARD_FAB2(SCH_1):PAGE188
    38 FM_GBE1_LVC3_MOD_ABS @BASEBOARD_FAB2_LIB.BASEBOARD_FAB2(SCH_1):FM_GBE1_LVC3_MOD_ABS    I27 @BASEBOARD_FAB2_LIB.BASEBOARD_FAB2(SCH_1):PAGE188
    39    GND @BASEBOARD_FAB2_LIB.BASEBOARD_FAB2(SCH_1):GND    I27 @BASEBOARD_FAB2_LIB.BASEBOARD_FAB2(SCH_1):PAGE188
     4    GND @BASEBOARD_FAB2_LIB.BASEBOARD_FAB2(SCH_1):GND    I27 @BASEBOARD_FAB2_LIB.BASEBOARD_FAB2(SCH_1):PAGE188
    40 KR_P0_OCP_TX_DP @BASEBOARD_FAB2_LIB.BASEBOARD_FAB2(SCH_1):KR_P0_OCP_TX_DP    I27 @BASEBOARD_FAB2_LIB.BASEBOARD_FAB2(SCH_1):PAGE188
    41 KR_P0_OCP_TX_DN @BASEBOARD_FAB2_LIB.BASEBOARD_FAB2(SCH_1):KR_P0_OCP_TX_DN    I27 @BASEBOARD_FAB2_LIB.BASEBOARD_FAB2(SCH_1):PAGE188
    42    GND @BASEBOARD_FAB2_LIB.BASEBOARD_FAB2(SCH_1):GND    I27 @BASEBOARD_FAB2_LIB.BASEBOARD_FAB2(SCH_1):PAGE188
    43 LED_GBE_P0_0 @BASEBOARD_FAB2_LIB.BASEBOARD_FAB2(SCH_1):LED_GBE_P0_0    I27 @BASEBOARD_FAB2_LIB.BASEBOARD_FAB2(SCH_1):PAGE188
    44 LED_GBE_P0_1 @BASEBOARD_FAB2_LIB.BASEBOARD_FAB2(SCH_1):LED_GBE_P0_1    I27 @BASEBOARD_FAB2_LIB.BASEBOARD_FAB2(SCH_1):PAGE188
    45    GND @BASEBOARD_FAB2_LIB.BASEBOARD_FAB2(SCH_1):GND    I27 @BASEBOARD_FAB2_LIB.BASEBOARD_FAB2(SCH_1):PAGE188
    46 KR_P1_OCP_TX_DP @BASEBOARD_FAB2_LIB.BASEBOARD_FAB2(SCH_1):KR_P1_OCP_TX_DP    I27 @BASEBOARD_FAB2_LIB.BASEBOARD_FAB2(SCH_1):PAGE188
    47 KR_P1_OCP_TX_DN @BASEBOARD_FAB2_LIB.BASEBOARD_FAB2(SCH_1):KR_P1_OCP_TX_DN    I27 @BASEBOARD_FAB2_LIB.BASEBOARD_FAB2(SCH_1):PAGE188
    48    GND @BASEBOARD_FAB2_LIB.BASEBOARD_FAB2(SCH_1):GND    I27 @BASEBOARD_FAB2_LIB.BASEBOARD_FAB2(SCH_1):PAGE188
    49 TP_SHARED_KR_MDC_0 @BASEBOARD_FAB2_LIB.BASEBOARD_FAB2(SCH_1):TP_SHARED_KR_MDC_0    I27 @BASEBOARD_FAB2_LIB.BASEBOARD_FAB2(SCH_1):PAGE188
     5     NC     NC    I27 @BASEBOARD_FAB2_LIB.BASEBOARD_FAB2(SCH_1):PAGE188
    50 TP_SHARED_KR_MDIO_0 @BASEBOARD_FAB2_LIB.BASEBOARD_FAB2(SCH_1):TP_SHARED_KR_MDIO_0    I27 @BASEBOARD_FAB2_LIB.BASEBOARD_FAB2(SCH_1):PAGE188
    51    GND @BASEBOARD_FAB2_LIB.BASEBOARD_FAB2(SCH_1):GND    I27 @BASEBOARD_FAB2_LIB.BASEBOARD_FAB2(SCH_1):PAGE188
    52 KR_P0_OCP_RX_DP @BASEBOARD_FAB2_LIB.BASEBOARD_FAB2(SCH_1):KR_P0_OCP_RX_DP    I27 @BASEBOARD_FAB2_LIB.BASEBOARD_FAB2(SCH_1):PAGE188
    53 KR_P0_OCP_RX_DN @BASEBOARD_FAB2_LIB.BASEBOARD_FAB2(SCH_1):KR_P0_OCP_RX_DN    I27 @BASEBOARD_FAB2_LIB.BASEBOARD_FAB2(SCH_1):PAGE188
    54    GND @BASEBOARD_FAB2_LIB.BASEBOARD_FAB2(SCH_1):GND    I27 @BASEBOARD_FAB2_LIB.BASEBOARD_FAB2(SCH_1):PAGE188
    55 LED_GBE_P3_0 @BASEBOARD_FAB2_LIB.BASEBOARD_FAB2(SCH_1):LED_GBE_P3_0    I27 @BASEBOARD_FAB2_LIB.BASEBOARD_FAB2(SCH_1):PAGE188
    56 LED_GBE_P3_1 @BASEBOARD_FAB2_LIB.BASEBOARD_FAB2(SCH_1):LED_GBE_P3_1    I27 @BASEBOARD_FAB2_LIB.BASEBOARD_FAB2(SCH_1):PAGE188
    57    GND @BASEBOARD_FAB2_LIB.BASEBOARD_FAB2(SCH_1):GND    I27 @BASEBOARD_FAB2_LIB.BASEBOARD_FAB2(SCH_1):PAGE188
    58 KR_P1_OCP_RX_DP @BASEBOARD_FAB2_LIB.BASEBOARD_FAB2(SCH_1):KR_P1_OCP_RX_DP    I27 @BASEBOARD_FAB2_LIB.BASEBOARD_FAB2(SCH_1):PAGE188
    59 KR_P1_OCP_RX_DN @BASEBOARD_FAB2_LIB.BASEBOARD_FAB2(SCH_1):KR_P1_OCP_RX_DN    I27 @BASEBOARD_FAB2_LIB.BASEBOARD_FAB2(SCH_1):PAGE188
     6     NC     NC    I27 @BASEBOARD_FAB2_LIB.BASEBOARD_FAB2(SCH_1):PAGE188
    60    GND @BASEBOARD_FAB2_LIB.BASEBOARD_FAB2(SCH_1):GND    I27 @BASEBOARD_FAB2_LIB.BASEBOARD_FAB2(SCH_1):PAGE188
    61 SMB_PCH_MEZZ_LOM2_SCL @BASEBOARD_FAB2_LIB.BASEBOARD_FAB2(SCH_1):SMB_PCH_MEZZ_LOM2_SCL    I27 @BASEBOARD_FAB2_LIB.BASEBOARD_FAB2(SCH_1):PAGE188
    62 SMB_PCH_MEZZ_LOM2_SDA @BASEBOARD_FAB2_LIB.BASEBOARD_FAB2(SCH_1):SMB_PCH_MEZZ_LOM2_SDA    I27 @BASEBOARD_FAB2_LIB.BASEBOARD_FAB2(SCH_1):PAGE188
    63    GND @BASEBOARD_FAB2_LIB.BASEBOARD_FAB2(SCH_1):GND    I27 @BASEBOARD_FAB2_LIB.BASEBOARD_FAB2(SCH_1):PAGE188
    64 FM_OCP_MEZZC_PRES_N @BASEBOARD_FAB2_LIB.BASEBOARD_FAB2(SCH_1):FM_OCP_MEZZC_PRES_N    I27 @BASEBOARD_FAB2_LIB.BASEBOARD_FAB2(SCH_1):PAGE188
     7    GND @BASEBOARD_FAB2_LIB.BASEBOARD_FAB2(SCH_1):GND    I27 @BASEBOARD_FAB2_LIB.BASEBOARD_FAB2(SCH_1):PAGE188
     8 LED_GBE_P1_0 @BASEBOARD_FAB2_LIB.BASEBOARD_FAB2(SCH_1):LED_GBE_P1_0    I27 @BASEBOARD_FAB2_LIB.BASEBOARD_FAB2(SCH_1):PAGE188
     9 LED_GBE_P1_1 @BASEBOARD_FAB2_LIB.BASEBOARD_FAB2(SCH_1):LED_GBE_P1_1    I27 @BASEBOARD_FAB2_LIB.BASEBOARD_FAB2(SCH_1):PAGE188

J8F1 SKT-MINI67P-41-GP_SOCKET-G4-SKA
     1    GND @BASEBOARD_FAB2_LIB.BASEBOARD_FAB2(SCH_1):GND   I143 @BASEBOARD_FAB2_LIB.BASEBOARD_FAB2(SCH_1):PAGE185
     3    GND @BASEBOARD_FAB2_LIB.BASEBOARD_FAB2(SCH_1):GND   I143 @BASEBOARD_FAB2_LIB.BASEBOARD_FAB2(SCH_1):PAGE185
     5 P3E_PCH_M2_RX_DN<3> @BASEBOARD_FAB2_LIB.BASEBOARD_FAB2(SCH_1):P3E_PCH_M2_RX_DN(3)   I143 @BASEBOARD_FAB2_LIB.BASEBOARD_FAB2(SCH_1):PAGE185
     7 P3E_PCH_M2_RX_DP<3> @BASEBOARD_FAB2_LIB.BASEBOARD_FAB2(SCH_1):P3E_PCH_M2_RX_DP(3)   I143 @BASEBOARD_FAB2_LIB.BASEBOARD_FAB2(SCH_1):PAGE185
     9    GND @BASEBOARD_FAB2_LIB.BASEBOARD_FAB2(SCH_1):GND   I143 @BASEBOARD_FAB2_LIB.BASEBOARD_FAB2(SCH_1):PAGE185
    11 P3E_PCH_M2_TX_C_DN<3> @BASEBOARD_FAB2_LIB.BASEBOARD_FAB2(SCH_1):P3E_PCH_M2_TX_C_DN(3)   I143 @BASEBOARD_FAB2_LIB.BASEBOARD_FAB2(SCH_1):PAGE185
    13 P3E_PCH_M2_TX_C_DP<3> @BASEBOARD_FAB2_LIB.BASEBOARD_FAB2(SCH_1):P3E_PCH_M2_TX_C_DP(3)   I143 @BASEBOARD_FAB2_LIB.BASEBOARD_FAB2(SCH_1):PAGE185
    15    GND @BASEBOARD_FAB2_LIB.BASEBOARD_FAB2(SCH_1):GND   I143 @BASEBOARD_FAB2_LIB.BASEBOARD_FAB2(SCH_1):PAGE185
    17 P3E_PCH_M2_RX_DN<2> @BASEBOARD_FAB2_LIB.BASEBOARD_FAB2(SCH_1):P3E_PCH_M2_RX_DN(2)   I143 @BASEBOARD_FAB2_LIB.BASEBOARD_FAB2(SCH_1):PAGE185
    19 P3E_PCH_M2_RX_DP<2> @BASEBOARD_FAB2_LIB.BASEBOARD_FAB2(SCH_1):P3E_PCH_M2_RX_DP(2)   I143 @BASEBOARD_FAB2_LIB.BASEBOARD_FAB2(SCH_1):PAGE185
    21    GND @BASEBOARD_FAB2_LIB.BASEBOARD_FAB2(SCH_1):GND   I143 @BASEBOARD_FAB2_LIB.BASEBOARD_FAB2(SCH_1):PAGE185
    23 P3E_PCH_M2_TX_C_DN<2> @BASEBOARD_FAB2_LIB.BASEBOARD_FAB2(SCH_1):P3E_PCH_M2_TX_C_DN(2)   I143 @BASEBOARD_FAB2_LIB.BASEBOARD_FAB2(SCH_1):PAGE185
    25 P3E_PCH_M2_TX_C_DP<2> @BASEBOARD_FAB2_LIB.BASEBOARD_FAB2(SCH_1):P3E_PCH_M2_TX_C_DP(2)   I143 @BASEBOARD_FAB2_LIB.BASEBOARD_FAB2(SCH_1):PAGE185
    27    GND @BASEBOARD_FAB2_LIB.BASEBOARD_FAB2(SCH_1):GND   I143 @BASEBOARD_FAB2_LIB.BASEBOARD_FAB2(SCH_1):PAGE185
    29 P3E_PCH_M2_RX_DN<1> @BASEBOARD_FAB2_LIB.BASEBOARD_FAB2(SCH_1):P3E_PCH_M2_RX_DN(1)   I143 @BASEBOARD_FAB2_LIB.BASEBOARD_FAB2(SCH_1):PAGE185
    31 P3E_PCH_M2_RX_DP<1> @BASEBOARD_FAB2_LIB.BASEBOARD_FAB2(SCH_1):P3E_PCH_M2_RX_DP(1)   I143 @BASEBOARD_FAB2_LIB.BASEBOARD_FAB2(SCH_1):PAGE185
    33    GND @BASEBOARD_FAB2_LIB.BASEBOARD_FAB2(SCH_1):GND   I143 @BASEBOARD_FAB2_LIB.BASEBOARD_FAB2(SCH_1):PAGE185
    35 P3E_PCH_M2_TX_C_DN<1> @BASEBOARD_FAB2_LIB.BASEBOARD_FAB2(SCH_1):P3E_PCH_M2_TX_C_DN(1)   I143 @BASEBOARD_FAB2_LIB.BASEBOARD_FAB2(SCH_1):PAGE185
    37 P3E_PCH_M2_TX_C_DP<1> @BASEBOARD_FAB2_LIB.BASEBOARD_FAB2(SCH_1):P3E_PCH_M2_TX_C_DP(1)   I143 @BASEBOARD_FAB2_LIB.BASEBOARD_FAB2(SCH_1):PAGE185
    39    GND @BASEBOARD_FAB2_LIB.BASEBOARD_FAB2(SCH_1):GND   I143 @BASEBOARD_FAB2_LIB.BASEBOARD_FAB2(SCH_1):PAGE185
    41 P3E_PCH_M2_SATA6G_RX_R_DP @BASEBOARD_FAB2_LIB.BASEBOARD_FAB2(SCH_1):P3E_PCH_M2_SATA6G_RX_R_DP   I143 @BASEBOARD_FAB2_LIB.BASEBOARD_FAB2(SCH_1):PAGE185
    43 P3E_PCH_M2_SATA6G_RX_R_DN @BASEBOARD_FAB2_LIB.BASEBOARD_FAB2(SCH_1):P3E_PCH_M2_SATA6G_RX_R_DN   I143 @BASEBOARD_FAB2_LIB.BASEBOARD_FAB2(SCH_1):PAGE185
    45    GND @BASEBOARD_FAB2_LIB.BASEBOARD_FAB2(SCH_1):GND   I143 @BASEBOARD_FAB2_LIB.BASEBOARD_FAB2(SCH_1):PAGE185
    47 P3E_PCH_M2_SATA6G_TX_R_DN @BASEBOARD_FAB2_LIB.BASEBOARD_FAB2(SCH_1):P3E_PCH_M2_SATA6G_TX_R_DN   I143 @BASEBOARD_FAB2_LIB.BASEBOARD_FAB2(SCH_1):PAGE185
    49 P3E_PCH_M2_SATA6G_TX_R_DP @BASEBOARD_FAB2_LIB.BASEBOARD_FAB2(SCH_1):P3E_PCH_M2_SATA6G_TX_R_DP   I143 @BASEBOARD_FAB2_LIB.BASEBOARD_FAB2(SCH_1):PAGE185
    51    GND @BASEBOARD_FAB2_LIB.BASEBOARD_FAB2(SCH_1):GND   I143 @BASEBOARD_FAB2_LIB.BASEBOARD_FAB2(SCH_1):PAGE185
    53 CLK_100M_M2_DN @BASEBOARD_FAB2_LIB.BASEBOARD_FAB2(SCH_1):CLK_100M_M2_DN   I143 @BASEBOARD_FAB2_LIB.BASEBOARD_FAB2(SCH_1):PAGE185
    55 CLK_100M_M2_DP @BASEBOARD_FAB2_LIB.BASEBOARD_FAB2(SCH_1):CLK_100M_M2_DP   I143 @BASEBOARD_FAB2_LIB.BASEBOARD_FAB2(SCH_1):PAGE185
    57    GND @BASEBOARD_FAB2_LIB.BASEBOARD_FAB2(SCH_1):GND   I143 @BASEBOARD_FAB2_LIB.BASEBOARD_FAB2(SCH_1):PAGE185
    67     NC     NC   I143 @BASEBOARD_FAB2_LIB.BASEBOARD_FAB2(SCH_1):PAGE185
    69 FM_M2_SSD_PEDET @BASEBOARD_FAB2_LIB.BASEBOARD_FAB2(SCH_1):FM_M2_SSD_PEDET   I143 @BASEBOARD_FAB2_LIB.BASEBOARD_FAB2(SCH_1):PAGE185
    71    GND @BASEBOARD_FAB2_LIB.BASEBOARD_FAB2(SCH_1):GND   I143 @BASEBOARD_FAB2_LIB.BASEBOARD_FAB2(SCH_1):PAGE185
    73    GND @BASEBOARD_FAB2_LIB.BASEBOARD_FAB2(SCH_1):GND   I143 @BASEBOARD_FAB2_LIB.BASEBOARD_FAB2(SCH_1):PAGE185
    75    GND @BASEBOARD_FAB2_LIB.BASEBOARD_FAB2(SCH_1):GND   I143 @BASEBOARD_FAB2_LIB.BASEBOARD_FAB2(SCH_1):PAGE185
     2   P3V3 @BASEBOARD_FAB2_LIB.BASEBOARD_FAB2(SCH_1):P3V3   I143 @BASEBOARD_FAB2_LIB.BASEBOARD_FAB2(SCH_1):PAGE185
     4   P3V3 @BASEBOARD_FAB2_LIB.BASEBOARD_FAB2(SCH_1):P3V3   I143 @BASEBOARD_FAB2_LIB.BASEBOARD_FAB2(SCH_1):PAGE185
     6 NC_M2<0> @BASEBOARD_FAB2_LIB.BASEBOARD_FAB2(SCH_1):NC_M2(0)   I143 @BASEBOARD_FAB2_LIB.BASEBOARD_FAB2(SCH_1):PAGE185
     8 NC_M2<1> @BASEBOARD_FAB2_LIB.BASEBOARD_FAB2(SCH_1):NC_M2(1)   I143 @BASEBOARD_FAB2_LIB.BASEBOARD_FAB2(SCH_1):PAGE185
    10 TP_LED_M2_ACT_N @BASEBOARD_FAB2_LIB.BASEBOARD_FAB2(SCH_1):TP_LED_M2_ACT_N   I143 @BASEBOARD_FAB2_LIB.BASEBOARD_FAB2(SCH_1):PAGE185
    12   P3V3 @BASEBOARD_FAB2_LIB.BASEBOARD_FAB2(SCH_1):P3V3   I143 @BASEBOARD_FAB2_LIB.BASEBOARD_FAB2(SCH_1):PAGE185
    14   P3V3 @BASEBOARD_FAB2_LIB.BASEBOARD_FAB2(SCH_1):P3V3   I143 @BASEBOARD_FAB2_LIB.BASEBOARD_FAB2(SCH_1):PAGE185
    16   P3V3 @BASEBOARD_FAB2_LIB.BASEBOARD_FAB2(SCH_1):P3V3   I143 @BASEBOARD_FAB2_LIB.BASEBOARD_FAB2(SCH_1):PAGE185
    18   P3V3 @BASEBOARD_FAB2_LIB.BASEBOARD_FAB2(SCH_1):P3V3   I143 @BASEBOARD_FAB2_LIB.BASEBOARD_FAB2(SCH_1):PAGE185
    20     NC     NC   I143 @BASEBOARD_FAB2_LIB.BASEBOARD_FAB2(SCH_1):PAGE185
    22     NC     NC   I143 @BASEBOARD_FAB2_LIB.BASEBOARD_FAB2(SCH_1):PAGE185
    24     NC     NC   I143 @BASEBOARD_FAB2_LIB.BASEBOARD_FAB2(SCH_1):PAGE185
    26     NC     NC   I143 @BASEBOARD_FAB2_LIB.BASEBOARD_FAB2(SCH_1):PAGE185
    28     NC     NC   I143 @BASEBOARD_FAB2_LIB.BASEBOARD_FAB2(SCH_1):PAGE185
    30     NC     NC   I143 @BASEBOARD_FAB2_LIB.BASEBOARD_FAB2(SCH_1):PAGE185
    32     NC     NC   I143 @BASEBOARD_FAB2_LIB.BASEBOARD_FAB2(SCH_1):PAGE185
    34     NC     NC   I143 @BASEBOARD_FAB2_LIB.BASEBOARD_FAB2(SCH_1):PAGE185
    36     NC     NC   I143 @BASEBOARD_FAB2_LIB.BASEBOARD_FAB2(SCH_1):PAGE185
    38 TP_M2_DEVSLP @BASEBOARD_FAB2_LIB.BASEBOARD_FAB2(SCH_1):TP_M2_DEVSLP   I143 @BASEBOARD_FAB2_LIB.BASEBOARD_FAB2(SCH_1):PAGE185
    40 SMB_M2_SCL @BASEBOARD_FAB2_LIB.BASEBOARD_FAB2(SCH_1):SMB_M2_SCL   I143 @BASEBOARD_FAB2_LIB.BASEBOARD_FAB2(SCH_1):PAGE185
    42 SMB_M2_SDA @BASEBOARD_FAB2_LIB.BASEBOARD_FAB2(SCH_1):SMB_M2_SDA   I143 @BASEBOARD_FAB2_LIB.BASEBOARD_FAB2(SCH_1):PAGE185
    44 SMB_M2_ALT_N @BASEBOARD_FAB2_LIB.BASEBOARD_FAB2(SCH_1):SMB_M2_ALT_N   I143 @BASEBOARD_FAB2_LIB.BASEBOARD_FAB2(SCH_1):PAGE185
    46     NC     NC   I143 @BASEBOARD_FAB2_LIB.BASEBOARD_FAB2(SCH_1):PAGE185
    48     NC     NC   I143 @BASEBOARD_FAB2_LIB.BASEBOARD_FAB2(SCH_1):PAGE185
    50 RST_PCIE_M2_DEV_IC_N @BASEBOARD_FAB2_LIB.BASEBOARD_FAB2(SCH_1):RST_PCIE_M2_DEV_IC_N   I143 @BASEBOARD_FAB2_LIB.BASEBOARD_FAB2(SCH_1):PAGE185
    52 PU_M2_CLK_REQ_N @BASEBOARD_FAB2_LIB.BASEBOARD_FAB2(SCH_1):PU_M2_CLK_REQ_N   I143 @BASEBOARD_FAB2_LIB.BASEBOARD_FAB2(SCH_1):PAGE185
    54 FM_PE_M2_WAKE_N @BASEBOARD_FAB2_LIB.BASEBOARD_FAB2(SCH_1):FM_PE_M2_WAKE_N   I143 @BASEBOARD_FAB2_LIB.BASEBOARD_FAB2(SCH_1):PAGE185
    56     NC     NC   I143 @BASEBOARD_FAB2_LIB.BASEBOARD_FAB2(SCH_1):PAGE185
    58     NC     NC   I143 @BASEBOARD_FAB2_LIB.BASEBOARD_FAB2(SCH_1):PAGE185
    68 TP_M2_32M_SUSCLK @BASEBOARD_FAB2_LIB.BASEBOARD_FAB2(SCH_1):TP_M2_32M_SUSCLK   I143 @BASEBOARD_FAB2_LIB.BASEBOARD_FAB2(SCH_1):PAGE185
    70   P3V3 @BASEBOARD_FAB2_LIB.BASEBOARD_FAB2(SCH_1):P3V3   I143 @BASEBOARD_FAB2_LIB.BASEBOARD_FAB2(SCH_1):PAGE185
    72   P3V3 @BASEBOARD_FAB2_LIB.BASEBOARD_FAB2(SCH_1):P3V3   I143 @BASEBOARD_FAB2_LIB.BASEBOARD_FAB2(SCH_1):PAGE185
    74   P3V3 @BASEBOARD_FAB2_LIB.BASEBOARD_FAB2(SCH_1):P3V3   I143 @BASEBOARD_FAB2_LIB.BASEBOARD_FAB2(SCH_1):PAGE185
    76    GND @BASEBOARD_FAB2_LIB.BASEBOARD_FAB2(SCH_1):GND   I143 @BASEBOARD_FAB2_LIB.BASEBOARD_FAB2(SCH_1):PAGE185
    77    GND @BASEBOARD_FAB2_LIB.BASEBOARD_FAB2(SCH_1):GND   I143 @BASEBOARD_FAB2_LIB.BASEBOARD_FAB2(SCH_1):PAGE185
   NP1     NC     NC   I143 @BASEBOARD_FAB2_LIB.BASEBOARD_FAB2(SCH_1):PAGE185
   NP2     NC     NC   I143 @BASEBOARD_FAB2_LIB.BASEBOARD_FAB2(SCH_1):PAGE185

J8G1 SCONN200_H68296001_SM-CONN,H68A
     1   P12V @BASEBOARD_FAB2_LIB.BASEBOARD_FAB2(SCH_1):P12V   I258 @BASEBOARD_FAB2_LIB.BASEBOARD_FAB2(SCH_1):PAGE108
     2   P12V @BASEBOARD_FAB2_LIB.BASEBOARD_FAB2(SCH_1):P12V   I258 @BASEBOARD_FAB2_LIB.BASEBOARD_FAB2(SCH_1):PAGE108
     3   P12V @BASEBOARD_FAB2_LIB.BASEBOARD_FAB2(SCH_1):P12V   I258 @BASEBOARD_FAB2_LIB.BASEBOARD_FAB2(SCH_1):PAGE108
     4   P12V @BASEBOARD_FAB2_LIB.BASEBOARD_FAB2(SCH_1):P12V   I258 @BASEBOARD_FAB2_LIB.BASEBOARD_FAB2(SCH_1):PAGE108
     5   P12V @BASEBOARD_FAB2_LIB.BASEBOARD_FAB2(SCH_1):P12V   I258 @BASEBOARD_FAB2_LIB.BASEBOARD_FAB2(SCH_1):PAGE108
     6   P12V @BASEBOARD_FAB2_LIB.BASEBOARD_FAB2(SCH_1):P12V   I258 @BASEBOARD_FAB2_LIB.BASEBOARD_FAB2(SCH_1):PAGE108
     7   P12V @BASEBOARD_FAB2_LIB.BASEBOARD_FAB2(SCH_1):P12V   I258 @BASEBOARD_FAB2_LIB.BASEBOARD_FAB2(SCH_1):PAGE108
     8   P12V @BASEBOARD_FAB2_LIB.BASEBOARD_FAB2(SCH_1):P12V   I258 @BASEBOARD_FAB2_LIB.BASEBOARD_FAB2(SCH_1):PAGE108
     9   P12V @BASEBOARD_FAB2_LIB.BASEBOARD_FAB2(SCH_1):P12V   I258 @BASEBOARD_FAB2_LIB.BASEBOARD_FAB2(SCH_1):PAGE108
    10   P12V @BASEBOARD_FAB2_LIB.BASEBOARD_FAB2(SCH_1):P12V   I258 @BASEBOARD_FAB2_LIB.BASEBOARD_FAB2(SCH_1):PAGE108
    11   P12V @BASEBOARD_FAB2_LIB.BASEBOARD_FAB2(SCH_1):P12V   I258 @BASEBOARD_FAB2_LIB.BASEBOARD_FAB2(SCH_1):PAGE108
    12   P12V @BASEBOARD_FAB2_LIB.BASEBOARD_FAB2(SCH_1):P12V   I258 @BASEBOARD_FAB2_LIB.BASEBOARD_FAB2(SCH_1):PAGE108
    13    GND @BASEBOARD_FAB2_LIB.BASEBOARD_FAB2(SCH_1):GND   I258 @BASEBOARD_FAB2_LIB.BASEBOARD_FAB2(SCH_1):PAGE108
    14    GND @BASEBOARD_FAB2_LIB.BASEBOARD_FAB2(SCH_1):GND   I258 @BASEBOARD_FAB2_LIB.BASEBOARD_FAB2(SCH_1):PAGE108
    15 SMB_SLOTX24_STBY_LVC3_SDA_R2 @BASEBOARD_FAB2_LIB.BASEBOARD_FAB2(SCH_1):SMB_SLOTX24_STBY_LVC3_SDA_R2   I258 @BASEBOARD_FAB2_LIB.BASEBOARD_FAB2(SCH_1):PAGE108
    16 IRQ_OOB_MGMT_RISER_ALERT_N @BASEBOARD_FAB2_LIB.BASEBOARD_FAB2(SCH_1):IRQ_OOB_MGMT_RISER_ALERT_N   I258 @BASEBOARD_FAB2_LIB.BASEBOARD_FAB2(SCH_1):PAGE108
    17 SMB_SLOTX24_STBY_LVC3_SCL_R2 @BASEBOARD_FAB2_LIB.BASEBOARD_FAB2(SCH_1):SMB_SLOTX24_STBY_LVC3_SCL_R2   I258 @BASEBOARD_FAB2_LIB.BASEBOARD_FAB2(SCH_1):PAGE108
    18 FM_SLT_CFG1 @BASEBOARD_FAB2_LIB.BASEBOARD_FAB2(SCH_1):FM_SLT_CFG1   I258 @BASEBOARD_FAB2_LIB.BASEBOARD_FAB2(SCH_1):PAGE108
    19 FM_SLT_CFG0 @BASEBOARD_FAB2_LIB.BASEBOARD_FAB2(SCH_1):FM_SLT_CFG0   I258 @BASEBOARD_FAB2_LIB.BASEBOARD_FAB2(SCH_1):PAGE108
    20 FM_PWRBRK_SLOT_N @BASEBOARD_FAB2_LIB.BASEBOARD_FAB2(SCH_1):FM_PWRBRK_SLOT_N   I258 @BASEBOARD_FAB2_LIB.BASEBOARD_FAB2(SCH_1):PAGE108
    21   P3V3 @BASEBOARD_FAB2_LIB.BASEBOARD_FAB2(SCH_1):P3V3   I258 @BASEBOARD_FAB2_LIB.BASEBOARD_FAB2(SCH_1):PAGE108
    22   P3V3 @BASEBOARD_FAB2_LIB.BASEBOARD_FAB2(SCH_1):P3V3   I258 @BASEBOARD_FAB2_LIB.BASEBOARD_FAB2(SCH_1):PAGE108
    23   P3V3 @BASEBOARD_FAB2_LIB.BASEBOARD_FAB2(SCH_1):P3V3   I258 @BASEBOARD_FAB2_LIB.BASEBOARD_FAB2(SCH_1):PAGE108
    24   P3V3 @BASEBOARD_FAB2_LIB.BASEBOARD_FAB2(SCH_1):P3V3   I258 @BASEBOARD_FAB2_LIB.BASEBOARD_FAB2(SCH_1):PAGE108
    25 P3V3_STBY @BASEBOARD_FAB2_LIB.BASEBOARD_FAB2(SCH_1):P3V3_STBY   I258 @BASEBOARD_FAB2_LIB.BASEBOARD_FAB2(SCH_1):PAGE108
    26    GND @BASEBOARD_FAB2_LIB.BASEBOARD_FAB2(SCH_1):GND   I258 @BASEBOARD_FAB2_LIB.BASEBOARD_FAB2(SCH_1):PAGE108
    27 PU_PCH_TLS_ENABLE_STRAP @BASEBOARD_FAB2_LIB.BASEBOARD_FAB2(SCH_1):PU_PCH_TLS_ENABLE_STRAP   I258 @BASEBOARD_FAB2_LIB.BASEBOARD_FAB2(SCH_1):PAGE108
    28 FM_PE_SLOTX24_WAKE_N @BASEBOARD_FAB2_LIB.BASEBOARD_FAB2(SCH_1):FM_PE_SLOTX24_WAKE_N   I258 @BASEBOARD_FAB2_LIB.BASEBOARD_FAB2(SCH_1):PAGE108
    29 RST_PCIE_RISER1_PERST_R_N @BASEBOARD_FAB2_LIB.BASEBOARD_FAB2(SCH_1):RST_PCIE_RISER1_PERST_R_N   I258 @BASEBOARD_FAB2_LIB.BASEBOARD_FAB2(SCH_1):PAGE108
    30 SMB_HOST_STBY_LVC3_SDA_R5 @BASEBOARD_FAB2_LIB.BASEBOARD_FAB2(SCH_1):SMB_HOST_STBY_LVC3_SDA_R5   I258 @BASEBOARD_FAB2_LIB.BASEBOARD_FAB2(SCH_1):PAGE108
    31    GND @BASEBOARD_FAB2_LIB.BASEBOARD_FAB2(SCH_1):GND   I258 @BASEBOARD_FAB2_LIB.BASEBOARD_FAB2(SCH_1):PAGE108
    32 SMB_HOST_STBY_LVC3_SCL_R5 @BASEBOARD_FAB2_LIB.BASEBOARD_FAB2(SCH_1):SMB_HOST_STBY_LVC3_SCL_R5   I258 @BASEBOARD_FAB2_LIB.BASEBOARD_FAB2(SCH_1):PAGE108
    33 CLK_100M_PCH_SLOTX24_S5_DP @BASEBOARD_FAB2_LIB.BASEBOARD_FAB2(SCH_1):CLK_100M_PCH_SLOTX24_S5_DP   I258 @BASEBOARD_FAB2_LIB.BASEBOARD_FAB2(SCH_1):PAGE108
    34    GND @BASEBOARD_FAB2_LIB.BASEBOARD_FAB2(SCH_1):GND   I258 @BASEBOARD_FAB2_LIB.BASEBOARD_FAB2(SCH_1):PAGE108
    35 CLK_100M_PCH_SLOTX24_S5_DN @BASEBOARD_FAB2_LIB.BASEBOARD_FAB2(SCH_1):CLK_100M_PCH_SLOTX24_S5_DN   I258 @BASEBOARD_FAB2_LIB.BASEBOARD_FAB2(SCH_1):PAGE108
    36 CLK_100M_PCH_SLOTX24_S4_DP @BASEBOARD_FAB2_LIB.BASEBOARD_FAB2(SCH_1):CLK_100M_PCH_SLOTX24_S4_DP   I258 @BASEBOARD_FAB2_LIB.BASEBOARD_FAB2(SCH_1):PAGE108
    37    GND @BASEBOARD_FAB2_LIB.BASEBOARD_FAB2(SCH_1):GND   I258 @BASEBOARD_FAB2_LIB.BASEBOARD_FAB2(SCH_1):PAGE108
    38 CLK_100M_PCH_SLOTX24_S4_DN @BASEBOARD_FAB2_LIB.BASEBOARD_FAB2(SCH_1):CLK_100M_PCH_SLOTX24_S4_DN   I258 @BASEBOARD_FAB2_LIB.BASEBOARD_FAB2(SCH_1):PAGE108
    39 CLK_100M_PCH_SLOTX24_S0_DP @BASEBOARD_FAB2_LIB.BASEBOARD_FAB2(SCH_1):CLK_100M_PCH_SLOTX24_S0_DP   I258 @BASEBOARD_FAB2_LIB.BASEBOARD_FAB2(SCH_1):PAGE108
    40    GND @BASEBOARD_FAB2_LIB.BASEBOARD_FAB2(SCH_1):GND   I258 @BASEBOARD_FAB2_LIB.BASEBOARD_FAB2(SCH_1):PAGE108
    41 CLK_100M_PCH_SLOTX24_S0_DN @BASEBOARD_FAB2_LIB.BASEBOARD_FAB2(SCH_1):CLK_100M_PCH_SLOTX24_S0_DN   I258 @BASEBOARD_FAB2_LIB.BASEBOARD_FAB2(SCH_1):PAGE108
    42 CLK_100M_PCH_SLOTX24_S1_DP @BASEBOARD_FAB2_LIB.BASEBOARD_FAB2(SCH_1):CLK_100M_PCH_SLOTX24_S1_DP   I258 @BASEBOARD_FAB2_LIB.BASEBOARD_FAB2(SCH_1):PAGE108
    43    GND @BASEBOARD_FAB2_LIB.BASEBOARD_FAB2(SCH_1):GND   I258 @BASEBOARD_FAB2_LIB.BASEBOARD_FAB2(SCH_1):PAGE108
    44 CLK_100M_PCH_SLOTX24_S1_DN @BASEBOARD_FAB2_LIB.BASEBOARD_FAB2(SCH_1):CLK_100M_PCH_SLOTX24_S1_DN   I258 @BASEBOARD_FAB2_LIB.BASEBOARD_FAB2(SCH_1):PAGE108
    45 CLK_100M_PCH_SLOTX24_S3_DP @BASEBOARD_FAB2_LIB.BASEBOARD_FAB2(SCH_1):CLK_100M_PCH_SLOTX24_S3_DP   I258 @BASEBOARD_FAB2_LIB.BASEBOARD_FAB2(SCH_1):PAGE108
    46    GND @BASEBOARD_FAB2_LIB.BASEBOARD_FAB2(SCH_1):GND   I258 @BASEBOARD_FAB2_LIB.BASEBOARD_FAB2(SCH_1):PAGE108
    47 CLK_100M_PCH_SLOTX24_S3_DN @BASEBOARD_FAB2_LIB.BASEBOARD_FAB2(SCH_1):CLK_100M_PCH_SLOTX24_S3_DN   I258 @BASEBOARD_FAB2_LIB.BASEBOARD_FAB2(SCH_1):PAGE108
    48 CLK_100M_PCH_SLOTX24_S2_DP @BASEBOARD_FAB2_LIB.BASEBOARD_FAB2(SCH_1):CLK_100M_PCH_SLOTX24_S2_DP   I258 @BASEBOARD_FAB2_LIB.BASEBOARD_FAB2(SCH_1):PAGE108
    49    GND @BASEBOARD_FAB2_LIB.BASEBOARD_FAB2(SCH_1):GND   I258 @BASEBOARD_FAB2_LIB.BASEBOARD_FAB2(SCH_1):PAGE108
    50 CLK_100M_PCH_SLOTX24_S2_DN @BASEBOARD_FAB2_LIB.BASEBOARD_FAB2(SCH_1):CLK_100M_PCH_SLOTX24_S2_DN   I258 @BASEBOARD_FAB2_LIB.BASEBOARD_FAB2(SCH_1):PAGE108
    51 P3E_CPU0_PE1_PCH_CON_TXN<15> @BASEBOARD_FAB2_LIB.BASEBOARD_FAB2(SCH_1):P3E_CPU0_PE1_PCH_CON_TXN(15)   I258 @BASEBOARD_FAB2_LIB.BASEBOARD_FAB2(SCH_1):PAGE108
    52    GND @BASEBOARD_FAB2_LIB.BASEBOARD_FAB2(SCH_1):GND   I258 @BASEBOARD_FAB2_LIB.BASEBOARD_FAB2(SCH_1):PAGE108
    53 P3E_CPU0_PE1_PCH_CON_TXP<15> @BASEBOARD_FAB2_LIB.BASEBOARD_FAB2(SCH_1):P3E_CPU0_PE1_PCH_CON_TXP(15)   I258 @BASEBOARD_FAB2_LIB.BASEBOARD_FAB2(SCH_1):PAGE108
    54 P3E_CPU0_PE1_PCH_CON_RXN<15> @BASEBOARD_FAB2_LIB.BASEBOARD_FAB2(SCH_1):P3E_CPU0_PE1_PCH_CON_RXN(15)   I258 @BASEBOARD_FAB2_LIB.BASEBOARD_FAB2(SCH_1):PAGE108
    55    GND @BASEBOARD_FAB2_LIB.BASEBOARD_FAB2(SCH_1):GND   I258 @BASEBOARD_FAB2_LIB.BASEBOARD_FAB2(SCH_1):PAGE108
    56 P3E_CPU0_PE1_PCH_CON_RXP<15> @BASEBOARD_FAB2_LIB.BASEBOARD_FAB2(SCH_1):P3E_CPU0_PE1_PCH_CON_RXP(15)   I258 @BASEBOARD_FAB2_LIB.BASEBOARD_FAB2(SCH_1):PAGE108
    57 P3E_CPU0_PE1_PCH_CON_TXP<14> @BASEBOARD_FAB2_LIB.BASEBOARD_FAB2(SCH_1):P3E_CPU0_PE1_PCH_CON_TXP(14)   I258 @BASEBOARD_FAB2_LIB.BASEBOARD_FAB2(SCH_1):PAGE108
    58    GND @BASEBOARD_FAB2_LIB.BASEBOARD_FAB2(SCH_1):GND   I258 @BASEBOARD_FAB2_LIB.BASEBOARD_FAB2(SCH_1):PAGE108
    59 P3E_CPU0_PE1_PCH_CON_TXN<14> @BASEBOARD_FAB2_LIB.BASEBOARD_FAB2(SCH_1):P3E_CPU0_PE1_PCH_CON_TXN(14)   I258 @BASEBOARD_FAB2_LIB.BASEBOARD_FAB2(SCH_1):PAGE108
    60 P3E_CPU0_PE1_PCH_CON_RXN<14> @BASEBOARD_FAB2_LIB.BASEBOARD_FAB2(SCH_1):P3E_CPU0_PE1_PCH_CON_RXN(14)   I258 @BASEBOARD_FAB2_LIB.BASEBOARD_FAB2(SCH_1):PAGE108
    61    GND @BASEBOARD_FAB2_LIB.BASEBOARD_FAB2(SCH_1):GND   I258 @BASEBOARD_FAB2_LIB.BASEBOARD_FAB2(SCH_1):PAGE108
    62 P3E_CPU0_PE1_PCH_CON_RXP<14> @BASEBOARD_FAB2_LIB.BASEBOARD_FAB2(SCH_1):P3E_CPU0_PE1_PCH_CON_RXP(14)   I258 @BASEBOARD_FAB2_LIB.BASEBOARD_FAB2(SCH_1):PAGE108
    63 TP_SLOTX24_RSVD63 @BASEBOARD_FAB2_LIB.BASEBOARD_FAB2(SCH_1):TP_SLOTX24_RSVD63   I258 @BASEBOARD_FAB2_LIB.BASEBOARD_FAB2(SCH_1):PAGE108
    64    GND @BASEBOARD_FAB2_LIB.BASEBOARD_FAB2(SCH_1):GND   I258 @BASEBOARD_FAB2_LIB.BASEBOARD_FAB2(SCH_1):PAGE108
    65    GND @BASEBOARD_FAB2_LIB.BASEBOARD_FAB2(SCH_1):GND   I258 @BASEBOARD_FAB2_LIB.BASEBOARD_FAB2(SCH_1):PAGE108
    66 TP_SLOTX24_RSVD66 @BASEBOARD_FAB2_LIB.BASEBOARD_FAB2(SCH_1):TP_SLOTX24_RSVD66   I258 @BASEBOARD_FAB2_LIB.BASEBOARD_FAB2(SCH_1):PAGE108
    67 P3E_CPU0_PE1_PCH_CON_TXN<13> @BASEBOARD_FAB2_LIB.BASEBOARD_FAB2(SCH_1):P3E_CPU0_PE1_PCH_CON_TXN(13)   I258 @BASEBOARD_FAB2_LIB.BASEBOARD_FAB2(SCH_1):PAGE108
    68    GND @BASEBOARD_FAB2_LIB.BASEBOARD_FAB2(SCH_1):GND   I258 @BASEBOARD_FAB2_LIB.BASEBOARD_FAB2(SCH_1):PAGE108
    69 P3E_CPU0_PE1_PCH_CON_TXP<13> @BASEBOARD_FAB2_LIB.BASEBOARD_FAB2(SCH_1):P3E_CPU0_PE1_PCH_CON_TXP(13)   I258 @BASEBOARD_FAB2_LIB.BASEBOARD_FAB2(SCH_1):PAGE108
    70 P3E_CPU0_PE1_PCH_CON_RXN<13> @BASEBOARD_FAB2_LIB.BASEBOARD_FAB2(SCH_1):P3E_CPU0_PE1_PCH_CON_RXN(13)   I258 @BASEBOARD_FAB2_LIB.BASEBOARD_FAB2(SCH_1):PAGE108
    71    GND @BASEBOARD_FAB2_LIB.BASEBOARD_FAB2(SCH_1):GND   I258 @BASEBOARD_FAB2_LIB.BASEBOARD_FAB2(SCH_1):PAGE108
    72 P3E_CPU0_PE1_PCH_CON_RXP<13> @BASEBOARD_FAB2_LIB.BASEBOARD_FAB2(SCH_1):P3E_CPU0_PE1_PCH_CON_RXP(13)   I258 @BASEBOARD_FAB2_LIB.BASEBOARD_FAB2(SCH_1):PAGE108
    73 P3E_CPU0_PE1_PCH_CON_TXN<12> @BASEBOARD_FAB2_LIB.BASEBOARD_FAB2(SCH_1):P3E_CPU0_PE1_PCH_CON_TXN(12)   I258 @BASEBOARD_FAB2_LIB.BASEBOARD_FAB2(SCH_1):PAGE108
    74    GND @BASEBOARD_FAB2_LIB.BASEBOARD_FAB2(SCH_1):GND   I258 @BASEBOARD_FAB2_LIB.BASEBOARD_FAB2(SCH_1):PAGE108
    75 P3E_CPU0_PE1_PCH_CON_TXP<12> @BASEBOARD_FAB2_LIB.BASEBOARD_FAB2(SCH_1):P3E_CPU0_PE1_PCH_CON_TXP(12)   I258 @BASEBOARD_FAB2_LIB.BASEBOARD_FAB2(SCH_1):PAGE108
    76 P3E_CPU0_PE1_PCH_CON_RXN<12> @BASEBOARD_FAB2_LIB.BASEBOARD_FAB2(SCH_1):P3E_CPU0_PE1_PCH_CON_RXN(12)   I258 @BASEBOARD_FAB2_LIB.BASEBOARD_FAB2(SCH_1):PAGE108
    77    GND @BASEBOARD_FAB2_LIB.BASEBOARD_FAB2(SCH_1):GND   I258 @BASEBOARD_FAB2_LIB.BASEBOARD_FAB2(SCH_1):PAGE108
    78 P3E_CPU0_PE1_PCH_CON_RXP<12> @BASEBOARD_FAB2_LIB.BASEBOARD_FAB2(SCH_1):P3E_CPU0_PE1_PCH_CON_RXP(12)   I258 @BASEBOARD_FAB2_LIB.BASEBOARD_FAB2(SCH_1):PAGE108
    79 P3E_CPU0_PE1_PCH_CON_TXN<11> @BASEBOARD_FAB2_LIB.BASEBOARD_FAB2(SCH_1):P3E_CPU0_PE1_PCH_CON_TXN(11)   I258 @BASEBOARD_FAB2_LIB.BASEBOARD_FAB2(SCH_1):PAGE108
    80    GND @BASEBOARD_FAB2_LIB.BASEBOARD_FAB2(SCH_1):GND   I258 @BASEBOARD_FAB2_LIB.BASEBOARD_FAB2(SCH_1):PAGE108
    81 P3E_CPU0_PE1_PCH_CON_TXP<11> @BASEBOARD_FAB2_LIB.BASEBOARD_FAB2(SCH_1):P3E_CPU0_PE1_PCH_CON_TXP(11)   I258 @BASEBOARD_FAB2_LIB.BASEBOARD_FAB2(SCH_1):PAGE108
    82 P3E_CPU0_PE1_PCH_CON_RXN<11> @BASEBOARD_FAB2_LIB.BASEBOARD_FAB2(SCH_1):P3E_CPU0_PE1_PCH_CON_RXN(11)   I258 @BASEBOARD_FAB2_LIB.BASEBOARD_FAB2(SCH_1):PAGE108
    83    GND @BASEBOARD_FAB2_LIB.BASEBOARD_FAB2(SCH_1):GND   I258 @BASEBOARD_FAB2_LIB.BASEBOARD_FAB2(SCH_1):PAGE108
    84 P3E_CPU0_PE1_PCH_CON_RXP<11> @BASEBOARD_FAB2_LIB.BASEBOARD_FAB2(SCH_1):P3E_CPU0_PE1_PCH_CON_RXP(11)   I258 @BASEBOARD_FAB2_LIB.BASEBOARD_FAB2(SCH_1):PAGE108
    85 P3E_CPU0_PE1_PCH_CON_TXN<10> @BASEBOARD_FAB2_LIB.BASEBOARD_FAB2(SCH_1):P3E_CPU0_PE1_PCH_CON_TXN(10)   I258 @BASEBOARD_FAB2_LIB.BASEBOARD_FAB2(SCH_1):PAGE108
    86    GND @BASEBOARD_FAB2_LIB.BASEBOARD_FAB2(SCH_1):GND   I258 @BASEBOARD_FAB2_LIB.BASEBOARD_FAB2(SCH_1):PAGE108
    87 P3E_CPU0_PE1_PCH_CON_TXP<10> @BASEBOARD_FAB2_LIB.BASEBOARD_FAB2(SCH_1):P3E_CPU0_PE1_PCH_CON_TXP(10)   I258 @BASEBOARD_FAB2_LIB.BASEBOARD_FAB2(SCH_1):PAGE108
    88 P3E_CPU0_PE1_PCH_CON_RXN<10> @BASEBOARD_FAB2_LIB.BASEBOARD_FAB2(SCH_1):P3E_CPU0_PE1_PCH_CON_RXN(10)   I258 @BASEBOARD_FAB2_LIB.BASEBOARD_FAB2(SCH_1):PAGE108
    89    GND @BASEBOARD_FAB2_LIB.BASEBOARD_FAB2(SCH_1):GND   I258 @BASEBOARD_FAB2_LIB.BASEBOARD_FAB2(SCH_1):PAGE108
    90 P3E_CPU0_PE1_PCH_CON_RXP<10> @BASEBOARD_FAB2_LIB.BASEBOARD_FAB2(SCH_1):P3E_CPU0_PE1_PCH_CON_RXP(10)   I258 @BASEBOARD_FAB2_LIB.BASEBOARD_FAB2(SCH_1):PAGE108
    91 P3E_CPU0_PE1_PCH_CON_TXN<9> @BASEBOARD_FAB2_LIB.BASEBOARD_FAB2(SCH_1):P3E_CPU0_PE1_PCH_CON_TXN(9)   I258 @BASEBOARD_FAB2_LIB.BASEBOARD_FAB2(SCH_1):PAGE108
    92    GND @BASEBOARD_FAB2_LIB.BASEBOARD_FAB2(SCH_1):GND   I258 @BASEBOARD_FAB2_LIB.BASEBOARD_FAB2(SCH_1):PAGE108
    93 P3E_CPU0_PE1_PCH_CON_TXP<9> @BASEBOARD_FAB2_LIB.BASEBOARD_FAB2(SCH_1):P3E_CPU0_PE1_PCH_CON_TXP(9)   I258 @BASEBOARD_FAB2_LIB.BASEBOARD_FAB2(SCH_1):PAGE108
    94 P3E_CPU0_PE1_PCH_CON_RXN<9> @BASEBOARD_FAB2_LIB.BASEBOARD_FAB2(SCH_1):P3E_CPU0_PE1_PCH_CON_RXN(9)   I258 @BASEBOARD_FAB2_LIB.BASEBOARD_FAB2(SCH_1):PAGE108
    95    GND @BASEBOARD_FAB2_LIB.BASEBOARD_FAB2(SCH_1):GND   I258 @BASEBOARD_FAB2_LIB.BASEBOARD_FAB2(SCH_1):PAGE108
    96 P3E_CPU0_PE1_PCH_CON_RXP<9> @BASEBOARD_FAB2_LIB.BASEBOARD_FAB2(SCH_1):P3E_CPU0_PE1_PCH_CON_RXP(9)   I258 @BASEBOARD_FAB2_LIB.BASEBOARD_FAB2(SCH_1):PAGE108
    97 P3E_CPU0_PE1_PCH_CON_TXN<8> @BASEBOARD_FAB2_LIB.BASEBOARD_FAB2(SCH_1):P3E_CPU0_PE1_PCH_CON_TXN(8)   I258 @BASEBOARD_FAB2_LIB.BASEBOARD_FAB2(SCH_1):PAGE108
    98    GND @BASEBOARD_FAB2_LIB.BASEBOARD_FAB2(SCH_1):GND   I258 @BASEBOARD_FAB2_LIB.BASEBOARD_FAB2(SCH_1):PAGE108
    99 P3E_CPU0_PE1_PCH_CON_TXP<8> @BASEBOARD_FAB2_LIB.BASEBOARD_FAB2(SCH_1):P3E_CPU0_PE1_PCH_CON_TXP(8)   I258 @BASEBOARD_FAB2_LIB.BASEBOARD_FAB2(SCH_1):PAGE108
   100 P3E_CPU0_PE1_PCH_CON_RXN<8> @BASEBOARD_FAB2_LIB.BASEBOARD_FAB2(SCH_1):P3E_CPU0_PE1_PCH_CON_RXN(8)   I258 @BASEBOARD_FAB2_LIB.BASEBOARD_FAB2(SCH_1):PAGE108
   MH1    GND @BASEBOARD_FAB2_LIB.BASEBOARD_FAB2(SCH_1):GND   I258 @BASEBOARD_FAB2_LIB.BASEBOARD_FAB2(SCH_1):PAGE108
   MH2    GND @BASEBOARD_FAB2_LIB.BASEBOARD_FAB2(SCH_1):GND   I258 @BASEBOARD_FAB2_LIB.BASEBOARD_FAB2(SCH_1):PAGE108
   101    GND @BASEBOARD_FAB2_LIB.BASEBOARD_FAB2(SCH_1):GND    I78 @BASEBOARD_FAB2_LIB.BASEBOARD_FAB2(SCH_1):PAGE109
   102 P3E_CPU0_PE1_PCH_CON_RXP<8> @BASEBOARD_FAB2_LIB.BASEBOARD_FAB2(SCH_1):P3E_CPU0_PE1_PCH_CON_RXP(8)    I78 @BASEBOARD_FAB2_LIB.BASEBOARD_FAB2(SCH_1):PAGE109
   103 P3E_CPU0_PE1_SS_C_TXP<7> @BASEBOARD_FAB2_LIB.BASEBOARD_FAB2(SCH_1):P3E_CPU0_PE1_SS_C_TXP(7)    I78 @BASEBOARD_FAB2_LIB.BASEBOARD_FAB2(SCH_1):PAGE109
   104    GND @BASEBOARD_FAB2_LIB.BASEBOARD_FAB2(SCH_1):GND    I78 @BASEBOARD_FAB2_LIB.BASEBOARD_FAB2(SCH_1):PAGE109
   105 P3E_CPU0_PE1_SS_C_TXN<7> @BASEBOARD_FAB2_LIB.BASEBOARD_FAB2(SCH_1):P3E_CPU0_PE1_SS_C_TXN(7)    I78 @BASEBOARD_FAB2_LIB.BASEBOARD_FAB2(SCH_1):PAGE109
   106 P3E_CPU0_PE1_SS_R_RXN<7> @BASEBOARD_FAB2_LIB.BASEBOARD_FAB2(SCH_1):P3E_CPU0_PE1_SS_R_RXN(7)    I78 @BASEBOARD_FAB2_LIB.BASEBOARD_FAB2(SCH_1):PAGE109
   107    GND @BASEBOARD_FAB2_LIB.BASEBOARD_FAB2(SCH_1):GND    I78 @BASEBOARD_FAB2_LIB.BASEBOARD_FAB2(SCH_1):PAGE109
   108 P3E_CPU0_PE1_SS_R_RXP<7> @BASEBOARD_FAB2_LIB.BASEBOARD_FAB2(SCH_1):P3E_CPU0_PE1_SS_R_RXP(7)    I78 @BASEBOARD_FAB2_LIB.BASEBOARD_FAB2(SCH_1):PAGE109
   109 P3E_CPU0_PE1_SS_C_TXN<6> @BASEBOARD_FAB2_LIB.BASEBOARD_FAB2(SCH_1):P3E_CPU0_PE1_SS_C_TXN(6)    I78 @BASEBOARD_FAB2_LIB.BASEBOARD_FAB2(SCH_1):PAGE109
   110    GND @BASEBOARD_FAB2_LIB.BASEBOARD_FAB2(SCH_1):GND    I78 @BASEBOARD_FAB2_LIB.BASEBOARD_FAB2(SCH_1):PAGE109
   111 P3E_CPU0_PE1_SS_C_TXP<6> @BASEBOARD_FAB2_LIB.BASEBOARD_FAB2(SCH_1):P3E_CPU0_PE1_SS_C_TXP(6)    I78 @BASEBOARD_FAB2_LIB.BASEBOARD_FAB2(SCH_1):PAGE109
   112 P3E_CPU0_PE1_SS_R_RXN<6> @BASEBOARD_FAB2_LIB.BASEBOARD_FAB2(SCH_1):P3E_CPU0_PE1_SS_R_RXN(6)    I78 @BASEBOARD_FAB2_LIB.BASEBOARD_FAB2(SCH_1):PAGE109
   113    GND @BASEBOARD_FAB2_LIB.BASEBOARD_FAB2(SCH_1):GND    I78 @BASEBOARD_FAB2_LIB.BASEBOARD_FAB2(SCH_1):PAGE109
   114 P3E_CPU0_PE1_SS_R_RXP<6> @BASEBOARD_FAB2_LIB.BASEBOARD_FAB2(SCH_1):P3E_CPU0_PE1_SS_R_RXP(6)    I78 @BASEBOARD_FAB2_LIB.BASEBOARD_FAB2(SCH_1):PAGE109
   115 P3E_CPU0_PE1_SS_C_TXN<5> @BASEBOARD_FAB2_LIB.BASEBOARD_FAB2(SCH_1):P3E_CPU0_PE1_SS_C_TXN(5)    I78 @BASEBOARD_FAB2_LIB.BASEBOARD_FAB2(SCH_1):PAGE109
   116    GND @BASEBOARD_FAB2_LIB.BASEBOARD_FAB2(SCH_1):GND    I78 @BASEBOARD_FAB2_LIB.BASEBOARD_FAB2(SCH_1):PAGE109
   117 P3E_CPU0_PE1_SS_C_TXP<5> @BASEBOARD_FAB2_LIB.BASEBOARD_FAB2(SCH_1):P3E_CPU0_PE1_SS_C_TXP(5)    I78 @BASEBOARD_FAB2_LIB.BASEBOARD_FAB2(SCH_1):PAGE109
   118 P3E_CPU0_PE1_SS_R_RXN<5> @BASEBOARD_FAB2_LIB.BASEBOARD_FAB2(SCH_1):P3E_CPU0_PE1_SS_R_RXN(5)    I78 @BASEBOARD_FAB2_LIB.BASEBOARD_FAB2(SCH_1):PAGE109
   119    GND @BASEBOARD_FAB2_LIB.BASEBOARD_FAB2(SCH_1):GND    I78 @BASEBOARD_FAB2_LIB.BASEBOARD_FAB2(SCH_1):PAGE109
   120 P3E_CPU0_PE1_SS_R_RXP<5> @BASEBOARD_FAB2_LIB.BASEBOARD_FAB2(SCH_1):P3E_CPU0_PE1_SS_R_RXP(5)    I78 @BASEBOARD_FAB2_LIB.BASEBOARD_FAB2(SCH_1):PAGE109
   121 P3E_CPU0_PE1_SS_C_TXN<4> @BASEBOARD_FAB2_LIB.BASEBOARD_FAB2(SCH_1):P3E_CPU0_PE1_SS_C_TXN(4)    I78 @BASEBOARD_FAB2_LIB.BASEBOARD_FAB2(SCH_1):PAGE109
   122    GND @BASEBOARD_FAB2_LIB.BASEBOARD_FAB2(SCH_1):GND    I78 @BASEBOARD_FAB2_LIB.BASEBOARD_FAB2(SCH_1):PAGE109
   123 P3E_CPU0_PE1_SS_C_TXP<4> @BASEBOARD_FAB2_LIB.BASEBOARD_FAB2(SCH_1):P3E_CPU0_PE1_SS_C_TXP(4)    I78 @BASEBOARD_FAB2_LIB.BASEBOARD_FAB2(SCH_1):PAGE109
   124 P3E_CPU0_PE1_SS_R_RXN<4> @BASEBOARD_FAB2_LIB.BASEBOARD_FAB2(SCH_1):P3E_CPU0_PE1_SS_R_RXN(4)    I78 @BASEBOARD_FAB2_LIB.BASEBOARD_FAB2(SCH_1):PAGE109
   125    GND @BASEBOARD_FAB2_LIB.BASEBOARD_FAB2(SCH_1):GND    I78 @BASEBOARD_FAB2_LIB.BASEBOARD_FAB2(SCH_1):PAGE109
   126 P3E_CPU0_PE1_SS_R_RXP<4> @BASEBOARD_FAB2_LIB.BASEBOARD_FAB2(SCH_1):P3E_CPU0_PE1_SS_R_RXP(4)    I78 @BASEBOARD_FAB2_LIB.BASEBOARD_FAB2(SCH_1):PAGE109
   127 P3E_CPU0_PE1_SS_C_TXN<3> @BASEBOARD_FAB2_LIB.BASEBOARD_FAB2(SCH_1):P3E_CPU0_PE1_SS_C_TXN(3)    I78 @BASEBOARD_FAB2_LIB.BASEBOARD_FAB2(SCH_1):PAGE109
   128    GND @BASEBOARD_FAB2_LIB.BASEBOARD_FAB2(SCH_1):GND    I78 @BASEBOARD_FAB2_LIB.BASEBOARD_FAB2(SCH_1):PAGE109
   129 P3E_CPU0_PE1_SS_C_TXP<3> @BASEBOARD_FAB2_LIB.BASEBOARD_FAB2(SCH_1):P3E_CPU0_PE1_SS_C_TXP(3)    I78 @BASEBOARD_FAB2_LIB.BASEBOARD_FAB2(SCH_1):PAGE109
   130 P3E_CPU0_PE1_SS_R_RXN<3> @BASEBOARD_FAB2_LIB.BASEBOARD_FAB2(SCH_1):P3E_CPU0_PE1_SS_R_RXN(3)    I78 @BASEBOARD_FAB2_LIB.BASEBOARD_FAB2(SCH_1):PAGE109
   131    GND @BASEBOARD_FAB2_LIB.BASEBOARD_FAB2(SCH_1):GND    I78 @BASEBOARD_FAB2_LIB.BASEBOARD_FAB2(SCH_1):PAGE109
   132 P3E_CPU0_PE1_SS_R_RXP<3> @BASEBOARD_FAB2_LIB.BASEBOARD_FAB2(SCH_1):P3E_CPU0_PE1_SS_R_RXP(3)    I78 @BASEBOARD_FAB2_LIB.BASEBOARD_FAB2(SCH_1):PAGE109
   133 P3E_CPU0_PE1_SS_C_TXN<2> @BASEBOARD_FAB2_LIB.BASEBOARD_FAB2(SCH_1):P3E_CPU0_PE1_SS_C_TXN(2)    I78 @BASEBOARD_FAB2_LIB.BASEBOARD_FAB2(SCH_1):PAGE109
   134    GND @BASEBOARD_FAB2_LIB.BASEBOARD_FAB2(SCH_1):GND    I78 @BASEBOARD_FAB2_LIB.BASEBOARD_FAB2(SCH_1):PAGE109
   135 P3E_CPU0_PE1_SS_C_TXP<2> @BASEBOARD_FAB2_LIB.BASEBOARD_FAB2(SCH_1):P3E_CPU0_PE1_SS_C_TXP(2)    I78 @BASEBOARD_FAB2_LIB.BASEBOARD_FAB2(SCH_1):PAGE109
   136 P3E_CPU0_PE1_SS_R_RXN<2> @BASEBOARD_FAB2_LIB.BASEBOARD_FAB2(SCH_1):P3E_CPU0_PE1_SS_R_RXN(2)    I78 @BASEBOARD_FAB2_LIB.BASEBOARD_FAB2(SCH_1):PAGE109
   137    GND @BASEBOARD_FAB2_LIB.BASEBOARD_FAB2(SCH_1):GND    I78 @BASEBOARD_FAB2_LIB.BASEBOARD_FAB2(SCH_1):PAGE109
   138 P3E_CPU0_PE1_SS_R_RXP<2> @BASEBOARD_FAB2_LIB.BASEBOARD_FAB2(SCH_1):P3E_CPU0_PE1_SS_R_RXP(2)    I78 @BASEBOARD_FAB2_LIB.BASEBOARD_FAB2(SCH_1):PAGE109
   139 P3E_CPU0_PE1_SS_C_TXN<1> @BASEBOARD_FAB2_LIB.BASEBOARD_FAB2(SCH_1):P3E_CPU0_PE1_SS_C_TXN(1)    I78 @BASEBOARD_FAB2_LIB.BASEBOARD_FAB2(SCH_1):PAGE109
   140    GND @BASEBOARD_FAB2_LIB.BASEBOARD_FAB2(SCH_1):GND    I78 @BASEBOARD_FAB2_LIB.BASEBOARD_FAB2(SCH_1):PAGE109
   141 P3E_CPU0_PE1_SS_C_TXP<1> @BASEBOARD_FAB2_LIB.BASEBOARD_FAB2(SCH_1):P3E_CPU0_PE1_SS_C_TXP(1)    I78 @BASEBOARD_FAB2_LIB.BASEBOARD_FAB2(SCH_1):PAGE109
   142 P3E_CPU0_PE1_SS_R_RXN<1> @BASEBOARD_FAB2_LIB.BASEBOARD_FAB2(SCH_1):P3E_CPU0_PE1_SS_R_RXN(1)    I78 @BASEBOARD_FAB2_LIB.BASEBOARD_FAB2(SCH_1):PAGE109
   143    GND @BASEBOARD_FAB2_LIB.BASEBOARD_FAB2(SCH_1):GND    I78 @BASEBOARD_FAB2_LIB.BASEBOARD_FAB2(SCH_1):PAGE109
   144 P3E_CPU0_PE1_SS_R_RXP<1> @BASEBOARD_FAB2_LIB.BASEBOARD_FAB2(SCH_1):P3E_CPU0_PE1_SS_R_RXP(1)    I78 @BASEBOARD_FAB2_LIB.BASEBOARD_FAB2(SCH_1):PAGE109
   145 P3E_CPU0_PE1_SS_C_TXN<0> @BASEBOARD_FAB2_LIB.BASEBOARD_FAB2(SCH_1):P3E_CPU0_PE1_SS_C_TXN(0)    I78 @BASEBOARD_FAB2_LIB.BASEBOARD_FAB2(SCH_1):PAGE109
   146    GND @BASEBOARD_FAB2_LIB.BASEBOARD_FAB2(SCH_1):GND    I78 @BASEBOARD_FAB2_LIB.BASEBOARD_FAB2(SCH_1):PAGE109
   147 P3E_CPU0_PE1_SS_C_TXP<0> @BASEBOARD_FAB2_LIB.BASEBOARD_FAB2(SCH_1):P3E_CPU0_PE1_SS_C_TXP(0)    I78 @BASEBOARD_FAB2_LIB.BASEBOARD_FAB2(SCH_1):PAGE109
   148 P3E_CPU0_PE1_SS_R_RXN<0> @BASEBOARD_FAB2_LIB.BASEBOARD_FAB2(SCH_1):P3E_CPU0_PE1_SS_R_RXN(0)    I78 @BASEBOARD_FAB2_LIB.BASEBOARD_FAB2(SCH_1):PAGE109
   149    GND @BASEBOARD_FAB2_LIB.BASEBOARD_FAB2(SCH_1):GND    I78 @BASEBOARD_FAB2_LIB.BASEBOARD_FAB2(SCH_1):PAGE109
   150 P3E_CPU0_PE1_SS_R_RXP<0> @BASEBOARD_FAB2_LIB.BASEBOARD_FAB2(SCH_1):P3E_CPU0_PE1_SS_R_RXP(0)    I78 @BASEBOARD_FAB2_LIB.BASEBOARD_FAB2(SCH_1):PAGE109
   151 P3E_CPU0_PE2_SS_C_TXN<0> @BASEBOARD_FAB2_LIB.BASEBOARD_FAB2(SCH_1):P3E_CPU0_PE2_SS_C_TXN(0)    I78 @BASEBOARD_FAB2_LIB.BASEBOARD_FAB2(SCH_1):PAGE109
   152    GND @BASEBOARD_FAB2_LIB.BASEBOARD_FAB2(SCH_1):GND    I78 @BASEBOARD_FAB2_LIB.BASEBOARD_FAB2(SCH_1):PAGE109
   153 P3E_CPU0_PE2_SS_C_TXP<0> @BASEBOARD_FAB2_LIB.BASEBOARD_FAB2(SCH_1):P3E_CPU0_PE2_SS_C_TXP(0)    I78 @BASEBOARD_FAB2_LIB.BASEBOARD_FAB2(SCH_1):PAGE109
   154 P3E_CPU0_PE2_SS_RXN<0> @BASEBOARD_FAB2_LIB.BASEBOARD_FAB2(SCH_1):P3E_CPU0_PE2_SS_RXN(0)    I78 @BASEBOARD_FAB2_LIB.BASEBOARD_FAB2(SCH_1):PAGE109
   155    GND @BASEBOARD_FAB2_LIB.BASEBOARD_FAB2(SCH_1):GND    I78 @BASEBOARD_FAB2_LIB.BASEBOARD_FAB2(SCH_1):PAGE109
   156 P3E_CPU0_PE2_SS_RXP<0> @BASEBOARD_FAB2_LIB.BASEBOARD_FAB2(SCH_1):P3E_CPU0_PE2_SS_RXP(0)    I78 @BASEBOARD_FAB2_LIB.BASEBOARD_FAB2(SCH_1):PAGE109
   157 P3E_CPU0_PE2_SS_C_TXP<1> @BASEBOARD_FAB2_LIB.BASEBOARD_FAB2(SCH_1):P3E_CPU0_PE2_SS_C_TXP(1)    I78 @BASEBOARD_FAB2_LIB.BASEBOARD_FAB2(SCH_1):PAGE109
   158    GND @BASEBOARD_FAB2_LIB.BASEBOARD_FAB2(SCH_1):GND    I78 @BASEBOARD_FAB2_LIB.BASEBOARD_FAB2(SCH_1):PAGE109
   159 P3E_CPU0_PE2_SS_C_TXN<1> @BASEBOARD_FAB2_LIB.BASEBOARD_FAB2(SCH_1):P3E_CPU0_PE2_SS_C_TXN(1)    I78 @BASEBOARD_FAB2_LIB.BASEBOARD_FAB2(SCH_1):PAGE109
   160 P3E_CPU0_PE2_SS_RXN<1> @BASEBOARD_FAB2_LIB.BASEBOARD_FAB2(SCH_1):P3E_CPU0_PE2_SS_RXN(1)    I78 @BASEBOARD_FAB2_LIB.BASEBOARD_FAB2(SCH_1):PAGE109
   161    GND @BASEBOARD_FAB2_LIB.BASEBOARD_FAB2(SCH_1):GND    I78 @BASEBOARD_FAB2_LIB.BASEBOARD_FAB2(SCH_1):PAGE109
   162 P3E_CPU0_PE2_SS_RXP<1> @BASEBOARD_FAB2_LIB.BASEBOARD_FAB2(SCH_1):P3E_CPU0_PE2_SS_RXP(1)    I78 @BASEBOARD_FAB2_LIB.BASEBOARD_FAB2(SCH_1):PAGE109
   163 P3E_CPU0_PE2_SS_C_TXN<2> @BASEBOARD_FAB2_LIB.BASEBOARD_FAB2(SCH_1):P3E_CPU0_PE2_SS_C_TXN(2)    I78 @BASEBOARD_FAB2_LIB.BASEBOARD_FAB2(SCH_1):PAGE109
   164    GND @BASEBOARD_FAB2_LIB.BASEBOARD_FAB2(SCH_1):GND    I78 @BASEBOARD_FAB2_LIB.BASEBOARD_FAB2(SCH_1):PAGE109
   165 P3E_CPU0_PE2_SS_C_TXP<2> @BASEBOARD_FAB2_LIB.BASEBOARD_FAB2(SCH_1):P3E_CPU0_PE2_SS_C_TXP(2)    I78 @BASEBOARD_FAB2_LIB.BASEBOARD_FAB2(SCH_1):PAGE109
   166 P3E_CPU0_PE2_SS_RXN<2> @BASEBOARD_FAB2_LIB.BASEBOARD_FAB2(SCH_1):P3E_CPU0_PE2_SS_RXN(2)    I78 @BASEBOARD_FAB2_LIB.BASEBOARD_FAB2(SCH_1):PAGE109
   167    GND @BASEBOARD_FAB2_LIB.BASEBOARD_FAB2(SCH_1):GND    I78 @BASEBOARD_FAB2_LIB.BASEBOARD_FAB2(SCH_1):PAGE109
   168 P3E_CPU0_PE2_SS_RXP<2> @BASEBOARD_FAB2_LIB.BASEBOARD_FAB2(SCH_1):P3E_CPU0_PE2_SS_RXP(2)    I78 @BASEBOARD_FAB2_LIB.BASEBOARD_FAB2(SCH_1):PAGE109
   169 P3E_CPU0_PE2_SS_C_TXN<3> @BASEBOARD_FAB2_LIB.BASEBOARD_FAB2(SCH_1):P3E_CPU0_PE2_SS_C_TXN(3)    I78 @BASEBOARD_FAB2_LIB.BASEBOARD_FAB2(SCH_1):PAGE109
   170    GND @BASEBOARD_FAB2_LIB.BASEBOARD_FAB2(SCH_1):GND    I78 @BASEBOARD_FAB2_LIB.BASEBOARD_FAB2(SCH_1):PAGE109
   171 P3E_CPU0_PE2_SS_C_TXP<3> @BASEBOARD_FAB2_LIB.BASEBOARD_FAB2(SCH_1):P3E_CPU0_PE2_SS_C_TXP(3)    I78 @BASEBOARD_FAB2_LIB.BASEBOARD_FAB2(SCH_1):PAGE109
   172 P3E_CPU0_PE2_SS_RXN<3> @BASEBOARD_FAB2_LIB.BASEBOARD_FAB2(SCH_1):P3E_CPU0_PE2_SS_RXN(3)    I78 @BASEBOARD_FAB2_LIB.BASEBOARD_FAB2(SCH_1):PAGE109
   173    GND @BASEBOARD_FAB2_LIB.BASEBOARD_FAB2(SCH_1):GND    I78 @BASEBOARD_FAB2_LIB.BASEBOARD_FAB2(SCH_1):PAGE109
   174 P3E_CPU0_PE2_SS_RXP<3> @BASEBOARD_FAB2_LIB.BASEBOARD_FAB2(SCH_1):P3E_CPU0_PE2_SS_RXP(3)    I78 @BASEBOARD_FAB2_LIB.BASEBOARD_FAB2(SCH_1):PAGE109
   175 P3E_CPU0_PE2_SS_C_TXN<4> @BASEBOARD_FAB2_LIB.BASEBOARD_FAB2(SCH_1):P3E_CPU0_PE2_SS_C_TXN(4)    I78 @BASEBOARD_FAB2_LIB.BASEBOARD_FAB2(SCH_1):PAGE109
   176    GND @BASEBOARD_FAB2_LIB.BASEBOARD_FAB2(SCH_1):GND    I78 @BASEBOARD_FAB2_LIB.BASEBOARD_FAB2(SCH_1):PAGE109
   177 P3E_CPU0_PE2_SS_C_TXP<4> @BASEBOARD_FAB2_LIB.BASEBOARD_FAB2(SCH_1):P3E_CPU0_PE2_SS_C_TXP(4)    I78 @BASEBOARD_FAB2_LIB.BASEBOARD_FAB2(SCH_1):PAGE109
   178 P3E_CPU0_PE2_SS_RXN<4> @BASEBOARD_FAB2_LIB.BASEBOARD_FAB2(SCH_1):P3E_CPU0_PE2_SS_RXN(4)    I78 @BASEBOARD_FAB2_LIB.BASEBOARD_FAB2(SCH_1):PAGE109
   179    GND @BASEBOARD_FAB2_LIB.BASEBOARD_FAB2(SCH_1):GND    I78 @BASEBOARD_FAB2_LIB.BASEBOARD_FAB2(SCH_1):PAGE109
   180 P3E_CPU0_PE2_SS_RXP<4> @BASEBOARD_FAB2_LIB.BASEBOARD_FAB2(SCH_1):P3E_CPU0_PE2_SS_RXP(4)    I78 @BASEBOARD_FAB2_LIB.BASEBOARD_FAB2(SCH_1):PAGE109
   181 P3E_CPU0_PE2_SS_C_TXN<5> @BASEBOARD_FAB2_LIB.BASEBOARD_FAB2(SCH_1):P3E_CPU0_PE2_SS_C_TXN(5)    I78 @BASEBOARD_FAB2_LIB.BASEBOARD_FAB2(SCH_1):PAGE109
   182    GND @BASEBOARD_FAB2_LIB.BASEBOARD_FAB2(SCH_1):GND    I78 @BASEBOARD_FAB2_LIB.BASEBOARD_FAB2(SCH_1):PAGE109
   183 P3E_CPU0_PE2_SS_C_TXP<5> @BASEBOARD_FAB2_LIB.BASEBOARD_FAB2(SCH_1):P3E_CPU0_PE2_SS_C_TXP(5)    I78 @BASEBOARD_FAB2_LIB.BASEBOARD_FAB2(SCH_1):PAGE109
   184 P3E_CPU0_PE2_SS_RXN<5> @BASEBOARD_FAB2_LIB.BASEBOARD_FAB2(SCH_1):P3E_CPU0_PE2_SS_RXN(5)    I78 @BASEBOARD_FAB2_LIB.BASEBOARD_FAB2(SCH_1):PAGE109
   185    GND @BASEBOARD_FAB2_LIB.BASEBOARD_FAB2(SCH_1):GND    I78 @BASEBOARD_FAB2_LIB.BASEBOARD_FAB2(SCH_1):PAGE109
   186 P3E_CPU0_PE2_SS_RXP<5> @BASEBOARD_FAB2_LIB.BASEBOARD_FAB2(SCH_1):P3E_CPU0_PE2_SS_RXP(5)    I78 @BASEBOARD_FAB2_LIB.BASEBOARD_FAB2(SCH_1):PAGE109
   187 P3E_CPU0_PE2_SS_C_TXN<6> @BASEBOARD_FAB2_LIB.BASEBOARD_FAB2(SCH_1):P3E_CPU0_PE2_SS_C_TXN(6)    I78 @BASEBOARD_FAB2_LIB.BASEBOARD_FAB2(SCH_1):PAGE109
   188    GND @BASEBOARD_FAB2_LIB.BASEBOARD_FAB2(SCH_1):GND    I78 @BASEBOARD_FAB2_LIB.BASEBOARD_FAB2(SCH_1):PAGE109
   189 P3E_CPU0_PE2_SS_C_TXP<6> @BASEBOARD_FAB2_LIB.BASEBOARD_FAB2(SCH_1):P3E_CPU0_PE2_SS_C_TXP(6)    I78 @BASEBOARD_FAB2_LIB.BASEBOARD_FAB2(SCH_1):PAGE109
   190 P3E_CPU0_PE2_SS_RXP<6> @BASEBOARD_FAB2_LIB.BASEBOARD_FAB2(SCH_1):P3E_CPU0_PE2_SS_RXP(6)    I78 @BASEBOARD_FAB2_LIB.BASEBOARD_FAB2(SCH_1):PAGE109
   191    GND @BASEBOARD_FAB2_LIB.BASEBOARD_FAB2(SCH_1):GND    I78 @BASEBOARD_FAB2_LIB.BASEBOARD_FAB2(SCH_1):PAGE109
   192 P3E_CPU0_PE2_SS_RXN<6> @BASEBOARD_FAB2_LIB.BASEBOARD_FAB2(SCH_1):P3E_CPU0_PE2_SS_RXN(6)    I78 @BASEBOARD_FAB2_LIB.BASEBOARD_FAB2(SCH_1):PAGE109
   193 P3E_CPU0_PE2_SS_C_TXN<7> @BASEBOARD_FAB2_LIB.BASEBOARD_FAB2(SCH_1):P3E_CPU0_PE2_SS_C_TXN(7)    I78 @BASEBOARD_FAB2_LIB.BASEBOARD_FAB2(SCH_1):PAGE109
   194    GND @BASEBOARD_FAB2_LIB.BASEBOARD_FAB2(SCH_1):GND    I78 @BASEBOARD_FAB2_LIB.BASEBOARD_FAB2(SCH_1):PAGE109
   195 P3E_CPU0_PE2_SS_C_TXP<7> @BASEBOARD_FAB2_LIB.BASEBOARD_FAB2(SCH_1):P3E_CPU0_PE2_SS_C_TXP(7)    I78 @BASEBOARD_FAB2_LIB.BASEBOARD_FAB2(SCH_1):PAGE109
   196 P3E_CPU0_PE2_SS_RXN<7> @BASEBOARD_FAB2_LIB.BASEBOARD_FAB2(SCH_1):P3E_CPU0_PE2_SS_RXN(7)    I78 @BASEBOARD_FAB2_LIB.BASEBOARD_FAB2(SCH_1):PAGE109
   197    GND @BASEBOARD_FAB2_LIB.BASEBOARD_FAB2(SCH_1):GND    I78 @BASEBOARD_FAB2_LIB.BASEBOARD_FAB2(SCH_1):PAGE109
   198 P3E_CPU0_PE2_SS_RXP<7> @BASEBOARD_FAB2_LIB.BASEBOARD_FAB2(SCH_1):P3E_CPU0_PE2_SS_RXP(7)    I78 @BASEBOARD_FAB2_LIB.BASEBOARD_FAB2(SCH_1):PAGE109
   199 FM_PRSNT_2_6_N @BASEBOARD_FAB2_LIB.BASEBOARD_FAB2(SCH_1):FM_PRSNT_2_6_N    I78 @BASEBOARD_FAB2_LIB.BASEBOARD_FAB2(SCH_1):PAGE109
   200    GND @BASEBOARD_FAB2_LIB.BASEBOARD_FAB2(SCH_1):GND    I78 @BASEBOARD_FAB2_LIB.BASEBOARD_FAB2(SCH_1):PAGE109

J8G2 CONN12_C73564003_PIP-CONN,C735A
     1 TP_JUMPER_BLOCK_1_1 @BASEBOARD_FAB2_LIB.BASEBOARD_FAB2(SCH_1):TP_JUMPER_BLOCK_1_1   I124 @BASEBOARD_FAB2_LIB.BASEBOARD_FAB2(SCH_1):PAGE135
    10 FM_DIS_ADR_DLY @BASEBOARD_FAB2_LIB.BASEBOARD_FAB2(SCH_1):FM_DIS_ADR_DLY   I124 @BASEBOARD_FAB2_LIB.BASEBOARD_FAB2(SCH_1):PAGE135
    11    GND @BASEBOARD_FAB2_LIB.BASEBOARD_FAB2(SCH_1):GND   I124 @BASEBOARD_FAB2_LIB.BASEBOARD_FAB2(SCH_1):PAGE135
    12    GND @BASEBOARD_FAB2_LIB.BASEBOARD_FAB2(SCH_1):GND   I124 @BASEBOARD_FAB2_LIB.BASEBOARD_FAB2(SCH_1):PAGE135
     2 TP_JUMPER_BLOCK_1_2 @BASEBOARD_FAB2_LIB.BASEBOARD_FAB2(SCH_1):TP_JUMPER_BLOCK_1_2   I124 @BASEBOARD_FAB2_LIB.BASEBOARD_FAB2(SCH_1):PAGE135
     3 RST_BMC_SRST_N @BASEBOARD_FAB2_LIB.BASEBOARD_FAB2(SCH_1):RST_BMC_SRST_N   I124 @BASEBOARD_FAB2_LIB.BASEBOARD_FAB2(SCH_1):PAGE135
     4 FM_IE_DISABLE_N @BASEBOARD_FAB2_LIB.BASEBOARD_FAB2(SCH_1):FM_IE_DISABLE_N   I124 @BASEBOARD_FAB2_LIB.BASEBOARD_FAB2(SCH_1):PAGE135
     5    GND @BASEBOARD_FAB2_LIB.BASEBOARD_FAB2(SCH_1):GND   I124 @BASEBOARD_FAB2_LIB.BASEBOARD_FAB2(SCH_1):PAGE135
     6    GND @BASEBOARD_FAB2_LIB.BASEBOARD_FAB2(SCH_1):GND   I124 @BASEBOARD_FAB2_LIB.BASEBOARD_FAB2(SCH_1):PAGE135
     7 TP_JUMPER_BLOCK_1_7 @BASEBOARD_FAB2_LIB.BASEBOARD_FAB2(SCH_1):TP_JUMPER_BLOCK_ 1_7   I124 @BASEBOARD_FAB2_LIB.BASEBOARD_FAB2(SCH_1):PAGE135
     8 TP_JUMPER_BLOCK_1_8 @BASEBOARD_FAB2_LIB.BASEBOARD_FAB2(SCH_1):TP_JUMPER_BLOCK_1_8   I124 @BASEBOARD_FAB2_LIB.BASEBOARD_FAB2(SCH_1):PAGE135
     9 FM_CPLD_UART_CH_LOCK_N @BASEBOARD_FAB2_LIB.BASEBOARD_FAB2(SCH_1):FM_CPLD_UART_CH_LOCK_N   I124 @BASEBOARD_FAB2_LIB.BASEBOARD_FAB2(SCH_1):PAGE135

J9A1 CONN4_D42317002_PIP-CONN,D4231A
     1    GND @BASEBOARD_FAB2_LIB.BASEBOARD_FAB2(SCH_1):GND   I131 @BASEBOARD_FAB2_LIB.BASEBOARD_FAB2(SCH_1):PAGE135
     2 PU_KEY_CONN_PIN2_R @BASEBOARD_FAB2_LIB.BASEBOARD_FAB2(SCH_1):PU_KEY_CONN_PIN2_R   I131 @BASEBOARD_FAB2_LIB.BASEBOARD_FAB2(SCH_1):PAGE135
     3    GND @BASEBOARD_FAB2_LIB.BASEBOARD_FAB2(SCH_1):GND   I131 @BASEBOARD_FAB2_LIB.BASEBOARD_FAB2(SCH_1):PAGE135
     4 FM_PCH_SATA_RAID_KEY_R @BASEBOARD_FAB2_LIB.BASEBOARD_FAB2(SCH_1):FM_PCH_SATA_RAID_KEY_R   I131 @BASEBOARD_FAB2_LIB.BASEBOARD_FAB2(SCH_1):PAGE135

J9A2 CONN14_H54902001_PIP-CONN,H549A
     1 LED_POSTCODE_0_R @BASEBOARD_FAB2_LIB.BASEBOARD_FAB2(SCH_1):LED_POSTCODE_0_R   I171 @BASEBOARD_FAB2_LIB.BASEBOARD_FAB2(SCH_1):PAGE155
    10 SPA_5V_SIN_SW @BASEBOARD_FAB2_LIB.BASEBOARD_FAB2(SCH_1):SPA_5V_SIN_SW   I171 @BASEBOARD_FAB2_LIB.BASEBOARD_FAB2(SCH_1):PAGE155
    11 FM_DEBUG_RST_BTN_N @BASEBOARD_FAB2_LIB.BASEBOARD_FAB2(SCH_1):FM_DEBUG_RST_BTN_N   I171 @BASEBOARD_FAB2_LIB.BASEBOARD_FAB2(SCH_1):PAGE155
    12 FM_UART_SWITCH_N @BASEBOARD_FAB2_LIB.BASEBOARD_FAB2(SCH_1):FM_UART_SWITCH_N   I171 @BASEBOARD_FAB2_LIB.BASEBOARD_FAB2(SCH_1):PAGE155
    13    GND @BASEBOARD_FAB2_LIB.BASEBOARD_FAB2(SCH_1):GND   I171 @BASEBOARD_FAB2_LIB.BASEBOARD_FAB2(SCH_1):PAGE155
    14 P5V_STBY_DGB_FS @BASEBOARD_FAB2_LIB.BASEBOARD_FAB2(SCH_1):P5V_STBY_DGB_FS   I171 @BASEBOARD_FAB2_LIB.BASEBOARD_FAB2(SCH_1):PAGE155
     2 LED_POSTCODE_1_R @BASEBOARD_FAB2_LIB.BASEBOARD_FAB2(SCH_1):LED_POSTCODE_1_R   I171 @BASEBOARD_FAB2_LIB.BASEBOARD_FAB2(SCH_1):PAGE155
     3 LED_POSTCODE_2_R @BASEBOARD_FAB2_LIB.BASEBOARD_FAB2(SCH_1):LED_POSTCODE_2_R   I171 @BASEBOARD_FAB2_LIB.BASEBOARD_FAB2(SCH_1):PAGE155
     4 LED_POSTCODE_3_R @BASEBOARD_FAB2_LIB.BASEBOARD_FAB2(SCH_1):LED_POSTCODE_3_R   I171 @BASEBOARD_FAB2_LIB.BASEBOARD_FAB2(SCH_1):PAGE155
     5 LED_POSTCODE_4_R @BASEBOARD_FAB2_LIB.BASEBOARD_FAB2(SCH_1):LED_POSTCODE_4_R   I171 @BASEBOARD_FAB2_LIB.BASEBOARD_FAB2(SCH_1):PAGE155
     6 LED_POSTCODE_5_R @BASEBOARD_FAB2_LIB.BASEBOARD_FAB2(SCH_1):LED_POSTCODE_5_R   I171 @BASEBOARD_FAB2_LIB.BASEBOARD_FAB2(SCH_1):PAGE155
     7 LED_POSTCODE_6_R @BASEBOARD_FAB2_LIB.BASEBOARD_FAB2(SCH_1):LED_POSTCODE_6_R   I171 @BASEBOARD_FAB2_LIB.BASEBOARD_FAB2(SCH_1):PAGE155
     8 LED_POSTCODE_7_R @BASEBOARD_FAB2_LIB.BASEBOARD_FAB2(SCH_1):LED_POSTCODE_7_R   I171 @BASEBOARD_FAB2_LIB.BASEBOARD_FAB2(SCH_1):PAGE155
     9 SPA_MID_DBG1_TX @BASEBOARD_FAB2_LIB.BASEBOARD_FAB2(SCH_1):SPA_MID_DBG1_TX   I171 @BASEBOARD_FAB2_LIB.BASEBOARD_FAB2(SCH_1):PAGE155

J9A3 SCONN60_C21100002_SMLF-CONN,C2A
     1 XDP_DEBUG_CONSENT_N @BASEBOARD_FAB2_LIB.BASEBOARD_FAB2(SCH_1):XDP_DEBUG_CONSENT_N    I26 @BASEBOARD_FAB2_LIB.BASEBOARD_FAB2(SCH_1):PAGE111
     3 XDP_PREQ_N @BASEBOARD_FAB2_LIB.BASEBOARD_FAB2(SCH_1):XDP_PREQ_N    I26 @BASEBOARD_FAB2_LIB.BASEBOARD_FAB2(SCH_1):PAGE111
     5 XDP_PRDY_N @BASEBOARD_FAB2_LIB.BASEBOARD_FAB2(SCH_1):XDP_PRDY_N    I26 @BASEBOARD_FAB2_LIB.BASEBOARD_FAB2(SCH_1):PAGE111
     7    GND @BASEBOARD_FAB2_LIB.BASEBOARD_FAB2(SCH_1):GND    I26 @BASEBOARD_FAB2_LIB.BASEBOARD_FAB2(SCH_1):PAGE111
     9 TP_XDP_OBSDATA_A0 @BASEBOARD_FAB2_LIB.BASEBOARD_FAB2(SCH_1):TP_XDP_OBSDATA_A0    I26 @BASEBOARD_FAB2_LIB.BASEBOARD_FAB2(SCH_1):PAGE111
    11 TP_XDP_OBSDATA_A1 @BASEBOARD_FAB2_LIB.BASEBOARD_FAB2(SCH_1):TP_XDP_OBSDATA_A1    I26 @BASEBOARD_FAB2_LIB.BASEBOARD_FAB2(SCH_1):PAGE111
    13    GND @BASEBOARD_FAB2_LIB.BASEBOARD_FAB2(SCH_1):GND    I26 @BASEBOARD_FAB2_LIB.BASEBOARD_FAB2(SCH_1):PAGE111
    15 TP_XDP_OBSDATA_A2 @BASEBOARD_FAB2_LIB.BASEBOARD_FAB2(SCH_1):TP_XDP_OBSDATA_A2    I26 @BASEBOARD_FAB2_LIB.BASEBOARD_FAB2(SCH_1):PAGE111
    17 TP_XDP_OBSDATA_A3 @BASEBOARD_FAB2_LIB.BASEBOARD_FAB2(SCH_1):TP_XDP_OBSDATA_A3    I26 @BASEBOARD_FAB2_LIB.BASEBOARD_FAB2(SCH_1):PAGE111
    19    GND @BASEBOARD_FAB2_LIB.BASEBOARD_FAB2(SCH_1):GND    I26 @BASEBOARD_FAB2_LIB.BASEBOARD_FAB2(SCH_1):PAGE111
    21 TP_XDP_OBSFN_B0 @BASEBOARD_FAB2_LIB.BASEBOARD_FAB2(SCH_1):TP_XDP_OBSFN_B0    I26 @BASEBOARD_FAB2_LIB.BASEBOARD_FAB2(SCH_1):PAGE111
    23 TP_XDP_OBSFN_B1 @BASEBOARD_FAB2_LIB.BASEBOARD_FAB2(SCH_1):TP_XDP_OBSFN_B1    I26 @BASEBOARD_FAB2_LIB.BASEBOARD_FAB2(SCH_1):PAGE111
    25    GND @BASEBOARD_FAB2_LIB.BASEBOARD_FAB2(SCH_1):GND    I26 @BASEBOARD_FAB2_LIB.BASEBOARD_FAB2(SCH_1):PAGE111
    27 TP_XDP_OBSDATA_B0 @BASEBOARD_FAB2_LIB.BASEBOARD_FAB2(SCH_1):TP_XDP_OBSDATA_B0    I26 @BASEBOARD_FAB2_LIB.BASEBOARD_FAB2(SCH_1):PAGE111
    29 TP_XDP_OBSDATA_B1 @BASEBOARD_FAB2_LIB.BASEBOARD_FAB2(SCH_1):TP_XDP_OBSDATA_B1    I26 @BASEBOARD_FAB2_LIB.BASEBOARD_FAB2(SCH_1):PAGE111
    31    GND @BASEBOARD_FAB2_LIB.BASEBOARD_FAB2(SCH_1):GND    I26 @BASEBOARD_FAB2_LIB.BASEBOARD_FAB2(SCH_1):PAGE111
    33 TP_XDP_OBSDATA_B2 @BASEBOARD_FAB2_LIB.BASEBOARD_FAB2(SCH_1):TP_XDP_OBSDATA_B2    I26 @BASEBOARD_FAB2_LIB.BASEBOARD_FAB2(SCH_1):PAGE111
    35 TP_XDP_OBSDATA_B3 @BASEBOARD_FAB2_LIB.BASEBOARD_FAB2(SCH_1):TP_XDP_OBSDATA_B3    I26 @BASEBOARD_FAB2_LIB.BASEBOARD_FAB2(SCH_1):PAGE111
    37    GND @BASEBOARD_FAB2_LIB.BASEBOARD_FAB2(SCH_1):GND    I26 @BASEBOARD_FAB2_LIB.BASEBOARD_FAB2(SCH_1):PAGE111
    39 XDP_RSMRST_N @BASEBOARD_FAB2_LIB.BASEBOARD_FAB2(SCH_1):XDP_RSMRST_N    I26 @BASEBOARD_FAB2_LIB.BASEBOARD_FAB2(SCH_1):PAGE111
    41 XDP_PWRGD_RST_N @BASEBOARD_FAB2_LIB.BASEBOARD_FAB2(SCH_1):XDP_PWRGD_RST_N    I26 @BASEBOARD_FAB2_LIB.BASEBOARD_FAB2(SCH_1):PAGE111
    43 P1V05_PCH_STBY @BASEBOARD_FAB2_LIB.BASEBOARD_FAB2(SCH_1):P1V05_PCH_STBY    I26 @BASEBOARD_FAB2_LIB.BASEBOARD_FAB2(SCH_1):PAGE111
    45 XDP_CPU_PWR_DEBUG_N @BASEBOARD_FAB2_LIB.BASEBOARD_FAB2(SCH_1):XDP_CPU_PWR_DEBUG_N    I26 @BASEBOARD_FAB2_LIB.BASEBOARD_FAB2(SCH_1):PAGE111
    47 XDP_SYSPWROK @BASEBOARD_FAB2_LIB.BASEBOARD_FAB2(SCH_1):XDP_SYSPWROK    I26 @BASEBOARD_FAB2_LIB.BASEBOARD_FAB2(SCH_1):PAGE111
    49    GND @BASEBOARD_FAB2_LIB.BASEBOARD_FAB2(SCH_1):GND    I26 @BASEBOARD_FAB2_LIB.BASEBOARD_FAB2(SCH_1):PAGE111
     2    GND @BASEBOARD_FAB2_LIB.BASEBOARD_FAB2(SCH_1):GND    I26 @BASEBOARD_FAB2_LIB.BASEBOARD_FAB2(SCH_1):PAGE111
     4 TP_XDP_CPU_OBSFN_C0 @BASEBOARD_FAB2_LIB.BASEBOARD_FAB2(SCH_1):TP_XDP_CPU_OBSFN_C0    I26 @BASEBOARD_FAB2_LIB.BASEBOARD_FAB2(SCH_1):PAGE111
     6 XDP_SPI_PCH_MOSI_BOOT_HALT_N @BASEBOARD_FAB2_LIB.BASEBOARD_FAB2(SCH_1):XDP_SPI_PCH_MOSI_BOOT_HALT_N    I26 @BASEBOARD_FAB2_LIB.BASEBOARD_FAB2(SCH_1):PAGE111
     8    GND @BASEBOARD_FAB2_LIB.BASEBOARD_FAB2(SCH_1):GND    I26 @BASEBOARD_FAB2_LIB.BASEBOARD_FAB2(SCH_1):PAGE111
    10 TP_XDP_CPU_OBSDATA_C0 @BASEBOARD_FAB2_LIB.BASEBOARD_FAB2(SCH_1):TP_XDP_CPU_OBSDATA_C0    I26 @BASEBOARD_FAB2_LIB.BASEBOARD_FAB2(SCH_1):PAGE111
    12 TP_XDP_CPU_OBSDATA_C1 @BASEBOARD_FAB2_LIB.BASEBOARD_FAB2(SCH_1):TP_XDP_CPU_OBSDATA_C1    I26 @BASEBOARD_FAB2_LIB.BASEBOARD_FAB2(SCH_1):PAGE111
    14    GND @BASEBOARD_FAB2_LIB.BASEBOARD_FAB2(SCH_1):GND    I26 @BASEBOARD_FAB2_LIB.BASEBOARD_FAB2(SCH_1):PAGE111
    16 TP_XDP_CPU_OBSDATA_C2 @BASEBOARD_FAB2_LIB.BASEBOARD_FAB2(SCH_1):TP_XDP_CPU_OBSDATA_C2    I26 @BASEBOARD_FAB2_LIB.BASEBOARD_FAB2(SCH_1):PAGE111
    18 TP_XDP_CPU_OBSDATA_C3 @BASEBOARD_FAB2_LIB.BASEBOARD_FAB2(SCH_1):TP_XDP_CPU_OBSDATA_C3    I26 @BASEBOARD_FAB2_LIB.BASEBOARD_FAB2(SCH_1):PAGE111
    20    GND @BASEBOARD_FAB2_LIB.BASEBOARD_FAB2(SCH_1):GND    I26 @BASEBOARD_FAB2_LIB.BASEBOARD_FAB2(SCH_1):PAGE111
    22 XDP_OBSFN_B0_MBP6_N @BASEBOARD_FAB2_LIB.BASEBOARD_FAB2(SCH_1):XDP_OBSFN_B0_MBP6_N    I26 @BASEBOARD_FAB2_LIB.BASEBOARD_FAB2(SCH_1):PAGE111
    24 XDP_OBSFN_B1_MBP7_N @BASEBOARD_FAB2_LIB.BASEBOARD_FAB2(SCH_1):XDP_OBSFN_B1_MBP7_N    I26 @BASEBOARD_FAB2_LIB.BASEBOARD_FAB2(SCH_1):PAGE111
    26    GND @BASEBOARD_FAB2_LIB.BASEBOARD_FAB2(SCH_1):GND    I26 @BASEBOARD_FAB2_LIB.BASEBOARD_FAB2(SCH_1):PAGE111
    28 TP_XDP_CPU_OBSDATA_D0 @BASEBOARD_FAB2_LIB.BASEBOARD_FAB2(SCH_1):TP_XDP_CPU_OBSDATA_D0    I26 @BASEBOARD_FAB2_LIB.BASEBOARD_FAB2(SCH_1):PAGE111
    30 TP_XDP_CPU_OBSDATA_D1 @BASEBOARD_FAB2_LIB.BASEBOARD_FAB2(SCH_1):TP_XDP_CPU_OBSDATA_D1    I26 @BASEBOARD_FAB2_LIB.BASEBOARD_FAB2(SCH_1):PAGE111
    32    GND @BASEBOARD_FAB2_LIB.BASEBOARD_FAB2(SCH_1):GND    I26 @BASEBOARD_FAB2_LIB.BASEBOARD_FAB2(SCH_1):PAGE111
    34 TP_XDP_CPU_OBSDATA_D2 @BASEBOARD_FAB2_LIB.BASEBOARD_FAB2(SCH_1):TP_XDP_CPU_OBSDATA_D2    I26 @BASEBOARD_FAB2_LIB.BASEBOARD_FAB2(SCH_1):PAGE111
    36 TP_XDP_CPU_OBSDATA_D3 @BASEBOARD_FAB2_LIB.BASEBOARD_FAB2(SCH_1):TP_XDP_CPU_OBSDATA_D3    I26 @BASEBOARD_FAB2_LIB.BASEBOARD_FAB2(SCH_1):PAGE111
    38    GND @BASEBOARD_FAB2_LIB.BASEBOARD_FAB2(SCH_1):GND    I26 @BASEBOARD_FAB2_LIB.BASEBOARD_FAB2(SCH_1):PAGE111
    40 CLK_100M_PCH_XDP_DP @BASEBOARD_FAB2_LIB.BASEBOARD_FAB2(SCH_1):CLK_100M_PCH_XDP_DP    I26 @BASEBOARD_FAB2_LIB.BASEBOARD_FAB2(SCH_1):PAGE111
    42 CLK_100M_PCH_XDP_DN @BASEBOARD_FAB2_LIB.BASEBOARD_FAB2(SCH_1):CLK_100M_PCH_XDP_DN    I26 @BASEBOARD_FAB2_LIB.BASEBOARD_FAB2(SCH_1):PAGE111
    44 P1V05_PCH_STBY @BASEBOARD_FAB2_LIB.BASEBOARD_FAB2(SCH_1):P1V05_PCH_STBY    I26 @BASEBOARD_FAB2_LIB.BASEBOARD_FAB2(SCH_1):PAGE111
    46 XDP_ITP_PMODE @BASEBOARD_FAB2_LIB.BASEBOARD_FAB2(SCH_1):XDP_ITP_PMODE    I26 @BASEBOARD_FAB2_LIB.BASEBOARD_FAB2(SCH_1):PAGE111
    48 XDP_RST_CO_N @BASEBOARD_FAB2_LIB.BASEBOARD_FAB2(SCH_1):XDP_RST_CO_N    I26 @BASEBOARD_FAB2_LIB.BASEBOARD_FAB2(SCH_1):PAGE111
    50    GND @BASEBOARD_FAB2_LIB.BASEBOARD_FAB2(SCH_1):GND    I26 @BASEBOARD_FAB2_LIB.BASEBOARD_FAB2(SCH_1):PAGE111
    51 SMB_HOST_STBY_LVC3_SDA @BASEBOARD_FAB2_LIB.BASEBOARD_FAB2(SCH_1):SMB_HOST_STBY_LVC3_SDA    I26 @BASEBOARD_FAB2_LIB.BASEBOARD_FAB2(SCH_1):PAGE111
    52 XDP_TDO @BASEBOARD_FAB2_LIB.BASEBOARD_FAB2(SCH_1):XDP_TDO    I26 @BASEBOARD_FAB2_LIB.BASEBOARD_FAB2(SCH_1):PAGE111
    53 SMB_HOST_STBY_LVC3_SCL @BASEBOARD_FAB2_LIB.BASEBOARD_FAB2(SCH_1):SMB_HOST_STBY_LVC3_SCL    I26 @BASEBOARD_FAB2_LIB.BASEBOARD_FAB2(SCH_1):PAGE111
    54 XDP_TRST_N @BASEBOARD_FAB2_LIB.BASEBOARD_FAB2(SCH_1):XDP_TRST_N    I26 @BASEBOARD_FAB2_LIB.BASEBOARD_FAB2(SCH_1):PAGE111
    55 XDP_PCH_TCK1 @BASEBOARD_FAB2_LIB.BASEBOARD_FAB2(SCH_1):XDP_PCH_TCK1    I26 @BASEBOARD_FAB2_LIB.BASEBOARD_FAB2(SCH_1):PAGE111
    56 XDP_TDI @BASEBOARD_FAB2_LIB.BASEBOARD_FAB2(SCH_1):XDP_TDI    I26 @BASEBOARD_FAB2_LIB.BASEBOARD_FAB2(SCH_1):PAGE111
    57 XDP_CPU_TCK0 @BASEBOARD_FAB2_LIB.BASEBOARD_FAB2(SCH_1):XDP_CPU_TCK0    I26 @BASEBOARD_FAB2_LIB.BASEBOARD_FAB2(SCH_1):PAGE111
    58 XDP_TMS @BASEBOARD_FAB2_LIB.BASEBOARD_FAB2(SCH_1):XDP_TMS    I26 @BASEBOARD_FAB2_LIB.BASEBOARD_FAB2(SCH_1):PAGE111
    59    GND @BASEBOARD_FAB2_LIB.BASEBOARD_FAB2(SCH_1):GND    I26 @BASEBOARD_FAB2_LIB.BASEBOARD_FAB2(SCH_1):PAGE111
    60 XDP_PRESENT_N @BASEBOARD_FAB2_LIB.BASEBOARD_FAB2(SCH_1):XDP_PRESENT_N    I26 @BASEBOARD_FAB2_LIB.BASEBOARD_FAB2(SCH_1):PAGE111

J9B1 CONN9_H51826001_PIP2-CONN,H518A
     2 USB2_P01_ESD_DN @BASEBOARD_FAB2_LIB.BASEBOARD_FAB2(SCH_1):USB2_P01_ESD_DN    I69 @BASEBOARD_FAB2_LIB.BASEBOARD_FAB2(SCH_1):PAGE176
     3 USB2_P01_ESD_DP @BASEBOARD_FAB2_LIB.BASEBOARD_FAB2(SCH_1):USB2_P01_ESD_DP    I69 @BASEBOARD_FAB2_LIB.BASEBOARD_FAB2(SCH_1):PAGE176
     4    GND @BASEBOARD_FAB2_LIB.BASEBOARD_FAB2(SCH_1):GND    I69 @BASEBOARD_FAB2_LIB.BASEBOARD_FAB2(SCH_1):PAGE176
     7 DEBUG_CARD2_PRSNT @BASEBOARD_FAB2_LIB.BASEBOARD_FAB2(SCH_1):DEBUG_CARD2_PRSNT    I69 @BASEBOARD_FAB2_LIB.BASEBOARD_FAB2(SCH_1):PAGE176
   MH1    GND @BASEBOARD_FAB2_LIB.BASEBOARD_FAB2(SCH_1):GND    I69 @BASEBOARD_FAB2_LIB.BASEBOARD_FAB2(SCH_1):PAGE176
   MH2    GND @BASEBOARD_FAB2_LIB.BASEBOARD_FAB2(SCH_1):GND    I69 @BASEBOARD_FAB2_LIB.BASEBOARD_FAB2(SCH_1):PAGE176
   MH3    GND @BASEBOARD_FAB2_LIB.BASEBOARD_FAB2(SCH_1):GND    I69 @BASEBOARD_FAB2_LIB.BASEBOARD_FAB2(SCH_1):PAGE176
   MH4    GND @BASEBOARD_FAB2_LIB.BASEBOARD_FAB2(SCH_1):GND    I69 @BASEBOARD_FAB2_LIB.BASEBOARD_FAB2(SCH_1):PAGE176
     5 SMB_DEBUG_STBY_LVC3_SCL_CONN @BASEBOARD_FAB2_LIB.BASEBOARD_FAB2(SCH_1):SMB_DEBUG_STBY_LVC3_SCL_CONN    I69 @BASEBOARD_FAB2_LIB.BASEBOARD_FAB2(SCH_1):PAGE176
     6 SMB_DEBUG_STBY_LVC3_SDA_CONN @BASEBOARD_FAB2_LIB.BASEBOARD_FAB2(SCH_1):SMB_DEBUG_STBY_LVC3_SDA_CONN    I69 @BASEBOARD_FAB2_LIB.BASEBOARD_FAB2(SCH_1):PAGE176
     8 SPA_MID_DBG2_TX @BASEBOARD_FAB2_LIB.BASEBOARD_FAB2(SCH_1):SPA_MID_DBG2_TX    I69 @BASEBOARD_FAB2_LIB.BASEBOARD_FAB2(SCH_1):PAGE176
     9 SPA_MID_DBG2_RX @BASEBOARD_FAB2_LIB.BASEBOARD_FAB2(SCH_1):SPA_MID_DBG2_RX    I69 @BASEBOARD_FAB2_LIB.BASEBOARD_FAB2(SCH_1):PAGE176
     1 P5V_USB @BASEBOARD_FAB2_LIB.BASEBOARD_FAB2(SCH_1):P5V_USB    I69 @BASEBOARD_FAB2_LIB.BASEBOARD_FAB2(SCH_1):PAGE176

J9B2 CONN3_C95678002_PIP-CONN,C9567A
     1 SMB_SMLINK0_STBY_LVC3_SDA @BASEBOARD_FAB2_LIB.BASEBOARD_FAB2(SCH_1):SMB_SMLINK0_STBY_LVC3_SDA   I281 @BASEBOARD_FAB2_LIB.BASEBOARD_FAB2(SCH_1):PAGE156
     2    GND @BASEBOARD_FAB2_LIB.BASEBOARD_FAB2(SCH_1):GND   I281 @BASEBOARD_FAB2_LIB.BASEBOARD_FAB2(SCH_1):PAGE156
     3 SMB_SMLINK0_STBY_LVC3_SCL @BASEBOARD_FAB2_LIB.BASEBOARD_FAB2(SCH_1):SMB_SMLINK0_STBY_LVC3_SCL   I281 @BASEBOARD_FAB2_LIB.BASEBOARD_FAB2(SCH_1):PAGE156

J9B3 SCONN120_A28699018_SM-SCONN,A2A
     1 FM_MEZZA_PRSNT1_N @BASEBOARD_FAB2_LIB.BASEBOARD_FAB2(SCH_1):FM_MEZZA_PRSNT1_N   I336 @BASEBOARD_FAB2_LIB.BASEBOARD_FAB2(SCH_1):PAGE186
    10    GND @BASEBOARD_FAB2_LIB.BASEBOARD_FAB2(SCH_1):GND   I336 @BASEBOARD_FAB2_LIB.BASEBOARD_FAB2(SCH_1):PAGE186
   100    GND @BASEBOARD_FAB2_LIB.BASEBOARD_FAB2(SCH_1):GND   I336 @BASEBOARD_FAB2_LIB.BASEBOARD_FAB2(SCH_1):PAGE186
   101 P3E_CPU0_PE3_OCP_RXN<10> @BASEBOARD_FAB2_LIB.BASEBOARD_FAB2(SCH_1):P3E_CPU0_PE3_OCP_RXN(10)   I336 @BASEBOARD_FAB2_LIB.BASEBOARD_FAB2(SCH_1):PAGE186
   102    GND @BASEBOARD_FAB2_LIB.BASEBOARD_FAB2(SCH_1):GND   I336 @BASEBOARD_FAB2_LIB.BASEBOARD_FAB2(SCH_1):PAGE186
   103    GND @BASEBOARD_FAB2_LIB.BASEBOARD_FAB2(SCH_1):GND   I336 @BASEBOARD_FAB2_LIB.BASEBOARD_FAB2(SCH_1):PAGE186
   104 P3E_OCP_CPU0_PE3_C_TXP<9> @BASEBOARD_FAB2_LIB.BASEBOARD_FAB2(SCH_1):P3E_OCP_CPU0_PE3_C_TXP(9)   I336 @BASEBOARD_FAB2_LIB.BASEBOARD_FAB2(SCH_1):PAGE186
   105    GND @BASEBOARD_FAB2_LIB.BASEBOARD_FAB2(SCH_1):GND   I336 @BASEBOARD_FAB2_LIB.BASEBOARD_FAB2(SCH_1):PAGE186
   106 P3E_OCP_CPU0_PE3_C_TXN<9> @BASEBOARD_FAB2_LIB.BASEBOARD_FAB2(SCH_1):P3E_OCP_CPU0_PE3_C_TXN(9)   I336 @BASEBOARD_FAB2_LIB.BASEBOARD_FAB2(SCH_1):PAGE186
   107 P3E_CPU0_PE3_OCP_RXP<9> @BASEBOARD_FAB2_LIB.BASEBOARD_FAB2(SCH_1):P3E_CPU0_PE3_OCP_RXP(9)   I336 @BASEBOARD_FAB2_LIB.BASEBOARD_FAB2(SCH_1):PAGE186
   108    GND @BASEBOARD_FAB2_LIB.BASEBOARD_FAB2(SCH_1):GND   I336 @BASEBOARD_FAB2_LIB.BASEBOARD_FAB2(SCH_1):PAGE186
   109 P3E_CPU0_PE3_OCP_RXN<9> @BASEBOARD_FAB2_LIB.BASEBOARD_FAB2(SCH_1):P3E_CPU0_PE3_OCP_RXN(9)   I336 @BASEBOARD_FAB2_LIB.BASEBOARD_FAB2(SCH_1):PAGE186
    11    GND @BASEBOARD_FAB2_LIB.BASEBOARD_FAB2(SCH_1):GND   I336 @BASEBOARD_FAB2_LIB.BASEBOARD_FAB2(SCH_1):PAGE186
   110    GND @BASEBOARD_FAB2_LIB.BASEBOARD_FAB2(SCH_1):GND   I336 @BASEBOARD_FAB2_LIB.BASEBOARD_FAB2(SCH_1):PAGE186
   111    GND @BASEBOARD_FAB2_LIB.BASEBOARD_FAB2(SCH_1):GND   I336 @BASEBOARD_FAB2_LIB.BASEBOARD_FAB2(SCH_1):PAGE186
   112 P3E_OCP_CPU0_PE3_C_TXP<8> @BASEBOARD_FAB2_LIB.BASEBOARD_FAB2(SCH_1):P3E_OCP_CPU0_PE3_C_TXP(8)   I336 @BASEBOARD_FAB2_LIB.BASEBOARD_FAB2(SCH_1):PAGE186
   113    GND @BASEBOARD_FAB2_LIB.BASEBOARD_FAB2(SCH_1):GND   I336 @BASEBOARD_FAB2_LIB.BASEBOARD_FAB2(SCH_1):PAGE186
   114 P3E_OCP_CPU0_PE3_C_TXN<8> @BASEBOARD_FAB2_LIB.BASEBOARD_FAB2(SCH_1):P3E_OCP_CPU0_PE3_C_TXN(8)   I336 @BASEBOARD_FAB2_LIB.BASEBOARD_FAB2(SCH_1):PAGE186
   115 P3E_CPU0_PE3_OCP_RXP<8> @BASEBOARD_FAB2_LIB.BASEBOARD_FAB2(SCH_1):P3E_CPU0_PE3_OCP_RXP(8)   I336 @BASEBOARD_FAB2_LIB.BASEBOARD_FAB2(SCH_1):PAGE186
   116    GND @BASEBOARD_FAB2_LIB.BASEBOARD_FAB2(SCH_1):GND   I336 @BASEBOARD_FAB2_LIB.BASEBOARD_FAB2(SCH_1):PAGE186
   117 P3E_CPU0_PE3_OCP_RXN<8> @BASEBOARD_FAB2_LIB.BASEBOARD_FAB2(SCH_1):P3E_CPU0_PE3_OCP_RXN(8)   I336 @BASEBOARD_FAB2_LIB.BASEBOARD_FAB2(SCH_1):PAGE186
   118    GND @BASEBOARD_FAB2_LIB.BASEBOARD_FAB2(SCH_1):GND   I336 @BASEBOARD_FAB2_LIB.BASEBOARD_FAB2(SCH_1):PAGE186
   119    GND @BASEBOARD_FAB2_LIB.BASEBOARD_FAB2(SCH_1):GND   I336 @BASEBOARD_FAB2_LIB.BASEBOARD_FAB2(SCH_1):PAGE186
    12 P3V3_STBY @BASEBOARD_FAB2_LIB.BASEBOARD_FAB2(SCH_1):P3V3_STBY   I336 @BASEBOARD_FAB2_LIB.BASEBOARD_FAB2(SCH_1):PAGE186
   120 FM_OCP_MEZZA_PRES_N @BASEBOARD_FAB2_LIB.BASEBOARD_FAB2(SCH_1):FM_OCP_MEZZA_PRES_N   I336 @BASEBOARD_FAB2_LIB.BASEBOARD_FAB2(SCH_1):PAGE186
    13 P3V3_STBY @BASEBOARD_FAB2_LIB.BASEBOARD_FAB2(SCH_1):P3V3_STBY   I336 @BASEBOARD_FAB2_LIB.BASEBOARD_FAB2(SCH_1):PAGE186
    14    GND @BASEBOARD_FAB2_LIB.BASEBOARD_FAB2(SCH_1):GND   I336 @BASEBOARD_FAB2_LIB.BASEBOARD_FAB2(SCH_1):PAGE186
    15    GND @BASEBOARD_FAB2_LIB.BASEBOARD_FAB2(SCH_1):GND   I336 @BASEBOARD_FAB2_LIB.BASEBOARD_FAB2(SCH_1):PAGE186
    16    GND @BASEBOARD_FAB2_LIB.BASEBOARD_FAB2(SCH_1):GND   I336 @BASEBOARD_FAB2_LIB.BASEBOARD_FAB2(SCH_1):PAGE186
    17    GND @BASEBOARD_FAB2_LIB.BASEBOARD_FAB2(SCH_1):GND   I336 @BASEBOARD_FAB2_LIB.BASEBOARD_FAB2(SCH_1):PAGE186
    18   P3V3 @BASEBOARD_FAB2_LIB.BASEBOARD_FAB2(SCH_1):P3V3   I336 @BASEBOARD_FAB2_LIB.BASEBOARD_FAB2(SCH_1):PAGE186
    19   P3V3 @BASEBOARD_FAB2_LIB.BASEBOARD_FAB2(SCH_1):P3V3   I336 @BASEBOARD_FAB2_LIB.BASEBOARD_FAB2(SCH_1):PAGE186
     2 P12V_STBY @BASEBOARD_FAB2_LIB.BASEBOARD_FAB2(SCH_1):P12V_STBY   I336 @BASEBOARD_FAB2_LIB.BASEBOARD_FAB2(SCH_1):PAGE186
    20   P3V3 @BASEBOARD_FAB2_LIB.BASEBOARD_FAB2(SCH_1):P3V3   I336 @BASEBOARD_FAB2_LIB.BASEBOARD_FAB2(SCH_1):PAGE186
    21   P3V3 @BASEBOARD_FAB2_LIB.BASEBOARD_FAB2(SCH_1):P3V3   I336 @BASEBOARD_FAB2_LIB.BASEBOARD_FAB2(SCH_1):PAGE186
    22   P3V3 @BASEBOARD_FAB2_LIB.BASEBOARD_FAB2(SCH_1):P3V3   I336 @BASEBOARD_FAB2_LIB.BASEBOARD_FAB2(SCH_1):PAGE186
    23   P3V3 @BASEBOARD_FAB2_LIB.BASEBOARD_FAB2(SCH_1):P3V3   I336 @BASEBOARD_FAB2_LIB.BASEBOARD_FAB2(SCH_1):PAGE186
    24   P3V3 @BASEBOARD_FAB2_LIB.BASEBOARD_FAB2(SCH_1):P3V3   I336 @BASEBOARD_FAB2_LIB.BASEBOARD_FAB2(SCH_1):PAGE186
    25   P3V3 @BASEBOARD_FAB2_LIB.BASEBOARD_FAB2(SCH_1):P3V3   I336 @BASEBOARD_FAB2_LIB.BASEBOARD_FAB2(SCH_1):PAGE186
    26    GND @BASEBOARD_FAB2_LIB.BASEBOARD_FAB2(SCH_1):GND   I336 @BASEBOARD_FAB2_LIB.BASEBOARD_FAB2(SCH_1):PAGE186
    27 RMII_BMC_OCP_CRSDV_R @BASEBOARD_FAB2_LIB.BASEBOARD_FAB2(SCH_1):RMII_BMC_OCP_CRSDV_R   I336 @BASEBOARD_FAB2_LIB.BASEBOARD_FAB2(SCH_1):PAGE186
    28 IRQ_MEZZ_LAN_ALERT_N @BASEBOARD_FAB2_LIB.BASEBOARD_FAB2(SCH_1):IRQ_MEZZ_LAN_ALERT_N   I336 @BASEBOARD_FAB2_LIB.BASEBOARD_FAB2(SCH_1):PAGE186
    29 CLK_50M_CKMNG_OCP @BASEBOARD_FAB2_LIB.BASEBOARD_FAB2(SCH_1):CLK_50M_CKMNG_OCP   I336 @BASEBOARD_FAB2_LIB.BASEBOARD_FAB2(SCH_1):PAGE186
     3 P5V_STBY @BASEBOARD_FAB2_LIB.BASEBOARD_FAB2(SCH_1):P5V_STBY   I336 @BASEBOARD_FAB2_LIB.BASEBOARD_FAB2(SCH_1):PAGE186
    30 SMB_OCP_FRU_STBY_LVC3_SCL @BASEBOARD_FAB2_LIB.BASEBOARD_FAB2(SCH_1):SMB_OCP_FRU_STBY_LVC3_SCL   I336 @BASEBOARD_FAB2_LIB.BASEBOARD_FAB2(SCH_1):PAGE186
    31 RMII_BMC_OCP_TXEN @BASEBOARD_FAB2_LIB.BASEBOARD_FAB2(SCH_1):RMII_BMC_OCP_TXEN   I336 @BASEBOARD_FAB2_LIB.BASEBOARD_FAB2(SCH_1):PAGE186
    32 SMB_OCP_FRU_STBY_LVC3_SDA @BASEBOARD_FAB2_LIB.BASEBOARD_FAB2(SCH_1):SMB_OCP_FRU_STBY_LVC3_SDA   I336 @BASEBOARD_FAB2_LIB.BASEBOARD_FAB2(SCH_1):PAGE186
    33 RST_PCIE_CPU_DEV0_R_N @BASEBOARD_FAB2_LIB.BASEBOARD_FAB2(SCH_1):RST_PCIE_CPU_DEV0_R_N   I336 @BASEBOARD_FAB2_LIB.BASEBOARD_FAB2(SCH_1):PAGE186
    34 FM_PE_OCP_WAKE_N @BASEBOARD_FAB2_LIB.BASEBOARD_FAB2(SCH_1):FM_PE_OCP_WAKE_N   I336 @BASEBOARD_FAB2_LIB.BASEBOARD_FAB2(SCH_1):PAGE186
    35 SMB_OCP_LAN_STBY_LVC3_SCL @BASEBOARD_FAB2_LIB.BASEBOARD_FAB2(SCH_1):SMB_OCP_LAN_STBY_LVC3_SCL   I336 @BASEBOARD_FAB2_LIB.BASEBOARD_FAB2(SCH_1):PAGE186
    36 RMII_BMC_OCP_RXER_R @BASEBOARD_FAB2_LIB.BASEBOARD_FAB2(SCH_1):RMII_BMC_OCP_RXER_R   I336 @BASEBOARD_FAB2_LIB.BASEBOARD_FAB2(SCH_1):PAGE186
    37 SMB_OCP_LAN_STBY_LVC3_SDA @BASEBOARD_FAB2_LIB.BASEBOARD_FAB2(SCH_1):SMB_OCP_LAN_STBY_LVC3_SDA   I336 @BASEBOARD_FAB2_LIB.BASEBOARD_FAB2(SCH_1):PAGE186
    38    GND @BASEBOARD_FAB2_LIB.BASEBOARD_FAB2(SCH_1):GND   I336 @BASEBOARD_FAB2_LIB.BASEBOARD_FAB2(SCH_1):PAGE186
    39    GND @BASEBOARD_FAB2_LIB.BASEBOARD_FAB2(SCH_1):GND   I336 @BASEBOARD_FAB2_LIB.BASEBOARD_FAB2(SCH_1):PAGE186
     4 P12V_STBY @BASEBOARD_FAB2_LIB.BASEBOARD_FAB2(SCH_1):P12V_STBY   I336 @BASEBOARD_FAB2_LIB.BASEBOARD_FAB2(SCH_1):PAGE186
    40 RMII_BMC_OCP_TXD0 @BASEBOARD_FAB2_LIB.BASEBOARD_FAB2(SCH_1):RMII_BMC_OCP_TXD0   I336 @BASEBOARD_FAB2_LIB.BASEBOARD_FAB2(SCH_1):PAGE186
    41    GND @BASEBOARD_FAB2_LIB.BASEBOARD_FAB2(SCH_1):GND   I336 @BASEBOARD_FAB2_LIB.BASEBOARD_FAB2(SCH_1):PAGE186
    42 RMII_BMC_OCP_TXD1 @BASEBOARD_FAB2_LIB.BASEBOARD_FAB2(SCH_1):RMII_BMC_OCP_TXD1   I336 @BASEBOARD_FAB2_LIB.BASEBOARD_FAB2(SCH_1):PAGE186
    43 RMII_BMC_OCP_RXD0_R @BASEBOARD_FAB2_LIB.BASEBOARD_FAB2(SCH_1):RMII_BMC_OCP_RXD0_R   I336 @BASEBOARD_FAB2_LIB.BASEBOARD_FAB2(SCH_1):PAGE186
    44    GND @BASEBOARD_FAB2_LIB.BASEBOARD_FAB2(SCH_1):GND   I336 @BASEBOARD_FAB2_LIB.BASEBOARD_FAB2(SCH_1):PAGE186
    45 RMII_BMC_OCP_RXD1_R @BASEBOARD_FAB2_LIB.BASEBOARD_FAB2(SCH_1):RMII_BMC_OCP_RXD1_R   I336 @BASEBOARD_FAB2_LIB.BASEBOARD_FAB2(SCH_1):PAGE186
    46    GND @BASEBOARD_FAB2_LIB.BASEBOARD_FAB2(SCH_1):GND   I336 @BASEBOARD_FAB2_LIB.BASEBOARD_FAB2(SCH_1):PAGE186
    47    GND @BASEBOARD_FAB2_LIB.BASEBOARD_FAB2(SCH_1):GND   I336 @BASEBOARD_FAB2_LIB.BASEBOARD_FAB2(SCH_1):PAGE186
    48 CLK_100M_MEZZ1_DP @BASEBOARD_FAB2_LIB.BASEBOARD_FAB2(SCH_1):CLK_100M_MEZZ1_DP   I336 @BASEBOARD_FAB2_LIB.BASEBOARD_FAB2(SCH_1):PAGE186
    49    GND @BASEBOARD_FAB2_LIB.BASEBOARD_FAB2(SCH_1):GND   I336 @BASEBOARD_FAB2_LIB.BASEBOARD_FAB2(SCH_1):PAGE186
     5 P5V_STBY @BASEBOARD_FAB2_LIB.BASEBOARD_FAB2(SCH_1):P5V_STBY   I336 @BASEBOARD_FAB2_LIB.BASEBOARD_FAB2(SCH_1):PAGE186
    50 CLK_100M_MEZZ1_DN @BASEBOARD_FAB2_LIB.BASEBOARD_FAB2(SCH_1):CLK_100M_MEZZ1_DN   I336 @BASEBOARD_FAB2_LIB.BASEBOARD_FAB2(SCH_1):PAGE186
    51 CLK_100M_MEZZ2_DP @BASEBOARD_FAB2_LIB.BASEBOARD_FAB2(SCH_1):CLK_100M_MEZZ2_DP   I336 @BASEBOARD_FAB2_LIB.BASEBOARD_FAB2(SCH_1):PAGE186
    52    GND @BASEBOARD_FAB2_LIB.BASEBOARD_FAB2(SCH_1):GND   I336 @BASEBOARD_FAB2_LIB.BASEBOARD_FAB2(SCH_1):PAGE186
    53 CLK_100M_MEZZ2_DN @BASEBOARD_FAB2_LIB.BASEBOARD_FAB2(SCH_1):CLK_100M_MEZZ2_DN   I336 @BASEBOARD_FAB2_LIB.BASEBOARD_FAB2(SCH_1):PAGE186
    54    GND @BASEBOARD_FAB2_LIB.BASEBOARD_FAB2(SCH_1):GND   I336 @BASEBOARD_FAB2_LIB.BASEBOARD_FAB2(SCH_1):PAGE186
    55    GND @BASEBOARD_FAB2_LIB.BASEBOARD_FAB2(SCH_1):GND   I336 @BASEBOARD_FAB2_LIB.BASEBOARD_FAB2(SCH_1):PAGE186
    56 P3E_OCP_CPU0_PE3_C_TXP<15> @BASEBOARD_FAB2_LIB.BASEBOARD_FAB2(SCH_1):P3E_OCP_CPU0_PE3_C_TXP(15)   I336 @BASEBOARD_FAB2_LIB.BASEBOARD_FAB2(SCH_1):PAGE186
    57    GND @BASEBOARD_FAB2_LIB.BASEBOARD_FAB2(SCH_1):GND   I336 @BASEBOARD_FAB2_LIB.BASEBOARD_FAB2(SCH_1):PAGE186
    58 P3E_OCP_CPU0_PE3_C_TXN<15> @BASEBOARD_FAB2_LIB.BASEBOARD_FAB2(SCH_1):P3E_OCP_CPU0_PE3_C_TXN(15)   I336 @BASEBOARD_FAB2_LIB.BASEBOARD_FAB2(SCH_1):PAGE186
    59 P3E_CPU0_PE3_OCP_RXP<15> @BASEBOARD_FAB2_LIB.BASEBOARD_FAB2(SCH_1):P3E_CPU0_PE3_OCP_RXP(15)   I336 @BASEBOARD_FAB2_LIB.BASEBOARD_FAB2(SCH_1):PAGE186
     6 P12V_STBY @BASEBOARD_FAB2_LIB.BASEBOARD_FAB2(SCH_1):P12V_STBY   I336 @BASEBOARD_FAB2_LIB.BASEBOARD_FAB2(SCH_1):PAGE186
    60    GND @BASEBOARD_FAB2_LIB.BASEBOARD_FAB2(SCH_1):GND   I336 @BASEBOARD_FAB2_LIB.BASEBOARD_FAB2(SCH_1):PAGE186
    61 P3E_CPU0_PE3_OCP_RXN<15> @BASEBOARD_FAB2_LIB.BASEBOARD_FAB2(SCH_1):P3E_CPU0_PE3_OCP_RXN(15)   I336 @BASEBOARD_FAB2_LIB.BASEBOARD_FAB2(SCH_1):PAGE186
    62    GND @BASEBOARD_FAB2_LIB.BASEBOARD_FAB2(SCH_1):GND   I336 @BASEBOARD_FAB2_LIB.BASEBOARD_FAB2(SCH_1):PAGE186
    63    GND @BASEBOARD_FAB2_LIB.BASEBOARD_FAB2(SCH_1):GND   I336 @BASEBOARD_FAB2_LIB.BASEBOARD_FAB2(SCH_1):PAGE186
    64 P3E_OCP_CPU0_PE3_C_TXP<14> @BASEBOARD_FAB2_LIB.BASEBOARD_FAB2(SCH_1):P3E_OCP_CPU0_PE3_C_TXP(14)   I336 @BASEBOARD_FAB2_LIB.BASEBOARD_FAB2(SCH_1):PAGE186
    65    GND @BASEBOARD_FAB2_LIB.BASEBOARD_FAB2(SCH_1):GND   I336 @BASEBOARD_FAB2_LIB.BASEBOARD_FAB2(SCH_1):PAGE186
    66 P3E_OCP_CPU0_PE3_C_TXN<14> @BASEBOARD_FAB2_LIB.BASEBOARD_FAB2(SCH_1):P3E_OCP_CPU0_PE3_C_TXN(14)   I336 @BASEBOARD_FAB2_LIB.BASEBOARD_FAB2(SCH_1):PAGE186
    67 P3E_CPU0_PE3_OCP_RXP<14> @BASEBOARD_FAB2_LIB.BASEBOARD_FAB2(SCH_1):P3E_CPU0_PE3_OCP_RXP(14)   I336 @BASEBOARD_FAB2_LIB.BASEBOARD_FAB2(SCH_1):PAGE186
    68    GND @BASEBOARD_FAB2_LIB.BASEBOARD_FAB2(SCH_1):GND   I336 @BASEBOARD_FAB2_LIB.BASEBOARD_FAB2(SCH_1):PAGE186
    69 P3E_CPU0_PE3_OCP_RXN<14> @BASEBOARD_FAB2_LIB.BASEBOARD_FAB2(SCH_1):P3E_CPU0_PE3_OCP_RXN(14)   I336 @BASEBOARD_FAB2_LIB.BASEBOARD_FAB2(SCH_1):PAGE186
     7 P5V_STBY @BASEBOARD_FAB2_LIB.BASEBOARD_FAB2(SCH_1):P5V_STBY   I336 @BASEBOARD_FAB2_LIB.BASEBOARD_FAB2(SCH_1):PAGE186
    70    GND @BASEBOARD_FAB2_LIB.BASEBOARD_FAB2(SCH_1):GND   I336 @BASEBOARD_FAB2_LIB.BASEBOARD_FAB2(SCH_1):PAGE186
    71    GND @BASEBOARD_FAB2_LIB.BASEBOARD_FAB2(SCH_1):GND   I336 @BASEBOARD_FAB2_LIB.BASEBOARD_FAB2(SCH_1):PAGE186
    72 P3E_OCP_CPU0_PE3_C_TXP<13> @BASEBOARD_FAB2_LIB.BASEBOARD_FAB2(SCH_1):P3E_OCP_CPU0_PE3_C_TXP(13)   I336 @BASEBOARD_FAB2_LIB.BASEBOARD_FAB2(SCH_1):PAGE186
    73    GND @BASEBOARD_FAB2_LIB.BASEBOARD_FAB2(SCH_1):GND   I336 @BASEBOARD_FAB2_LIB.BASEBOARD_FAB2(SCH_1):PAGE186
    74 P3E_OCP_CPU0_PE3_C_TXN<13> @BASEBOARD_FAB2_LIB.BASEBOARD_FAB2(SCH_1):P3E_OCP_CPU0_PE3_C_TXN(13)   I336 @BASEBOARD_FAB2_LIB.BASEBOARD_FAB2(SCH_1):PAGE186
    75 P3E_CPU0_PE3_OCP_RXP<13> @BASEBOARD_FAB2_LIB.BASEBOARD_FAB2(SCH_1):P3E_CPU0_PE3_OCP_RXP(13)   I336 @BASEBOARD_FAB2_LIB.BASEBOARD_FAB2(SCH_1):PAGE186
    76    GND @BASEBOARD_FAB2_LIB.BASEBOARD_FAB2(SCH_1):GND   I336 @BASEBOARD_FAB2_LIB.BASEBOARD_FAB2(SCH_1):PAGE186
    77 P3E_CPU0_PE3_OCP_RXN<13> @BASEBOARD_FAB2_LIB.BASEBOARD_FAB2(SCH_1):P3E_CPU0_PE3_OCP_RXN(13)   I336 @BASEBOARD_FAB2_LIB.BASEBOARD_FAB2(SCH_1):PAGE186
    78    GND @BASEBOARD_FAB2_LIB.BASEBOARD_FAB2(SCH_1):GND   I336 @BASEBOARD_FAB2_LIB.BASEBOARD_FAB2(SCH_1):PAGE186
    79    GND @BASEBOARD_FAB2_LIB.BASEBOARD_FAB2(SCH_1):GND   I336 @BASEBOARD_FAB2_LIB.BASEBOARD_FAB2(SCH_1):PAGE186
     8    GND @BASEBOARD_FAB2_LIB.BASEBOARD_FAB2(SCH_1):GND   I336 @BASEBOARD_FAB2_LIB.BASEBOARD_FAB2(SCH_1):PAGE186
    80 P3E_OCP_CPU0_PE3_C_TXP<12> @BASEBOARD_FAB2_LIB.BASEBOARD_FAB2(SCH_1):P3E_OCP_CPU0_PE3_C_TXP(12)   I336 @BASEBOARD_FAB2_LIB.BASEBOARD_FAB2(SCH_1):PAGE186
    81    GND @BASEBOARD_FAB2_LIB.BASEBOARD_FAB2(SCH_1):GND   I336 @BASEBOARD_FAB2_LIB.BASEBOARD_FAB2(SCH_1):PAGE186
    82 P3E_OCP_CPU0_PE3_C_TXN<12> @BASEBOARD_FAB2_LIB.BASEBOARD_FAB2(SCH_1):P3E_OCP_CPU0_PE3_C_TXN(12)   I336 @BASEBOARD_FAB2_LIB.BASEBOARD_FAB2(SCH_1):PAGE186
    83 P3E_CPU0_PE3_OCP_RXP<12> @BASEBOARD_FAB2_LIB.BASEBOARD_FAB2(SCH_1):P3E_CPU0_PE3_OCP_RXP(12)   I336 @BASEBOARD_FAB2_LIB.BASEBOARD_FAB2(SCH_1):PAGE186
    84    GND @BASEBOARD_FAB2_LIB.BASEBOARD_FAB2(SCH_1):GND   I336 @BASEBOARD_FAB2_LIB.BASEBOARD_FAB2(SCH_1):PAGE186
    85 P3E_CPU0_PE3_OCP_RXN<12> @BASEBOARD_FAB2_LIB.BASEBOARD_FAB2(SCH_1):P3E_CPU0_PE3_OCP_RXN(12)   I336 @BASEBOARD_FAB2_LIB.BASEBOARD_FAB2(SCH_1):PAGE186
    86    GND @BASEBOARD_FAB2_LIB.BASEBOARD_FAB2(SCH_1):GND   I336 @BASEBOARD_FAB2_LIB.BASEBOARD_FAB2(SCH_1):PAGE186
    87    GND @BASEBOARD_FAB2_LIB.BASEBOARD_FAB2(SCH_1):GND   I336 @BASEBOARD_FAB2_LIB.BASEBOARD_FAB2(SCH_1):PAGE186
    88 P3E_OCP_CPU0_PE3_C_TXP<11> @BASEBOARD_FAB2_LIB.BASEBOARD_FAB2(SCH_1):P3E_OCP_CPU0_PE3_C_TXP(11)   I336 @BASEBOARD_FAB2_LIB.BASEBOARD_FAB2(SCH_1):PAGE186
    89    GND @BASEBOARD_FAB2_LIB.BASEBOARD_FAB2(SCH_1):GND   I336 @BASEBOARD_FAB2_LIB.BASEBOARD_FAB2(SCH_1):PAGE186
     9    GND @BASEBOARD_FAB2_LIB.BASEBOARD_FAB2(SCH_1):GND   I336 @BASEBOARD_FAB2_LIB.BASEBOARD_FAB2(SCH_1):PAGE186
    90 P3E_OCP_CPU0_PE3_C_TXN<11> @BASEBOARD_FAB2_LIB.BASEBOARD_FAB2(SCH_1):P3E_OCP_CPU0_PE3_C_TXN(11)   I336 @BASEBOARD_FAB2_LIB.BASEBOARD_FAB2(SCH_1):PAGE186
    91 P3E_CPU0_PE3_OCP_RXP<11> @BASEBOARD_FAB2_LIB.BASEBOARD_FAB2(SCH_1):P3E_CPU0_PE3_OCP_RXP(11)   I336 @BASEBOARD_FAB2_LIB.BASEBOARD_FAB2(SCH_1):PAGE186
    92    GND @BASEBOARD_FAB2_LIB.BASEBOARD_FAB2(SCH_1):GND   I336 @BASEBOARD_FAB2_LIB.BASEBOARD_FAB2(SCH_1):PAGE186
    93 P3E_CPU0_PE3_OCP_RXN<11> @BASEBOARD_FAB2_LIB.BASEBOARD_FAB2(SCH_1):P3E_CPU0_PE3_OCP_RXN(11)   I336 @BASEBOARD_FAB2_LIB.BASEBOARD_FAB2(SCH_1):PAGE186
    94    GND @BASEBOARD_FAB2_LIB.BASEBOARD_FAB2(SCH_1):GND   I336 @BASEBOARD_FAB2_LIB.BASEBOARD_FAB2(SCH_1):PAGE186
    95    GND @BASEBOARD_FAB2_LIB.BASEBOARD_FAB2(SCH_1):GND   I336 @BASEBOARD_FAB2_LIB.BASEBOARD_FAB2(SCH_1):PAGE186
    96 P3E_OCP_CPU0_PE3_C_TXP<10> @BASEBOARD_FAB2_LIB.BASEBOARD_FAB2(SCH_1):P3E_OCP_CPU0_PE3_C_TXP(10)   I336 @BASEBOARD_FAB2_LIB.BASEBOARD_FAB2(SCH_1):PAGE186
    97    GND @BASEBOARD_FAB2_LIB.BASEBOARD_FAB2(SCH_1):GND   I336 @BASEBOARD_FAB2_LIB.BASEBOARD_FAB2(SCH_1):PAGE186
    98 P3E_OCP_CPU0_PE3_C_TXN<10> @BASEBOARD_FAB2_LIB.BASEBOARD_FAB2(SCH_1):P3E_OCP_CPU0_PE3_C_TXN(10)   I336 @BASEBOARD_FAB2_LIB.BASEBOARD_FAB2(SCH_1):PAGE186
    99 P3E_CPU0_PE3_OCP_RXP<10> @BASEBOARD_FAB2_LIB.BASEBOARD_FAB2(SCH_1):P3E_CPU0_PE3_OCP_RXP(10)   I336 @BASEBOARD_FAB2_LIB.BASEBOARD_FAB2(SCH_1):PAGE186

J9B4 SCONN10_C12536004_SMLF-CONN,C1A
     1 JTAG_MCP_TCK_R @BASEBOARD_FAB2_LIB.BASEBOARD_FAB2(SCH_1):JTAG_MCP_TCK_R   I175 @BASEBOARD_FAB2_LIB.BASEBOARD_FAB2(SCH_1):PAGE113
     2    GND @BASEBOARD_FAB2_LIB.BASEBOARD_FAB2(SCH_1):GND   I175 @BASEBOARD_FAB2_LIB.BASEBOARD_FAB2(SCH_1):PAGE113
     3 JTAG_MCP_MUX_TDO @BASEBOARD_FAB2_LIB.BASEBOARD_FAB2(SCH_1):JTAG_MCP_MUX_TDO   I175 @BASEBOARD_FAB2_LIB.BASEBOARD_FAB2(SCH_1):PAGE113
     4 P1V8_MCP_CPU0 @BASEBOARD_FAB2_LIB.BASEBOARD_FAB2(SCH_1):P1V8_MCP_CPU0   I175 @BASEBOARD_FAB2_LIB.BASEBOARD_FAB2(SCH_1):PAGE113
     5 JTAG_MCP_TMS_R @BASEBOARD_FAB2_LIB.BASEBOARD_FAB2(SCH_1):JTAG_MCP_TMS_R   I175 @BASEBOARD_FAB2_LIB.BASEBOARD_FAB2(SCH_1):PAGE113
     6 JTAG_MCP_TRST_N @BASEBOARD_FAB2_LIB.BASEBOARD_FAB2(SCH_1):JTAG_MCP_TRST_N   I175 @BASEBOARD_FAB2_LIB.BASEBOARD_FAB2(SCH_1):PAGE113
     7 PWRGD_CPU0_G_R @BASEBOARD_FAB2_LIB.BASEBOARD_FAB2(SCH_1):PWRGD_CPU0_G_R   I175 @BASEBOARD_FAB2_LIB.BASEBOARD_FAB2(SCH_1):PAGE113
     8 TP_JTAG_MCP_IO8_RSVD @BASEBOARD_FAB2_LIB.BASEBOARD_FAB2(SCH_1):TP_JTAG_MCP_IO8_RSVD   I175 @BASEBOARD_FAB2_LIB.BASEBOARD_FAB2(SCH_1):PAGE113
     9 JTAG_MCP_MUX_TDI @BASEBOARD_FAB2_LIB.BASEBOARD_FAB2(SCH_1):JTAG_MCP_MUX_TDI   I175 @BASEBOARD_FAB2_LIB.BASEBOARD_FAB2(SCH_1):PAGE113
    10    GND @BASEBOARD_FAB2_LIB.BASEBOARD_FAB2(SCH_1):GND   I175 @BASEBOARD_FAB2_LIB.BASEBOARD_FAB2(SCH_1):PAGE113

J9G1 CONN12_C73564003_PIP-CONN,C735A
     1 PU_UV_HIGH_SET @BASEBOARD_FAB2_LIB.BASEBOARD_FAB2(SCH_1):PU_UV_HIGH_SET   I128 @BASEBOARD_FAB2_LIB.BASEBOARD_FAB2(SCH_1):PAGE137
    10 SPI_BMC_BT_CS0_N @BASEBOARD_FAB2_LIB.BASEBOARD_FAB2(SCH_1):SPI_BMC_BT_CS0_N   I128 @BASEBOARD_FAB2_LIB.BASEBOARD_FAB2(SCH_1):PAGE137
    11 PD_IE_DEBUG_MODE @BASEBOARD_FAB2_LIB.BASEBOARD_FAB2(SCH_1):PD_IE_DEBUG_MODE   I128 @BASEBOARD_FAB2_LIB.BASEBOARD_FAB2(SCH_1):PAGE137
    12 PD_SPI_BMC_BT_CS0_N @BASEBOARD_FAB2_LIB.BASEBOARD_FAB2(SCH_1):PD_SPI_BMC_BT_CS0_N   I128 @BASEBOARD_FAB2_LIB.BASEBOARD_FAB2(SCH_1):PAGE137
     2 TP_RST_RTCRST_N @BASEBOARD_FAB2_LIB.BASEBOARD_FAB2(SCH_1):TP_RST_RTCRST_N   I128 @BASEBOARD_FAB2_LIB.BASEBOARD_FAB2(SCH_1):PAGE137
     3 UV_HIGH_SET @BASEBOARD_FAB2_LIB.BASEBOARD_FAB2(SCH_1):UV_HIGH_SET   I128 @BASEBOARD_FAB2_LIB.BASEBOARD_FAB2(SCH_1):PAGE137
     4 RST_RTCRST_N @BASEBOARD_FAB2_LIB.BASEBOARD_FAB2(SCH_1):RST_RTCRST_N   I128 @BASEBOARD_FAB2_LIB.BASEBOARD_FAB2(SCH_1):PAGE137
     5 PD_UV_HIGH_SET @BASEBOARD_FAB2_LIB.BASEBOARD_FAB2(SCH_1):PD_UV_HIGH_SET   I128 @BASEBOARD_FAB2_LIB.BASEBOARD_FAB2(SCH_1):PAGE137
     6 PD_RST_RTCRST_N @BASEBOARD_FAB2_LIB.BASEBOARD_FAB2(SCH_1):PD_RST_RTCRST_N   I128 @BASEBOARD_FAB2_LIB.BASEBOARD_FAB2(SCH_1):PAGE137
     7 TP_IE_DEBUG_MODE @BASEBOARD_FAB2_LIB.BASEBOARD_FAB2(SCH_1):TP_IE_DEBUG_MODE   I128 @BASEBOARD_FAB2_LIB.BASEBOARD_FAB2(SCH_1):PAGE137
     8 PU_SPI_BMC_BT_CS0_N @BASEBOARD_FAB2_LIB.BASEBOARD_FAB2(SCH_1):PU_SPI_BMC_BT_CS0_N   I128 @BASEBOARD_FAB2_LIB.BASEBOARD_FAB2(SCH_1):PAGE137
     9 FM_UART_PRES_N @BASEBOARD_FAB2_LIB.BASEBOARD_FAB2(SCH_1):FM_UART_PRES_N   I128 @BASEBOARD_FAB2_LIB.BASEBOARD_FAB2(SCH_1):PAGE137

J9L1 SCONN288_H44441003_PIP-SCONN,HA
    79 M_M_MA<0> @BASEBOARD_FAB2_LIB.BASEBOARD_FAB2(SCH_1):M_M_MA(0)   I111 @BASEBOARD_FAB2_LIB.BASEBOARD_FAB2(SCH_1):PAGE88
    72 M_M_MA<1> @BASEBOARD_FAB2_LIB.BASEBOARD_FAB2(SCH_1):M_M_MA(1)   I111 @BASEBOARD_FAB2_LIB.BASEBOARD_FAB2(SCH_1):PAGE88
   225 M_M_MA<10> @BASEBOARD_FAB2_LIB.BASEBOARD_FAB2(SCH_1):M_M_MA(10)   I111 @BASEBOARD_FAB2_LIB.BASEBOARD_FAB2(SCH_1):PAGE88
   210 M_M_MA<11> @BASEBOARD_FAB2_LIB.BASEBOARD_FAB2(SCH_1):M_M_MA(11)   I111 @BASEBOARD_FAB2_LIB.BASEBOARD_FAB2(SCH_1):PAGE88
    65 M_M_MA<12> @BASEBOARD_FAB2_LIB.BASEBOARD_FAB2(SCH_1):M_M_MA(12)   I111 @BASEBOARD_FAB2_LIB.BASEBOARD_FAB2(SCH_1):PAGE88
   232 M_M_MA<13> @BASEBOARD_FAB2_LIB.BASEBOARD_FAB2(SCH_1):M_M_MA(13)   I111 @BASEBOARD_FAB2_LIB.BASEBOARD_FAB2(SCH_1):PAGE88
   228 M_M_MA<14> @BASEBOARD_FAB2_LIB.BASEBOARD_FAB2(SCH_1):M_M_MA(14)   I111 @BASEBOARD_FAB2_LIB.BASEBOARD_FAB2(SCH_1):PAGE88
    86 M_M_MA<15> @BASEBOARD_FAB2_LIB.BASEBOARD_FAB2(SCH_1):M_M_MA(15)   I111 @BASEBOARD_FAB2_LIB.BASEBOARD_FAB2(SCH_1):PAGE88
    82 M_M_MA<16> @BASEBOARD_FAB2_LIB.BASEBOARD_FAB2(SCH_1):M_M_MA(16)   I111 @BASEBOARD_FAB2_LIB.BASEBOARD_FAB2(SCH_1):PAGE88
   234 M_M_MA<17> @BASEBOARD_FAB2_LIB.BASEBOARD_FAB2(SCH_1):M_M_MA(17)   I111 @BASEBOARD_FAB2_LIB.BASEBOARD_FAB2(SCH_1):PAGE88
   216 M_M_MA<2> @BASEBOARD_FAB2_LIB.BASEBOARD_FAB2(SCH_1):M_M_MA(2)   I111 @BASEBOARD_FAB2_LIB.BASEBOARD_FAB2(SCH_1):PAGE88
    71 M_M_MA<3> @BASEBOARD_FAB2_LIB.BASEBOARD_FAB2(SCH_1):M_M_MA(3)   I111 @BASEBOARD_FAB2_LIB.BASEBOARD_FAB2(SCH_1):PAGE88
   214 M_M_MA<4> @BASEBOARD_FAB2_LIB.BASEBOARD_FAB2(SCH_1):M_M_MA(4)   I111 @BASEBOARD_FAB2_LIB.BASEBOARD_FAB2(SCH_1):PAGE88
   213 M_M_MA<5> @BASEBOARD_FAB2_LIB.BASEBOARD_FAB2(SCH_1):M_M_MA(5)   I111 @BASEBOARD_FAB2_LIB.BASEBOARD_FAB2(SCH_1):PAGE88
    69 M_M_MA<6> @BASEBOARD_FAB2_LIB.BASEBOARD_FAB2(SCH_1):M_M_MA(6)   I111 @BASEBOARD_FAB2_LIB.BASEBOARD_FAB2(SCH_1):PAGE88
   211 M_M_MA<7> @BASEBOARD_FAB2_LIB.BASEBOARD_FAB2(SCH_1):M_M_MA(7)   I111 @BASEBOARD_FAB2_LIB.BASEBOARD_FAB2(SCH_1):PAGE88
    68 M_M_MA<8> @BASEBOARD_FAB2_LIB.BASEBOARD_FAB2(SCH_1):M_M_MA(8)   I111 @BASEBOARD_FAB2_LIB.BASEBOARD_FAB2(SCH_1):PAGE88
    66 M_M_MA<9> @BASEBOARD_FAB2_LIB.BASEBOARD_FAB2(SCH_1):M_M_MA(9)   I111 @BASEBOARD_FAB2_LIB.BASEBOARD_FAB2(SCH_1):PAGE88
    62 M_M_ACT_N @BASEBOARD_FAB2_LIB.BASEBOARD_FAB2(SCH_1):M_M_ACT_N   I111 @BASEBOARD_FAB2_LIB.BASEBOARD_FAB2(SCH_1):PAGE88
   208 M_M_ALERT_N @BASEBOARD_FAB2_LIB.BASEBOARD_FAB2(SCH_1):M_M_ALERT_N   I111 @BASEBOARD_FAB2_LIB.BASEBOARD_FAB2(SCH_1):PAGE88
   224 M_M_BA<1> @BASEBOARD_FAB2_LIB.BASEBOARD_FAB2(SCH_1):M_M_BA(1)   I111 @BASEBOARD_FAB2_LIB.BASEBOARD_FAB2(SCH_1):PAGE88
    81 M_M_BA<0> @BASEBOARD_FAB2_LIB.BASEBOARD_FAB2(SCH_1):M_M_BA(0)   I111 @BASEBOARD_FAB2_LIB.BASEBOARD_FAB2(SCH_1):PAGE88
   207 M_M_BG<1> @BASEBOARD_FAB2_LIB.BASEBOARD_FAB2(SCH_1):M_M_BG(1)   I111 @BASEBOARD_FAB2_LIB.BASEBOARD_FAB2(SCH_1):PAGE88
    63 M_M_BG<0> @BASEBOARD_FAB2_LIB.BASEBOARD_FAB2(SCH_1):M_M_BG(0)   I111 @BASEBOARD_FAB2_LIB.BASEBOARD_FAB2(SCH_1):PAGE88
   235 M_M_C<2> @BASEBOARD_FAB2_LIB.BASEBOARD_FAB2(SCH_1):M_M_C(2)   I111 @BASEBOARD_FAB2_LIB.BASEBOARD_FAB2(SCH_1):PAGE88
   199 M_M_ECC<7> @BASEBOARD_FAB2_LIB.BASEBOARD_FAB2(SCH_1):M_M_ECC(7)   I111 @BASEBOARD_FAB2_LIB.BASEBOARD_FAB2(SCH_1):PAGE88
    54 M_M_ECC<6> @BASEBOARD_FAB2_LIB.BASEBOARD_FAB2(SCH_1):M_M_ECC(6)   I111 @BASEBOARD_FAB2_LIB.BASEBOARD_FAB2(SCH_1):PAGE88
   192 M_M_ECC<5> @BASEBOARD_FAB2_LIB.BASEBOARD_FAB2(SCH_1):M_M_ECC(5)   I111 @BASEBOARD_FAB2_LIB.BASEBOARD_FAB2(SCH_1):PAGE88
    47 M_M_ECC<4> @BASEBOARD_FAB2_LIB.BASEBOARD_FAB2(SCH_1):M_M_ECC(4)   I111 @BASEBOARD_FAB2_LIB.BASEBOARD_FAB2(SCH_1):PAGE88
   201 M_M_ECC<3> @BASEBOARD_FAB2_LIB.BASEBOARD_FAB2(SCH_1):M_M_ECC(3)   I111 @BASEBOARD_FAB2_LIB.BASEBOARD_FAB2(SCH_1):PAGE88
    56 M_M_ECC<2> @BASEBOARD_FAB2_LIB.BASEBOARD_FAB2(SCH_1):M_M_ECC(2)   I111 @BASEBOARD_FAB2_LIB.BASEBOARD_FAB2(SCH_1):PAGE88
   194 M_M_ECC<1> @BASEBOARD_FAB2_LIB.BASEBOARD_FAB2(SCH_1):M_M_ECC(1)   I111 @BASEBOARD_FAB2_LIB.BASEBOARD_FAB2(SCH_1):PAGE88
    49 M_M_ECC<0> @BASEBOARD_FAB2_LIB.BASEBOARD_FAB2(SCH_1):M_M_ECC(0)   I111 @BASEBOARD_FAB2_LIB.BASEBOARD_FAB2(SCH_1):PAGE88
    75 M_M_CLK_DN<2> @BASEBOARD_FAB2_LIB.BASEBOARD_FAB2(SCH_1):M_M_CLK_DN(2)   I111 @BASEBOARD_FAB2_LIB.BASEBOARD_FAB2(SCH_1):PAGE88
    74 M_M_CLK_DP<2> @BASEBOARD_FAB2_LIB.BASEBOARD_FAB2(SCH_1):M_M_CLK_DP(2)   I111 @BASEBOARD_FAB2_LIB.BASEBOARD_FAB2(SCH_1):PAGE88
   219 M_M_CLK_DN<3> @BASEBOARD_FAB2_LIB.BASEBOARD_FAB2(SCH_1):M_M_CLK_DN(3)   I111 @BASEBOARD_FAB2_LIB.BASEBOARD_FAB2(SCH_1):PAGE88
   218 M_M_CLK_DP<3> @BASEBOARD_FAB2_LIB.BASEBOARD_FAB2(SCH_1):M_M_CLK_DP(3)   I111 @BASEBOARD_FAB2_LIB.BASEBOARD_FAB2(SCH_1):PAGE88
   203 M_M_CKE<3> @BASEBOARD_FAB2_LIB.BASEBOARD_FAB2(SCH_1):M_M_CKE(3)   I111 @BASEBOARD_FAB2_LIB.BASEBOARD_FAB2(SCH_1):PAGE88
    60 M_M_CKE<2> @BASEBOARD_FAB2_LIB.BASEBOARD_FAB2(SCH_1):M_M_CKE(2)   I111 @BASEBOARD_FAB2_LIB.BASEBOARD_FAB2(SCH_1):PAGE88
   280 M_M_DQ<63> @BASEBOARD_FAB2_LIB.BASEBOARD_FAB2(SCH_1):M_M_DQ(63)   I111 @BASEBOARD_FAB2_LIB.BASEBOARD_FAB2(SCH_1):PAGE88
   135 M_M_DQ<62> @BASEBOARD_FAB2_LIB.BASEBOARD_FAB2(SCH_1):M_M_DQ(62)   I111 @BASEBOARD_FAB2_LIB.BASEBOARD_FAB2(SCH_1):PAGE88
   273 M_M_DQ<61> @BASEBOARD_FAB2_LIB.BASEBOARD_FAB2(SCH_1):M_M_DQ(61)   I111 @BASEBOARD_FAB2_LIB.BASEBOARD_FAB2(SCH_1):PAGE88
   128 M_M_DQ<60> @BASEBOARD_FAB2_LIB.BASEBOARD_FAB2(SCH_1):M_M_DQ(60)   I111 @BASEBOARD_FAB2_LIB.BASEBOARD_FAB2(SCH_1):PAGE88
   282 M_M_DQ<59> @BASEBOARD_FAB2_LIB.BASEBOARD_FAB2(SCH_1):M_M_DQ(59)   I111 @BASEBOARD_FAB2_LIB.BASEBOARD_FAB2(SCH_1):PAGE88
   137 M_M_DQ<58> @BASEBOARD_FAB2_LIB.BASEBOARD_FAB2(SCH_1):M_M_DQ(58)   I111 @BASEBOARD_FAB2_LIB.BASEBOARD_FAB2(SCH_1):PAGE88
   275 M_M_DQ<57> @BASEBOARD_FAB2_LIB.BASEBOARD_FAB2(SCH_1):M_M_DQ(57)   I111 @BASEBOARD_FAB2_LIB.BASEBOARD_FAB2(SCH_1):PAGE88
   130 M_M_DQ<56> @BASEBOARD_FAB2_LIB.BASEBOARD_FAB2(SCH_1):M_M_DQ(56)   I111 @BASEBOARD_FAB2_LIB.BASEBOARD_FAB2(SCH_1):PAGE88
   269 M_M_DQ<55> @BASEBOARD_FAB2_LIB.BASEBOARD_FAB2(SCH_1):M_M_DQ(55)   I111 @BASEBOARD_FAB2_LIB.BASEBOARD_FAB2(SCH_1):PAGE88
   124 M_M_DQ<54> @BASEBOARD_FAB2_LIB.BASEBOARD_FAB2(SCH_1):M_M_DQ(54)   I111 @BASEBOARD_FAB2_LIB.BASEBOARD_FAB2(SCH_1):PAGE88
   262 M_M_DQ<53> @BASEBOARD_FAB2_LIB.BASEBOARD_FAB2(SCH_1):M_M_DQ(53)   I111 @BASEBOARD_FAB2_LIB.BASEBOARD_FAB2(SCH_1):PAGE88
   117 M_M_DQ<52> @BASEBOARD_FAB2_LIB.BASEBOARD_FAB2(SCH_1):M_M_DQ(52)   I111 @BASEBOARD_FAB2_LIB.BASEBOARD_FAB2(SCH_1):PAGE88
   271 M_M_DQ<51> @BASEBOARD_FAB2_LIB.BASEBOARD_FAB2(SCH_1):M_M_DQ(51)   I111 @BASEBOARD_FAB2_LIB.BASEBOARD_FAB2(SCH_1):PAGE88
   126 M_M_DQ<50> @BASEBOARD_FAB2_LIB.BASEBOARD_FAB2(SCH_1):M_M_DQ(50)   I111 @BASEBOARD_FAB2_LIB.BASEBOARD_FAB2(SCH_1):PAGE88
   264 M_M_DQ<49> @BASEBOARD_FAB2_LIB.BASEBOARD_FAB2(SCH_1):M_M_DQ(49)   I111 @BASEBOARD_FAB2_LIB.BASEBOARD_FAB2(SCH_1):PAGE88
   119 M_M_DQ<48> @BASEBOARD_FAB2_LIB.BASEBOARD_FAB2(SCH_1):M_M_DQ(48)   I111 @BASEBOARD_FAB2_LIB.BASEBOARD_FAB2(SCH_1):PAGE88
   258 M_M_DQ<47> @BASEBOARD_FAB2_LIB.BASEBOARD_FAB2(SCH_1):M_M_DQ(47)   I111 @BASEBOARD_FAB2_LIB.BASEBOARD_FAB2(SCH_1):PAGE88
   113 M_M_DQ<46> @BASEBOARD_FAB2_LIB.BASEBOARD_FAB2(SCH_1):M_M_DQ(46)   I111 @BASEBOARD_FAB2_LIB.BASEBOARD_FAB2(SCH_1):PAGE88
   251 M_M_DQ<45> @BASEBOARD_FAB2_LIB.BASEBOARD_FAB2(SCH_1):M_M_DQ(45)   I111 @BASEBOARD_FAB2_LIB.BASEBOARD_FAB2(SCH_1):PAGE88
   106 M_M_DQ<44> @BASEBOARD_FAB2_LIB.BASEBOARD_FAB2(SCH_1):M_M_DQ(44)   I111 @BASEBOARD_FAB2_LIB.BASEBOARD_FAB2(SCH_1):PAGE88
   260 M_M_DQ<43> @BASEBOARD_FAB2_LIB.BASEBOARD_FAB2(SCH_1):M_M_DQ(43)   I111 @BASEBOARD_FAB2_LIB.BASEBOARD_FAB2(SCH_1):PAGE88
   115 M_M_DQ<42> @BASEBOARD_FAB2_LIB.BASEBOARD_FAB2(SCH_1):M_M_DQ(42)   I111 @BASEBOARD_FAB2_LIB.BASEBOARD_FAB2(SCH_1):PAGE88
   253 M_M_DQ<41> @BASEBOARD_FAB2_LIB.BASEBOARD_FAB2(SCH_1):M_M_DQ(41)   I111 @BASEBOARD_FAB2_LIB.BASEBOARD_FAB2(SCH_1):PAGE88
   108 M_M_DQ<40> @BASEBOARD_FAB2_LIB.BASEBOARD_FAB2(SCH_1):M_M_DQ(40)   I111 @BASEBOARD_FAB2_LIB.BASEBOARD_FAB2(SCH_1):PAGE88
   247 M_M_DQ<39> @BASEBOARD_FAB2_LIB.BASEBOARD_FAB2(SCH_1):M_M_DQ(39)   I111 @BASEBOARD_FAB2_LIB.BASEBOARD_FAB2(SCH_1):PAGE88
   102 M_M_DQ<38> @BASEBOARD_FAB2_LIB.BASEBOARD_FAB2(SCH_1):M_M_DQ(38)   I111 @BASEBOARD_FAB2_LIB.BASEBOARD_FAB2(SCH_1):PAGE88
   240 M_M_DQ<37> @BASEBOARD_FAB2_LIB.BASEBOARD_FAB2(SCH_1):M_M_DQ(37)   I111 @BASEBOARD_FAB2_LIB.BASEBOARD_FAB2(SCH_1):PAGE88
    95 M_M_DQ<36> @BASEBOARD_FAB2_LIB.BASEBOARD_FAB2(SCH_1):M_M_DQ(36)   I111 @BASEBOARD_FAB2_LIB.BASEBOARD_FAB2(SCH_1):PAGE88
   249 M_M_DQ<35> @BASEBOARD_FAB2_LIB.BASEBOARD_FAB2(SCH_1):M_M_DQ(35)   I111 @BASEBOARD_FAB2_LIB.BASEBOARD_FAB2(SCH_1):PAGE88
   104 M_M_DQ<34> @BASEBOARD_FAB2_LIB.BASEBOARD_FAB2(SCH_1):M_M_DQ(34)   I111 @BASEBOARD_FAB2_LIB.BASEBOARD_FAB2(SCH_1):PAGE88
   242 M_M_DQ<33> @BASEBOARD_FAB2_LIB.BASEBOARD_FAB2(SCH_1):M_M_DQ(33)   I111 @BASEBOARD_FAB2_LIB.BASEBOARD_FAB2(SCH_1):PAGE88
    97 M_M_DQ<32> @BASEBOARD_FAB2_LIB.BASEBOARD_FAB2(SCH_1):M_M_DQ(32)   I111 @BASEBOARD_FAB2_LIB.BASEBOARD_FAB2(SCH_1):PAGE88
   188 M_M_DQ<31> @BASEBOARD_FAB2_LIB.BASEBOARD_FAB2(SCH_1):M_M_DQ(31)   I111 @BASEBOARD_FAB2_LIB.BASEBOARD_FAB2(SCH_1):PAGE88
    43 M_M_DQ<30> @BASEBOARD_FAB2_LIB.BASEBOARD_FAB2(SCH_1):M_M_DQ(30)   I111 @BASEBOARD_FAB2_LIB.BASEBOARD_FAB2(SCH_1):PAGE88
   181 M_M_DQ<29> @BASEBOARD_FAB2_LIB.BASEBOARD_FAB2(SCH_1):M_M_DQ(29)   I111 @BASEBOARD_FAB2_LIB.BASEBOARD_FAB2(SCH_1):PAGE88
    36 M_M_DQ<28> @BASEBOARD_FAB2_LIB.BASEBOARD_FAB2(SCH_1):M_M_DQ(28)   I111 @BASEBOARD_FAB2_LIB.BASEBOARD_FAB2(SCH_1):PAGE88
   190 M_M_DQ<27> @BASEBOARD_FAB2_LIB.BASEBOARD_FAB2(SCH_1):M_M_DQ(27)   I111 @BASEBOARD_FAB2_LIB.BASEBOARD_FAB2(SCH_1):PAGE88
    45 M_M_DQ<26> @BASEBOARD_FAB2_LIB.BASEBOARD_FAB2(SCH_1):M_M_DQ(26)   I111 @BASEBOARD_FAB2_LIB.BASEBOARD_FAB2(SCH_1):PAGE88
   183 M_M_DQ<25> @BASEBOARD_FAB2_LIB.BASEBOARD_FAB2(SCH_1):M_M_DQ(25)   I111 @BASEBOARD_FAB2_LIB.BASEBOARD_FAB2(SCH_1):PAGE88
    38 M_M_DQ<24> @BASEBOARD_FAB2_LIB.BASEBOARD_FAB2(SCH_1):M_M_DQ(24)   I111 @BASEBOARD_FAB2_LIB.BASEBOARD_FAB2(SCH_1):PAGE88
   177 M_M_DQ<23> @BASEBOARD_FAB2_LIB.BASEBOARD_FAB2(SCH_1):M_M_DQ(23)   I111 @BASEBOARD_FAB2_LIB.BASEBOARD_FAB2(SCH_1):PAGE88
    32 M_M_DQ<22> @BASEBOARD_FAB2_LIB.BASEBOARD_FAB2(SCH_1):M_M_DQ(22)   I111 @BASEBOARD_FAB2_LIB.BASEBOARD_FAB2(SCH_1):PAGE88
   170 M_M_DQ<21> @BASEBOARD_FAB2_LIB.BASEBOARD_FAB2(SCH_1):M_M_DQ(21)   I111 @BASEBOARD_FAB2_LIB.BASEBOARD_FAB2(SCH_1):PAGE88
    25 M_M_DQ<20> @BASEBOARD_FAB2_LIB.BASEBOARD_FAB2(SCH_1):M_M_DQ(20)   I111 @BASEBOARD_FAB2_LIB.BASEBOARD_FAB2(SCH_1):PAGE88
   179 M_M_DQ<19> @BASEBOARD_FAB2_LIB.BASEBOARD_FAB2(SCH_1):M_M_DQ(19)   I111 @BASEBOARD_FAB2_LIB.BASEBOARD_FAB2(SCH_1):PAGE88
    34 M_M_DQ<18> @BASEBOARD_FAB2_LIB.BASEBOARD_FAB2(SCH_1):M_M_DQ(18)   I111 @BASEBOARD_FAB2_LIB.BASEBOARD_FAB2(SCH_1):PAGE88
   172 M_M_DQ<17> @BASEBOARD_FAB2_LIB.BASEBOARD_FAB2(SCH_1):M_M_DQ(17)   I111 @BASEBOARD_FAB2_LIB.BASEBOARD_FAB2(SCH_1):PAGE88
    27 M_M_DQ<16> @BASEBOARD_FAB2_LIB.BASEBOARD_FAB2(SCH_1):M_M_DQ(16)   I111 @BASEBOARD_FAB2_LIB.BASEBOARD_FAB2(SCH_1):PAGE88
   166 M_M_DQ<15> @BASEBOARD_FAB2_LIB.BASEBOARD_FAB2(SCH_1):M_M_DQ(15)   I111 @BASEBOARD_FAB2_LIB.BASEBOARD_FAB2(SCH_1):PAGE88
    21 M_M_DQ<14> @BASEBOARD_FAB2_LIB.BASEBOARD_FAB2(SCH_1):M_M_DQ(14)   I111 @BASEBOARD_FAB2_LIB.BASEBOARD_FAB2(SCH_1):PAGE88
   159 M_M_DQ<13> @BASEBOARD_FAB2_LIB.BASEBOARD_FAB2(SCH_1):M_M_DQ(13)   I111 @BASEBOARD_FAB2_LIB.BASEBOARD_FAB2(SCH_1):PAGE88
    14 M_M_DQ<12> @BASEBOARD_FAB2_LIB.BASEBOARD_FAB2(SCH_1):M_M_DQ(12)   I111 @BASEBOARD_FAB2_LIB.BASEBOARD_FAB2(SCH_1):PAGE88
   168 M_M_DQ<11> @BASEBOARD_FAB2_LIB.BASEBOARD_FAB2(SCH_1):M_M_DQ(11)   I111 @BASEBOARD_FAB2_LIB.BASEBOARD_FAB2(SCH_1):PAGE88
    23 M_M_DQ<10> @BASEBOARD_FAB2_LIB.BASEBOARD_FAB2(SCH_1):M_M_DQ(10)   I111 @BASEBOARD_FAB2_LIB.BASEBOARD_FAB2(SCH_1):PAGE88
   161 M_M_DQ<9> @BASEBOARD_FAB2_LIB.BASEBOARD_FAB2(SCH_1):M_M_DQ(9)   I111 @BASEBOARD_FAB2_LIB.BASEBOARD_FAB2(SCH_1):PAGE88
    16 M_M_DQ<8> @BASEBOARD_FAB2_LIB.BASEBOARD_FAB2(SCH_1):M_M_DQ(8)   I111 @BASEBOARD_FAB2_LIB.BASEBOARD_FAB2(SCH_1):PAGE88
   155 M_M_DQ<7> @BASEBOARD_FAB2_LIB.BASEBOARD_FAB2(SCH_1):M_M_DQ(7)   I111 @BASEBOARD_FAB2_LIB.BASEBOARD_FAB2(SCH_1):PAGE88
    10 M_M_DQ<6> @BASEBOARD_FAB2_LIB.BASEBOARD_FAB2(SCH_1):M_M_DQ(6)   I111 @BASEBOARD_FAB2_LIB.BASEBOARD_FAB2(SCH_1):PAGE88
   148 M_M_DQ<5> @BASEBOARD_FAB2_LIB.BASEBOARD_FAB2(SCH_1):M_M_DQ(5)   I111 @BASEBOARD_FAB2_LIB.BASEBOARD_FAB2(SCH_1):PAGE88
     3 M_M_DQ<4> @BASEBOARD_FAB2_LIB.BASEBOARD_FAB2(SCH_1):M_M_DQ(4)   I111 @BASEBOARD_FAB2_LIB.BASEBOARD_FAB2(SCH_1):PAGE88
   157 M_M_DQ<3> @BASEBOARD_FAB2_LIB.BASEBOARD_FAB2(SCH_1):M_M_DQ(3)   I111 @BASEBOARD_FAB2_LIB.BASEBOARD_FAB2(SCH_1):PAGE88
    12 M_M_DQ<2> @BASEBOARD_FAB2_LIB.BASEBOARD_FAB2(SCH_1):M_M_DQ(2)   I111 @BASEBOARD_FAB2_LIB.BASEBOARD_FAB2(SCH_1):PAGE88
   150 M_M_DQ<1> @BASEBOARD_FAB2_LIB.BASEBOARD_FAB2(SCH_1):M_M_DQ(1)   I111 @BASEBOARD_FAB2_LIB.BASEBOARD_FAB2(SCH_1):PAGE88
     5 M_M_DQ<0> @BASEBOARD_FAB2_LIB.BASEBOARD_FAB2(SCH_1):M_M_DQ(0)   I111 @BASEBOARD_FAB2_LIB.BASEBOARD_FAB2(SCH_1):PAGE88
    78 FM_DIMM_EVENT_COD_N @BASEBOARD_FAB2_LIB.BASEBOARD_FAB2(SCH_1):FM_DIMM_EVENT_COD_N   I111 @BASEBOARD_FAB2_LIB.BASEBOARD_FAB2(SCH_1):PAGE88
    91 M_M_ODT<3> @BASEBOARD_FAB2_LIB.BASEBOARD_FAB2(SCH_1):M_M_ODT(3)   I111 @BASEBOARD_FAB2_LIB.BASEBOARD_FAB2(SCH_1):PAGE88
    87 M_M_ODT<2> @BASEBOARD_FAB2_LIB.BASEBOARD_FAB2(SCH_1):M_M_ODT(2)   I111 @BASEBOARD_FAB2_LIB.BASEBOARD_FAB2(SCH_1):PAGE88
   222 M_M_PAR @BASEBOARD_FAB2_LIB.BASEBOARD_FAB2(SCH_1):M_M_PAR   I111 @BASEBOARD_FAB2_LIB.BASEBOARD_FAB2(SCH_1):PAGE88
    58 M_KLM_RST_N @BASEBOARD_FAB2_LIB.BASEBOARD_FAB2(SCH_1):M_KLM_RST_N   I111 @BASEBOARD_FAB2_LIB.BASEBOARD_FAB2(SCH_1):PAGE88
   144 TP_CH_M_DIMM_M1_RFU_2 @BASEBOARD_FAB2_LIB.BASEBOARD_FAB2(SCH_1):TP_CH_M_DIMM_M1_RFU_2   I111 @BASEBOARD_FAB2_LIB.BASEBOARD_FAB2(SCH_1):PAGE88
   227 TP_CH_M_DIMM_M1_RFU_1 @BASEBOARD_FAB2_LIB.BASEBOARD_FAB2(SCH_1):TP_CH_M_DIMM_M1_RFU_1   I111 @BASEBOARD_FAB2_LIB.BASEBOARD_FAB2(SCH_1):PAGE88
   205 TP_CH_M_DIMM_M1_RFU_0 @BASEBOARD_FAB2_LIB.BASEBOARD_FAB2(SCH_1):TP_CH_M_DIMM_M1_RFU_0   I111 @BASEBOARD_FAB2_LIB.BASEBOARD_FAB2(SCH_1):PAGE88
    84 M_M_CS_N<4> @BASEBOARD_FAB2_LIB.BASEBOARD_FAB2(SCH_1):M_M_CS_N(4)   I111 @BASEBOARD_FAB2_LIB.BASEBOARD_FAB2(SCH_1):PAGE88
    89 M_M_CS_N<5> @BASEBOARD_FAB2_LIB.BASEBOARD_FAB2(SCH_1):M_M_CS_N(5)   I111 @BASEBOARD_FAB2_LIB.BASEBOARD_FAB2(SCH_1):PAGE88
    93 M_M_CS_N<6> @BASEBOARD_FAB2_LIB.BASEBOARD_FAB2(SCH_1):M_M_CS_N(6)   I111 @BASEBOARD_FAB2_LIB.BASEBOARD_FAB2(SCH_1):PAGE88
   237 M_M_CS_N<7> @BASEBOARD_FAB2_LIB.BASEBOARD_FAB2(SCH_1):M_M_CS_N(7)   I111 @BASEBOARD_FAB2_LIB.BASEBOARD_FAB2(SCH_1):PAGE88
   238 PVPP_KLM @BASEBOARD_FAB2_LIB.BASEBOARD_FAB2(SCH_1):PVPP_KLM   I111 @BASEBOARD_FAB2_LIB.BASEBOARD_FAB2(SCH_1):PAGE88
   140    GND @BASEBOARD_FAB2_LIB.BASEBOARD_FAB2(SCH_1):GND   I111 @BASEBOARD_FAB2_LIB.BASEBOARD_FAB2(SCH_1):PAGE88
   139 PVPP_KLM @BASEBOARD_FAB2_LIB.BASEBOARD_FAB2(SCH_1):PVPP_KLM   I111 @BASEBOARD_FAB2_LIB.BASEBOARD_FAB2(SCH_1):PAGE88
   230 FM_ADR_COMPLETE_KLM_N @BASEBOARD_FAB2_LIB.BASEBOARD_FAB2(SCH_1):FM_ADR_COMPLETE_KLM_N   I111 @BASEBOARD_FAB2_LIB.BASEBOARD_FAB2(SCH_1):PAGE88
   141 SMB_DDR_KLM_VPP_SCL @BASEBOARD_FAB2_LIB.BASEBOARD_FAB2(SCH_1):SMB_DDR_KLM_VPP_SCL   I111 @BASEBOARD_FAB2_LIB.BASEBOARD_FAB2(SCH_1):PAGE88
   285 SMB_DDR_KLM_VPP_SDA @BASEBOARD_FAB2_LIB.BASEBOARD_FAB2(SCH_1):SMB_DDR_KLM_VPP_SDA   I111 @BASEBOARD_FAB2_LIB.BASEBOARD_FAB2(SCH_1):PAGE88
   284 PVPP_KLM @BASEBOARD_FAB2_LIB.BASEBOARD_FAB2(SCH_1):PVPP_KLM   I111 @BASEBOARD_FAB2_LIB.BASEBOARD_FAB2(SCH_1):PAGE88
   146 M_M_VREF @BASEBOARD_FAB2_LIB.BASEBOARD_FAB2(SCH_1):M_M_VREF   I111 @BASEBOARD_FAB2_LIB.BASEBOARD_FAB2(SCH_1):PAGE88
   152 M_M_DQS_DN<0> @BASEBOARD_FAB2_LIB.BASEBOARD_FAB2(SCH_1):M_M_DQS_DN(0)    I87 @BASEBOARD_FAB2_LIB.BASEBOARD_FAB2(SCH_1):PAGE88
   153 M_M_DQS_DP<0> @BASEBOARD_FAB2_LIB.BASEBOARD_FAB2(SCH_1):M_M_DQS_DP(0)    I87 @BASEBOARD_FAB2_LIB.BASEBOARD_FAB2(SCH_1):PAGE88
    19 M_M_DQS_DN<10> @BASEBOARD_FAB2_LIB.BASEBOARD_FAB2(SCH_1):M_M_DQS_DN(10)    I87 @BASEBOARD_FAB2_LIB.BASEBOARD_FAB2(SCH_1):PAGE88
    18 M_M_DQS_DP<10> @BASEBOARD_FAB2_LIB.BASEBOARD_FAB2(SCH_1):M_M_DQS_DP(10)    I87 @BASEBOARD_FAB2_LIB.BASEBOARD_FAB2(SCH_1):PAGE88
    30 M_M_DQS_DN<11> @BASEBOARD_FAB2_LIB.BASEBOARD_FAB2(SCH_1):M_M_DQS_DN(11)    I87 @BASEBOARD_FAB2_LIB.BASEBOARD_FAB2(SCH_1):PAGE88
    29 M_M_DQS_DP<11> @BASEBOARD_FAB2_LIB.BASEBOARD_FAB2(SCH_1):M_M_DQS_DP(11)    I87 @BASEBOARD_FAB2_LIB.BASEBOARD_FAB2(SCH_1):PAGE88
    41 M_M_DQS_DN<12> @BASEBOARD_FAB2_LIB.BASEBOARD_FAB2(SCH_1):M_M_DQS_DN(12)    I87 @BASEBOARD_FAB2_LIB.BASEBOARD_FAB2(SCH_1):PAGE88
    40 M_M_DQS_DP<12> @BASEBOARD_FAB2_LIB.BASEBOARD_FAB2(SCH_1):M_M_DQS_DP(12)    I87 @BASEBOARD_FAB2_LIB.BASEBOARD_FAB2(SCH_1):PAGE88
   100 M_M_DQS_DN<13> @BASEBOARD_FAB2_LIB.BASEBOARD_FAB2(SCH_1):M_M_DQS_DN(13)    I87 @BASEBOARD_FAB2_LIB.BASEBOARD_FAB2(SCH_1):PAGE88
    99 M_M_DQS_DP<13> @BASEBOARD_FAB2_LIB.BASEBOARD_FAB2(SCH_1):M_M_DQS_DP(13)    I87 @BASEBOARD_FAB2_LIB.BASEBOARD_FAB2(SCH_1):PAGE88
   111 M_M_DQS_DN<14> @BASEBOARD_FAB2_LIB.BASEBOARD_FAB2(SCH_1):M_M_DQS_DN(14)    I87 @BASEBOARD_FAB2_LIB.BASEBOARD_FAB2(SCH_1):PAGE88
   110 M_M_DQS_DP<14> @BASEBOARD_FAB2_LIB.BASEBOARD_FAB2(SCH_1):M_M_DQS_DP(14)    I87 @BASEBOARD_FAB2_LIB.BASEBOARD_FAB2(SCH_1):PAGE88
   122 M_M_DQS_DN<15> @BASEBOARD_FAB2_LIB.BASEBOARD_FAB2(SCH_1):M_M_DQS_DN(15)    I87 @BASEBOARD_FAB2_LIB.BASEBOARD_FAB2(SCH_1):PAGE88
   121 M_M_DQS_DP<15> @BASEBOARD_FAB2_LIB.BASEBOARD_FAB2(SCH_1):M_M_DQS_DP(15)    I87 @BASEBOARD_FAB2_LIB.BASEBOARD_FAB2(SCH_1):PAGE88
   133 M_M_DQS_DN<16> @BASEBOARD_FAB2_LIB.BASEBOARD_FAB2(SCH_1):M_M_DQS_DN(16)    I87 @BASEBOARD_FAB2_LIB.BASEBOARD_FAB2(SCH_1):PAGE88
   132 M_M_DQS_DP<16> @BASEBOARD_FAB2_LIB.BASEBOARD_FAB2(SCH_1):M_M_DQS_DP(16)    I87 @BASEBOARD_FAB2_LIB.BASEBOARD_FAB2(SCH_1):PAGE88
    52 M_M_DQS_DN<17> @BASEBOARD_FAB2_LIB.BASEBOARD_FAB2(SCH_1):M_M_DQS_DN(17)    I87 @BASEBOARD_FAB2_LIB.BASEBOARD_FAB2(SCH_1):PAGE88
    51 M_M_DQS_DP<17> @BASEBOARD_FAB2_LIB.BASEBOARD_FAB2(SCH_1):M_M_DQS_DP(17)    I87 @BASEBOARD_FAB2_LIB.BASEBOARD_FAB2(SCH_1):PAGE88
   163 M_M_DQS_DN<1> @BASEBOARD_FAB2_LIB.BASEBOARD_FAB2(SCH_1):M_M_DQS_DN(1)    I87 @BASEBOARD_FAB2_LIB.BASEBOARD_FAB2(SCH_1):PAGE88
   164 M_M_DQS_DP<1> @BASEBOARD_FAB2_LIB.BASEBOARD_FAB2(SCH_1):M_M_DQS_DP(1)    I87 @BASEBOARD_FAB2_LIB.BASEBOARD_FAB2(SCH_1):PAGE88
   174 M_M_DQS_DN<2> @BASEBOARD_FAB2_LIB.BASEBOARD_FAB2(SCH_1):M_M_DQS_DN(2)    I87 @BASEBOARD_FAB2_LIB.BASEBOARD_FAB2(SCH_1):PAGE88
   175 M_M_DQS_DP<2> @BASEBOARD_FAB2_LIB.BASEBOARD_FAB2(SCH_1):M_M_DQS_DP(2)    I87 @BASEBOARD_FAB2_LIB.BASEBOARD_FAB2(SCH_1):PAGE88
   185 M_M_DQS_DN<3> @BASEBOARD_FAB2_LIB.BASEBOARD_FAB2(SCH_1):M_M_DQS_DN(3)    I87 @BASEBOARD_FAB2_LIB.BASEBOARD_FAB2(SCH_1):PAGE88
   186 M_M_DQS_DP<3> @BASEBOARD_FAB2_LIB.BASEBOARD_FAB2(SCH_1):M_M_DQS_DP(3)    I87 @BASEBOARD_FAB2_LIB.BASEBOARD_FAB2(SCH_1):PAGE88
   244 M_M_DQS_DN<4> @BASEBOARD_FAB2_LIB.BASEBOARD_FAB2(SCH_1):M_M_DQS_DN(4)    I87 @BASEBOARD_FAB2_LIB.BASEBOARD_FAB2(SCH_1):PAGE88
   245 M_M_DQS_DP<4> @BASEBOARD_FAB2_LIB.BASEBOARD_FAB2(SCH_1):M_M_DQS_DP(4)    I87 @BASEBOARD_FAB2_LIB.BASEBOARD_FAB2(SCH_1):PAGE88
   255 M_M_DQS_DN<5> @BASEBOARD_FAB2_LIB.BASEBOARD_FAB2(SCH_1):M_M_DQS_DN(5)    I87 @BASEBOARD_FAB2_LIB.BASEBOARD_FAB2(SCH_1):PAGE88
   256 M_M_DQS_DP<5> @BASEBOARD_FAB2_LIB.BASEBOARD_FAB2(SCH_1):M_M_DQS_DP(5)    I87 @BASEBOARD_FAB2_LIB.BASEBOARD_FAB2(SCH_1):PAGE88
   266 M_M_DQS_DN<6> @BASEBOARD_FAB2_LIB.BASEBOARD_FAB2(SCH_1):M_M_DQS_DN(6)    I87 @BASEBOARD_FAB2_LIB.BASEBOARD_FAB2(SCH_1):PAGE88
   267 M_M_DQS_DP<6> @BASEBOARD_FAB2_LIB.BASEBOARD_FAB2(SCH_1):M_M_DQS_DP(6)    I87 @BASEBOARD_FAB2_LIB.BASEBOARD_FAB2(SCH_1):PAGE88
   277 M_M_DQS_DN<7> @BASEBOARD_FAB2_LIB.BASEBOARD_FAB2(SCH_1):M_M_DQS_DN(7)    I87 @BASEBOARD_FAB2_LIB.BASEBOARD_FAB2(SCH_1):PAGE88
   278 M_M_DQS_DP<7> @BASEBOARD_FAB2_LIB.BASEBOARD_FAB2(SCH_1):M_M_DQS_DP(7)    I87 @BASEBOARD_FAB2_LIB.BASEBOARD_FAB2(SCH_1):PAGE88
   196 M_M_DQS_DN<8> @BASEBOARD_FAB2_LIB.BASEBOARD_FAB2(SCH_1):M_M_DQS_DN(8)    I87 @BASEBOARD_FAB2_LIB.BASEBOARD_FAB2(SCH_1):PAGE88
   197 M_M_DQS_DP<8> @BASEBOARD_FAB2_LIB.BASEBOARD_FAB2(SCH_1):M_M_DQS_DP(8)    I87 @BASEBOARD_FAB2_LIB.BASEBOARD_FAB2(SCH_1):PAGE88
     8 M_M_DQS_DN<9> @BASEBOARD_FAB2_LIB.BASEBOARD_FAB2(SCH_1):M_M_DQS_DN(9)    I87 @BASEBOARD_FAB2_LIB.BASEBOARD_FAB2(SCH_1):PAGE88
     7 M_M_DQS_DP<9> @BASEBOARD_FAB2_LIB.BASEBOARD_FAB2(SCH_1):M_M_DQS_DP(9)    I87 @BASEBOARD_FAB2_LIB.BASEBOARD_FAB2(SCH_1):PAGE88
     2    GND @BASEBOARD_FAB2_LIB.BASEBOARD_FAB2(SCH_1):GND    I25 @BASEBOARD_FAB2_LIB.BASEBOARD_FAB2(SCH_1):PAGE88
     4    GND @BASEBOARD_FAB2_LIB.BASEBOARD_FAB2(SCH_1):GND    I25 @BASEBOARD_FAB2_LIB.BASEBOARD_FAB2(SCH_1):PAGE88
     6    GND @BASEBOARD_FAB2_LIB.BASEBOARD_FAB2(SCH_1):GND    I25 @BASEBOARD_FAB2_LIB.BASEBOARD_FAB2(SCH_1):PAGE88
     9    GND @BASEBOARD_FAB2_LIB.BASEBOARD_FAB2(SCH_1):GND    I25 @BASEBOARD_FAB2_LIB.BASEBOARD_FAB2(SCH_1):PAGE88
    11    GND @BASEBOARD_FAB2_LIB.BASEBOARD_FAB2(SCH_1):GND    I25 @BASEBOARD_FAB2_LIB.BASEBOARD_FAB2(SCH_1):PAGE88
    13    GND @BASEBOARD_FAB2_LIB.BASEBOARD_FAB2(SCH_1):GND    I25 @BASEBOARD_FAB2_LIB.BASEBOARD_FAB2(SCH_1):PAGE88
    15    GND @BASEBOARD_FAB2_LIB.BASEBOARD_FAB2(SCH_1):GND    I25 @BASEBOARD_FAB2_LIB.BASEBOARD_FAB2(SCH_1):PAGE88
    17    GND @BASEBOARD_FAB2_LIB.BASEBOARD_FAB2(SCH_1):GND    I25 @BASEBOARD_FAB2_LIB.BASEBOARD_FAB2(SCH_1):PAGE88
    20    GND @BASEBOARD_FAB2_LIB.BASEBOARD_FAB2(SCH_1):GND    I25 @BASEBOARD_FAB2_LIB.BASEBOARD_FAB2(SCH_1):PAGE88
    22    GND @BASEBOARD_FAB2_LIB.BASEBOARD_FAB2(SCH_1):GND    I25 @BASEBOARD_FAB2_LIB.BASEBOARD_FAB2(SCH_1):PAGE88
    24    GND @BASEBOARD_FAB2_LIB.BASEBOARD_FAB2(SCH_1):GND    I25 @BASEBOARD_FAB2_LIB.BASEBOARD_FAB2(SCH_1):PAGE88
    26    GND @BASEBOARD_FAB2_LIB.BASEBOARD_FAB2(SCH_1):GND    I25 @BASEBOARD_FAB2_LIB.BASEBOARD_FAB2(SCH_1):PAGE88
    28    GND @BASEBOARD_FAB2_LIB.BASEBOARD_FAB2(SCH_1):GND    I25 @BASEBOARD_FAB2_LIB.BASEBOARD_FAB2(SCH_1):PAGE88
    31    GND @BASEBOARD_FAB2_LIB.BASEBOARD_FAB2(SCH_1):GND    I25 @BASEBOARD_FAB2_LIB.BASEBOARD_FAB2(SCH_1):PAGE88
    33    GND @BASEBOARD_FAB2_LIB.BASEBOARD_FAB2(SCH_1):GND    I25 @BASEBOARD_FAB2_LIB.BASEBOARD_FAB2(SCH_1):PAGE88
    35    GND @BASEBOARD_FAB2_LIB.BASEBOARD_FAB2(SCH_1):GND    I25 @BASEBOARD_FAB2_LIB.BASEBOARD_FAB2(SCH_1):PAGE88
    37    GND @BASEBOARD_FAB2_LIB.BASEBOARD_FAB2(SCH_1):GND    I25 @BASEBOARD_FAB2_LIB.BASEBOARD_FAB2(SCH_1):PAGE88
    39    GND @BASEBOARD_FAB2_LIB.BASEBOARD_FAB2(SCH_1):GND    I25 @BASEBOARD_FAB2_LIB.BASEBOARD_FAB2(SCH_1):PAGE88
    42    GND @BASEBOARD_FAB2_LIB.BASEBOARD_FAB2(SCH_1):GND    I25 @BASEBOARD_FAB2_LIB.BASEBOARD_FAB2(SCH_1):PAGE88
    44    GND @BASEBOARD_FAB2_LIB.BASEBOARD_FAB2(SCH_1):GND    I25 @BASEBOARD_FAB2_LIB.BASEBOARD_FAB2(SCH_1):PAGE88
    46    GND @BASEBOARD_FAB2_LIB.BASEBOARD_FAB2(SCH_1):GND    I25 @BASEBOARD_FAB2_LIB.BASEBOARD_FAB2(SCH_1):PAGE88
    48    GND @BASEBOARD_FAB2_LIB.BASEBOARD_FAB2(SCH_1):GND    I25 @BASEBOARD_FAB2_LIB.BASEBOARD_FAB2(SCH_1):PAGE88
    50    GND @BASEBOARD_FAB2_LIB.BASEBOARD_FAB2(SCH_1):GND    I25 @BASEBOARD_FAB2_LIB.BASEBOARD_FAB2(SCH_1):PAGE88
    53    GND @BASEBOARD_FAB2_LIB.BASEBOARD_FAB2(SCH_1):GND    I25 @BASEBOARD_FAB2_LIB.BASEBOARD_FAB2(SCH_1):PAGE88
    55    GND @BASEBOARD_FAB2_LIB.BASEBOARD_FAB2(SCH_1):GND    I25 @BASEBOARD_FAB2_LIB.BASEBOARD_FAB2(SCH_1):PAGE88
    57    GND @BASEBOARD_FAB2_LIB.BASEBOARD_FAB2(SCH_1):GND    I25 @BASEBOARD_FAB2_LIB.BASEBOARD_FAB2(SCH_1):PAGE88
    94    GND @BASEBOARD_FAB2_LIB.BASEBOARD_FAB2(SCH_1):GND    I25 @BASEBOARD_FAB2_LIB.BASEBOARD_FAB2(SCH_1):PAGE88
    96    GND @BASEBOARD_FAB2_LIB.BASEBOARD_FAB2(SCH_1):GND    I25 @BASEBOARD_FAB2_LIB.BASEBOARD_FAB2(SCH_1):PAGE88
    98    GND @BASEBOARD_FAB2_LIB.BASEBOARD_FAB2(SCH_1):GND    I25 @BASEBOARD_FAB2_LIB.BASEBOARD_FAB2(SCH_1):PAGE88
   101    GND @BASEBOARD_FAB2_LIB.BASEBOARD_FAB2(SCH_1):GND    I25 @BASEBOARD_FAB2_LIB.BASEBOARD_FAB2(SCH_1):PAGE88
   103    GND @BASEBOARD_FAB2_LIB.BASEBOARD_FAB2(SCH_1):GND    I25 @BASEBOARD_FAB2_LIB.BASEBOARD_FAB2(SCH_1):PAGE88
   105    GND @BASEBOARD_FAB2_LIB.BASEBOARD_FAB2(SCH_1):GND    I25 @BASEBOARD_FAB2_LIB.BASEBOARD_FAB2(SCH_1):PAGE88
   107    GND @BASEBOARD_FAB2_LIB.BASEBOARD_FAB2(SCH_1):GND    I25 @BASEBOARD_FAB2_LIB.BASEBOARD_FAB2(SCH_1):PAGE88
   109    GND @BASEBOARD_FAB2_LIB.BASEBOARD_FAB2(SCH_1):GND    I25 @BASEBOARD_FAB2_LIB.BASEBOARD_FAB2(SCH_1):PAGE88
   112    GND @BASEBOARD_FAB2_LIB.BASEBOARD_FAB2(SCH_1):GND    I25 @BASEBOARD_FAB2_LIB.BASEBOARD_FAB2(SCH_1):PAGE88
   114    GND @BASEBOARD_FAB2_LIB.BASEBOARD_FAB2(SCH_1):GND    I25 @BASEBOARD_FAB2_LIB.BASEBOARD_FAB2(SCH_1):PAGE88
   116    GND @BASEBOARD_FAB2_LIB.BASEBOARD_FAB2(SCH_1):GND    I25 @BASEBOARD_FAB2_LIB.BASEBOARD_FAB2(SCH_1):PAGE88
   118    GND @BASEBOARD_FAB2_LIB.BASEBOARD_FAB2(SCH_1):GND    I25 @BASEBOARD_FAB2_LIB.BASEBOARD_FAB2(SCH_1):PAGE88
   120    GND @BASEBOARD_FAB2_LIB.BASEBOARD_FAB2(SCH_1):GND    I25 @BASEBOARD_FAB2_LIB.BASEBOARD_FAB2(SCH_1):PAGE88
   123    GND @BASEBOARD_FAB2_LIB.BASEBOARD_FAB2(SCH_1):GND    I25 @BASEBOARD_FAB2_LIB.BASEBOARD_FAB2(SCH_1):PAGE88
   125    GND @BASEBOARD_FAB2_LIB.BASEBOARD_FAB2(SCH_1):GND    I25 @BASEBOARD_FAB2_LIB.BASEBOARD_FAB2(SCH_1):PAGE88
   127    GND @BASEBOARD_FAB2_LIB.BASEBOARD_FAB2(SCH_1):GND    I25 @BASEBOARD_FAB2_LIB.BASEBOARD_FAB2(SCH_1):PAGE88
   129    GND @BASEBOARD_FAB2_LIB.BASEBOARD_FAB2(SCH_1):GND    I25 @BASEBOARD_FAB2_LIB.BASEBOARD_FAB2(SCH_1):PAGE88
   131    GND @BASEBOARD_FAB2_LIB.BASEBOARD_FAB2(SCH_1):GND    I25 @BASEBOARD_FAB2_LIB.BASEBOARD_FAB2(SCH_1):PAGE88
   134    GND @BASEBOARD_FAB2_LIB.BASEBOARD_FAB2(SCH_1):GND    I25 @BASEBOARD_FAB2_LIB.BASEBOARD_FAB2(SCH_1):PAGE88
   136    GND @BASEBOARD_FAB2_LIB.BASEBOARD_FAB2(SCH_1):GND    I25 @BASEBOARD_FAB2_LIB.BASEBOARD_FAB2(SCH_1):PAGE88
   138    GND @BASEBOARD_FAB2_LIB.BASEBOARD_FAB2(SCH_1):GND    I25 @BASEBOARD_FAB2_LIB.BASEBOARD_FAB2(SCH_1):PAGE88
   147    GND @BASEBOARD_FAB2_LIB.BASEBOARD_FAB2(SCH_1):GND    I25 @BASEBOARD_FAB2_LIB.BASEBOARD_FAB2(SCH_1):PAGE88
   149    GND @BASEBOARD_FAB2_LIB.BASEBOARD_FAB2(SCH_1):GND    I25 @BASEBOARD_FAB2_LIB.BASEBOARD_FAB2(SCH_1):PAGE88
   151    GND @BASEBOARD_FAB2_LIB.BASEBOARD_FAB2(SCH_1):GND    I25 @BASEBOARD_FAB2_LIB.BASEBOARD_FAB2(SCH_1):PAGE88
   154    GND @BASEBOARD_FAB2_LIB.BASEBOARD_FAB2(SCH_1):GND    I25 @BASEBOARD_FAB2_LIB.BASEBOARD_FAB2(SCH_1):PAGE88
   156    GND @BASEBOARD_FAB2_LIB.BASEBOARD_FAB2(SCH_1):GND    I25 @BASEBOARD_FAB2_LIB.BASEBOARD_FAB2(SCH_1):PAGE88
   158    GND @BASEBOARD_FAB2_LIB.BASEBOARD_FAB2(SCH_1):GND    I25 @BASEBOARD_FAB2_LIB.BASEBOARD_FAB2(SCH_1):PAGE88
   160    GND @BASEBOARD_FAB2_LIB.BASEBOARD_FAB2(SCH_1):GND    I25 @BASEBOARD_FAB2_LIB.BASEBOARD_FAB2(SCH_1):PAGE88
   162    GND @BASEBOARD_FAB2_LIB.BASEBOARD_FAB2(SCH_1):GND    I25 @BASEBOARD_FAB2_LIB.BASEBOARD_FAB2(SCH_1):PAGE88
   165    GND @BASEBOARD_FAB2_LIB.BASEBOARD_FAB2(SCH_1):GND    I25 @BASEBOARD_FAB2_LIB.BASEBOARD_FAB2(SCH_1):PAGE88
   167    GND @BASEBOARD_FAB2_LIB.BASEBOARD_FAB2(SCH_1):GND    I25 @BASEBOARD_FAB2_LIB.BASEBOARD_FAB2(SCH_1):PAGE88
   169    GND @BASEBOARD_FAB2_LIB.BASEBOARD_FAB2(SCH_1):GND    I25 @BASEBOARD_FAB2_LIB.BASEBOARD_FAB2(SCH_1):PAGE88
   171    GND @BASEBOARD_FAB2_LIB.BASEBOARD_FAB2(SCH_1):GND    I25 @BASEBOARD_FAB2_LIB.BASEBOARD_FAB2(SCH_1):PAGE88
   173    GND @BASEBOARD_FAB2_LIB.BASEBOARD_FAB2(SCH_1):GND    I25 @BASEBOARD_FAB2_LIB.BASEBOARD_FAB2(SCH_1):PAGE88
   176    GND @BASEBOARD_FAB2_LIB.BASEBOARD_FAB2(SCH_1):GND    I25 @BASEBOARD_FAB2_LIB.BASEBOARD_FAB2(SCH_1):PAGE88
   178    GND @BASEBOARD_FAB2_LIB.BASEBOARD_FAB2(SCH_1):GND    I25 @BASEBOARD_FAB2_LIB.BASEBOARD_FAB2(SCH_1):PAGE88
   180    GND @BASEBOARD_FAB2_LIB.BASEBOARD_FAB2(SCH_1):GND    I25 @BASEBOARD_FAB2_LIB.BASEBOARD_FAB2(SCH_1):PAGE88
   182    GND @BASEBOARD_FAB2_LIB.BASEBOARD_FAB2(SCH_1):GND    I25 @BASEBOARD_FAB2_LIB.BASEBOARD_FAB2(SCH_1):PAGE88
   184    GND @BASEBOARD_FAB2_LIB.BASEBOARD_FAB2(SCH_1):GND    I25 @BASEBOARD_FAB2_LIB.BASEBOARD_FAB2(SCH_1):PAGE88
   187    GND @BASEBOARD_FAB2_LIB.BASEBOARD_FAB2(SCH_1):GND    I25 @BASEBOARD_FAB2_LIB.BASEBOARD_FAB2(SCH_1):PAGE88
   189    GND @BASEBOARD_FAB2_LIB.BASEBOARD_FAB2(SCH_1):GND    I25 @BASEBOARD_FAB2_LIB.BASEBOARD_FAB2(SCH_1):PAGE88
   191    GND @BASEBOARD_FAB2_LIB.BASEBOARD_FAB2(SCH_1):GND    I25 @BASEBOARD_FAB2_LIB.BASEBOARD_FAB2(SCH_1):PAGE88
   193    GND @BASEBOARD_FAB2_LIB.BASEBOARD_FAB2(SCH_1):GND    I25 @BASEBOARD_FAB2_LIB.BASEBOARD_FAB2(SCH_1):PAGE88
   195    GND @BASEBOARD_FAB2_LIB.BASEBOARD_FAB2(SCH_1):GND    I25 @BASEBOARD_FAB2_LIB.BASEBOARD_FAB2(SCH_1):PAGE88
   198    GND @BASEBOARD_FAB2_LIB.BASEBOARD_FAB2(SCH_1):GND    I25 @BASEBOARD_FAB2_LIB.BASEBOARD_FAB2(SCH_1):PAGE88
   200    GND @BASEBOARD_FAB2_LIB.BASEBOARD_FAB2(SCH_1):GND    I25 @BASEBOARD_FAB2_LIB.BASEBOARD_FAB2(SCH_1):PAGE88
   202    GND @BASEBOARD_FAB2_LIB.BASEBOARD_FAB2(SCH_1):GND    I25 @BASEBOARD_FAB2_LIB.BASEBOARD_FAB2(SCH_1):PAGE88
   239    GND @BASEBOARD_FAB2_LIB.BASEBOARD_FAB2(SCH_1):GND    I25 @BASEBOARD_FAB2_LIB.BASEBOARD_FAB2(SCH_1):PAGE88
   241    GND @BASEBOARD_FAB2_LIB.BASEBOARD_FAB2(SCH_1):GND    I25 @BASEBOARD_FAB2_LIB.BASEBOARD_FAB2(SCH_1):PAGE88
   243    GND @BASEBOARD_FAB2_LIB.BASEBOARD_FAB2(SCH_1):GND    I25 @BASEBOARD_FAB2_LIB.BASEBOARD_FAB2(SCH_1):PAGE88
   246    GND @BASEBOARD_FAB2_LIB.BASEBOARD_FAB2(SCH_1):GND    I25 @BASEBOARD_FAB2_LIB.BASEBOARD_FAB2(SCH_1):PAGE88
   248    GND @BASEBOARD_FAB2_LIB.BASEBOARD_FAB2(SCH_1):GND    I25 @BASEBOARD_FAB2_LIB.BASEBOARD_FAB2(SCH_1):PAGE88
   250    GND @BASEBOARD_FAB2_LIB.BASEBOARD_FAB2(SCH_1):GND    I25 @BASEBOARD_FAB2_LIB.BASEBOARD_FAB2(SCH_1):PAGE88
   252    GND @BASEBOARD_FAB2_LIB.BASEBOARD_FAB2(SCH_1):GND    I25 @BASEBOARD_FAB2_LIB.BASEBOARD_FAB2(SCH_1):PAGE88
   254    GND @BASEBOARD_FAB2_LIB.BASEBOARD_FAB2(SCH_1):GND    I25 @BASEBOARD_FAB2_LIB.BASEBOARD_FAB2(SCH_1):PAGE88
   257    GND @BASEBOARD_FAB2_LIB.BASEBOARD_FAB2(SCH_1):GND    I25 @BASEBOARD_FAB2_LIB.BASEBOARD_FAB2(SCH_1):PAGE88
   259    GND @BASEBOARD_FAB2_LIB.BASEBOARD_FAB2(SCH_1):GND    I25 @BASEBOARD_FAB2_LIB.BASEBOARD_FAB2(SCH_1):PAGE88
   261    GND @BASEBOARD_FAB2_LIB.BASEBOARD_FAB2(SCH_1):GND    I25 @BASEBOARD_FAB2_LIB.BASEBOARD_FAB2(SCH_1):PAGE88
   263    GND @BASEBOARD_FAB2_LIB.BASEBOARD_FAB2(SCH_1):GND    I25 @BASEBOARD_FAB2_LIB.BASEBOARD_FAB2(SCH_1):PAGE88
   265    GND @BASEBOARD_FAB2_LIB.BASEBOARD_FAB2(SCH_1):GND    I25 @BASEBOARD_FAB2_LIB.BASEBOARD_FAB2(SCH_1):PAGE88
   268    GND @BASEBOARD_FAB2_LIB.BASEBOARD_FAB2(SCH_1):GND    I25 @BASEBOARD_FAB2_LIB.BASEBOARD_FAB2(SCH_1):PAGE88
   270    GND @BASEBOARD_FAB2_LIB.BASEBOARD_FAB2(SCH_1):GND    I25 @BASEBOARD_FAB2_LIB.BASEBOARD_FAB2(SCH_1):PAGE88
   272    GND @BASEBOARD_FAB2_LIB.BASEBOARD_FAB2(SCH_1):GND    I25 @BASEBOARD_FAB2_LIB.BASEBOARD_FAB2(SCH_1):PAGE88
   274    GND @BASEBOARD_FAB2_LIB.BASEBOARD_FAB2(SCH_1):GND    I25 @BASEBOARD_FAB2_LIB.BASEBOARD_FAB2(SCH_1):PAGE88
   276    GND @BASEBOARD_FAB2_LIB.BASEBOARD_FAB2(SCH_1):GND    I25 @BASEBOARD_FAB2_LIB.BASEBOARD_FAB2(SCH_1):PAGE88
   279    GND @BASEBOARD_FAB2_LIB.BASEBOARD_FAB2(SCH_1):GND    I25 @BASEBOARD_FAB2_LIB.BASEBOARD_FAB2(SCH_1):PAGE88
   281    GND @BASEBOARD_FAB2_LIB.BASEBOARD_FAB2(SCH_1):GND    I25 @BASEBOARD_FAB2_LIB.BASEBOARD_FAB2(SCH_1):PAGE88
   283    GND @BASEBOARD_FAB2_LIB.BASEBOARD_FAB2(SCH_1):GND    I25 @BASEBOARD_FAB2_LIB.BASEBOARD_FAB2(SCH_1):PAGE88
     1 P12V_NVDIMM_KLM @BASEBOARD_FAB2_LIB.BASEBOARD_FAB2(SCH_1):P12V_NVDIMM_KLM   I168 @BASEBOARD_FAB2_LIB.BASEBOARD_FAB2(SCH_1):PAGE88
   145 P12V_NVDIMM_KLM @BASEBOARD_FAB2_LIB.BASEBOARD_FAB2(SCH_1):P12V_NVDIMM_KLM   I168 @BASEBOARD_FAB2_LIB.BASEBOARD_FAB2(SCH_1):PAGE88
    59 PVDDQ_KLM @BASEBOARD_FAB2_LIB.BASEBOARD_FAB2(SCH_1):PVDDQ_KLM   I168 @BASEBOARD_FAB2_LIB.BASEBOARD_FAB2(SCH_1):PAGE88
    61 PVDDQ_KLM @BASEBOARD_FAB2_LIB.BASEBOARD_FAB2(SCH_1):PVDDQ_KLM   I168 @BASEBOARD_FAB2_LIB.BASEBOARD_FAB2(SCH_1):PAGE88
    64 PVDDQ_KLM @BASEBOARD_FAB2_LIB.BASEBOARD_FAB2(SCH_1):PVDDQ_KLM   I168 @BASEBOARD_FAB2_LIB.BASEBOARD_FAB2(SCH_1):PAGE88
    67 PVDDQ_KLM @BASEBOARD_FAB2_LIB.BASEBOARD_FAB2(SCH_1):PVDDQ_KLM   I168 @BASEBOARD_FAB2_LIB.BASEBOARD_FAB2(SCH_1):PAGE88
    70 PVDDQ_KLM @BASEBOARD_FAB2_LIB.BASEBOARD_FAB2(SCH_1):PVDDQ_KLM   I168 @BASEBOARD_FAB2_LIB.BASEBOARD_FAB2(SCH_1):PAGE88
    73 PVDDQ_KLM @BASEBOARD_FAB2_LIB.BASEBOARD_FAB2(SCH_1):PVDDQ_KLM   I168 @BASEBOARD_FAB2_LIB.BASEBOARD_FAB2(SCH_1):PAGE88
    76 PVDDQ_KLM @BASEBOARD_FAB2_LIB.BASEBOARD_FAB2(SCH_1):PVDDQ_KLM   I168 @BASEBOARD_FAB2_LIB.BASEBOARD_FAB2(SCH_1):PAGE88
    80 PVDDQ_KLM @BASEBOARD_FAB2_LIB.BASEBOARD_FAB2(SCH_1):PVDDQ_KLM   I168 @BASEBOARD_FAB2_LIB.BASEBOARD_FAB2(SCH_1):PAGE88
    83 PVDDQ_KLM @BASEBOARD_FAB2_LIB.BASEBOARD_FAB2(SCH_1):PVDDQ_KLM   I168 @BASEBOARD_FAB2_LIB.BASEBOARD_FAB2(SCH_1):PAGE88
    85 PVDDQ_KLM @BASEBOARD_FAB2_LIB.BASEBOARD_FAB2(SCH_1):PVDDQ_KLM   I168 @BASEBOARD_FAB2_LIB.BASEBOARD_FAB2(SCH_1):PAGE88
    88 PVDDQ_KLM @BASEBOARD_FAB2_LIB.BASEBOARD_FAB2(SCH_1):PVDDQ_KLM   I168 @BASEBOARD_FAB2_LIB.BASEBOARD_FAB2(SCH_1):PAGE88
    90 PVDDQ_KLM @BASEBOARD_FAB2_LIB.BASEBOARD_FAB2(SCH_1):PVDDQ_KLM   I168 @BASEBOARD_FAB2_LIB.BASEBOARD_FAB2(SCH_1):PAGE88
    92 PVDDQ_KLM @BASEBOARD_FAB2_LIB.BASEBOARD_FAB2(SCH_1):PVDDQ_KLM   I168 @BASEBOARD_FAB2_LIB.BASEBOARD_FAB2(SCH_1):PAGE88
   204 PVDDQ_KLM @BASEBOARD_FAB2_LIB.BASEBOARD_FAB2(SCH_1):PVDDQ_KLM   I168 @BASEBOARD_FAB2_LIB.BASEBOARD_FAB2(SCH_1):PAGE88
   206 PVDDQ_KLM @BASEBOARD_FAB2_LIB.BASEBOARD_FAB2(SCH_1):PVDDQ_KLM   I168 @BASEBOARD_FAB2_LIB.BASEBOARD_FAB2(SCH_1):PAGE88
   209 PVDDQ_KLM @BASEBOARD_FAB2_LIB.BASEBOARD_FAB2(SCH_1):PVDDQ_KLM   I168 @BASEBOARD_FAB2_LIB.BASEBOARD_FAB2(SCH_1):PAGE88
   212 PVDDQ_KLM @BASEBOARD_FAB2_LIB.BASEBOARD_FAB2(SCH_1):PVDDQ_KLM   I168 @BASEBOARD_FAB2_LIB.BASEBOARD_FAB2(SCH_1):PAGE88
   215 PVDDQ_KLM @BASEBOARD_FAB2_LIB.BASEBOARD_FAB2(SCH_1):PVDDQ_KLM   I168 @BASEBOARD_FAB2_LIB.BASEBOARD_FAB2(SCH_1):PAGE88
   217 PVDDQ_KLM @BASEBOARD_FAB2_LIB.BASEBOARD_FAB2(SCH_1):PVDDQ_KLM   I168 @BASEBOARD_FAB2_LIB.BASEBOARD_FAB2(SCH_1):PAGE88
   220 PVDDQ_KLM @BASEBOARD_FAB2_LIB.BASEBOARD_FAB2(SCH_1):PVDDQ_KLM   I168 @BASEBOARD_FAB2_LIB.BASEBOARD_FAB2(SCH_1):PAGE88
   223 PVDDQ_KLM @BASEBOARD_FAB2_LIB.BASEBOARD_FAB2(SCH_1):PVDDQ_KLM   I168 @BASEBOARD_FAB2_LIB.BASEBOARD_FAB2(SCH_1):PAGE88
   226 PVDDQ_KLM @BASEBOARD_FAB2_LIB.BASEBOARD_FAB2(SCH_1):PVDDQ_KLM   I168 @BASEBOARD_FAB2_LIB.BASEBOARD_FAB2(SCH_1):PAGE88
   229 PVDDQ_KLM @BASEBOARD_FAB2_LIB.BASEBOARD_FAB2(SCH_1):PVDDQ_KLM   I168 @BASEBOARD_FAB2_LIB.BASEBOARD_FAB2(SCH_1):PAGE88
   231 PVDDQ_KLM @BASEBOARD_FAB2_LIB.BASEBOARD_FAB2(SCH_1):PVDDQ_KLM   I168 @BASEBOARD_FAB2_LIB.BASEBOARD_FAB2(SCH_1):PAGE88
   233 PVDDQ_KLM @BASEBOARD_FAB2_LIB.BASEBOARD_FAB2(SCH_1):PVDDQ_KLM   I168 @BASEBOARD_FAB2_LIB.BASEBOARD_FAB2(SCH_1):PAGE88
   236 PVDDQ_KLM @BASEBOARD_FAB2_LIB.BASEBOARD_FAB2(SCH_1):PVDDQ_KLM   I168 @BASEBOARD_FAB2_LIB.BASEBOARD_FAB2(SCH_1):PAGE88
   142 PVPP_KLM @BASEBOARD_FAB2_LIB.BASEBOARD_FAB2(SCH_1):PVPP_KLM   I168 @BASEBOARD_FAB2_LIB.BASEBOARD_FAB2(SCH_1):PAGE88
   143 PVPP_KLM @BASEBOARD_FAB2_LIB.BASEBOARD_FAB2(SCH_1):PVPP_KLM   I168 @BASEBOARD_FAB2_LIB.BASEBOARD_FAB2(SCH_1):PAGE88
   288 PVPP_KLM @BASEBOARD_FAB2_LIB.BASEBOARD_FAB2(SCH_1):PVPP_KLM   I168 @BASEBOARD_FAB2_LIB.BASEBOARD_FAB2(SCH_1):PAGE88
   286 PVPP_KLM @BASEBOARD_FAB2_LIB.BASEBOARD_FAB2(SCH_1):PVPP_KLM   I168 @BASEBOARD_FAB2_LIB.BASEBOARD_FAB2(SCH_1):PAGE88
   287 PVPP_KLM @BASEBOARD_FAB2_LIB.BASEBOARD_FAB2(SCH_1):PVPP_KLM   I168 @BASEBOARD_FAB2_LIB.BASEBOARD_FAB2(SCH_1):PAGE88
    77 PVTT_KLM @BASEBOARD_FAB2_LIB.BASEBOARD_FAB2(SCH_1):PVTT_KLM   I168 @BASEBOARD_FAB2_LIB.BASEBOARD_FAB2(SCH_1):PAGE88
   221 PVTT_KLM @BASEBOARD_FAB2_LIB.BASEBOARD_FAB2(SCH_1):PVTT_KLM   I168 @BASEBOARD_FAB2_LIB.BASEBOARD_FAB2(SCH_1):PAGE88

J9L2 SCONN288_H44441003_PIP-SCONN,HA
    79 M_L_MA<0> @BASEBOARD_FAB2_LIB.BASEBOARD_FAB2(SCH_1):M_L_MA(0)    I12 @BASEBOARD_FAB2_LIB.BASEBOARD_FAB2(SCH_1):PAGE86
    72 M_L_MA<1> @BASEBOARD_FAB2_LIB.BASEBOARD_FAB2(SCH_1):M_L_MA(1)    I12 @BASEBOARD_FAB2_LIB.BASEBOARD_FAB2(SCH_1):PAGE86
   225 M_L_MA<10> @BASEBOARD_FAB2_LIB.BASEBOARD_FAB2(SCH_1):M_L_MA(10)    I12 @BASEBOARD_FAB2_LIB.BASEBOARD_FAB2(SCH_1):PAGE86
   210 M_L_MA<11> @BASEBOARD_FAB2_LIB.BASEBOARD_FAB2(SCH_1):M_L_MA(11)    I12 @BASEBOARD_FAB2_LIB.BASEBOARD_FAB2(SCH_1):PAGE86
    65 M_L_MA<12> @BASEBOARD_FAB2_LIB.BASEBOARD_FAB2(SCH_1):M_L_MA(12)    I12 @BASEBOARD_FAB2_LIB.BASEBOARD_FAB2(SCH_1):PAGE86
   232 M_L_MA<13> @BASEBOARD_FAB2_LIB.BASEBOARD_FAB2(SCH_1):M_L_MA(13)    I12 @BASEBOARD_FAB2_LIB.BASEBOARD_FAB2(SCH_1):PAGE86
   228 M_L_MA<14> @BASEBOARD_FAB2_LIB.BASEBOARD_FAB2(SCH_1):M_L_MA(14)    I12 @BASEBOARD_FAB2_LIB.BASEBOARD_FAB2(SCH_1):PAGE86
    86 M_L_MA<15> @BASEBOARD_FAB2_LIB.BASEBOARD_FAB2(SCH_1):M_L_MA(15)    I12 @BASEBOARD_FAB2_LIB.BASEBOARD_FAB2(SCH_1):PAGE86
    82 M_L_MA<16> @BASEBOARD_FAB2_LIB.BASEBOARD_FAB2(SCH_1):M_L_MA(16)    I12 @BASEBOARD_FAB2_LIB.BASEBOARD_FAB2(SCH_1):PAGE86
   234 M_L_MA<17> @BASEBOARD_FAB2_LIB.BASEBOARD_FAB2(SCH_1):M_L_MA(17)    I12 @BASEBOARD_FAB2_LIB.BASEBOARD_FAB2(SCH_1):PAGE86
   216 M_L_MA<2> @BASEBOARD_FAB2_LIB.BASEBOARD_FAB2(SCH_1):M_L_MA(2)    I12 @BASEBOARD_FAB2_LIB.BASEBOARD_FAB2(SCH_1):PAGE86
    71 M_L_MA<3> @BASEBOARD_FAB2_LIB.BASEBOARD_FAB2(SCH_1):M_L_MA(3)    I12 @BASEBOARD_FAB2_LIB.BASEBOARD_FAB2(SCH_1):PAGE86
   214 M_L_MA<4> @BASEBOARD_FAB2_LIB.BASEBOARD_FAB2(SCH_1):M_L_MA(4)    I12 @BASEBOARD_FAB2_LIB.BASEBOARD_FAB2(SCH_1):PAGE86
   213 M_L_MA<5> @BASEBOARD_FAB2_LIB.BASEBOARD_FAB2(SCH_1):M_L_MA(5)    I12 @BASEBOARD_FAB2_LIB.BASEBOARD_FAB2(SCH_1):PAGE86
    69 M_L_MA<6> @BASEBOARD_FAB2_LIB.BASEBOARD_FAB2(SCH_1):M_L_MA(6)    I12 @BASEBOARD_FAB2_LIB.BASEBOARD_FAB2(SCH_1):PAGE86
   211 M_L_MA<7> @BASEBOARD_FAB2_LIB.BASEBOARD_FAB2(SCH_1):M_L_MA(7)    I12 @BASEBOARD_FAB2_LIB.BASEBOARD_FAB2(SCH_1):PAGE86
    68 M_L_MA<8> @BASEBOARD_FAB2_LIB.BASEBOARD_FAB2(SCH_1):M_L_MA(8)    I12 @BASEBOARD_FAB2_LIB.BASEBOARD_FAB2(SCH_1):PAGE86
    66 M_L_MA<9> @BASEBOARD_FAB2_LIB.BASEBOARD_FAB2(SCH_1):M_L_MA(9)    I12 @BASEBOARD_FAB2_LIB.BASEBOARD_FAB2(SCH_1):PAGE86
    62 M_L_ACT_N @BASEBOARD_FAB2_LIB.BASEBOARD_FAB2(SCH_1):M_L_ACT_N    I12 @BASEBOARD_FAB2_LIB.BASEBOARD_FAB2(SCH_1):PAGE86
   208 M_L_ALERT_N @BASEBOARD_FAB2_LIB.BASEBOARD_FAB2(SCH_1):M_L_ALERT_N    I12 @BASEBOARD_FAB2_LIB.BASEBOARD_FAB2(SCH_1):PAGE86
   224 M_L_BA<1> @BASEBOARD_FAB2_LIB.BASEBOARD_FAB2(SCH_1):M_L_BA(1)    I12 @BASEBOARD_FAB2_LIB.BASEBOARD_FAB2(SCH_1):PAGE86
    81 M_L_BA<0> @BASEBOARD_FAB2_LIB.BASEBOARD_FAB2(SCH_1):M_L_BA(0)    I12 @BASEBOARD_FAB2_LIB.BASEBOARD_FAB2(SCH_1):PAGE86
   207 M_L_BG<1> @BASEBOARD_FAB2_LIB.BASEBOARD_FAB2(SCH_1):M_L_BG(1)    I12 @BASEBOARD_FAB2_LIB.BASEBOARD_FAB2(SCH_1):PAGE86
    63 M_L_BG<0> @BASEBOARD_FAB2_LIB.BASEBOARD_FAB2(SCH_1):M_L_BG(0)    I12 @BASEBOARD_FAB2_LIB.BASEBOARD_FAB2(SCH_1):PAGE86
   235 M_L_C<2> @BASEBOARD_FAB2_LIB.BASEBOARD_FAB2(SCH_1):M_L_C(2)    I12 @BASEBOARD_FAB2_LIB.BASEBOARD_FAB2(SCH_1):PAGE86
   199 M_L_ECC<7> @BASEBOARD_FAB2_LIB.BASEBOARD_FAB2(SCH_1):M_L_ECC(7)    I12 @BASEBOARD_FAB2_LIB.BASEBOARD_FAB2(SCH_1):PAGE86
    54 M_L_ECC<6> @BASEBOARD_FAB2_LIB.BASEBOARD_FAB2(SCH_1):M_L_ECC(6)    I12 @BASEBOARD_FAB2_LIB.BASEBOARD_FAB2(SCH_1):PAGE86
   192 M_L_ECC<5> @BASEBOARD_FAB2_LIB.BASEBOARD_FAB2(SCH_1):M_L_ECC(5)    I12 @BASEBOARD_FAB2_LIB.BASEBOARD_FAB2(SCH_1):PAGE86
    47 M_L_ECC<4> @BASEBOARD_FAB2_LIB.BASEBOARD_FAB2(SCH_1):M_L_ECC(4)    I12 @BASEBOARD_FAB2_LIB.BASEBOARD_FAB2(SCH_1):PAGE86
   201 M_L_ECC<3> @BASEBOARD_FAB2_LIB.BASEBOARD_FAB2(SCH_1):M_L_ECC(3)    I12 @BASEBOARD_FAB2_LIB.BASEBOARD_FAB2(SCH_1):PAGE86
    56 M_L_ECC<2> @BASEBOARD_FAB2_LIB.BASEBOARD_FAB2(SCH_1):M_L_ECC(2)    I12 @BASEBOARD_FAB2_LIB.BASEBOARD_FAB2(SCH_1):PAGE86
   194 M_L_ECC<1> @BASEBOARD_FAB2_LIB.BASEBOARD_FAB2(SCH_1):M_L_ECC(1)    I12 @BASEBOARD_FAB2_LIB.BASEBOARD_FAB2(SCH_1):PAGE86
    49 M_L_ECC<0> @BASEBOARD_FAB2_LIB.BASEBOARD_FAB2(SCH_1):M_L_ECC(0)    I12 @BASEBOARD_FAB2_LIB.BASEBOARD_FAB2(SCH_1):PAGE86
    75 M_L_CLK_DN<2> @BASEBOARD_FAB2_LIB.BASEBOARD_FAB2(SCH_1):M_L_CLK_DN(2)    I12 @BASEBOARD_FAB2_LIB.BASEBOARD_FAB2(SCH_1):PAGE86
    74 M_L_CLK_DP<2> @BASEBOARD_FAB2_LIB.BASEBOARD_FAB2(SCH_1):M_L_CLK_DP(2)    I12 @BASEBOARD_FAB2_LIB.BASEBOARD_FAB2(SCH_1):PAGE86
   219 M_L_CLK_DN<3> @BASEBOARD_FAB2_LIB.BASEBOARD_FAB2(SCH_1):M_L_CLK_DN(3)    I12 @BASEBOARD_FAB2_LIB.BASEBOARD_FAB2(SCH_1):PAGE86
   218 M_L_CLK_DP<3> @BASEBOARD_FAB2_LIB.BASEBOARD_FAB2(SCH_1):M_L_CLK_DP(3)    I12 @BASEBOARD_FAB2_LIB.BASEBOARD_FAB2(SCH_1):PAGE86
   203 M_L_CKE<3> @BASEBOARD_FAB2_LIB.BASEBOARD_FAB2(SCH_1):M_L_CKE(3)    I12 @BASEBOARD_FAB2_LIB.BASEBOARD_FAB2(SCH_1):PAGE86
    60 M_L_CKE<2> @BASEBOARD_FAB2_LIB.BASEBOARD_FAB2(SCH_1):M_L_CKE(2)    I12 @BASEBOARD_FAB2_LIB.BASEBOARD_FAB2(SCH_1):PAGE86
   280 M_L_DQ<63> @BASEBOARD_FAB2_LIB.BASEBOARD_FAB2(SCH_1):M_L_DQ(63)    I12 @BASEBOARD_FAB2_LIB.BASEBOARD_FAB2(SCH_1):PAGE86
   135 M_L_DQ<62> @BASEBOARD_FAB2_LIB.BASEBOARD_FAB2(SCH_1):M_L_DQ(62)    I12 @BASEBOARD_FAB2_LIB.BASEBOARD_FAB2(SCH_1):PAGE86
   273 M_L_DQ<61> @BASEBOARD_FAB2_LIB.BASEBOARD_FAB2(SCH_1):M_L_DQ(61)    I12 @BASEBOARD_FAB2_LIB.BASEBOARD_FAB2(SCH_1):PAGE86
   128 M_L_DQ<60> @BASEBOARD_FAB2_LIB.BASEBOARD_FAB2(SCH_1):M_L_DQ(60)    I12 @BASEBOARD_FAB2_LIB.BASEBOARD_FAB2(SCH_1):PAGE86
   282 M_L_DQ<59> @BASEBOARD_FAB2_LIB.BASEBOARD_FAB2(SCH_1):M_L_DQ(59)    I12 @BASEBOARD_FAB2_LIB.BASEBOARD_FAB2(SCH_1):PAGE86
   137 M_L_DQ<58> @BASEBOARD_FAB2_LIB.BASEBOARD_FAB2(SCH_1):M_L_DQ(58)    I12 @BASEBOARD_FAB2_LIB.BASEBOARD_FAB2(SCH_1):PAGE86
   275 M_L_DQ<57> @BASEBOARD_FAB2_LIB.BASEBOARD_FAB2(SCH_1):M_L_DQ(57)    I12 @BASEBOARD_FAB2_LIB.BASEBOARD_FAB2(SCH_1):PAGE86
   130 M_L_DQ<56> @BASEBOARD_FAB2_LIB.BASEBOARD_FAB2(SCH_1):M_L_DQ(56)    I12 @BASEBOARD_FAB2_LIB.BASEBOARD_FAB2(SCH_1):PAGE86
   269 M_L_DQ<55> @BASEBOARD_FAB2_LIB.BASEBOARD_FAB2(SCH_1):M_L_DQ(55)    I12 @BASEBOARD_FAB2_LIB.BASEBOARD_FAB2(SCH_1):PAGE86
   124 M_L_DQ<54> @BASEBOARD_FAB2_LIB.BASEBOARD_FAB2(SCH_1):M_L_DQ(54)    I12 @BASEBOARD_FAB2_LIB.BASEBOARD_FAB2(SCH_1):PAGE86
   262 M_L_DQ<53> @BASEBOARD_FAB2_LIB.BASEBOARD_FAB2(SCH_1):M_L_DQ(53)    I12 @BASEBOARD_FAB2_LIB.BASEBOARD_FAB2(SCH_1):PAGE86
   117 M_L_DQ<52> @BASEBOARD_FAB2_LIB.BASEBOARD_FAB2(SCH_1):M_L_DQ(52)    I12 @BASEBOARD_FAB2_LIB.BASEBOARD_FAB2(SCH_1):PAGE86
   271 M_L_DQ<51> @BASEBOARD_FAB2_LIB.BASEBOARD_FAB2(SCH_1):M_L_DQ(51)    I12 @BASEBOARD_FAB2_LIB.BASEBOARD_FAB2(SCH_1):PAGE86
   126 M_L_DQ<50> @BASEBOARD_FAB2_LIB.BASEBOARD_FAB2(SCH_1):M_L_DQ(50)    I12 @BASEBOARD_FAB2_LIB.BASEBOARD_FAB2(SCH_1):PAGE86
   264 M_L_DQ<49> @BASEBOARD_FAB2_LIB.BASEBOARD_FAB2(SCH_1):M_L_DQ(49)    I12 @BASEBOARD_FAB2_LIB.BASEBOARD_FAB2(SCH_1):PAGE86
   119 M_L_DQ<48> @BASEBOARD_FAB2_LIB.BASEBOARD_FAB2(SCH_1):M_L_DQ(48)    I12 @BASEBOARD_FAB2_LIB.BASEBOARD_FAB2(SCH_1):PAGE86
   258 M_L_DQ<47> @BASEBOARD_FAB2_LIB.BASEBOARD_FAB2(SCH_1):M_L_DQ(47)    I12 @BASEBOARD_FAB2_LIB.BASEBOARD_FAB2(SCH_1):PAGE86
   113 M_L_DQ<46> @BASEBOARD_FAB2_LIB.BASEBOARD_FAB2(SCH_1):M_L_DQ(46)    I12 @BASEBOARD_FAB2_LIB.BASEBOARD_FAB2(SCH_1):PAGE86
   251 M_L_DQ<45> @BASEBOARD_FAB2_LIB.BASEBOARD_FAB2(SCH_1):M_L_DQ(45)    I12 @BASEBOARD_FAB2_LIB.BASEBOARD_FAB2(SCH_1):PAGE86
   106 M_L_DQ<44> @BASEBOARD_FAB2_LIB.BASEBOARD_FAB2(SCH_1):M_L_DQ(44)    I12 @BASEBOARD_FAB2_LIB.BASEBOARD_FAB2(SCH_1):PAGE86
   260 M_L_DQ<43> @BASEBOARD_FAB2_LIB.BASEBOARD_FAB2(SCH_1):M_L_DQ(43)    I12 @BASEBOARD_FAB2_LIB.BASEBOARD_FAB2(SCH_1):PAGE86
   115 M_L_DQ<42> @BASEBOARD_FAB2_LIB.BASEBOARD_FAB2(SCH_1):M_L_DQ(42)    I12 @BASEBOARD_FAB2_LIB.BASEBOARD_FAB2(SCH_1):PAGE86
   253 M_L_DQ<41> @BASEBOARD_FAB2_LIB.BASEBOARD_FAB2(SCH_1):M_L_DQ(41)    I12 @BASEBOARD_FAB2_LIB.BASEBOARD_FAB2(SCH_1):PAGE86
   108 M_L_DQ<40> @BASEBOARD_FAB2_LIB.BASEBOARD_FAB2(SCH_1):M_L_DQ(40)    I12 @BASEBOARD_FAB2_LIB.BASEBOARD_FAB2(SCH_1):PAGE86
   247 M_L_DQ<39> @BASEBOARD_FAB2_LIB.BASEBOARD_FAB2(SCH_1):M_L_DQ(39)    I12 @BASEBOARD_FAB2_LIB.BASEBOARD_FAB2(SCH_1):PAGE86
   102 M_L_DQ<38> @BASEBOARD_FAB2_LIB.BASEBOARD_FAB2(SCH_1):M_L_DQ(38)    I12 @BASEBOARD_FAB2_LIB.BASEBOARD_FAB2(SCH_1):PAGE86
   240 M_L_DQ<37> @BASEBOARD_FAB2_LIB.BASEBOARD_FAB2(SCH_1):M_L_DQ(37)    I12 @BASEBOARD_FAB2_LIB.BASEBOARD_FAB2(SCH_1):PAGE86
    95 M_L_DQ<36> @BASEBOARD_FAB2_LIB.BASEBOARD_FAB2(SCH_1):M_L_DQ(36)    I12 @BASEBOARD_FAB2_LIB.BASEBOARD_FAB2(SCH_1):PAGE86
   249 M_L_DQ<35> @BASEBOARD_FAB2_LIB.BASEBOARD_FAB2(SCH_1):M_L_DQ(35)    I12 @BASEBOARD_FAB2_LIB.BASEBOARD_FAB2(SCH_1):PAGE86
   104 M_L_DQ<34> @BASEBOARD_FAB2_LIB.BASEBOARD_FAB2(SCH_1):M_L_DQ(34)    I12 @BASEBOARD_FAB2_LIB.BASEBOARD_FAB2(SCH_1):PAGE86
   242 M_L_DQ<33> @BASEBOARD_FAB2_LIB.BASEBOARD_FAB2(SCH_1):M_L_DQ(33)    I12 @BASEBOARD_FAB2_LIB.BASEBOARD_FAB2(SCH_1):PAGE86
    97 M_L_DQ<32> @BASEBOARD_FAB2_LIB.BASEBOARD_FAB2(SCH_1):M_L_DQ(32)    I12 @BASEBOARD_FAB2_LIB.BASEBOARD_FAB2(SCH_1):PAGE86
   188 M_L_DQ<31> @BASEBOARD_FAB2_LIB.BASEBOARD_FAB2(SCH_1):M_L_DQ(31)    I12 @BASEBOARD_FAB2_LIB.BASEBOARD_FAB2(SCH_1):PAGE86
    43 M_L_DQ<30> @BASEBOARD_FAB2_LIB.BASEBOARD_FAB2(SCH_1):M_L_DQ(30)    I12 @BASEBOARD_FAB2_LIB.BASEBOARD_FAB2(SCH_1):PAGE86
   181 M_L_DQ<29> @BASEBOARD_FAB2_LIB.BASEBOARD_FAB2(SCH_1):M_L_DQ(29)    I12 @BASEBOARD_FAB2_LIB.BASEBOARD_FAB2(SCH_1):PAGE86
    36 M_L_DQ<28> @BASEBOARD_FAB2_LIB.BASEBOARD_FAB2(SCH_1):M_L_DQ(28)    I12 @BASEBOARD_FAB2_LIB.BASEBOARD_FAB2(SCH_1):PAGE86
   190 M_L_DQ<27> @BASEBOARD_FAB2_LIB.BASEBOARD_FAB2(SCH_1):M_L_DQ(27)    I12 @BASEBOARD_FAB2_LIB.BASEBOARD_FAB2(SCH_1):PAGE86
    45 M_L_DQ<26> @BASEBOARD_FAB2_LIB.BASEBOARD_FAB2(SCH_1):M_L_DQ(26)    I12 @BASEBOARD_FAB2_LIB.BASEBOARD_FAB2(SCH_1):PAGE86
   183 M_L_DQ<25> @BASEBOARD_FAB2_LIB.BASEBOARD_FAB2(SCH_1):M_L_DQ(25)    I12 @BASEBOARD_FAB2_LIB.BASEBOARD_FAB2(SCH_1):PAGE86
    38 M_L_DQ<24> @BASEBOARD_FAB2_LIB.BASEBOARD_FAB2(SCH_1):M_L_DQ(24)    I12 @BASEBOARD_FAB2_LIB.BASEBOARD_FAB2(SCH_1):PAGE86
   177 M_L_DQ<23> @BASEBOARD_FAB2_LIB.BASEBOARD_FAB2(SCH_1):M_L_DQ(23)    I12 @BASEBOARD_FAB2_LIB.BASEBOARD_FAB2(SCH_1):PAGE86
    32 M_L_DQ<22> @BASEBOARD_FAB2_LIB.BASEBOARD_FAB2(SCH_1):M_L_DQ(22)    I12 @BASEBOARD_FAB2_LIB.BASEBOARD_FAB2(SCH_1):PAGE86
   170 M_L_DQ<21> @BASEBOARD_FAB2_LIB.BASEBOARD_FAB2(SCH_1):M_L_DQ(21)    I12 @BASEBOARD_FAB2_LIB.BASEBOARD_FAB2(SCH_1):PAGE86
    25 M_L_DQ<20> @BASEBOARD_FAB2_LIB.BASEBOARD_FAB2(SCH_1):M_L_DQ(20)    I12 @BASEBOARD_FAB2_LIB.BASEBOARD_FAB2(SCH_1):PAGE86
   179 M_L_DQ<19> @BASEBOARD_FAB2_LIB.BASEBOARD_FAB2(SCH_1):M_L_DQ(19)    I12 @BASEBOARD_FAB2_LIB.BASEBOARD_FAB2(SCH_1):PAGE86
    34 M_L_DQ<18> @BASEBOARD_FAB2_LIB.BASEBOARD_FAB2(SCH_1):M_L_DQ(18)    I12 @BASEBOARD_FAB2_LIB.BASEBOARD_FAB2(SCH_1):PAGE86
   172 M_L_DQ<17> @BASEBOARD_FAB2_LIB.BASEBOARD_FAB2(SCH_1):M_L_DQ(17)    I12 @BASEBOARD_FAB2_LIB.BASEBOARD_FAB2(SCH_1):PAGE86
    27 M_L_DQ<16> @BASEBOARD_FAB2_LIB.BASEBOARD_FAB2(SCH_1):M_L_DQ(16)    I12 @BASEBOARD_FAB2_LIB.BASEBOARD_FAB2(SCH_1):PAGE86
   166 M_L_DQ<15> @BASEBOARD_FAB2_LIB.BASEBOARD_FAB2(SCH_1):M_L_DQ(15)    I12 @BASEBOARD_FAB2_LIB.BASEBOARD_FAB2(SCH_1):PAGE86
    21 M_L_DQ<14> @BASEBOARD_FAB2_LIB.BASEBOARD_FAB2(SCH_1):M_L_DQ(14)    I12 @BASEBOARD_FAB2_LIB.BASEBOARD_FAB2(SCH_1):PAGE86
   159 M_L_DQ<13> @BASEBOARD_FAB2_LIB.BASEBOARD_FAB2(SCH_1):M_L_DQ(13)    I12 @BASEBOARD_FAB2_LIB.BASEBOARD_FAB2(SCH_1):PAGE86
    14 M_L_DQ<12> @BASEBOARD_FAB2_LIB.BASEBOARD_FAB2(SCH_1):M_L_DQ(12)    I12 @BASEBOARD_FAB2_LIB.BASEBOARD_FAB2(SCH_1):PAGE86
   168 M_L_DQ<11> @BASEBOARD_FAB2_LIB.BASEBOARD_FAB2(SCH_1):M_L_DQ(11)    I12 @BASEBOARD_FAB2_LIB.BASEBOARD_FAB2(SCH_1):PAGE86
    23 M_L_DQ<10> @BASEBOARD_FAB2_LIB.BASEBOARD_FAB2(SCH_1):M_L_DQ(10)    I12 @BASEBOARD_FAB2_LIB.BASEBOARD_FAB2(SCH_1):PAGE86
   161 M_L_DQ<9> @BASEBOARD_FAB2_LIB.BASEBOARD_FAB2(SCH_1):M_L_DQ(9)    I12 @BASEBOARD_FAB2_LIB.BASEBOARD_FAB2(SCH_1):PAGE86
    16 M_L_DQ<8> @BASEBOARD_FAB2_LIB.BASEBOARD_FAB2(SCH_1):M_L_DQ(8)    I12 @BASEBOARD_FAB2_LIB.BASEBOARD_FAB2(SCH_1):PAGE86
   155 M_L_DQ<7> @BASEBOARD_FAB2_LIB.BASEBOARD_FAB2(SCH_1):M_L_DQ(7)    I12 @BASEBOARD_FAB2_LIB.BASEBOARD_FAB2(SCH_1):PAGE86
    10 M_L_DQ<6> @BASEBOARD_FAB2_LIB.BASEBOARD_FAB2(SCH_1):M_L_DQ(6)    I12 @BASEBOARD_FAB2_LIB.BASEBOARD_FAB2(SCH_1):PAGE86
   148 M_L_DQ<5> @BASEBOARD_FAB2_LIB.BASEBOARD_FAB2(SCH_1):M_L_DQ(5)    I12 @BASEBOARD_FAB2_LIB.BASEBOARD_FAB2(SCH_1):PAGE86
     3 M_L_DQ<4> @BASEBOARD_FAB2_LIB.BASEBOARD_FAB2(SCH_1):M_L_DQ(4)    I12 @BASEBOARD_FAB2_LIB.BASEBOARD_FAB2(SCH_1):PAGE86
   157 M_L_DQ<3> @BASEBOARD_FAB2_LIB.BASEBOARD_FAB2(SCH_1):M_L_DQ(3)    I12 @BASEBOARD_FAB2_LIB.BASEBOARD_FAB2(SCH_1):PAGE86
    12 M_L_DQ<2> @BASEBOARD_FAB2_LIB.BASEBOARD_FAB2(SCH_1):M_L_DQ(2)    I12 @BASEBOARD_FAB2_LIB.BASEBOARD_FAB2(SCH_1):PAGE86
   150 M_L_DQ<1> @BASEBOARD_FAB2_LIB.BASEBOARD_FAB2(SCH_1):M_L_DQ(1)    I12 @BASEBOARD_FAB2_LIB.BASEBOARD_FAB2(SCH_1):PAGE86
     5 M_L_DQ<0> @BASEBOARD_FAB2_LIB.BASEBOARD_FAB2(SCH_1):M_L_DQ(0)    I12 @BASEBOARD_FAB2_LIB.BASEBOARD_FAB2(SCH_1):PAGE86
    78 FM_DIMM_EVENT_COD_N @BASEBOARD_FAB2_LIB.BASEBOARD_FAB2(SCH_1):FM_DIMM_EVENT_COD_N    I12 @BASEBOARD_FAB2_LIB.BASEBOARD_FAB2(SCH_1):PAGE86
    91 M_L_ODT<3> @BASEBOARD_FAB2_LIB.BASEBOARD_FAB2(SCH_1):M_L_ODT(3)    I12 @BASEBOARD_FAB2_LIB.BASEBOARD_FAB2(SCH_1):PAGE86
    87 M_L_ODT<2> @BASEBOARD_FAB2_LIB.BASEBOARD_FAB2(SCH_1):M_L_ODT(2)    I12 @BASEBOARD_FAB2_LIB.BASEBOARD_FAB2(SCH_1):PAGE86
   222 M_L_PAR @BASEBOARD_FAB2_LIB.BASEBOARD_FAB2(SCH_1):M_L_PAR    I12 @BASEBOARD_FAB2_LIB.BASEBOARD_FAB2(SCH_1):PAGE86
    58 M_KLM_RST_N @BASEBOARD_FAB2_LIB.BASEBOARD_FAB2(SCH_1):M_KLM_RST_N    I12 @BASEBOARD_FAB2_LIB.BASEBOARD_FAB2(SCH_1):PAGE86
   144 TP_CH_L_DIMM0_RFU_2 @BASEBOARD_FAB2_LIB.BASEBOARD_FAB2(SCH_1):TP_CH_L_DIMM0_RFU_2    I12 @BASEBOARD_FAB2_LIB.BASEBOARD_FAB2(SCH_1):PAGE86
   227 TP_CH_L_DIMM0_RFU_1 @BASEBOARD_FAB2_LIB.BASEBOARD_FAB2(SCH_1):TP_CH_L_DIMM0_RFU_1    I12 @BASEBOARD_FAB2_LIB.BASEBOARD_FAB2(SCH_1):PAGE86
   205 TP_CH_L_DIMM0_RFU_0 @BASEBOARD_FAB2_LIB.BASEBOARD_FAB2(SCH_1):TP_CH_L_DIMM0_RFU_0    I12 @BASEBOARD_FAB2_LIB.BASEBOARD_FAB2(SCH_1):PAGE86
    84 M_L_CS_N<4> @BASEBOARD_FAB2_LIB.BASEBOARD_FAB2(SCH_1):M_L_CS_N(4)    I12 @BASEBOARD_FAB2_LIB.BASEBOARD_FAB2(SCH_1):PAGE86
    89 M_L_CS_N<5> @BASEBOARD_FAB2_LIB.BASEBOARD_FAB2(SCH_1):M_L_CS_N(5)    I12 @BASEBOARD_FAB2_LIB.BASEBOARD_FAB2(SCH_1):PAGE86
    93 M_L_CS_N<6> @BASEBOARD_FAB2_LIB.BASEBOARD_FAB2(SCH_1):M_L_CS_N(6)    I12 @BASEBOARD_FAB2_LIB.BASEBOARD_FAB2(SCH_1):PAGE86
   237 M_L_CS_N<7> @BASEBOARD_FAB2_LIB.BASEBOARD_FAB2(SCH_1):M_L_CS_N(7)    I12 @BASEBOARD_FAB2_LIB.BASEBOARD_FAB2(SCH_1):PAGE86
   238    GND @BASEBOARD_FAB2_LIB.BASEBOARD_FAB2(SCH_1):GND    I12 @BASEBOARD_FAB2_LIB.BASEBOARD_FAB2(SCH_1):PAGE86
   140 PVPP_KLM @BASEBOARD_FAB2_LIB.BASEBOARD_FAB2(SCH_1):PVPP_KLM    I12 @BASEBOARD_FAB2_LIB.BASEBOARD_FAB2(SCH_1):PAGE86
   139 PVPP_KLM @BASEBOARD_FAB2_LIB.BASEBOARD_FAB2(SCH_1):PVPP_KLM    I12 @BASEBOARD_FAB2_LIB.BASEBOARD_FAB2(SCH_1):PAGE86
   230 FM_ADR_COMPLETE_KLM_N @BASEBOARD_FAB2_LIB.BASEBOARD_FAB2(SCH_1):FM_ADR_COMPLETE_KLM_N    I12 @BASEBOARD_FAB2_LIB.BASEBOARD_FAB2(SCH_1):PAGE86
   141 SMB_DDR_KLM_VPP_SCL @BASEBOARD_FAB2_LIB.BASEBOARD_FAB2(SCH_1):SMB_DDR_KLM_VPP_SCL    I12 @BASEBOARD_FAB2_LIB.BASEBOARD_FAB2(SCH_1):PAGE86
   285 SMB_DDR_KLM_VPP_SDA @BASEBOARD_FAB2_LIB.BASEBOARD_FAB2(SCH_1):SMB_DDR_KLM_VPP_SDA    I12 @BASEBOARD_FAB2_LIB.BASEBOARD_FAB2(SCH_1):PAGE86
   284 PVPP_KLM @BASEBOARD_FAB2_LIB.BASEBOARD_FAB2(SCH_1):PVPP_KLM    I12 @BASEBOARD_FAB2_LIB.BASEBOARD_FAB2(SCH_1):PAGE86
   146 M_L_VREF @BASEBOARD_FAB2_LIB.BASEBOARD_FAB2(SCH_1):M_L_VREF    I12 @BASEBOARD_FAB2_LIB.BASEBOARD_FAB2(SCH_1):PAGE86
   152 M_L_DQS_DN<0> @BASEBOARD_FAB2_LIB.BASEBOARD_FAB2(SCH_1):M_L_DQS_DN(0)   I100 @BASEBOARD_FAB2_LIB.BASEBOARD_FAB2(SCH_1):PAGE86
   153 M_L_DQS_DP<0> @BASEBOARD_FAB2_LIB.BASEBOARD_FAB2(SCH_1):M_L_DQS_DP(0)   I100 @BASEBOARD_FAB2_LIB.BASEBOARD_FAB2(SCH_1):PAGE86
    19 M_L_DQS_DN<10> @BASEBOARD_FAB2_LIB.BASEBOARD_FAB2(SCH_1):M_L_DQS_DN(10)   I100 @BASEBOARD_FAB2_LIB.BASEBOARD_FAB2(SCH_1):PAGE86
    18 M_L_DQS_DP<10> @BASEBOARD_FAB2_LIB.BASEBOARD_FAB2(SCH_1):M_L_DQS_DP(10)   I100 @BASEBOARD_FAB2_LIB.BASEBOARD_FAB2(SCH_1):PAGE86
    30 M_L_DQS_DN<11> @BASEBOARD_FAB2_LIB.BASEBOARD_FAB2(SCH_1):M_L_DQS_DN(11)   I100 @BASEBOARD_FAB2_LIB.BASEBOARD_FAB2(SCH_1):PAGE86
    29 M_L_DQS_DP<11> @BASEBOARD_FAB2_LIB.BASEBOARD_FAB2(SCH_1):M_L_DQS_DP(11)   I100 @BASEBOARD_FAB2_LIB.BASEBOARD_FAB2(SCH_1):PAGE86
    41 M_L_DQS_DN<12> @BASEBOARD_FAB2_LIB.BASEBOARD_FAB2(SCH_1):M_L_DQS_DN(12)   I100 @BASEBOARD_FAB2_LIB.BASEBOARD_FAB2(SCH_1):PAGE86
    40 M_L_DQS_DP<12> @BASEBOARD_FAB2_LIB.BASEBOARD_FAB2(SCH_1):M_L_DQS_DP(12)   I100 @BASEBOARD_FAB2_LIB.BASEBOARD_FAB2(SCH_1):PAGE86
   100 M_L_DQS_DN<13> @BASEBOARD_FAB2_LIB.BASEBOARD_FAB2(SCH_1):M_L_DQS_DN(13)   I100 @BASEBOARD_FAB2_LIB.BASEBOARD_FAB2(SCH_1):PAGE86
    99 M_L_DQS_DP<13> @BASEBOARD_FAB2_LIB.BASEBOARD_FAB2(SCH_1):M_L_DQS_DP(13)   I100 @BASEBOARD_FAB2_LIB.BASEBOARD_FAB2(SCH_1):PAGE86
   111 M_L_DQS_DN<14> @BASEBOARD_FAB2_LIB.BASEBOARD_FAB2(SCH_1):M_L_DQS_DN(14)   I100 @BASEBOARD_FAB2_LIB.BASEBOARD_FAB2(SCH_1):PAGE86
   110 M_L_DQS_DP<14> @BASEBOARD_FAB2_LIB.BASEBOARD_FAB2(SCH_1):M_L_DQS_DP(14)   I100 @BASEBOARD_FAB2_LIB.BASEBOARD_FAB2(SCH_1):PAGE86
   122 M_L_DQS_DN<15> @BASEBOARD_FAB2_LIB.BASEBOARD_FAB2(SCH_1):M_L_DQS_DN(15)   I100 @BASEBOARD_FAB2_LIB.BASEBOARD_FAB2(SCH_1):PAGE86
   121 M_L_DQS_DP<15> @BASEBOARD_FAB2_LIB.BASEBOARD_FAB2(SCH_1):M_L_DQS_DP(15)   I100 @BASEBOARD_FAB2_LIB.BASEBOARD_FAB2(SCH_1):PAGE86
   133 M_L_DQS_DN<16> @BASEBOARD_FAB2_LIB.BASEBOARD_FAB2(SCH_1):M_L_DQS_DN(16)   I100 @BASEBOARD_FAB2_LIB.BASEBOARD_FAB2(SCH_1):PAGE86
   132 M_L_DQS_DP<16> @BASEBOARD_FAB2_LIB.BASEBOARD_FAB2(SCH_1):M_L_DQS_DP(16)   I100 @BASEBOARD_FAB2_LIB.BASEBOARD_FAB2(SCH_1):PAGE86
    52 M_L_DQS_DN<17> @BASEBOARD_FAB2_LIB.BASEBOARD_FAB2(SCH_1):M_L_DQS_DN(17)   I100 @BASEBOARD_FAB2_LIB.BASEBOARD_FAB2(SCH_1):PAGE86
    51 M_L_DQS_DP<17> @BASEBOARD_FAB2_LIB.BASEBOARD_FAB2(SCH_1):M_L_DQS_DP(17)   I100 @BASEBOARD_FAB2_LIB.BASEBOARD_FAB2(SCH_1):PAGE86
   163 M_L_DQS_DN<1> @BASEBOARD_FAB2_LIB.BASEBOARD_FAB2(SCH_1):M_L_DQS_DN(1)   I100 @BASEBOARD_FAB2_LIB.BASEBOARD_FAB2(SCH_1):PAGE86
   164 M_L_DQS_DP<1> @BASEBOARD_FAB2_LIB.BASEBOARD_FAB2(SCH_1):M_L_DQS_DP(1)   I100 @BASEBOARD_FAB2_LIB.BASEBOARD_FAB2(SCH_1):PAGE86
   174 M_L_DQS_DN<2> @BASEBOARD_FAB2_LIB.BASEBOARD_FAB2(SCH_1):M_L_DQS_DN(2)   I100 @BASEBOARD_FAB2_LIB.BASEBOARD_FAB2(SCH_1):PAGE86
   175 M_L_DQS_DP<2> @BASEBOARD_FAB2_LIB.BASEBOARD_FAB2(SCH_1):M_L_DQS_DP(2)   I100 @BASEBOARD_FAB2_LIB.BASEBOARD_FAB2(SCH_1):PAGE86
   185 M_L_DQS_DN<3> @BASEBOARD_FAB2_LIB.BASEBOARD_FAB2(SCH_1):M_L_DQS_DN(3)   I100 @BASEBOARD_FAB2_LIB.BASEBOARD_FAB2(SCH_1):PAGE86
   186 M_L_DQS_DP<3> @BASEBOARD_FAB2_LIB.BASEBOARD_FAB2(SCH_1):M_L_DQS_DP(3)   I100 @BASEBOARD_FAB2_LIB.BASEBOARD_FAB2(SCH_1):PAGE86
   244 M_L_DQS_DN<4> @BASEBOARD_FAB2_LIB.BASEBOARD_FAB2(SCH_1):M_L_DQS_DN(4)   I100 @BASEBOARD_FAB2_LIB.BASEBOARD_FAB2(SCH_1):PAGE86
   245 M_L_DQS_DP<4> @BASEBOARD_FAB2_LIB.BASEBOARD_FAB2(SCH_1):M_L_DQS_DP(4)   I100 @BASEBOARD_FAB2_LIB.BASEBOARD_FAB2(SCH_1):PAGE86
   255 M_L_DQS_DN<5> @BASEBOARD_FAB2_LIB.BASEBOARD_FAB2(SCH_1):M_L_DQS_DN(5)   I100 @BASEBOARD_FAB2_LIB.BASEBOARD_FAB2(SCH_1):PAGE86
   256 M_L_DQS_DP<5> @BASEBOARD_FAB2_LIB.BASEBOARD_FAB2(SCH_1):M_L_DQS_DP(5)   I100 @BASEBOARD_FAB2_LIB.BASEBOARD_FAB2(SCH_1):PAGE86
   266 M_L_DQS_DN<6> @BASEBOARD_FAB2_LIB.BASEBOARD_FAB2(SCH_1):M_L_DQS_DN(6)   I100 @BASEBOARD_FAB2_LIB.BASEBOARD_FAB2(SCH_1):PAGE86
   267 M_L_DQS_DP<6> @BASEBOARD_FAB2_LIB.BASEBOARD_FAB2(SCH_1):M_L_DQS_DP(6)   I100 @BASEBOARD_FAB2_LIB.BASEBOARD_FAB2(SCH_1):PAGE86
   277 M_L_DQS_DN<7> @BASEBOARD_FAB2_LIB.BASEBOARD_FAB2(SCH_1):M_L_DQS_DN(7)   I100 @BASEBOARD_FAB2_LIB.BASEBOARD_FAB2(SCH_1):PAGE86
   278 M_L_DQS_DP<7> @BASEBOARD_FAB2_LIB.BASEBOARD_FAB2(SCH_1):M_L_DQS_DP(7)   I100 @BASEBOARD_FAB2_LIB.BASEBOARD_FAB2(SCH_1):PAGE86
   196 M_L_DQS_DN<8> @BASEBOARD_FAB2_LIB.BASEBOARD_FAB2(SCH_1):M_L_DQS_DN(8)   I100 @BASEBOARD_FAB2_LIB.BASEBOARD_FAB2(SCH_1):PAGE86
   197 M_L_DQS_DP<8> @BASEBOARD_FAB2_LIB.BASEBOARD_FAB2(SCH_1):M_L_DQS_DP(8)   I100 @BASEBOARD_FAB2_LIB.BASEBOARD_FAB2(SCH_1):PAGE86
     8 M_L_DQS_DN<9> @BASEBOARD_FAB2_LIB.BASEBOARD_FAB2(SCH_1):M_L_DQS_DN(9)   I100 @BASEBOARD_FAB2_LIB.BASEBOARD_FAB2(SCH_1):PAGE86
     7 M_L_DQS_DP<9> @BASEBOARD_FAB2_LIB.BASEBOARD_FAB2(SCH_1):M_L_DQS_DP(9)   I100 @BASEBOARD_FAB2_LIB.BASEBOARD_FAB2(SCH_1):PAGE86
     2    GND @BASEBOARD_FAB2_LIB.BASEBOARD_FAB2(SCH_1):GND   I138 @BASEBOARD_FAB2_LIB.BASEBOARD_FAB2(SCH_1):PAGE86
     4    GND @BASEBOARD_FAB2_LIB.BASEBOARD_FAB2(SCH_1):GND   I138 @BASEBOARD_FAB2_LIB.BASEBOARD_FAB2(SCH_1):PAGE86
     6    GND @BASEBOARD_FAB2_LIB.BASEBOARD_FAB2(SCH_1):GND   I138 @BASEBOARD_FAB2_LIB.BASEBOARD_FAB2(SCH_1):PAGE86
     9    GND @BASEBOARD_FAB2_LIB.BASEBOARD_FAB2(SCH_1):GND   I138 @BASEBOARD_FAB2_LIB.BASEBOARD_FAB2(SCH_1):PAGE86
    11    GND @BASEBOARD_FAB2_LIB.BASEBOARD_FAB2(SCH_1):GND   I138 @BASEBOARD_FAB2_LIB.BASEBOARD_FAB2(SCH_1):PAGE86
    13    GND @BASEBOARD_FAB2_LIB.BASEBOARD_FAB2(SCH_1):GND   I138 @BASEBOARD_FAB2_LIB.BASEBOARD_FAB2(SCH_1):PAGE86
    15    GND @BASEBOARD_FAB2_LIB.BASEBOARD_FAB2(SCH_1):GND   I138 @BASEBOARD_FAB2_LIB.BASEBOARD_FAB2(SCH_1):PAGE86
    17    GND @BASEBOARD_FAB2_LIB.BASEBOARD_FAB2(SCH_1):GND   I138 @BASEBOARD_FAB2_LIB.BASEBOARD_FAB2(SCH_1):PAGE86
    20    GND @BASEBOARD_FAB2_LIB.BASEBOARD_FAB2(SCH_1):GND   I138 @BASEBOARD_FAB2_LIB.BASEBOARD_FAB2(SCH_1):PAGE86
    22    GND @BASEBOARD_FAB2_LIB.BASEBOARD_FAB2(SCH_1):GND   I138 @BASEBOARD_FAB2_LIB.BASEBOARD_FAB2(SCH_1):PAGE86
    24    GND @BASEBOARD_FAB2_LIB.BASEBOARD_FAB2(SCH_1):GND   I138 @BASEBOARD_FAB2_LIB.BASEBOARD_FAB2(SCH_1):PAGE86
    26    GND @BASEBOARD_FAB2_LIB.BASEBOARD_FAB2(SCH_1):GND   I138 @BASEBOARD_FAB2_LIB.BASEBOARD_FAB2(SCH_1):PAGE86
    28    GND @BASEBOARD_FAB2_LIB.BASEBOARD_FAB2(SCH_1):GND   I138 @BASEBOARD_FAB2_LIB.BASEBOARD_FAB2(SCH_1):PAGE86
    31    GND @BASEBOARD_FAB2_LIB.BASEBOARD_FAB2(SCH_1):GND   I138 @BASEBOARD_FAB2_LIB.BASEBOARD_FAB2(SCH_1):PAGE86
    33    GND @BASEBOARD_FAB2_LIB.BASEBOARD_FAB2(SCH_1):GND   I138 @BASEBOARD_FAB2_LIB.BASEBOARD_FAB2(SCH_1):PAGE86
    35    GND @BASEBOARD_FAB2_LIB.BASEBOARD_FAB2(SCH_1):GND   I138 @BASEBOARD_FAB2_LIB.BASEBOARD_FAB2(SCH_1):PAGE86
    37    GND @BASEBOARD_FAB2_LIB.BASEBOARD_FAB2(SCH_1):GND   I138 @BASEBOARD_FAB2_LIB.BASEBOARD_FAB2(SCH_1):PAGE86
    39    GND @BASEBOARD_FAB2_LIB.BASEBOARD_FAB2(SCH_1):GND   I138 @BASEBOARD_FAB2_LIB.BASEBOARD_FAB2(SCH_1):PAGE86
    42    GND @BASEBOARD_FAB2_LIB.BASEBOARD_FAB2(SCH_1):GND   I138 @BASEBOARD_FAB2_LIB.BASEBOARD_FAB2(SCH_1):PAGE86
    44    GND @BASEBOARD_FAB2_LIB.BASEBOARD_FAB2(SCH_1):GND   I138 @BASEBOARD_FAB2_LIB.BASEBOARD_FAB2(SCH_1):PAGE86
    46    GND @BASEBOARD_FAB2_LIB.BASEBOARD_FAB2(SCH_1):GND   I138 @BASEBOARD_FAB2_LIB.BASEBOARD_FAB2(SCH_1):PAGE86
    48    GND @BASEBOARD_FAB2_LIB.BASEBOARD_FAB2(SCH_1):GND   I138 @BASEBOARD_FAB2_LIB.BASEBOARD_FAB2(SCH_1):PAGE86
    50    GND @BASEBOARD_FAB2_LIB.BASEBOARD_FAB2(SCH_1):GND   I138 @BASEBOARD_FAB2_LIB.BASEBOARD_FAB2(SCH_1):PAGE86
    53    GND @BASEBOARD_FAB2_LIB.BASEBOARD_FAB2(SCH_1):GND   I138 @BASEBOARD_FAB2_LIB.BASEBOARD_FAB2(SCH_1):PAGE86
    55    GND @BASEBOARD_FAB2_LIB.BASEBOARD_FAB2(SCH_1):GND   I138 @BASEBOARD_FAB2_LIB.BASEBOARD_FAB2(SCH_1):PAGE86
    57    GND @BASEBOARD_FAB2_LIB.BASEBOARD_FAB2(SCH_1):GND   I138 @BASEBOARD_FAB2_LIB.BASEBOARD_FAB2(SCH_1):PAGE86
    94    GND @BASEBOARD_FAB2_LIB.BASEBOARD_FAB2(SCH_1):GND   I138 @BASEBOARD_FAB2_LIB.BASEBOARD_FAB2(SCH_1):PAGE86
    96    GND @BASEBOARD_FAB2_LIB.BASEBOARD_FAB2(SCH_1):GND   I138 @BASEBOARD_FAB2_LIB.BASEBOARD_FAB2(SCH_1):PAGE86
    98    GND @BASEBOARD_FAB2_LIB.BASEBOARD_FAB2(SCH_1):GND   I138 @BASEBOARD_FAB2_LIB.BASEBOARD_FAB2(SCH_1):PAGE86
   101    GND @BASEBOARD_FAB2_LIB.BASEBOARD_FAB2(SCH_1):GND   I138 @BASEBOARD_FAB2_LIB.BASEBOARD_FAB2(SCH_1):PAGE86
   103    GND @BASEBOARD_FAB2_LIB.BASEBOARD_FAB2(SCH_1):GND   I138 @BASEBOARD_FAB2_LIB.BASEBOARD_FAB2(SCH_1):PAGE86
   105    GND @BASEBOARD_FAB2_LIB.BASEBOARD_FAB2(SCH_1):GND   I138 @BASEBOARD_FAB2_LIB.BASEBOARD_FAB2(SCH_1):PAGE86
   107    GND @BASEBOARD_FAB2_LIB.BASEBOARD_FAB2(SCH_1):GND   I138 @BASEBOARD_FAB2_LIB.BASEBOARD_FAB2(SCH_1):PAGE86
   109    GND @BASEBOARD_FAB2_LIB.BASEBOARD_FAB2(SCH_1):GND   I138 @BASEBOARD_FAB2_LIB.BASEBOARD_FAB2(SCH_1):PAGE86
   112    GND @BASEBOARD_FAB2_LIB.BASEBOARD_FAB2(SCH_1):GND   I138 @BASEBOARD_FAB2_LIB.BASEBOARD_FAB2(SCH_1):PAGE86
   114    GND @BASEBOARD_FAB2_LIB.BASEBOARD_FAB2(SCH_1):GND   I138 @BASEBOARD_FAB2_LIB.BASEBOARD_FAB2(SCH_1):PAGE86
   116    GND @BASEBOARD_FAB2_LIB.BASEBOARD_FAB2(SCH_1):GND   I138 @BASEBOARD_FAB2_LIB.BASEBOARD_FAB2(SCH_1):PAGE86
   118    GND @BASEBOARD_FAB2_LIB.BASEBOARD_FAB2(SCH_1):GND   I138 @BASEBOARD_FAB2_LIB.BASEBOARD_FAB2(SCH_1):PAGE86
   120    GND @BASEBOARD_FAB2_LIB.BASEBOARD_FAB2(SCH_1):GND   I138 @BASEBOARD_FAB2_LIB.BASEBOARD_FAB2(SCH_1):PAGE86
   123    GND @BASEBOARD_FAB2_LIB.BASEBOARD_FAB2(SCH_1):GND   I138 @BASEBOARD_FAB2_LIB.BASEBOARD_FAB2(SCH_1):PAGE86
   125    GND @BASEBOARD_FAB2_LIB.BASEBOARD_FAB2(SCH_1):GND   I138 @BASEBOARD_FAB2_LIB.BASEBOARD_FAB2(SCH_1):PAGE86
   127    GND @BASEBOARD_FAB2_LIB.BASEBOARD_FAB2(SCH_1):GND   I138 @BASEBOARD_FAB2_LIB.BASEBOARD_FAB2(SCH_1):PAGE86
   129    GND @BASEBOARD_FAB2_LIB.BASEBOARD_FAB2(SCH_1):GND   I138 @BASEBOARD_FAB2_LIB.BASEBOARD_FAB2(SCH_1):PAGE86
   131    GND @BASEBOARD_FAB2_LIB.BASEBOARD_FAB2(SCH_1):GND   I138 @BASEBOARD_FAB2_LIB.BASEBOARD_FAB2(SCH_1):PAGE86
   134    GND @BASEBOARD_FAB2_LIB.BASEBOARD_FAB2(SCH_1):GND   I138 @BASEBOARD_FAB2_LIB.BASEBOARD_FAB2(SCH_1):PAGE86
   136    GND @BASEBOARD_FAB2_LIB.BASEBOARD_FAB2(SCH_1):GND   I138 @BASEBOARD_FAB2_LIB.BASEBOARD_FAB2(SCH_1):PAGE86
   138    GND @BASEBOARD_FAB2_LIB.BASEBOARD_FAB2(SCH_1):GND   I138 @BASEBOARD_FAB2_LIB.BASEBOARD_FAB2(SCH_1):PAGE86
   147    GND @BASEBOARD_FAB2_LIB.BASEBOARD_FAB2(SCH_1):GND   I138 @BASEBOARD_FAB2_LIB.BASEBOARD_FAB2(SCH_1):PAGE86
   149    GND @BASEBOARD_FAB2_LIB.BASEBOARD_FAB2(SCH_1):GND   I138 @BASEBOARD_FAB2_LIB.BASEBOARD_FAB2(SCH_1):PAGE86
   151    GND @BASEBOARD_FAB2_LIB.BASEBOARD_FAB2(SCH_1):GND   I138 @BASEBOARD_FAB2_LIB.BASEBOARD_FAB2(SCH_1):PAGE86
   154    GND @BASEBOARD_FAB2_LIB.BASEBOARD_FAB2(SCH_1):GND   I138 @BASEBOARD_FAB2_LIB.BASEBOARD_FAB2(SCH_1):PAGE86
   156    GND @BASEBOARD_FAB2_LIB.BASEBOARD_FAB2(SCH_1):GND   I138 @BASEBOARD_FAB2_LIB.BASEBOARD_FAB2(SCH_1):PAGE86
   158    GND @BASEBOARD_FAB2_LIB.BASEBOARD_FAB2(SCH_1):GND   I138 @BASEBOARD_FAB2_LIB.BASEBOARD_FAB2(SCH_1):PAGE86
   160    GND @BASEBOARD_FAB2_LIB.BASEBOARD_FAB2(SCH_1):GND   I138 @BASEBOARD_FAB2_LIB.BASEBOARD_FAB2(SCH_1):PAGE86
   162    GND @BASEBOARD_FAB2_LIB.BASEBOARD_FAB2(SCH_1):GND   I138 @BASEBOARD_FAB2_LIB.BASEBOARD_FAB2(SCH_1):PAGE86
   165    GND @BASEBOARD_FAB2_LIB.BASEBOARD_FAB2(SCH_1):GND   I138 @BASEBOARD_FAB2_LIB.BASEBOARD_FAB2(SCH_1):PAGE86
   167    GND @BASEBOARD_FAB2_LIB.BASEBOARD_FAB2(SCH_1):GND   I138 @BASEBOARD_FAB2_LIB.BASEBOARD_FAB2(SCH_1):PAGE86
   169    GND @BASEBOARD_FAB2_LIB.BASEBOARD_FAB2(SCH_1):GND   I138 @BASEBOARD_FAB2_LIB.BASEBOARD_FAB2(SCH_1):PAGE86
   171    GND @BASEBOARD_FAB2_LIB.BASEBOARD_FAB2(SCH_1):GND   I138 @BASEBOARD_FAB2_LIB.BASEBOARD_FAB2(SCH_1):PAGE86
   173    GND @BASEBOARD_FAB2_LIB.BASEBOARD_FAB2(SCH_1):GND   I138 @BASEBOARD_FAB2_LIB.BASEBOARD_FAB2(SCH_1):PAGE86
   176    GND @BASEBOARD_FAB2_LIB.BASEBOARD_FAB2(SCH_1):GND   I138 @BASEBOARD_FAB2_LIB.BASEBOARD_FAB2(SCH_1):PAGE86
   178    GND @BASEBOARD_FAB2_LIB.BASEBOARD_FAB2(SCH_1):GND   I138 @BASEBOARD_FAB2_LIB.BASEBOARD_FAB2(SCH_1):PAGE86
   180    GND @BASEBOARD_FAB2_LIB.BASEBOARD_FAB2(SCH_1):GND   I138 @BASEBOARD_FAB2_LIB.BASEBOARD_FAB2(SCH_1):PAGE86
   182    GND @BASEBOARD_FAB2_LIB.BASEBOARD_FAB2(SCH_1):GND   I138 @BASEBOARD_FAB2_LIB.BASEBOARD_FAB2(SCH_1):PAGE86
   184    GND @BASEBOARD_FAB2_LIB.BASEBOARD_FAB2(SCH_1):GND   I138 @BASEBOARD_FAB2_LIB.BASEBOARD_FAB2(SCH_1):PAGE86
   187    GND @BASEBOARD_FAB2_LIB.BASEBOARD_FAB2(SCH_1):GND   I138 @BASEBOARD_FAB2_LIB.BASEBOARD_FAB2(SCH_1):PAGE86
   189    GND @BASEBOARD_FAB2_LIB.BASEBOARD_FAB2(SCH_1):GND   I138 @BASEBOARD_FAB2_LIB.BASEBOARD_FAB2(SCH_1):PAGE86
   191    GND @BASEBOARD_FAB2_LIB.BASEBOARD_FAB2(SCH_1):GND   I138 @BASEBOARD_FAB2_LIB.BASEBOARD_FAB2(SCH_1):PAGE86
   193    GND @BASEBOARD_FAB2_LIB.BASEBOARD_FAB2(SCH_1):GND   I138 @BASEBOARD_FAB2_LIB.BASEBOARD_FAB2(SCH_1):PAGE86
   195    GND @BASEBOARD_FAB2_LIB.BASEBOARD_FAB2(SCH_1):GND   I138 @BASEBOARD_FAB2_LIB.BASEBOARD_FAB2(SCH_1):PAGE86
   198    GND @BASEBOARD_FAB2_LIB.BASEBOARD_FAB2(SCH_1):GND   I138 @BASEBOARD_FAB2_LIB.BASEBOARD_FAB2(SCH_1):PAGE86
   200    GND @BASEBOARD_FAB2_LIB.BASEBOARD_FAB2(SCH_1):GND   I138 @BASEBOARD_FAB2_LIB.BASEBOARD_FAB2(SCH_1):PAGE86
   202    GND @BASEBOARD_FAB2_LIB.BASEBOARD_FAB2(SCH_1):GND   I138 @BASEBOARD_FAB2_LIB.BASEBOARD_FAB2(SCH_1):PAGE86
   239    GND @BASEBOARD_FAB2_LIB.BASEBOARD_FAB2(SCH_1):GND   I138 @BASEBOARD_FAB2_LIB.BASEBOARD_FAB2(SCH_1):PAGE86
   241    GND @BASEBOARD_FAB2_LIB.BASEBOARD_FAB2(SCH_1):GND   I138 @BASEBOARD_FAB2_LIB.BASEBOARD_FAB2(SCH_1):PAGE86
   243    GND @BASEBOARD_FAB2_LIB.BASEBOARD_FAB2(SCH_1):GND   I138 @BASEBOARD_FAB2_LIB.BASEBOARD_FAB2(SCH_1):PAGE86
   246    GND @BASEBOARD_FAB2_LIB.BASEBOARD_FAB2(SCH_1):GND   I138 @BASEBOARD_FAB2_LIB.BASEBOARD_FAB2(SCH_1):PAGE86
   248    GND @BASEBOARD_FAB2_LIB.BASEBOARD_FAB2(SCH_1):GND   I138 @BASEBOARD_FAB2_LIB.BASEBOARD_FAB2(SCH_1):PAGE86
   250    GND @BASEBOARD_FAB2_LIB.BASEBOARD_FAB2(SCH_1):GND   I138 @BASEBOARD_FAB2_LIB.BASEBOARD_FAB2(SCH_1):PAGE86
   252    GND @BASEBOARD_FAB2_LIB.BASEBOARD_FAB2(SCH_1):GND   I138 @BASEBOARD_FAB2_LIB.BASEBOARD_FAB2(SCH_1):PAGE86
   254    GND @BASEBOARD_FAB2_LIB.BASEBOARD_FAB2(SCH_1):GND   I138 @BASEBOARD_FAB2_LIB.BASEBOARD_FAB2(SCH_1):PAGE86
   257    GND @BASEBOARD_FAB2_LIB.BASEBOARD_FAB2(SCH_1):GND   I138 @BASEBOARD_FAB2_LIB.BASEBOARD_FAB2(SCH_1):PAGE86
   259    GND @BASEBOARD_FAB2_LIB.BASEBOARD_FAB2(SCH_1):GND   I138 @BASEBOARD_FAB2_LIB.BASEBOARD_FAB2(SCH_1):PAGE86
   261    GND @BASEBOARD_FAB2_LIB.BASEBOARD_FAB2(SCH_1):GND   I138 @BASEBOARD_FAB2_LIB.BASEBOARD_FAB2(SCH_1):PAGE86
   263    GND @BASEBOARD_FAB2_LIB.BASEBOARD_FAB2(SCH_1):GND   I138 @BASEBOARD_FAB2_LIB.BASEBOARD_FAB2(SCH_1):PAGE86
   265    GND @BASEBOARD_FAB2_LIB.BASEBOARD_FAB2(SCH_1):GND   I138 @BASEBOARD_FAB2_LIB.BASEBOARD_FAB2(SCH_1):PAGE86
   268    GND @BASEBOARD_FAB2_LIB.BASEBOARD_FAB2(SCH_1):GND   I138 @BASEBOARD_FAB2_LIB.BASEBOARD_FAB2(SCH_1):PAGE86
   270    GND @BASEBOARD_FAB2_LIB.BASEBOARD_FAB2(SCH_1):GND   I138 @BASEBOARD_FAB2_LIB.BASEBOARD_FAB2(SCH_1):PAGE86
   272    GND @BASEBOARD_FAB2_LIB.BASEBOARD_FAB2(SCH_1):GND   I138 @BASEBOARD_FAB2_LIB.BASEBOARD_FAB2(SCH_1):PAGE86
   274    GND @BASEBOARD_FAB2_LIB.BASEBOARD_FAB2(SCH_1):GND   I138 @BASEBOARD_FAB2_LIB.BASEBOARD_FAB2(SCH_1):PAGE86
   276    GND @BASEBOARD_FAB2_LIB.BASEBOARD_FAB2(SCH_1):GND   I138 @BASEBOARD_FAB2_LIB.BASEBOARD_FAB2(SCH_1):PAGE86
   279    GND @BASEBOARD_FAB2_LIB.BASEBOARD_FAB2(SCH_1):GND   I138 @BASEBOARD_FAB2_LIB.BASEBOARD_FAB2(SCH_1):PAGE86
   281    GND @BASEBOARD_FAB2_LIB.BASEBOARD_FAB2(SCH_1):GND   I138 @BASEBOARD_FAB2_LIB.BASEBOARD_FAB2(SCH_1):PAGE86
   283    GND @BASEBOARD_FAB2_LIB.BASEBOARD_FAB2(SCH_1):GND   I138 @BASEBOARD_FAB2_LIB.BASEBOARD_FAB2(SCH_1):PAGE86
     1 P12V_NVDIMM_KLM @BASEBOARD_FAB2_LIB.BASEBOARD_FAB2(SCH_1):P12V_NVDIMM_KLM    I55 @BASEBOARD_FAB2_LIB.BASEBOARD_FAB2(SCH_1):PAGE86
   145 P12V_NVDIMM_KLM @BASEBOARD_FAB2_LIB.BASEBOARD_FAB2(SCH_1):P12V_NVDIMM_KLM    I55 @BASEBOARD_FAB2_LIB.BASEBOARD_FAB2(SCH_1):PAGE86
    59 PVDDQ_KLM @BASEBOARD_FAB2_LIB.BASEBOARD_FAB2(SCH_1):PVDDQ_KLM    I55 @BASEBOARD_FAB2_LIB.BASEBOARD_FAB2(SCH_1):PAGE86
    61 PVDDQ_KLM @BASEBOARD_FAB2_LIB.BASEBOARD_FAB2(SCH_1):PVDDQ_KLM    I55 @BASEBOARD_FAB2_LIB.BASEBOARD_FAB2(SCH_1):PAGE86
    64 PVDDQ_KLM @BASEBOARD_FAB2_LIB.BASEBOARD_FAB2(SCH_1):PVDDQ_KLM    I55 @BASEBOARD_FAB2_LIB.BASEBOARD_FAB2(SCH_1):PAGE86
    67 PVDDQ_KLM @BASEBOARD_FAB2_LIB.BASEBOARD_FAB2(SCH_1):PVDDQ_KLM    I55 @BASEBOARD_FAB2_LIB.BASEBOARD_FAB2(SCH_1):PAGE86
    70 PVDDQ_KLM @BASEBOARD_FAB2_LIB.BASEBOARD_FAB2(SCH_1):PVDDQ_KLM    I55 @BASEBOARD_FAB2_LIB.BASEBOARD_FAB2(SCH_1):PAGE86
    73 PVDDQ_KLM @BASEBOARD_FAB2_LIB.BASEBOARD_FAB2(SCH_1):PVDDQ_KLM    I55 @BASEBOARD_FAB2_LIB.BASEBOARD_FAB2(SCH_1):PAGE86
    76 PVDDQ_KLM @BASEBOARD_FAB2_LIB.BASEBOARD_FAB2(SCH_1):PVDDQ_KLM    I55 @BASEBOARD_FAB2_LIB.BASEBOARD_FAB2(SCH_1):PAGE86
    80 PVDDQ_KLM @BASEBOARD_FAB2_LIB.BASEBOARD_FAB2(SCH_1):PVDDQ_KLM    I55 @BASEBOARD_FAB2_LIB.BASEBOARD_FAB2(SCH_1):PAGE86
    83 PVDDQ_KLM @BASEBOARD_FAB2_LIB.BASEBOARD_FAB2(SCH_1):PVDDQ_KLM    I55 @BASEBOARD_FAB2_LIB.BASEBOARD_FAB2(SCH_1):PAGE86
    85 PVDDQ_KLM @BASEBOARD_FAB2_LIB.BASEBOARD_FAB2(SCH_1):PVDDQ_KLM    I55 @BASEBOARD_FAB2_LIB.BASEBOARD_FAB2(SCH_1):PAGE86
    88 PVDDQ_KLM @BASEBOARD_FAB2_LIB.BASEBOARD_FAB2(SCH_1):PVDDQ_KLM    I55 @BASEBOARD_FAB2_LIB.BASEBOARD_FAB2(SCH_1):PAGE86
    90 PVDDQ_KLM @BASEBOARD_FAB2_LIB.BASEBOARD_FAB2(SCH_1):PVDDQ_KLM    I55 @BASEBOARD_FAB2_LIB.BASEBOARD_FAB2(SCH_1):PAGE86
    92 PVDDQ_KLM @BASEBOARD_FAB2_LIB.BASEBOARD_FAB2(SCH_1):PVDDQ_KLM    I55 @BASEBOARD_FAB2_LIB.BASEBOARD_FAB2(SCH_1):PAGE86
   204 PVDDQ_KLM @BASEBOARD_FAB2_LIB.BASEBOARD_FAB2(SCH_1):PVDDQ_KLM    I55 @BASEBOARD_FAB2_LIB.BASEBOARD_FAB2(SCH_1):PAGE86
   206 PVDDQ_KLM @BASEBOARD_FAB2_LIB.BASEBOARD_FAB2(SCH_1):PVDDQ_KLM    I55 @BASEBOARD_FAB2_LIB.BASEBOARD_FAB2(SCH_1):PAGE86
   209 PVDDQ_KLM @BASEBOARD_FAB2_LIB.BASEBOARD_FAB2(SCH_1):PVDDQ_KLM    I55 @BASEBOARD_FAB2_LIB.BASEBOARD_FAB2(SCH_1):PAGE86
   212 PVDDQ_KLM @BASEBOARD_FAB2_LIB.BASEBOARD_FAB2(SCH_1):PVDDQ_KLM    I55 @BASEBOARD_FAB2_LIB.BASEBOARD_FAB2(SCH_1):PAGE86
   215 PVDDQ_KLM @BASEBOARD_FAB2_LIB.BASEBOARD_FAB2(SCH_1):PVDDQ_KLM    I55 @BASEBOARD_FAB2_LIB.BASEBOARD_FAB2(SCH_1):PAGE86
   217 PVDDQ_KLM @BASEBOARD_FAB2_LIB.BASEBOARD_FAB2(SCH_1):PVDDQ_KLM    I55 @BASEBOARD_FAB2_LIB.BASEBOARD_FAB2(SCH_1):PAGE86
   220 PVDDQ_KLM @BASEBOARD_FAB2_LIB.BASEBOARD_FAB2(SCH_1):PVDDQ_KLM    I55 @BASEBOARD_FAB2_LIB.BASEBOARD_FAB2(SCH_1):PAGE86
   223 PVDDQ_KLM @BASEBOARD_FAB2_LIB.BASEBOARD_FAB2(SCH_1):PVDDQ_KLM    I55 @BASEBOARD_FAB2_LIB.BASEBOARD_FAB2(SCH_1):PAGE86
   226 PVDDQ_KLM @BASEBOARD_FAB2_LIB.BASEBOARD_FAB2(SCH_1):PVDDQ_KLM    I55 @BASEBOARD_FAB2_LIB.BASEBOARD_FAB2(SCH_1):PAGE86
   229 PVDDQ_KLM @BASEBOARD_FAB2_LIB.BASEBOARD_FAB2(SCH_1):PVDDQ_KLM    I55 @BASEBOARD_FAB2_LIB.BASEBOARD_FAB2(SCH_1):PAGE86
   231 PVDDQ_KLM @BASEBOARD_FAB2_LIB.BASEBOARD_FAB2(SCH_1):PVDDQ_KLM    I55 @BASEBOARD_FAB2_LIB.BASEBOARD_FAB2(SCH_1):PAGE86
   233 PVDDQ_KLM @BASEBOARD_FAB2_LIB.BASEBOARD_FAB2(SCH_1):PVDDQ_KLM    I55 @BASEBOARD_FAB2_LIB.BASEBOARD_FAB2(SCH_1):PAGE86
   236 PVDDQ_KLM @BASEBOARD_FAB2_LIB.BASEBOARD_FAB2(SCH_1):PVDDQ_KLM    I55 @BASEBOARD_FAB2_LIB.BASEBOARD_FAB2(SCH_1):PAGE86
   142 PVPP_KLM @BASEBOARD_FAB2_LIB.BASEBOARD_FAB2(SCH_1):PVPP_KLM    I55 @BASEBOARD_FAB2_LIB.BASEBOARD_FAB2(SCH_1):PAGE86
   143 PVPP_KLM @BASEBOARD_FAB2_LIB.BASEBOARD_FAB2(SCH_1):PVPP_KLM    I55 @BASEBOARD_FAB2_LIB.BASEBOARD_FAB2(SCH_1):PAGE86
   288 PVPP_KLM @BASEBOARD_FAB2_LIB.BASEBOARD_FAB2(SCH_1):PVPP_KLM    I55 @BASEBOARD_FAB2_LIB.BASEBOARD_FAB2(SCH_1):PAGE86
   286 PVPP_KLM @BASEBOARD_FAB2_LIB.BASEBOARD_FAB2(SCH_1):PVPP_KLM    I55 @BASEBOARD_FAB2_LIB.BASEBOARD_FAB2(SCH_1):PAGE86
   287 PVPP_KLM @BASEBOARD_FAB2_LIB.BASEBOARD_FAB2(SCH_1):PVPP_KLM    I55 @BASEBOARD_FAB2_LIB.BASEBOARD_FAB2(SCH_1):PAGE86
    77 PVTT_KLM @BASEBOARD_FAB2_LIB.BASEBOARD_FAB2(SCH_1):PVTT_KLM    I55 @BASEBOARD_FAB2_LIB.BASEBOARD_FAB2(SCH_1):PAGE86
   221 PVTT_KLM @BASEBOARD_FAB2_LIB.BASEBOARD_FAB2(SCH_1):PVTT_KLM    I55 @BASEBOARD_FAB2_LIB.BASEBOARD_FAB2(SCH_1):PAGE86

J9M1 SCONN288_H44441003_PIP-SCONN,HA
    79 M_K_MA<0> @BASEBOARD_FAB2_LIB.BASEBOARD_FAB2(SCH_1):M_K_MA(0)    I14 @BASEBOARD_FAB2_LIB.BASEBOARD_FAB2(SCH_1):PAGE84
    72 M_K_MA<1> @BASEBOARD_FAB2_LIB.BASEBOARD_FAB2(SCH_1):M_K_MA(1)    I14 @BASEBOARD_FAB2_LIB.BASEBOARD_FAB2(SCH_1):PAGE84
   225 M_K_MA<10> @BASEBOARD_FAB2_LIB.BASEBOARD_FAB2(SCH_1):M_K_MA(10)    I14 @BASEBOARD_FAB2_LIB.BASEBOARD_FAB2(SCH_1):PAGE84
   210 M_K_MA<11> @BASEBOARD_FAB2_LIB.BASEBOARD_FAB2(SCH_1):M_K_MA(11)    I14 @BASEBOARD_FAB2_LIB.BASEBOARD_FAB2(SCH_1):PAGE84
    65 M_K_MA<12> @BASEBOARD_FAB2_LIB.BASEBOARD_FAB2(SCH_1):M_K_MA(12)    I14 @BASEBOARD_FAB2_LIB.BASEBOARD_FAB2(SCH_1):PAGE84
   232 M_K_MA<13> @BASEBOARD_FAB2_LIB.BASEBOARD_FAB2(SCH_1):M_K_MA(13)    I14 @BASEBOARD_FAB2_LIB.BASEBOARD_FAB2(SCH_1):PAGE84
   228 M_K_MA<14> @BASEBOARD_FAB2_LIB.BASEBOARD_FAB2(SCH_1):M_K_MA(14)    I14 @BASEBOARD_FAB2_LIB.BASEBOARD_FAB2(SCH_1):PAGE84
    86 M_K_MA<15> @BASEBOARD_FAB2_LIB.BASEBOARD_FAB2(SCH_1):M_K_MA(15)    I14 @BASEBOARD_FAB2_LIB.BASEBOARD_FAB2(SCH_1):PAGE84
    82 M_K_MA<16> @BASEBOARD_FAB2_LIB.BASEBOARD_FAB2(SCH_1):M_K_MA(16)    I14 @BASEBOARD_FAB2_LIB.BASEBOARD_FAB2(SCH_1):PAGE84
   234 M_K_MA<17> @BASEBOARD_FAB2_LIB.BASEBOARD_FAB2(SCH_1):M_K_MA(17)    I14 @BASEBOARD_FAB2_LIB.BASEBOARD_FAB2(SCH_1):PAGE84
   216 M_K_MA<2> @BASEBOARD_FAB2_LIB.BASEBOARD_FAB2(SCH_1):M_K_MA(2)    I14 @BASEBOARD_FAB2_LIB.BASEBOARD_FAB2(SCH_1):PAGE84
    71 M_K_MA<3> @BASEBOARD_FAB2_LIB.BASEBOARD_FAB2(SCH_1):M_K_MA(3)    I14 @BASEBOARD_FAB2_LIB.BASEBOARD_FAB2(SCH_1):PAGE84
   214 M_K_MA<4> @BASEBOARD_FAB2_LIB.BASEBOARD_FAB2(SCH_1):M_K_MA(4)    I14 @BASEBOARD_FAB2_LIB.BASEBOARD_FAB2(SCH_1):PAGE84
   213 M_K_MA<5> @BASEBOARD_FAB2_LIB.BASEBOARD_FAB2(SCH_1):M_K_MA(5)    I14 @BASEBOARD_FAB2_LIB.BASEBOARD_FAB2(SCH_1):PAGE84
    69 M_K_MA<6> @BASEBOARD_FAB2_LIB.BASEBOARD_FAB2(SCH_1):M_K_MA(6)    I14 @BASEBOARD_FAB2_LIB.BASEBOARD_FAB2(SCH_1):PAGE84
   211 M_K_MA<7> @BASEBOARD_FAB2_LIB.BASEBOARD_FAB2(SCH_1):M_K_MA(7)    I14 @BASEBOARD_FAB2_LIB.BASEBOARD_FAB2(SCH_1):PAGE84
    68 M_K_MA<8> @BASEBOARD_FAB2_LIB.BASEBOARD_FAB2(SCH_1):M_K_MA(8)    I14 @BASEBOARD_FAB2_LIB.BASEBOARD_FAB2(SCH_1):PAGE84
    66 M_K_MA<9> @BASEBOARD_FAB2_LIB.BASEBOARD_FAB2(SCH_1):M_K_MA(9)    I14 @BASEBOARD_FAB2_LIB.BASEBOARD_FAB2(SCH_1):PAGE84
    62 M_K_ACT_N @BASEBOARD_FAB2_LIB.BASEBOARD_FAB2(SCH_1):M_K_ACT_N    I14 @BASEBOARD_FAB2_LIB.BASEBOARD_FAB2(SCH_1):PAGE84
   208 M_K_ALERT_N @BASEBOARD_FAB2_LIB.BASEBOARD_FAB2(SCH_1):M_K_ALERT_N    I14 @BASEBOARD_FAB2_LIB.BASEBOARD_FAB2(SCH_1):PAGE84
   224 M_K_BA<1> @BASEBOARD_FAB2_LIB.BASEBOARD_FAB2(SCH_1):M_K_BA(1)    I14 @BASEBOARD_FAB2_LIB.BASEBOARD_FAB2(SCH_1):PAGE84
    81 M_K_BA<0> @BASEBOARD_FAB2_LIB.BASEBOARD_FAB2(SCH_1):M_K_BA(0)    I14 @BASEBOARD_FAB2_LIB.BASEBOARD_FAB2(SCH_1):PAGE84
   207 M_K_BG<1> @BASEBOARD_FAB2_LIB.BASEBOARD_FAB2(SCH_1):M_K_BG(1)    I14 @BASEBOARD_FAB2_LIB.BASEBOARD_FAB2(SCH_1):PAGE84
    63 M_K_BG<0> @BASEBOARD_FAB2_LIB.BASEBOARD_FAB2(SCH_1):M_K_BG(0)    I14 @BASEBOARD_FAB2_LIB.BASEBOARD_FAB2(SCH_1):PAGE84
   235 M_K_C<2> @BASEBOARD_FAB2_LIB.BASEBOARD_FAB2(SCH_1):M_K_C(2)    I14 @BASEBOARD_FAB2_LIB.BASEBOARD_FAB2(SCH_1):PAGE84
   199 M_K_ECC<7> @BASEBOARD_FAB2_LIB.BASEBOARD_FAB2(SCH_1):M_K_ECC(7)    I14 @BASEBOARD_FAB2_LIB.BASEBOARD_FAB2(SCH_1):PAGE84
    54 M_K_ECC<6> @BASEBOARD_FAB2_LIB.BASEBOARD_FAB2(SCH_1):M_K_ECC(6)    I14 @BASEBOARD_FAB2_LIB.BASEBOARD_FAB2(SCH_1):PAGE84
   192 M_K_ECC<5> @BASEBOARD_FAB2_LIB.BASEBOARD_FAB2(SCH_1):M_K_ECC(5)    I14 @BASEBOARD_FAB2_LIB.BASEBOARD_FAB2(SCH_1):PAGE84
    47 M_K_ECC<4> @BASEBOARD_FAB2_LIB.BASEBOARD_FAB2(SCH_1):M_K_ECC(4)    I14 @BASEBOARD_FAB2_LIB.BASEBOARD_FAB2(SCH_1):PAGE84
   201 M_K_ECC<3> @BASEBOARD_FAB2_LIB.BASEBOARD_FAB2(SCH_1):M_K_ECC(3)    I14 @BASEBOARD_FAB2_LIB.BASEBOARD_FAB2(SCH_1):PAGE84
    56 M_K_ECC<2> @BASEBOARD_FAB2_LIB.BASEBOARD_FAB2(SCH_1):M_K_ECC(2)    I14 @BASEBOARD_FAB2_LIB.BASEBOARD_FAB2(SCH_1):PAGE84
   194 M_K_ECC<1> @BASEBOARD_FAB2_LIB.BASEBOARD_FAB2(SCH_1):M_K_ECC(1)    I14 @BASEBOARD_FAB2_LIB.BASEBOARD_FAB2(SCH_1):PAGE84
    49 M_K_ECC<0> @BASEBOARD_FAB2_LIB.BASEBOARD_FAB2(SCH_1):M_K_ECC(0)    I14 @BASEBOARD_FAB2_LIB.BASEBOARD_FAB2(SCH_1):PAGE84
    75 M_K_CLK_DN<2> @BASEBOARD_FAB2_LIB.BASEBOARD_FAB2(SCH_1):M_K_CLK_DN(2)    I14 @BASEBOARD_FAB2_LIB.BASEBOARD_FAB2(SCH_1):PAGE84
    74 M_K_CLK_DP<2> @BASEBOARD_FAB2_LIB.BASEBOARD_FAB2(SCH_1):M_K_CLK_DP(2)    I14 @BASEBOARD_FAB2_LIB.BASEBOARD_FAB2(SCH_1):PAGE84
   219 M_K_CLK_DN<3> @BASEBOARD_FAB2_LIB.BASEBOARD_FAB2(SCH_1):M_K_CLK_DN(3)    I14 @BASEBOARD_FAB2_LIB.BASEBOARD_FAB2(SCH_1):PAGE84
   218 M_K_CLK_DP<3> @BASEBOARD_FAB2_LIB.BASEBOARD_FAB2(SCH_1):M_K_CLK_DP(3)    I14 @BASEBOARD_FAB2_LIB.BASEBOARD_FAB2(SCH_1):PAGE84
   203 M_K_CKE<3> @BASEBOARD_FAB2_LIB.BASEBOARD_FAB2(SCH_1):M_K_CKE(3)    I14 @BASEBOARD_FAB2_LIB.BASEBOARD_FAB2(SCH_1):PAGE84
    60 M_K_CKE<2> @BASEBOARD_FAB2_LIB.BASEBOARD_FAB2(SCH_1):M_K_CKE(2)    I14 @BASEBOARD_FAB2_LIB.BASEBOARD_FAB2(SCH_1):PAGE84
   280 M_K_DQ<63> @BASEBOARD_FAB2_LIB.BASEBOARD_FAB2(SCH_1):M_K_DQ(63)    I14 @BASEBOARD_FAB2_LIB.BASEBOARD_FAB2(SCH_1):PAGE84
   135 M_K_DQ<62> @BASEBOARD_FAB2_LIB.BASEBOARD_FAB2(SCH_1):M_K_DQ(62)    I14 @BASEBOARD_FAB2_LIB.BASEBOARD_FAB2(SCH_1):PAGE84
   273 M_K_DQ<61> @BASEBOARD_FAB2_LIB.BASEBOARD_FAB2(SCH_1):M_K_DQ(61)    I14 @BASEBOARD_FAB2_LIB.BASEBOARD_FAB2(SCH_1):PAGE84
   128 M_K_DQ<60> @BASEBOARD_FAB2_LIB.BASEBOARD_FAB2(SCH_1):M_K_DQ(60)    I14 @BASEBOARD_FAB2_LIB.BASEBOARD_FAB2(SCH_1):PAGE84
   282 M_K_DQ<59> @BASEBOARD_FAB2_LIB.BASEBOARD_FAB2(SCH_1):M_K_DQ(59)    I14 @BASEBOARD_FAB2_LIB.BASEBOARD_FAB2(SCH_1):PAGE84
   137 M_K_DQ<58> @BASEBOARD_FAB2_LIB.BASEBOARD_FAB2(SCH_1):M_K_DQ(58)    I14 @BASEBOARD_FAB2_LIB.BASEBOARD_FAB2(SCH_1):PAGE84
   275 M_K_DQ<57> @BASEBOARD_FAB2_LIB.BASEBOARD_FAB2(SCH_1):M_K_DQ(57)    I14 @BASEBOARD_FAB2_LIB.BASEBOARD_FAB2(SCH_1):PAGE84
   130 M_K_DQ<56> @BASEBOARD_FAB2_LIB.BASEBOARD_FAB2(SCH_1):M_K_DQ(56)    I14 @BASEBOARD_FAB2_LIB.BASEBOARD_FAB2(SCH_1):PAGE84
   269 M_K_DQ<55> @BASEBOARD_FAB2_LIB.BASEBOARD_FAB2(SCH_1):M_K_DQ(55)    I14 @BASEBOARD_FAB2_LIB.BASEBOARD_FAB2(SCH_1):PAGE84
   124 M_K_DQ<54> @BASEBOARD_FAB2_LIB.BASEBOARD_FAB2(SCH_1):M_K_DQ(54)    I14 @BASEBOARD_FAB2_LIB.BASEBOARD_FAB2(SCH_1):PAGE84
   262 M_K_DQ<53> @BASEBOARD_FAB2_LIB.BASEBOARD_FAB2(SCH_1):M_K_DQ(53)    I14 @BASEBOARD_FAB2_LIB.BASEBOARD_FAB2(SCH_1):PAGE84
   117 M_K_DQ<52> @BASEBOARD_FAB2_LIB.BASEBOARD_FAB2(SCH_1):M_K_DQ(52)    I14 @BASEBOARD_FAB2_LIB.BASEBOARD_FAB2(SCH_1):PAGE84
   271 M_K_DQ<51> @BASEBOARD_FAB2_LIB.BASEBOARD_FAB2(SCH_1):M_K_DQ(51)    I14 @BASEBOARD_FAB2_LIB.BASEBOARD_FAB2(SCH_1):PAGE84
   126 M_K_DQ<50> @BASEBOARD_FAB2_LIB.BASEBOARD_FAB2(SCH_1):M_K_DQ(50)    I14 @BASEBOARD_FAB2_LIB.BASEBOARD_FAB2(SCH_1):PAGE84
   264 M_K_DQ<49> @BASEBOARD_FAB2_LIB.BASEBOARD_FAB2(SCH_1):M_K_DQ(49)    I14 @BASEBOARD_FAB2_LIB.BASEBOARD_FAB2(SCH_1):PAGE84
   119 M_K_DQ<48> @BASEBOARD_FAB2_LIB.BASEBOARD_FAB2(SCH_1):M_K_DQ(48)    I14 @BASEBOARD_FAB2_LIB.BASEBOARD_FAB2(SCH_1):PAGE84
   258 M_K_DQ<47> @BASEBOARD_FAB2_LIB.BASEBOARD_FAB2(SCH_1):M_K_DQ(47)    I14 @BASEBOARD_FAB2_LIB.BASEBOARD_FAB2(SCH_1):PAGE84
   113 M_K_DQ<46> @BASEBOARD_FAB2_LIB.BASEBOARD_FAB2(SCH_1):M_K_DQ(46)    I14 @BASEBOARD_FAB2_LIB.BASEBOARD_FAB2(SCH_1):PAGE84
   251 M_K_DQ<45> @BASEBOARD_FAB2_LIB.BASEBOARD_FAB2(SCH_1):M_K_DQ(45)    I14 @BASEBOARD_FAB2_LIB.BASEBOARD_FAB2(SCH_1):PAGE84
   106 M_K_DQ<44> @BASEBOARD_FAB2_LIB.BASEBOARD_FAB2(SCH_1):M_K_DQ(44)    I14 @BASEBOARD_FAB2_LIB.BASEBOARD_FAB2(SCH_1):PAGE84
   260 M_K_DQ<43> @BASEBOARD_FAB2_LIB.BASEBOARD_FAB2(SCH_1):M_K_DQ(43)    I14 @BASEBOARD_FAB2_LIB.BASEBOARD_FAB2(SCH_1):PAGE84
   115 M_K_DQ<42> @BASEBOARD_FAB2_LIB.BASEBOARD_FAB2(SCH_1):M_K_DQ(42)    I14 @BASEBOARD_FAB2_LIB.BASEBOARD_FAB2(SCH_1):PAGE84
   253 M_K_DQ<41> @BASEBOARD_FAB2_LIB.BASEBOARD_FAB2(SCH_1):M_K_DQ(41)    I14 @BASEBOARD_FAB2_LIB.BASEBOARD_FAB2(SCH_1):PAGE84
   108 M_K_DQ<40> @BASEBOARD_FAB2_LIB.BASEBOARD_FAB2(SCH_1):M_K_DQ(40)    I14 @BASEBOARD_FAB2_LIB.BASEBOARD_FAB2(SCH_1):PAGE84
   247 M_K_DQ<39> @BASEBOARD_FAB2_LIB.BASEBOARD_FAB2(SCH_1):M_K_DQ(39)    I14 @BASEBOARD_FAB2_LIB.BASEBOARD_FAB2(SCH_1):PAGE84
   102 M_K_DQ<38> @BASEBOARD_FAB2_LIB.BASEBOARD_FAB2(SCH_1):M_K_DQ(38)    I14 @BASEBOARD_FAB2_LIB.BASEBOARD_FAB2(SCH_1):PAGE84
   240 M_K_DQ<37> @BASEBOARD_FAB2_LIB.BASEBOARD_FAB2(SCH_1):M_K_DQ(37)    I14 @BASEBOARD_FAB2_LIB.BASEBOARD_FAB2(SCH_1):PAGE84
    95 M_K_DQ<36> @BASEBOARD_FAB2_LIB.BASEBOARD_FAB2(SCH_1):M_K_DQ(36)    I14 @BASEBOARD_FAB2_LIB.BASEBOARD_FAB2(SCH_1):PAGE84
   249 M_K_DQ<35> @BASEBOARD_FAB2_LIB.BASEBOARD_FAB2(SCH_1):M_K_DQ(35)    I14 @BASEBOARD_FAB2_LIB.BASEBOARD_FAB2(SCH_1):PAGE84
   104 M_K_DQ<34> @BASEBOARD_FAB2_LIB.BASEBOARD_FAB2(SCH_1):M_K_DQ(34)    I14 @BASEBOARD_FAB2_LIB.BASEBOARD_FAB2(SCH_1):PAGE84
   242 M_K_DQ<33> @BASEBOARD_FAB2_LIB.BASEBOARD_FAB2(SCH_1):M_K_DQ(33)    I14 @BASEBOARD_FAB2_LIB.BASEBOARD_FAB2(SCH_1):PAGE84
    97 M_K_DQ<32> @BASEBOARD_FAB2_LIB.BASEBOARD_FAB2(SCH_1):M_K_DQ(32)    I14 @BASEBOARD_FAB2_LIB.BASEBOARD_FAB2(SCH_1):PAGE84
   188 M_K_DQ<31> @BASEBOARD_FAB2_LIB.BASEBOARD_FAB2(SCH_1):M_K_DQ(31)    I14 @BASEBOARD_FAB2_LIB.BASEBOARD_FAB2(SCH_1):PAGE84
    43 M_K_DQ<30> @BASEBOARD_FAB2_LIB.BASEBOARD_FAB2(SCH_1):M_K_DQ(30)    I14 @BASEBOARD_FAB2_LIB.BASEBOARD_FAB2(SCH_1):PAGE84
   181 M_K_DQ<29> @BASEBOARD_FAB2_LIB.BASEBOARD_FAB2(SCH_1):M_K_DQ(29)    I14 @BASEBOARD_FAB2_LIB.BASEBOARD_FAB2(SCH_1):PAGE84
    36 M_K_DQ<28> @BASEBOARD_FAB2_LIB.BASEBOARD_FAB2(SCH_1):M_K_DQ(28)    I14 @BASEBOARD_FAB2_LIB.BASEBOARD_FAB2(SCH_1):PAGE84
   190 M_K_DQ<27> @BASEBOARD_FAB2_LIB.BASEBOARD_FAB2(SCH_1):M_K_DQ(27)    I14 @BASEBOARD_FAB2_LIB.BASEBOARD_FAB2(SCH_1):PAGE84
    45 M_K_DQ<26> @BASEBOARD_FAB2_LIB.BASEBOARD_FAB2(SCH_1):M_K_DQ(26)    I14 @BASEBOARD_FAB2_LIB.BASEBOARD_FAB2(SCH_1):PAGE84
   183 M_K_DQ<25> @BASEBOARD_FAB2_LIB.BASEBOARD_FAB2(SCH_1):M_K_DQ(25)    I14 @BASEBOARD_FAB2_LIB.BASEBOARD_FAB2(SCH_1):PAGE84
    38 M_K_DQ<24> @BASEBOARD_FAB2_LIB.BASEBOARD_FAB2(SCH_1):M_K_DQ(24)    I14 @BASEBOARD_FAB2_LIB.BASEBOARD_FAB2(SCH_1):PAGE84
   177 M_K_DQ<23> @BASEBOARD_FAB2_LIB.BASEBOARD_FAB2(SCH_1):M_K_DQ(23)    I14 @BASEBOARD_FAB2_LIB.BASEBOARD_FAB2(SCH_1):PAGE84
    32 M_K_DQ<22> @BASEBOARD_FAB2_LIB.BASEBOARD_FAB2(SCH_1):M_K_DQ(22)    I14 @BASEBOARD_FAB2_LIB.BASEBOARD_FAB2(SCH_1):PAGE84
   170 M_K_DQ<21> @BASEBOARD_FAB2_LIB.BASEBOARD_FAB2(SCH_1):M_K_DQ(21)    I14 @BASEBOARD_FAB2_LIB.BASEBOARD_FAB2(SCH_1):PAGE84
    25 M_K_DQ<20> @BASEBOARD_FAB2_LIB.BASEBOARD_FAB2(SCH_1):M_K_DQ(20)    I14 @BASEBOARD_FAB2_LIB.BASEBOARD_FAB2(SCH_1):PAGE84
   179 M_K_DQ<19> @BASEBOARD_FAB2_LIB.BASEBOARD_FAB2(SCH_1):M_K_DQ(19)    I14 @BASEBOARD_FAB2_LIB.BASEBOARD_FAB2(SCH_1):PAGE84
    34 M_K_DQ<18> @BASEBOARD_FAB2_LIB.BASEBOARD_FAB2(SCH_1):M_K_DQ(18)    I14 @BASEBOARD_FAB2_LIB.BASEBOARD_FAB2(SCH_1):PAGE84
   172 M_K_DQ<17> @BASEBOARD_FAB2_LIB.BASEBOARD_FAB2(SCH_1):M_K_DQ(17)    I14 @BASEBOARD_FAB2_LIB.BASEBOARD_FAB2(SCH_1):PAGE84
    27 M_K_DQ<16> @BASEBOARD_FAB2_LIB.BASEBOARD_FAB2(SCH_1):M_K_DQ(16)    I14 @BASEBOARD_FAB2_LIB.BASEBOARD_FAB2(SCH_1):PAGE84
   166 M_K_DQ<15> @BASEBOARD_FAB2_LIB.BASEBOARD_FAB2(SCH_1):M_K_DQ(15)    I14 @BASEBOARD_FAB2_LIB.BASEBOARD_FAB2(SCH_1):PAGE84
    21 M_K_DQ<14> @BASEBOARD_FAB2_LIB.BASEBOARD_FAB2(SCH_1):M_K_DQ(14)    I14 @BASEBOARD_FAB2_LIB.BASEBOARD_FAB2(SCH_1):PAGE84
   159 M_K_DQ<13> @BASEBOARD_FAB2_LIB.BASEBOARD_FAB2(SCH_1):M_K_DQ(13)    I14 @BASEBOARD_FAB2_LIB.BASEBOARD_FAB2(SCH_1):PAGE84
    14 M_K_DQ<12> @BASEBOARD_FAB2_LIB.BASEBOARD_FAB2(SCH_1):M_K_DQ(12)    I14 @BASEBOARD_FAB2_LIB.BASEBOARD_FAB2(SCH_1):PAGE84
   168 M_K_DQ<11> @BASEBOARD_FAB2_LIB.BASEBOARD_FAB2(SCH_1):M_K_DQ(11)    I14 @BASEBOARD_FAB2_LIB.BASEBOARD_FAB2(SCH_1):PAGE84
    23 M_K_DQ<10> @BASEBOARD_FAB2_LIB.BASEBOARD_FAB2(SCH_1):M_K_DQ(10)    I14 @BASEBOARD_FAB2_LIB.BASEBOARD_FAB2(SCH_1):PAGE84
   161 M_K_DQ<9> @BASEBOARD_FAB2_LIB.BASEBOARD_FAB2(SCH_1):M_K_DQ(9)    I14 @BASEBOARD_FAB2_LIB.BASEBOARD_FAB2(SCH_1):PAGE84
    16 M_K_DQ<8> @BASEBOARD_FAB2_LIB.BASEBOARD_FAB2(SCH_1):M_K_DQ(8)    I14 @BASEBOARD_FAB2_LIB.BASEBOARD_FAB2(SCH_1):PAGE84
   155 M_K_DQ<7> @BASEBOARD_FAB2_LIB.BASEBOARD_FAB2(SCH_1):M_K_DQ(7)    I14 @BASEBOARD_FAB2_LIB.BASEBOARD_FAB2(SCH_1):PAGE84
    10 M_K_DQ<6> @BASEBOARD_FAB2_LIB.BASEBOARD_FAB2(SCH_1):M_K_DQ(6)    I14 @BASEBOARD_FAB2_LIB.BASEBOARD_FAB2(SCH_1):PAGE84
   148 M_K_DQ<5> @BASEBOARD_FAB2_LIB.BASEBOARD_FAB2(SCH_1):M_K_DQ(5)    I14 @BASEBOARD_FAB2_LIB.BASEBOARD_FAB2(SCH_1):PAGE84
     3 M_K_DQ<4> @BASEBOARD_FAB2_LIB.BASEBOARD_FAB2(SCH_1):M_K_DQ(4)    I14 @BASEBOARD_FAB2_LIB.BASEBOARD_FAB2(SCH_1):PAGE84
   157 M_K_DQ<3> @BASEBOARD_FAB2_LIB.BASEBOARD_FAB2(SCH_1):M_K_DQ(3)    I14 @BASEBOARD_FAB2_LIB.BASEBOARD_FAB2(SCH_1):PAGE84
    12 M_K_DQ<2> @BASEBOARD_FAB2_LIB.BASEBOARD_FAB2(SCH_1):M_K_DQ(2)    I14 @BASEBOARD_FAB2_LIB.BASEBOARD_FAB2(SCH_1):PAGE84
   150 M_K_DQ<1> @BASEBOARD_FAB2_LIB.BASEBOARD_FAB2(SCH_1):M_K_DQ(1)    I14 @BASEBOARD_FAB2_LIB.BASEBOARD_FAB2(SCH_1):PAGE84
     5 M_K_DQ<0> @BASEBOARD_FAB2_LIB.BASEBOARD_FAB2(SCH_1):M_K_DQ(0)    I14 @BASEBOARD_FAB2_LIB.BASEBOARD_FAB2(SCH_1):PAGE84
    78 FM_DIMM_EVENT_COD_N @BASEBOARD_FAB2_LIB.BASEBOARD_FAB2(SCH_1):FM_DIMM_EVENT_COD_N    I14 @BASEBOARD_FAB2_LIB.BASEBOARD_FAB2(SCH_1):PAGE84
    91 M_K_ODT<3> @BASEBOARD_FAB2_LIB.BASEBOARD_FAB2(SCH_1):M_K_ODT(3)    I14 @BASEBOARD_FAB2_LIB.BASEBOARD_FAB2(SCH_1):PAGE84
    87 M_K_ODT<2> @BASEBOARD_FAB2_LIB.BASEBOARD_FAB2(SCH_1):M_K_ODT(2)    I14 @BASEBOARD_FAB2_LIB.BASEBOARD_FAB2(SCH_1):PAGE84
   222 M_K_PAR @BASEBOARD_FAB2_LIB.BASEBOARD_FAB2(SCH_1):M_K_PAR    I14 @BASEBOARD_FAB2_LIB.BASEBOARD_FAB2(SCH_1):PAGE84
    58 M_KLM_RST_N @BASEBOARD_FAB2_LIB.BASEBOARD_FAB2(SCH_1):M_KLM_RST_N    I14 @BASEBOARD_FAB2_LIB.BASEBOARD_FAB2(SCH_1):PAGE84
   144 TP_CH_K_DIMM0_RFU_2 @BASEBOARD_FAB2_LIB.BASEBOARD_FAB2(SCH_1):TP_CH_K_DIMM0_RFU_2    I14 @BASEBOARD_FAB2_LIB.BASEBOARD_FAB2(SCH_1):PAGE84
   227 TP_CH_K_DIMM0_RFU_1 @BASEBOARD_FAB2_LIB.BASEBOARD_FAB2(SCH_1):TP_CH_K_DIMM0_RFU_1    I14 @BASEBOARD_FAB2_LIB.BASEBOARD_FAB2(SCH_1):PAGE84
   205 TP_CH_K_DIMM0_RFU_0 @BASEBOARD_FAB2_LIB.BASEBOARD_FAB2(SCH_1):TP_CH_K_DIMM0_RFU_0    I14 @BASEBOARD_FAB2_LIB.BASEBOARD_FAB2(SCH_1):PAGE84
    84 M_K_CS_N<4> @BASEBOARD_FAB2_LIB.BASEBOARD_FAB2(SCH_1):M_K_CS_N(4)    I14 @BASEBOARD_FAB2_LIB.BASEBOARD_FAB2(SCH_1):PAGE84
    89 M_K_CS_N<5> @BASEBOARD_FAB2_LIB.BASEBOARD_FAB2(SCH_1):M_K_CS_N(5)    I14 @BASEBOARD_FAB2_LIB.BASEBOARD_FAB2(SCH_1):PAGE84
    93 M_K_CS_N<6> @BASEBOARD_FAB2_LIB.BASEBOARD_FAB2(SCH_1):M_K_CS_N(6)    I14 @BASEBOARD_FAB2_LIB.BASEBOARD_FAB2(SCH_1):PAGE84
   237 M_K_CS_N<7> @BASEBOARD_FAB2_LIB.BASEBOARD_FAB2(SCH_1):M_K_CS_N(7)    I14 @BASEBOARD_FAB2_LIB.BASEBOARD_FAB2(SCH_1):PAGE84
   238    GND @BASEBOARD_FAB2_LIB.BASEBOARD_FAB2(SCH_1):GND    I14 @BASEBOARD_FAB2_LIB.BASEBOARD_FAB2(SCH_1):PAGE84
   140    GND @BASEBOARD_FAB2_LIB.BASEBOARD_FAB2(SCH_1):GND    I14 @BASEBOARD_FAB2_LIB.BASEBOARD_FAB2(SCH_1):PAGE84
   139 PVPP_KLM @BASEBOARD_FAB2_LIB.BASEBOARD_FAB2(SCH_1):PVPP_KLM    I14 @BASEBOARD_FAB2_LIB.BASEBOARD_FAB2(SCH_1):PAGE84
   230 FM_ADR_COMPLETE_KLM_N @BASEBOARD_FAB2_LIB.BASEBOARD_FAB2(SCH_1):FM_ADR_COMPLETE_KLM_N    I14 @BASEBOARD_FAB2_LIB.BASEBOARD_FAB2(SCH_1):PAGE84
   141 SMB_DDR_KLM_VPP_SCL @BASEBOARD_FAB2_LIB.BASEBOARD_FAB2(SCH_1):SMB_DDR_KLM_VPP_SCL    I14 @BASEBOARD_FAB2_LIB.BASEBOARD_FAB2(SCH_1):PAGE84
   285 SMB_DDR_KLM_VPP_SDA @BASEBOARD_FAB2_LIB.BASEBOARD_FAB2(SCH_1):SMB_DDR_KLM_VPP_SDA    I14 @BASEBOARD_FAB2_LIB.BASEBOARD_FAB2(SCH_1):PAGE84
   284 PVPP_KLM @BASEBOARD_FAB2_LIB.BASEBOARD_FAB2(SCH_1):PVPP_KLM    I14 @BASEBOARD_FAB2_LIB.BASEBOARD_FAB2(SCH_1):PAGE84
   146 M_K_VREF @BASEBOARD_FAB2_LIB.BASEBOARD_FAB2(SCH_1):M_K_VREF    I14 @BASEBOARD_FAB2_LIB.BASEBOARD_FAB2(SCH_1):PAGE84
   152 M_K_DQS_DN<0> @BASEBOARD_FAB2_LIB.BASEBOARD_FAB2(SCH_1):M_K_DQS_DN(0)   I102 @BASEBOARD_FAB2_LIB.BASEBOARD_FAB2(SCH_1):PAGE84
   153 M_K_DQS_DP<0> @BASEBOARD_FAB2_LIB.BASEBOARD_FAB2(SCH_1):M_K_DQS_DP(0)   I102 @BASEBOARD_FAB2_LIB.BASEBOARD_FAB2(SCH_1):PAGE84
    19 M_K_DQS_DN<10> @BASEBOARD_FAB2_LIB.BASEBOARD_FAB2(SCH_1):M_K_DQS_DN(10)   I102 @BASEBOARD_FAB2_LIB.BASEBOARD_FAB2(SCH_1):PAGE84
    18 M_K_DQS_DP<10> @BASEBOARD_FAB2_LIB.BASEBOARD_FAB2(SCH_1):M_K_DQS_DP(10)   I102 @BASEBOARD_FAB2_LIB.BASEBOARD_FAB2(SCH_1):PAGE84
    30 M_K_DQS_DN<11> @BASEBOARD_FAB2_LIB.BASEBOARD_FAB2(SCH_1):M_K_DQS_DN(11)   I102 @BASEBOARD_FAB2_LIB.BASEBOARD_FAB2(SCH_1):PAGE84
    29 M_K_DQS_DP<11> @BASEBOARD_FAB2_LIB.BASEBOARD_FAB2(SCH_1):M_K_DQS_DP(11)   I102 @BASEBOARD_FAB2_LIB.BASEBOARD_FAB2(SCH_1):PAGE84
    41 M_K_DQS_DN<12> @BASEBOARD_FAB2_LIB.BASEBOARD_FAB2(SCH_1):M_K_DQS_DN(12)   I102 @BASEBOARD_FAB2_LIB.BASEBOARD_FAB2(SCH_1):PAGE84
    40 M_K_DQS_DP<12> @BASEBOARD_FAB2_LIB.BASEBOARD_FAB2(SCH_1):M_K_DQS_DP(12)   I102 @BASEBOARD_FAB2_LIB.BASEBOARD_FAB2(SCH_1):PAGE84
   100 M_K_DQS_DN<13> @BASEBOARD_FAB2_LIB.BASEBOARD_FAB2(SCH_1):M_K_DQS_DN(13)   I102 @BASEBOARD_FAB2_LIB.BASEBOARD_FAB2(SCH_1):PAGE84
    99 M_K_DQS_DP<13> @BASEBOARD_FAB2_LIB.BASEBOARD_FAB2(SCH_1):M_K_DQS_DP(13)   I102 @BASEBOARD_FAB2_LIB.BASEBOARD_FAB2(SCH_1):PAGE84
   111 M_K_DQS_DN<14> @BASEBOARD_FAB2_LIB.BASEBOARD_FAB2(SCH_1):M_K_DQS_DN(14)   I102 @BASEBOARD_FAB2_LIB.BASEBOARD_FAB2(SCH_1):PAGE84
   110 M_K_DQS_DP<14> @BASEBOARD_FAB2_LIB.BASEBOARD_FAB2(SCH_1):M_K_DQS_DP(14)   I102 @BASEBOARD_FAB2_LIB.BASEBOARD_FAB2(SCH_1):PAGE84
   122 M_K_DQS_DN<15> @BASEBOARD_FAB2_LIB.BASEBOARD_FAB2(SCH_1):M_K_DQS_DN(15)   I102 @BASEBOARD_FAB2_LIB.BASEBOARD_FAB2(SCH_1):PAGE84
   121 M_K_DQS_DP<15> @BASEBOARD_FAB2_LIB.BASEBOARD_FAB2(SCH_1):M_K_DQS_DP(15)   I102 @BASEBOARD_FAB2_LIB.BASEBOARD_FAB2(SCH_1):PAGE84
   133 M_K_DQS_DN<16> @BASEBOARD_FAB2_LIB.BASEBOARD_FAB2(SCH_1):M_K_DQS_DN(16)   I102 @BASEBOARD_FAB2_LIB.BASEBOARD_FAB2(SCH_1):PAGE84
   132 M_K_DQS_DP<16> @BASEBOARD_FAB2_LIB.BASEBOARD_FAB2(SCH_1):M_K_DQS_DP(16)   I102 @BASEBOARD_FAB2_LIB.BASEBOARD_FAB2(SCH_1):PAGE84
    52 M_K_DQS_DN<17> @BASEBOARD_FAB2_LIB.BASEBOARD_FAB2(SCH_1):M_K_DQS_DN(17)   I102 @BASEBOARD_FAB2_LIB.BASEBOARD_FAB2(SCH_1):PAGE84
    51 M_K_DQS_DP<17> @BASEBOARD_FAB2_LIB.BASEBOARD_FAB2(SCH_1):M_K_DQS_DP(17)   I102 @BASEBOARD_FAB2_LIB.BASEBOARD_FAB2(SCH_1):PAGE84
   163 M_K_DQS_DN<1> @BASEBOARD_FAB2_LIB.BASEBOARD_FAB2(SCH_1):M_K_DQS_DN(1)   I102 @BASEBOARD_FAB2_LIB.BASEBOARD_FAB2(SCH_1):PAGE84
   164 M_K_DQS_DP<1> @BASEBOARD_FAB2_LIB.BASEBOARD_FAB2(SCH_1):M_K_DQS_DP(1)   I102 @BASEBOARD_FAB2_LIB.BASEBOARD_FAB2(SCH_1):PAGE84
   174 M_K_DQS_DN<2> @BASEBOARD_FAB2_LIB.BASEBOARD_FAB2(SCH_1):M_K_DQS_DN(2)   I102 @BASEBOARD_FAB2_LIB.BASEBOARD_FAB2(SCH_1):PAGE84
   175 M_K_DQS_DP<2> @BASEBOARD_FAB2_LIB.BASEBOARD_FAB2(SCH_1):M_K_DQS_DP(2)   I102 @BASEBOARD_FAB2_LIB.BASEBOARD_FAB2(SCH_1):PAGE84
   185 M_K_DQS_DN<3> @BASEBOARD_FAB2_LIB.BASEBOARD_FAB2(SCH_1):M_K_DQS_DN(3)   I102 @BASEBOARD_FAB2_LIB.BASEBOARD_FAB2(SCH_1):PAGE84
   186 M_K_DQS_DP<3> @BASEBOARD_FAB2_LIB.BASEBOARD_FAB2(SCH_1):M_K_DQS_DP(3)   I102 @BASEBOARD_FAB2_LIB.BASEBOARD_FAB2(SCH_1):PAGE84
   244 M_K_DQS_DN<4> @BASEBOARD_FAB2_LIB.BASEBOARD_FAB2(SCH_1):M_K_DQS_DN(4)   I102 @BASEBOARD_FAB2_LIB.BASEBOARD_FAB2(SCH_1):PAGE84
   245 M_K_DQS_DP<4> @BASEBOARD_FAB2_LIB.BASEBOARD_FAB2(SCH_1):M_K_DQS_DP(4)   I102 @BASEBOARD_FAB2_LIB.BASEBOARD_FAB2(SCH_1):PAGE84
   255 M_K_DQS_DN<5> @BASEBOARD_FAB2_LIB.BASEBOARD_FAB2(SCH_1):M_K_DQS_DN(5)   I102 @BASEBOARD_FAB2_LIB.BASEBOARD_FAB2(SCH_1):PAGE84
   256 M_K_DQS_DP<5> @BASEBOARD_FAB2_LIB.BASEBOARD_FAB2(SCH_1):M_K_DQS_DP(5)   I102 @BASEBOARD_FAB2_LIB.BASEBOARD_FAB2(SCH_1):PAGE84
   266 M_K_DQS_DN<6> @BASEBOARD_FAB2_LIB.BASEBOARD_FAB2(SCH_1):M_K_DQS_DN(6)   I102 @BASEBOARD_FAB2_LIB.BASEBOARD_FAB2(SCH_1):PAGE84
   267 M_K_DQS_DP<6> @BASEBOARD_FAB2_LIB.BASEBOARD_FAB2(SCH_1):M_K_DQS_DP(6)   I102 @BASEBOARD_FAB2_LIB.BASEBOARD_FAB2(SCH_1):PAGE84
   277 M_K_DQS_DN<7> @BASEBOARD_FAB2_LIB.BASEBOARD_FAB2(SCH_1):M_K_DQS_DN(7)   I102 @BASEBOARD_FAB2_LIB.BASEBOARD_FAB2(SCH_1):PAGE84
   278 M_K_DQS_DP<7> @BASEBOARD_FAB2_LIB.BASEBOARD_FAB2(SCH_1):M_K_DQS_DP(7)   I102 @BASEBOARD_FAB2_LIB.BASEBOARD_FAB2(SCH_1):PAGE84
   196 M_K_DQS_DN<8> @BASEBOARD_FAB2_LIB.BASEBOARD_FAB2(SCH_1):M_K_DQS_DN(8)   I102 @BASEBOARD_FAB2_LIB.BASEBOARD_FAB2(SCH_1):PAGE84
   197 M_K_DQS_DP<8> @BASEBOARD_FAB2_LIB.BASEBOARD_FAB2(SCH_1):M_K_DQS_DP(8)   I102 @BASEBOARD_FAB2_LIB.BASEBOARD_FAB2(SCH_1):PAGE84
     8 M_K_DQS_DN<9> @BASEBOARD_FAB2_LIB.BASEBOARD_FAB2(SCH_1):M_K_DQS_DN(9)   I102 @BASEBOARD_FAB2_LIB.BASEBOARD_FAB2(SCH_1):PAGE84
     7 M_K_DQS_DP<9> @BASEBOARD_FAB2_LIB.BASEBOARD_FAB2(SCH_1):M_K_DQS_DP(9)   I102 @BASEBOARD_FAB2_LIB.BASEBOARD_FAB2(SCH_1):PAGE84
     2    GND @BASEBOARD_FAB2_LIB.BASEBOARD_FAB2(SCH_1):GND   I138 @BASEBOARD_FAB2_LIB.BASEBOARD_FAB2(SCH_1):PAGE84
     4    GND @BASEBOARD_FAB2_LIB.BASEBOARD_FAB2(SCH_1):GND   I138 @BASEBOARD_FAB2_LIB.BASEBOARD_FAB2(SCH_1):PAGE84
     6    GND @BASEBOARD_FAB2_LIB.BASEBOARD_FAB2(SCH_1):GND   I138 @BASEBOARD_FAB2_LIB.BASEBOARD_FAB2(SCH_1):PAGE84
     9    GND @BASEBOARD_FAB2_LIB.BASEBOARD_FAB2(SCH_1):GND   I138 @BASEBOARD_FAB2_LIB.BASEBOARD_FAB2(SCH_1):PAGE84
    11    GND @BASEBOARD_FAB2_LIB.BASEBOARD_FAB2(SCH_1):GND   I138 @BASEBOARD_FAB2_LIB.BASEBOARD_FAB2(SCH_1):PAGE84
    13    GND @BASEBOARD_FAB2_LIB.BASEBOARD_FAB2(SCH_1):GND   I138 @BASEBOARD_FAB2_LIB.BASEBOARD_FAB2(SCH_1):PAGE84
    15    GND @BASEBOARD_FAB2_LIB.BASEBOARD_FAB2(SCH_1):GND   I138 @BASEBOARD_FAB2_LIB.BASEBOARD_FAB2(SCH_1):PAGE84
    17    GND @BASEBOARD_FAB2_LIB.BASEBOARD_FAB2(SCH_1):GND   I138 @BASEBOARD_FAB2_LIB.BASEBOARD_FAB2(SCH_1):PAGE84
    20    GND @BASEBOARD_FAB2_LIB.BASEBOARD_FAB2(SCH_1):GND   I138 @BASEBOARD_FAB2_LIB.BASEBOARD_FAB2(SCH_1):PAGE84
    22    GND @BASEBOARD_FAB2_LIB.BASEBOARD_FAB2(SCH_1):GND   I138 @BASEBOARD_FAB2_LIB.BASEBOARD_FAB2(SCH_1):PAGE84
    24    GND @BASEBOARD_FAB2_LIB.BASEBOARD_FAB2(SCH_1):GND   I138 @BASEBOARD_FAB2_LIB.BASEBOARD_FAB2(SCH_1):PAGE84
    26    GND @BASEBOARD_FAB2_LIB.BASEBOARD_FAB2(SCH_1):GND   I138 @BASEBOARD_FAB2_LIB.BASEBOARD_FAB2(SCH_1):PAGE84
    28    GND @BASEBOARD_FAB2_LIB.BASEBOARD_FAB2(SCH_1):GND   I138 @BASEBOARD_FAB2_LIB.BASEBOARD_FAB2(SCH_1):PAGE84
    31    GND @BASEBOARD_FAB2_LIB.BASEBOARD_FAB2(SCH_1):GND   I138 @BASEBOARD_FAB2_LIB.BASEBOARD_FAB2(SCH_1):PAGE84
    33    GND @BASEBOARD_FAB2_LIB.BASEBOARD_FAB2(SCH_1):GND   I138 @BASEBOARD_FAB2_LIB.BASEBOARD_FAB2(SCH_1):PAGE84
    35    GND @BASEBOARD_FAB2_LIB.BASEBOARD_FAB2(SCH_1):GND   I138 @BASEBOARD_FAB2_LIB.BASEBOARD_FAB2(SCH_1):PAGE84
    37    GND @BASEBOARD_FAB2_LIB.BASEBOARD_FAB2(SCH_1):GND   I138 @BASEBOARD_FAB2_LIB.BASEBOARD_FAB2(SCH_1):PAGE84
    39    GND @BASEBOARD_FAB2_LIB.BASEBOARD_FAB2(SCH_1):GND   I138 @BASEBOARD_FAB2_LIB.BASEBOARD_FAB2(SCH_1):PAGE84
    42    GND @BASEBOARD_FAB2_LIB.BASEBOARD_FAB2(SCH_1):GND   I138 @BASEBOARD_FAB2_LIB.BASEBOARD_FAB2(SCH_1):PAGE84
    44    GND @BASEBOARD_FAB2_LIB.BASEBOARD_FAB2(SCH_1):GND   I138 @BASEBOARD_FAB2_LIB.BASEBOARD_FAB2(SCH_1):PAGE84
    46    GND @BASEBOARD_FAB2_LIB.BASEBOARD_FAB2(SCH_1):GND   I138 @BASEBOARD_FAB2_LIB.BASEBOARD_FAB2(SCH_1):PAGE84
    48    GND @BASEBOARD_FAB2_LIB.BASEBOARD_FAB2(SCH_1):GND   I138 @BASEBOARD_FAB2_LIB.BASEBOARD_FAB2(SCH_1):PAGE84
    50    GND @BASEBOARD_FAB2_LIB.BASEBOARD_FAB2(SCH_1):GND   I138 @BASEBOARD_FAB2_LIB.BASEBOARD_FAB2(SCH_1):PAGE84
    53    GND @BASEBOARD_FAB2_LIB.BASEBOARD_FAB2(SCH_1):GND   I138 @BASEBOARD_FAB2_LIB.BASEBOARD_FAB2(SCH_1):PAGE84
    55    GND @BASEBOARD_FAB2_LIB.BASEBOARD_FAB2(SCH_1):GND   I138 @BASEBOARD_FAB2_LIB.BASEBOARD_FAB2(SCH_1):PAGE84
    57    GND @BASEBOARD_FAB2_LIB.BASEBOARD_FAB2(SCH_1):GND   I138 @BASEBOARD_FAB2_LIB.BASEBOARD_FAB2(SCH_1):PAGE84
    94    GND @BASEBOARD_FAB2_LIB.BASEBOARD_FAB2(SCH_1):GND   I138 @BASEBOARD_FAB2_LIB.BASEBOARD_FAB2(SCH_1):PAGE84
    96    GND @BASEBOARD_FAB2_LIB.BASEBOARD_FAB2(SCH_1):GND   I138 @BASEBOARD_FAB2_LIB.BASEBOARD_FAB2(SCH_1):PAGE84
    98    GND @BASEBOARD_FAB2_LIB.BASEBOARD_FAB2(SCH_1):GND   I138 @BASEBOARD_FAB2_LIB.BASEBOARD_FAB2(SCH_1):PAGE84
   101    GND @BASEBOARD_FAB2_LIB.BASEBOARD_FAB2(SCH_1):GND   I138 @BASEBOARD_FAB2_LIB.BASEBOARD_FAB2(SCH_1):PAGE84
   103    GND @BASEBOARD_FAB2_LIB.BASEBOARD_FAB2(SCH_1):GND   I138 @BASEBOARD_FAB2_LIB.BASEBOARD_FAB2(SCH_1):PAGE84
   105    GND @BASEBOARD_FAB2_LIB.BASEBOARD_FAB2(SCH_1):GND   I138 @BASEBOARD_FAB2_LIB.BASEBOARD_FAB2(SCH_1):PAGE84
   107    GND @BASEBOARD_FAB2_LIB.BASEBOARD_FAB2(SCH_1):GND   I138 @BASEBOARD_FAB2_LIB.BASEBOARD_FAB2(SCH_1):PAGE84
   109    GND @BASEBOARD_FAB2_LIB.BASEBOARD_FAB2(SCH_1):GND   I138 @BASEBOARD_FAB2_LIB.BASEBOARD_FAB2(SCH_1):PAGE84
   112    GND @BASEBOARD_FAB2_LIB.BASEBOARD_FAB2(SCH_1):GND   I138 @BASEBOARD_FAB2_LIB.BASEBOARD_FAB2(SCH_1):PAGE84
   114    GND @BASEBOARD_FAB2_LIB.BASEBOARD_FAB2(SCH_1):GND   I138 @BASEBOARD_FAB2_LIB.BASEBOARD_FAB2(SCH_1):PAGE84
   116    GND @BASEBOARD_FAB2_LIB.BASEBOARD_FAB2(SCH_1):GND   I138 @BASEBOARD_FAB2_LIB.BASEBOARD_FAB2(SCH_1):PAGE84
   118    GND @BASEBOARD_FAB2_LIB.BASEBOARD_FAB2(SCH_1):GND   I138 @BASEBOARD_FAB2_LIB.BASEBOARD_FAB2(SCH_1):PAGE84
   120    GND @BASEBOARD_FAB2_LIB.BASEBOARD_FAB2(SCH_1):GND   I138 @BASEBOARD_FAB2_LIB.BASEBOARD_FAB2(SCH_1):PAGE84
   123    GND @BASEBOARD_FAB2_LIB.BASEBOARD_FAB2(SCH_1):GND   I138 @BASEBOARD_FAB2_LIB.BASEBOARD_FAB2(SCH_1):PAGE84
   125    GND @BASEBOARD_FAB2_LIB.BASEBOARD_FAB2(SCH_1):GND   I138 @BASEBOARD_FAB2_LIB.BASEBOARD_FAB2(SCH_1):PAGE84
   127    GND @BASEBOARD_FAB2_LIB.BASEBOARD_FAB2(SCH_1):GND   I138 @BASEBOARD_FAB2_LIB.BASEBOARD_FAB2(SCH_1):PAGE84
   129    GND @BASEBOARD_FAB2_LIB.BASEBOARD_FAB2(SCH_1):GND   I138 @BASEBOARD_FAB2_LIB.BASEBOARD_FAB2(SCH_1):PAGE84
   131    GND @BASEBOARD_FAB2_LIB.BASEBOARD_FAB2(SCH_1):GND   I138 @BASEBOARD_FAB2_LIB.BASEBOARD_FAB2(SCH_1):PAGE84
   134    GND @BASEBOARD_FAB2_LIB.BASEBOARD_FAB2(SCH_1):GND   I138 @BASEBOARD_FAB2_LIB.BASEBOARD_FAB2(SCH_1):PAGE84
   136    GND @BASEBOARD_FAB2_LIB.BASEBOARD_FAB2(SCH_1):GND   I138 @BASEBOARD_FAB2_LIB.BASEBOARD_FAB2(SCH_1):PAGE84
   138    GND @BASEBOARD_FAB2_LIB.BASEBOARD_FAB2(SCH_1):GND   I138 @BASEBOARD_FAB2_LIB.BASEBOARD_FAB2(SCH_1):PAGE84
   147    GND @BASEBOARD_FAB2_LIB.BASEBOARD_FAB2(SCH_1):GND   I138 @BASEBOARD_FAB2_LIB.BASEBOARD_FAB2(SCH_1):PAGE84
   149    GND @BASEBOARD_FAB2_LIB.BASEBOARD_FAB2(SCH_1):GND   I138 @BASEBOARD_FAB2_LIB.BASEBOARD_FAB2(SCH_1):PAGE84
   151    GND @BASEBOARD_FAB2_LIB.BASEBOARD_FAB2(SCH_1):GND   I138 @BASEBOARD_FAB2_LIB.BASEBOARD_FAB2(SCH_1):PAGE84
   154    GND @BASEBOARD_FAB2_LIB.BASEBOARD_FAB2(SCH_1):GND   I138 @BASEBOARD_FAB2_LIB.BASEBOARD_FAB2(SCH_1):PAGE84
   156    GND @BASEBOARD_FAB2_LIB.BASEBOARD_FAB2(SCH_1):GND   I138 @BASEBOARD_FAB2_LIB.BASEBOARD_FAB2(SCH_1):PAGE84
   158    GND @BASEBOARD_FAB2_LIB.BASEBOARD_FAB2(SCH_1):GND   I138 @BASEBOARD_FAB2_LIB.BASEBOARD_FAB2(SCH_1):PAGE84
   160    GND @BASEBOARD_FAB2_LIB.BASEBOARD_FAB2(SCH_1):GND   I138 @BASEBOARD_FAB2_LIB.BASEBOARD_FAB2(SCH_1):PAGE84
   162    GND @BASEBOARD_FAB2_LIB.BASEBOARD_FAB2(SCH_1):GND   I138 @BASEBOARD_FAB2_LIB.BASEBOARD_FAB2(SCH_1):PAGE84
   165    GND @BASEBOARD_FAB2_LIB.BASEBOARD_FAB2(SCH_1):GND   I138 @BASEBOARD_FAB2_LIB.BASEBOARD_FAB2(SCH_1):PAGE84
   167    GND @BASEBOARD_FAB2_LIB.BASEBOARD_FAB2(SCH_1):GND   I138 @BASEBOARD_FAB2_LIB.BASEBOARD_FAB2(SCH_1):PAGE84
   169    GND @BASEBOARD_FAB2_LIB.BASEBOARD_FAB2(SCH_1):GND   I138 @BASEBOARD_FAB2_LIB.BASEBOARD_FAB2(SCH_1):PAGE84
   171    GND @BASEBOARD_FAB2_LIB.BASEBOARD_FAB2(SCH_1):GND   I138 @BASEBOARD_FAB2_LIB.BASEBOARD_FAB2(SCH_1):PAGE84
   173    GND @BASEBOARD_FAB2_LIB.BASEBOARD_FAB2(SCH_1):GND   I138 @BASEBOARD_FAB2_LIB.BASEBOARD_FAB2(SCH_1):PAGE84
   176    GND @BASEBOARD_FAB2_LIB.BASEBOARD_FAB2(SCH_1):GND   I138 @BASEBOARD_FAB2_LIB.BASEBOARD_FAB2(SCH_1):PAGE84
   178    GND @BASEBOARD_FAB2_LIB.BASEBOARD_FAB2(SCH_1):GND   I138 @BASEBOARD_FAB2_LIB.BASEBOARD_FAB2(SCH_1):PAGE84
   180    GND @BASEBOARD_FAB2_LIB.BASEBOARD_FAB2(SCH_1):GND   I138 @BASEBOARD_FAB2_LIB.BASEBOARD_FAB2(SCH_1):PAGE84
   182    GND @BASEBOARD_FAB2_LIB.BASEBOARD_FAB2(SCH_1):GND   I138 @BASEBOARD_FAB2_LIB.BASEBOARD_FAB2(SCH_1):PAGE84
   184    GND @BASEBOARD_FAB2_LIB.BASEBOARD_FAB2(SCH_1):GND   I138 @BASEBOARD_FAB2_LIB.BASEBOARD_FAB2(SCH_1):PAGE84
   187    GND @BASEBOARD_FAB2_LIB.BASEBOARD_FAB2(SCH_1):GND   I138 @BASEBOARD_FAB2_LIB.BASEBOARD_FAB2(SCH_1):PAGE84
   189    GND @BASEBOARD_FAB2_LIB.BASEBOARD_FAB2(SCH_1):GND   I138 @BASEBOARD_FAB2_LIB.BASEBOARD_FAB2(SCH_1):PAGE84
   191    GND @BASEBOARD_FAB2_LIB.BASEBOARD_FAB2(SCH_1):GND   I138 @BASEBOARD_FAB2_LIB.BASEBOARD_FAB2(SCH_1):PAGE84
   193    GND @BASEBOARD_FAB2_LIB.BASEBOARD_FAB2(SCH_1):GND   I138 @BASEBOARD_FAB2_LIB.BASEBOARD_FAB2(SCH_1):PAGE84
   195    GND @BASEBOARD_FAB2_LIB.BASEBOARD_FAB2(SCH_1):GND   I138 @BASEBOARD_FAB2_LIB.BASEBOARD_FAB2(SCH_1):PAGE84
   198    GND @BASEBOARD_FAB2_LIB.BASEBOARD_FAB2(SCH_1):GND   I138 @BASEBOARD_FAB2_LIB.BASEBOARD_FAB2(SCH_1):PAGE84
   200    GND @BASEBOARD_FAB2_LIB.BASEBOARD_FAB2(SCH_1):GND   I138 @BASEBOARD_FAB2_LIB.BASEBOARD_FAB2(SCH_1):PAGE84
   202    GND @BASEBOARD_FAB2_LIB.BASEBOARD_FAB2(SCH_1):GND   I138 @BASEBOARD_FAB2_LIB.BASEBOARD_FAB2(SCH_1):PAGE84
   239    GND @BASEBOARD_FAB2_LIB.BASEBOARD_FAB2(SCH_1):GND   I138 @BASEBOARD_FAB2_LIB.BASEBOARD_FAB2(SCH_1):PAGE84
   241    GND @BASEBOARD_FAB2_LIB.BASEBOARD_FAB2(SCH_1):GND   I138 @BASEBOARD_FAB2_LIB.BASEBOARD_FAB2(SCH_1):PAGE84
   243    GND @BASEBOARD_FAB2_LIB.BASEBOARD_FAB2(SCH_1):GND   I138 @BASEBOARD_FAB2_LIB.BASEBOARD_FAB2(SCH_1):PAGE84
   246    GND @BASEBOARD_FAB2_LIB.BASEBOARD_FAB2(SCH_1):GND   I138 @BASEBOARD_FAB2_LIB.BASEBOARD_FAB2(SCH_1):PAGE84
   248    GND @BASEBOARD_FAB2_LIB.BASEBOARD_FAB2(SCH_1):GND   I138 @BASEBOARD_FAB2_LIB.BASEBOARD_FAB2(SCH_1):PAGE84
   250    GND @BASEBOARD_FAB2_LIB.BASEBOARD_FAB2(SCH_1):GND   I138 @BASEBOARD_FAB2_LIB.BASEBOARD_FAB2(SCH_1):PAGE84
   252    GND @BASEBOARD_FAB2_LIB.BASEBOARD_FAB2(SCH_1):GND   I138 @BASEBOARD_FAB2_LIB.BASEBOARD_FAB2(SCH_1):PAGE84
   254    GND @BASEBOARD_FAB2_LIB.BASEBOARD_FAB2(SCH_1):GND   I138 @BASEBOARD_FAB2_LIB.BASEBOARD_FAB2(SCH_1):PAGE84
   257    GND @BASEBOARD_FAB2_LIB.BASEBOARD_FAB2(SCH_1):GND   I138 @BASEBOARD_FAB2_LIB.BASEBOARD_FAB2(SCH_1):PAGE84
   259    GND @BASEBOARD_FAB2_LIB.BASEBOARD_FAB2(SCH_1):GND   I138 @BASEBOARD_FAB2_LIB.BASEBOARD_FAB2(SCH_1):PAGE84
   261    GND @BASEBOARD_FAB2_LIB.BASEBOARD_FAB2(SCH_1):GND   I138 @BASEBOARD_FAB2_LIB.BASEBOARD_FAB2(SCH_1):PAGE84
   263    GND @BASEBOARD_FAB2_LIB.BASEBOARD_FAB2(SCH_1):GND   I138 @BASEBOARD_FAB2_LIB.BASEBOARD_FAB2(SCH_1):PAGE84
   265    GND @BASEBOARD_FAB2_LIB.BASEBOARD_FAB2(SCH_1):GND   I138 @BASEBOARD_FAB2_LIB.BASEBOARD_FAB2(SCH_1):PAGE84
   268    GND @BASEBOARD_FAB2_LIB.BASEBOARD_FAB2(SCH_1):GND   I138 @BASEBOARD_FAB2_LIB.BASEBOARD_FAB2(SCH_1):PAGE84
   270    GND @BASEBOARD_FAB2_LIB.BASEBOARD_FAB2(SCH_1):GND   I138 @BASEBOARD_FAB2_LIB.BASEBOARD_FAB2(SCH_1):PAGE84
   272    GND @BASEBOARD_FAB2_LIB.BASEBOARD_FAB2(SCH_1):GND   I138 @BASEBOARD_FAB2_LIB.BASEBOARD_FAB2(SCH_1):PAGE84
   274    GND @BASEBOARD_FAB2_LIB.BASEBOARD_FAB2(SCH_1):GND   I138 @BASEBOARD_FAB2_LIB.BASEBOARD_FAB2(SCH_1):PAGE84
   276    GND @BASEBOARD_FAB2_LIB.BASEBOARD_FAB2(SCH_1):GND   I138 @BASEBOARD_FAB2_LIB.BASEBOARD_FAB2(SCH_1):PAGE84
   279    GND @BASEBOARD_FAB2_LIB.BASEBOARD_FAB2(SCH_1):GND   I138 @BASEBOARD_FAB2_LIB.BASEBOARD_FAB2(SCH_1):PAGE84
   281    GND @BASEBOARD_FAB2_LIB.BASEBOARD_FAB2(SCH_1):GND   I138 @BASEBOARD_FAB2_LIB.BASEBOARD_FAB2(SCH_1):PAGE84
   283    GND @BASEBOARD_FAB2_LIB.BASEBOARD_FAB2(SCH_1):GND   I138 @BASEBOARD_FAB2_LIB.BASEBOARD_FAB2(SCH_1):PAGE84
     1 P12V_NVDIMM_KLM @BASEBOARD_FAB2_LIB.BASEBOARD_FAB2(SCH_1):P12V_NVDIMM_KLM    I57 @BASEBOARD_FAB2_LIB.BASEBOARD_FAB2(SCH_1):PAGE84
   145 P12V_NVDIMM_KLM @BASEBOARD_FAB2_LIB.BASEBOARD_FAB2(SCH_1):P12V_NVDIMM_KLM    I57 @BASEBOARD_FAB2_LIB.BASEBOARD_FAB2(SCH_1):PAGE84
    59 PVDDQ_KLM @BASEBOARD_FAB2_LIB.BASEBOARD_FAB2(SCH_1):PVDDQ_KLM    I57 @BASEBOARD_FAB2_LIB.BASEBOARD_FAB2(SCH_1):PAGE84
    61 PVDDQ_KLM @BASEBOARD_FAB2_LIB.BASEBOARD_FAB2(SCH_1):PVDDQ_KLM    I57 @BASEBOARD_FAB2_LIB.BASEBOARD_FAB2(SCH_1):PAGE84
    64 PVDDQ_KLM @BASEBOARD_FAB2_LIB.BASEBOARD_FAB2(SCH_1):PVDDQ_KLM    I57 @BASEBOARD_FAB2_LIB.BASEBOARD_FAB2(SCH_1):PAGE84
    67 PVDDQ_KLM @BASEBOARD_FAB2_LIB.BASEBOARD_FAB2(SCH_1):PVDDQ_KLM    I57 @BASEBOARD_FAB2_LIB.BASEBOARD_FAB2(SCH_1):PAGE84
    70 PVDDQ_KLM @BASEBOARD_FAB2_LIB.BASEBOARD_FAB2(SCH_1):PVDDQ_KLM    I57 @BASEBOARD_FAB2_LIB.BASEBOARD_FAB2(SCH_1):PAGE84
    73 PVDDQ_KLM @BASEBOARD_FAB2_LIB.BASEBOARD_FAB2(SCH_1):PVDDQ_KLM    I57 @BASEBOARD_FAB2_LIB.BASEBOARD_FAB2(SCH_1):PAGE84
    76 PVDDQ_KLM @BASEBOARD_FAB2_LIB.BASEBOARD_FAB2(SCH_1):PVDDQ_KLM    I57 @BASEBOARD_FAB2_LIB.BASEBOARD_FAB2(SCH_1):PAGE84
    80 PVDDQ_KLM @BASEBOARD_FAB2_LIB.BASEBOARD_FAB2(SCH_1):PVDDQ_KLM    I57 @BASEBOARD_FAB2_LIB.BASEBOARD_FAB2(SCH_1):PAGE84
    83 PVDDQ_KLM @BASEBOARD_FAB2_LIB.BASEBOARD_FAB2(SCH_1):PVDDQ_KLM    I57 @BASEBOARD_FAB2_LIB.BASEBOARD_FAB2(SCH_1):PAGE84
    85 PVDDQ_KLM @BASEBOARD_FAB2_LIB.BASEBOARD_FAB2(SCH_1):PVDDQ_KLM    I57 @BASEBOARD_FAB2_LIB.BASEBOARD_FAB2(SCH_1):PAGE84
    88 PVDDQ_KLM @BASEBOARD_FAB2_LIB.BASEBOARD_FAB2(SCH_1):PVDDQ_KLM    I57 @BASEBOARD_FAB2_LIB.BASEBOARD_FAB2(SCH_1):PAGE84
    90 PVDDQ_KLM @BASEBOARD_FAB2_LIB.BASEBOARD_FAB2(SCH_1):PVDDQ_KLM    I57 @BASEBOARD_FAB2_LIB.BASEBOARD_FAB2(SCH_1):PAGE84
    92 PVDDQ_KLM @BASEBOARD_FAB2_LIB.BASEBOARD_FAB2(SCH_1):PVDDQ_KLM    I57 @BASEBOARD_FAB2_LIB.BASEBOARD_FAB2(SCH_1):PAGE84
   204 PVDDQ_KLM @BASEBOARD_FAB2_LIB.BASEBOARD_FAB2(SCH_1):PVDDQ_KLM    I57 @BASEBOARD_FAB2_LIB.BASEBOARD_FAB2(SCH_1):PAGE84
   206 PVDDQ_KLM @BASEBOARD_FAB2_LIB.BASEBOARD_FAB2(SCH_1):PVDDQ_KLM    I57 @BASEBOARD_FAB2_LIB.BASEBOARD_FAB2(SCH_1):PAGE84
   209 PVDDQ_KLM @BASEBOARD_FAB2_LIB.BASEBOARD_FAB2(SCH_1):PVDDQ_KLM    I57 @BASEBOARD_FAB2_LIB.BASEBOARD_FAB2(SCH_1):PAGE84
   212 PVDDQ_KLM @BASEBOARD_FAB2_LIB.BASEBOARD_FAB2(SCH_1):PVDDQ_KLM    I57 @BASEBOARD_FAB2_LIB.BASEBOARD_FAB2(SCH_1):PAGE84
   215 PVDDQ_KLM @BASEBOARD_FAB2_LIB.BASEBOARD_FAB2(SCH_1):PVDDQ_KLM    I57 @BASEBOARD_FAB2_LIB.BASEBOARD_FAB2(SCH_1):PAGE84
   217 PVDDQ_KLM @BASEBOARD_FAB2_LIB.BASEBOARD_FAB2(SCH_1):PVDDQ_KLM    I57 @BASEBOARD_FAB2_LIB.BASEBOARD_FAB2(SCH_1):PAGE84
   220 PVDDQ_KLM @BASEBOARD_FAB2_LIB.BASEBOARD_FAB2(SCH_1):PVDDQ_KLM    I57 @BASEBOARD_FAB2_LIB.BASEBOARD_FAB2(SCH_1):PAGE84
   223 PVDDQ_KLM @BASEBOARD_FAB2_LIB.BASEBOARD_FAB2(SCH_1):PVDDQ_KLM    I57 @BASEBOARD_FAB2_LIB.BASEBOARD_FAB2(SCH_1):PAGE84
   226 PVDDQ_KLM @BASEBOARD_FAB2_LIB.BASEBOARD_FAB2(SCH_1):PVDDQ_KLM    I57 @BASEBOARD_FAB2_LIB.BASEBOARD_FAB2(SCH_1):PAGE84
   229 PVDDQ_KLM @BASEBOARD_FAB2_LIB.BASEBOARD_FAB2(SCH_1):PVDDQ_KLM    I57 @BASEBOARD_FAB2_LIB.BASEBOARD_FAB2(SCH_1):PAGE84
   231 PVDDQ_KLM @BASEBOARD_FAB2_LIB.BASEBOARD_FAB2(SCH_1):PVDDQ_KLM    I57 @BASEBOARD_FAB2_LIB.BASEBOARD_FAB2(SCH_1):PAGE84
   233 PVDDQ_KLM @BASEBOARD_FAB2_LIB.BASEBOARD_FAB2(SCH_1):PVDDQ_KLM    I57 @BASEBOARD_FAB2_LIB.BASEBOARD_FAB2(SCH_1):PAGE84
   236 PVDDQ_KLM @BASEBOARD_FAB2_LIB.BASEBOARD_FAB2(SCH_1):PVDDQ_KLM    I57 @BASEBOARD_FAB2_LIB.BASEBOARD_FAB2(SCH_1):PAGE84
   142 PVPP_KLM @BASEBOARD_FAB2_LIB.BASEBOARD_FAB2(SCH_1):PVPP_KLM    I57 @BASEBOARD_FAB2_LIB.BASEBOARD_FAB2(SCH_1):PAGE84
   143 PVPP_KLM @BASEBOARD_FAB2_LIB.BASEBOARD_FAB2(SCH_1):PVPP_KLM    I57 @BASEBOARD_FAB2_LIB.BASEBOARD_FAB2(SCH_1):PAGE84
   288 PVPP_KLM @BASEBOARD_FAB2_LIB.BASEBOARD_FAB2(SCH_1):PVPP_KLM    I57 @BASEBOARD_FAB2_LIB.BASEBOARD_FAB2(SCH_1):PAGE84
   286 PVPP_KLM @BASEBOARD_FAB2_LIB.BASEBOARD_FAB2(SCH_1):PVPP_KLM    I57 @BASEBOARD_FAB2_LIB.BASEBOARD_FAB2(SCH_1):PAGE84
   287 PVPP_KLM @BASEBOARD_FAB2_LIB.BASEBOARD_FAB2(SCH_1):PVPP_KLM    I57 @BASEBOARD_FAB2_LIB.BASEBOARD_FAB2(SCH_1):PAGE84
    77 PVTT_KLM @BASEBOARD_FAB2_LIB.BASEBOARD_FAB2(SCH_1):PVTT_KLM    I57 @BASEBOARD_FAB2_LIB.BASEBOARD_FAB2(SCH_1):PAGE84
   221 PVTT_KLM @BASEBOARD_FAB2_LIB.BASEBOARD_FAB2(SCH_1):PVTT_KLM    I57 @BASEBOARD_FAB2_LIB.BASEBOARD_FAB2(SCH_1):PAGE84

J9T1 SCONN288_H44441003_PIP-SCONN,HA
    79 M_G_MA<0> @BASEBOARD_FAB2_LIB.BASEBOARD_FAB2(SCH_1):M_G_MA(0)    I13 @BASEBOARD_FAB2_LIB.BASEBOARD_FAB2(SCH_1):PAGE78
    72 M_G_MA<1> @BASEBOARD_FAB2_LIB.BASEBOARD_FAB2(SCH_1):M_G_MA(1)    I13 @BASEBOARD_FAB2_LIB.BASEBOARD_FAB2(SCH_1):PAGE78
   225 M_G_MA<10> @BASEBOARD_FAB2_LIB.BASEBOARD_FAB2(SCH_1):M_G_MA(10)    I13 @BASEBOARD_FAB2_LIB.BASEBOARD_FAB2(SCH_1):PAGE78
   210 M_G_MA<11> @BASEBOARD_FAB2_LIB.BASEBOARD_FAB2(SCH_1):M_G_MA(11)    I13 @BASEBOARD_FAB2_LIB.BASEBOARD_FAB2(SCH_1):PAGE78
    65 M_G_MA<12> @BASEBOARD_FAB2_LIB.BASEBOARD_FAB2(SCH_1):M_G_MA(12)    I13 @BASEBOARD_FAB2_LIB.BASEBOARD_FAB2(SCH_1):PAGE78
   232 M_G_MA<13> @BASEBOARD_FAB2_LIB.BASEBOARD_FAB2(SCH_1):M_G_MA(13)    I13 @BASEBOARD_FAB2_LIB.BASEBOARD_FAB2(SCH_1):PAGE78
   228 M_G_MA<14> @BASEBOARD_FAB2_LIB.BASEBOARD_FAB2(SCH_1):M_G_MA(14)    I13 @BASEBOARD_FAB2_LIB.BASEBOARD_FAB2(SCH_1):PAGE78
    86 M_G_MA<15> @BASEBOARD_FAB2_LIB.BASEBOARD_FAB2(SCH_1):M_G_MA(15)    I13 @BASEBOARD_FAB2_LIB.BASEBOARD_FAB2(SCH_1):PAGE78
    82 M_G_MA<16> @BASEBOARD_FAB2_LIB.BASEBOARD_FAB2(SCH_1):M_G_MA(16)    I13 @BASEBOARD_FAB2_LIB.BASEBOARD_FAB2(SCH_1):PAGE78
   234 M_G_MA<17> @BASEBOARD_FAB2_LIB.BASEBOARD_FAB2(SCH_1):M_G_MA(17)    I13 @BASEBOARD_FAB2_LIB.BASEBOARD_FAB2(SCH_1):PAGE78
   216 M_G_MA<2> @BASEBOARD_FAB2_LIB.BASEBOARD_FAB2(SCH_1):M_G_MA(2)    I13 @BASEBOARD_FAB2_LIB.BASEBOARD_FAB2(SCH_1):PAGE78
    71 M_G_MA<3> @BASEBOARD_FAB2_LIB.BASEBOARD_FAB2(SCH_1):M_G_MA(3)    I13 @BASEBOARD_FAB2_LIB.BASEBOARD_FAB2(SCH_1):PAGE78
   214 M_G_MA<4> @BASEBOARD_FAB2_LIB.BASEBOARD_FAB2(SCH_1):M_G_MA(4)    I13 @BASEBOARD_FAB2_LIB.BASEBOARD_FAB2(SCH_1):PAGE78
   213 M_G_MA<5> @BASEBOARD_FAB2_LIB.BASEBOARD_FAB2(SCH_1):M_G_MA(5)    I13 @BASEBOARD_FAB2_LIB.BASEBOARD_FAB2(SCH_1):PAGE78
    69 M_G_MA<6> @BASEBOARD_FAB2_LIB.BASEBOARD_FAB2(SCH_1):M_G_MA(6)    I13 @BASEBOARD_FAB2_LIB.BASEBOARD_FAB2(SCH_1):PAGE78
   211 M_G_MA<7> @BASEBOARD_FAB2_LIB.BASEBOARD_FAB2(SCH_1):M_G_MA(7)    I13 @BASEBOARD_FAB2_LIB.BASEBOARD_FAB2(SCH_1):PAGE78
    68 M_G_MA<8> @BASEBOARD_FAB2_LIB.BASEBOARD_FAB2(SCH_1):M_G_MA(8)    I13 @BASEBOARD_FAB2_LIB.BASEBOARD_FAB2(SCH_1):PAGE78
    66 M_G_MA<9> @BASEBOARD_FAB2_LIB.BASEBOARD_FAB2(SCH_1):M_G_MA(9)    I13 @BASEBOARD_FAB2_LIB.BASEBOARD_FAB2(SCH_1):PAGE78
    62 M_G_ACT_N @BASEBOARD_FAB2_LIB.BASEBOARD_FAB2(SCH_1):M_G_ACT_N    I13 @BASEBOARD_FAB2_LIB.BASEBOARD_FAB2(SCH_1):PAGE78
   208 M_G_ALERT_N @BASEBOARD_FAB2_LIB.BASEBOARD_FAB2(SCH_1):M_G_ALERT_N    I13 @BASEBOARD_FAB2_LIB.BASEBOARD_FAB2(SCH_1):PAGE78
   224 M_G_BA<1> @BASEBOARD_FAB2_LIB.BASEBOARD_FAB2(SCH_1):M_G_BA(1)    I13 @BASEBOARD_FAB2_LIB.BASEBOARD_FAB2(SCH_1):PAGE78
    81 M_G_BA<0> @BASEBOARD_FAB2_LIB.BASEBOARD_FAB2(SCH_1):M_G_BA(0)    I13 @BASEBOARD_FAB2_LIB.BASEBOARD_FAB2(SCH_1):PAGE78
   207 M_G_BG<1> @BASEBOARD_FAB2_LIB.BASEBOARD_FAB2(SCH_1):M_G_BG(1)    I13 @BASEBOARD_FAB2_LIB.BASEBOARD_FAB2(SCH_1):PAGE78
    63 M_G_BG<0> @BASEBOARD_FAB2_LIB.BASEBOARD_FAB2(SCH_1):M_G_BG(0)    I13 @BASEBOARD_FAB2_LIB.BASEBOARD_FAB2(SCH_1):PAGE78
   235 M_G_C<2> @BASEBOARD_FAB2_LIB.BASEBOARD_FAB2(SCH_1):M_G_C(2)    I13 @BASEBOARD_FAB2_LIB.BASEBOARD_FAB2(SCH_1):PAGE78
   199 M_G_ECC<7> @BASEBOARD_FAB2_LIB.BASEBOARD_FAB2(SCH_1):M_G_ECC(7)    I13 @BASEBOARD_FAB2_LIB.BASEBOARD_FAB2(SCH_1):PAGE78
    54 M_G_ECC<6> @BASEBOARD_FAB2_LIB.BASEBOARD_FAB2(SCH_1):M_G_ECC(6)    I13 @BASEBOARD_FAB2_LIB.BASEBOARD_FAB2(SCH_1):PAGE78
   192 M_G_ECC<5> @BASEBOARD_FAB2_LIB.BASEBOARD_FAB2(SCH_1):M_G_ECC(5)    I13 @BASEBOARD_FAB2_LIB.BASEBOARD_FAB2(SCH_1):PAGE78
    47 M_G_ECC<4> @BASEBOARD_FAB2_LIB.BASEBOARD_FAB2(SCH_1):M_G_ECC(4)    I13 @BASEBOARD_FAB2_LIB.BASEBOARD_FAB2(SCH_1):PAGE78
   201 M_G_ECC<3> @BASEBOARD_FAB2_LIB.BASEBOARD_FAB2(SCH_1):M_G_ECC(3)    I13 @BASEBOARD_FAB2_LIB.BASEBOARD_FAB2(SCH_1):PAGE78
    56 M_G_ECC<2> @BASEBOARD_FAB2_LIB.BASEBOARD_FAB2(SCH_1):M_G_ECC(2)    I13 @BASEBOARD_FAB2_LIB.BASEBOARD_FAB2(SCH_1):PAGE78
   194 M_G_ECC<1> @BASEBOARD_FAB2_LIB.BASEBOARD_FAB2(SCH_1):M_G_ECC(1)    I13 @BASEBOARD_FAB2_LIB.BASEBOARD_FAB2(SCH_1):PAGE78
    49 M_G_ECC<0> @BASEBOARD_FAB2_LIB.BASEBOARD_FAB2(SCH_1):M_G_ECC(0)    I13 @BASEBOARD_FAB2_LIB.BASEBOARD_FAB2(SCH_1):PAGE78
    75 M_G_CLK_DN<2> @BASEBOARD_FAB2_LIB.BASEBOARD_FAB2(SCH_1):M_G_CLK_DN(2)    I13 @BASEBOARD_FAB2_LIB.BASEBOARD_FAB2(SCH_1):PAGE78
    74 M_G_CLK_DP<2> @BASEBOARD_FAB2_LIB.BASEBOARD_FAB2(SCH_1):M_G_CLK_DP(2)    I13 @BASEBOARD_FAB2_LIB.BASEBOARD_FAB2(SCH_1):PAGE78
   219 M_G_CLK_DN<3> @BASEBOARD_FAB2_LIB.BASEBOARD_FAB2(SCH_1):M_G_CLK_DN(3)    I13 @BASEBOARD_FAB2_LIB.BASEBOARD_FAB2(SCH_1):PAGE78
   218 M_G_CLK_DP<3> @BASEBOARD_FAB2_LIB.BASEBOARD_FAB2(SCH_1):M_G_CLK_DP(3)    I13 @BASEBOARD_FAB2_LIB.BASEBOARD_FAB2(SCH_1):PAGE78
   203 M_G_CKE<3> @BASEBOARD_FAB2_LIB.BASEBOARD_FAB2(SCH_1):M_G_CKE(3)    I13 @BASEBOARD_FAB2_LIB.BASEBOARD_FAB2(SCH_1):PAGE78
    60 M_G_CKE<2> @BASEBOARD_FAB2_LIB.BASEBOARD_FAB2(SCH_1):M_G_CKE(2)    I13 @BASEBOARD_FAB2_LIB.BASEBOARD_FAB2(SCH_1):PAGE78
   280 M_G_DQ<63> @BASEBOARD_FAB2_LIB.BASEBOARD_FAB2(SCH_1):M_G_DQ(63)    I13 @BASEBOARD_FAB2_LIB.BASEBOARD_FAB2(SCH_1):PAGE78
   135 M_G_DQ<62> @BASEBOARD_FAB2_LIB.BASEBOARD_FAB2(SCH_1):M_G_DQ(62)    I13 @BASEBOARD_FAB2_LIB.BASEBOARD_FAB2(SCH_1):PAGE78
   273 M_G_DQ<61> @BASEBOARD_FAB2_LIB.BASEBOARD_FAB2(SCH_1):M_G_DQ(61)    I13 @BASEBOARD_FAB2_LIB.BASEBOARD_FAB2(SCH_1):PAGE78
   128 M_G_DQ<60> @BASEBOARD_FAB2_LIB.BASEBOARD_FAB2(SCH_1):M_G_DQ(60)    I13 @BASEBOARD_FAB2_LIB.BASEBOARD_FAB2(SCH_1):PAGE78
   282 M_G_DQ<59> @BASEBOARD_FAB2_LIB.BASEBOARD_FAB2(SCH_1):M_G_DQ(59)    I13 @BASEBOARD_FAB2_LIB.BASEBOARD_FAB2(SCH_1):PAGE78
   137 M_G_DQ<58> @BASEBOARD_FAB2_LIB.BASEBOARD_FAB2(SCH_1):M_G_DQ(58)    I13 @BASEBOARD_FAB2_LIB.BASEBOARD_FAB2(SCH_1):PAGE78
   275 M_G_DQ<57> @BASEBOARD_FAB2_LIB.BASEBOARD_FAB2(SCH_1):M_G_DQ(57)    I13 @BASEBOARD_FAB2_LIB.BASEBOARD_FAB2(SCH_1):PAGE78
   130 M_G_DQ<56> @BASEBOARD_FAB2_LIB.BASEBOARD_FAB2(SCH_1):M_G_DQ(56)    I13 @BASEBOARD_FAB2_LIB.BASEBOARD_FAB2(SCH_1):PAGE78
   269 M_G_DQ<55> @BASEBOARD_FAB2_LIB.BASEBOARD_FAB2(SCH_1):M_G_DQ(55)    I13 @BASEBOARD_FAB2_LIB.BASEBOARD_FAB2(SCH_1):PAGE78
   124 M_G_DQ<54> @BASEBOARD_FAB2_LIB.BASEBOARD_FAB2(SCH_1):M_G_DQ(54)    I13 @BASEBOARD_FAB2_LIB.BASEBOARD_FAB2(SCH_1):PAGE78
   262 M_G_DQ<53> @BASEBOARD_FAB2_LIB.BASEBOARD_FAB2(SCH_1):M_G_DQ(53)    I13 @BASEBOARD_FAB2_LIB.BASEBOARD_FAB2(SCH_1):PAGE78
   117 M_G_DQ<52> @BASEBOARD_FAB2_LIB.BASEBOARD_FAB2(SCH_1):M_G_DQ(52)    I13 @BASEBOARD_FAB2_LIB.BASEBOARD_FAB2(SCH_1):PAGE78
   271 M_G_DQ<51> @BASEBOARD_FAB2_LIB.BASEBOARD_FAB2(SCH_1):M_G_DQ(51)    I13 @BASEBOARD_FAB2_LIB.BASEBOARD_FAB2(SCH_1):PAGE78
   126 M_G_DQ<50> @BASEBOARD_FAB2_LIB.BASEBOARD_FAB2(SCH_1):M_G_DQ(50)    I13 @BASEBOARD_FAB2_LIB.BASEBOARD_FAB2(SCH_1):PAGE78
   264 M_G_DQ<49> @BASEBOARD_FAB2_LIB.BASEBOARD_FAB2(SCH_1):M_G_DQ(49)    I13 @BASEBOARD_FAB2_LIB.BASEBOARD_FAB2(SCH_1):PAGE78
   119 M_G_DQ<48> @BASEBOARD_FAB2_LIB.BASEBOARD_FAB2(SCH_1):M_G_DQ(48)    I13 @BASEBOARD_FAB2_LIB.BASEBOARD_FAB2(SCH_1):PAGE78
   258 M_G_DQ<47> @BASEBOARD_FAB2_LIB.BASEBOARD_FAB2(SCH_1):M_G_DQ(47)    I13 @BASEBOARD_FAB2_LIB.BASEBOARD_FAB2(SCH_1):PAGE78
   113 M_G_DQ<46> @BASEBOARD_FAB2_LIB.BASEBOARD_FAB2(SCH_1):M_G_DQ(46)    I13 @BASEBOARD_FAB2_LIB.BASEBOARD_FAB2(SCH_1):PAGE78
   251 M_G_DQ<45> @BASEBOARD_FAB2_LIB.BASEBOARD_FAB2(SCH_1):M_G_DQ(45)    I13 @BASEBOARD_FAB2_LIB.BASEBOARD_FAB2(SCH_1):PAGE78
   106 M_G_DQ<44> @BASEBOARD_FAB2_LIB.BASEBOARD_FAB2(SCH_1):M_G_DQ(44)    I13 @BASEBOARD_FAB2_LIB.BASEBOARD_FAB2(SCH_1):PAGE78
   260 M_G_DQ<43> @BASEBOARD_FAB2_LIB.BASEBOARD_FAB2(SCH_1):M_G_DQ(43)    I13 @BASEBOARD_FAB2_LIB.BASEBOARD_FAB2(SCH_1):PAGE78
   115 M_G_DQ<42> @BASEBOARD_FAB2_LIB.BASEBOARD_FAB2(SCH_1):M_G_DQ(42)    I13 @BASEBOARD_FAB2_LIB.BASEBOARD_FAB2(SCH_1):PAGE78
   253 M_G_DQ<41> @BASEBOARD_FAB2_LIB.BASEBOARD_FAB2(SCH_1):M_G_DQ(41)    I13 @BASEBOARD_FAB2_LIB.BASEBOARD_FAB2(SCH_1):PAGE78
   108 M_G_DQ<40> @BASEBOARD_FAB2_LIB.BASEBOARD_FAB2(SCH_1):M_G_DQ(40)    I13 @BASEBOARD_FAB2_LIB.BASEBOARD_FAB2(SCH_1):PAGE78
   247 M_G_DQ<39> @BASEBOARD_FAB2_LIB.BASEBOARD_FAB2(SCH_1):M_G_DQ(39)    I13 @BASEBOARD_FAB2_LIB.BASEBOARD_FAB2(SCH_1):PAGE78
   102 M_G_DQ<38> @BASEBOARD_FAB2_LIB.BASEBOARD_FAB2(SCH_1):M_G_DQ(38)    I13 @BASEBOARD_FAB2_LIB.BASEBOARD_FAB2(SCH_1):PAGE78
   240 M_G_DQ<37> @BASEBOARD_FAB2_LIB.BASEBOARD_FAB2(SCH_1):M_G_DQ(37)    I13 @BASEBOARD_FAB2_LIB.BASEBOARD_FAB2(SCH_1):PAGE78
    95 M_G_DQ<36> @BASEBOARD_FAB2_LIB.BASEBOARD_FAB2(SCH_1):M_G_DQ(36)    I13 @BASEBOARD_FAB2_LIB.BASEBOARD_FAB2(SCH_1):PAGE78
   249 M_G_DQ<35> @BASEBOARD_FAB2_LIB.BASEBOARD_FAB2(SCH_1):M_G_DQ(35)    I13 @BASEBOARD_FAB2_LIB.BASEBOARD_FAB2(SCH_1):PAGE78
   104 M_G_DQ<34> @BASEBOARD_FAB2_LIB.BASEBOARD_FAB2(SCH_1):M_G_DQ(34)    I13 @BASEBOARD_FAB2_LIB.BASEBOARD_FAB2(SCH_1):PAGE78
   242 M_G_DQ<33> @BASEBOARD_FAB2_LIB.BASEBOARD_FAB2(SCH_1):M_G_DQ(33)    I13 @BASEBOARD_FAB2_LIB.BASEBOARD_FAB2(SCH_1):PAGE78
    97 M_G_DQ<32> @BASEBOARD_FAB2_LIB.BASEBOARD_FAB2(SCH_1):M_G_DQ(32)    I13 @BASEBOARD_FAB2_LIB.BASEBOARD_FAB2(SCH_1):PAGE78
   188 M_G_DQ<31> @BASEBOARD_FAB2_LIB.BASEBOARD_FAB2(SCH_1):M_G_DQ(31)    I13 @BASEBOARD_FAB2_LIB.BASEBOARD_FAB2(SCH_1):PAGE78
    43 M_G_DQ<30> @BASEBOARD_FAB2_LIB.BASEBOARD_FAB2(SCH_1):M_G_DQ(30)    I13 @BASEBOARD_FAB2_LIB.BASEBOARD_FAB2(SCH_1):PAGE78
   181 M_G_DQ<29> @BASEBOARD_FAB2_LIB.BASEBOARD_FAB2(SCH_1):M_G_DQ(29)    I13 @BASEBOARD_FAB2_LIB.BASEBOARD_FAB2(SCH_1):PAGE78
    36 M_G_DQ<28> @BASEBOARD_FAB2_LIB.BASEBOARD_FAB2(SCH_1):M_G_DQ(28)    I13 @BASEBOARD_FAB2_LIB.BASEBOARD_FAB2(SCH_1):PAGE78
   190 M_G_DQ<27> @BASEBOARD_FAB2_LIB.BASEBOARD_FAB2(SCH_1):M_G_DQ(27)    I13 @BASEBOARD_FAB2_LIB.BASEBOARD_FAB2(SCH_1):PAGE78
    45 M_G_DQ<26> @BASEBOARD_FAB2_LIB.BASEBOARD_FAB2(SCH_1):M_G_DQ(26)    I13 @BASEBOARD_FAB2_LIB.BASEBOARD_FAB2(SCH_1):PAGE78
   183 M_G_DQ<25> @BASEBOARD_FAB2_LIB.BASEBOARD_FAB2(SCH_1):M_G_DQ(25)    I13 @BASEBOARD_FAB2_LIB.BASEBOARD_FAB2(SCH_1):PAGE78
    38 M_G_DQ<24> @BASEBOARD_FAB2_LIB.BASEBOARD_FAB2(SCH_1):M_G_DQ(24)    I13 @BASEBOARD_FAB2_LIB.BASEBOARD_FAB2(SCH_1):PAGE78
   177 M_G_DQ<23> @BASEBOARD_FAB2_LIB.BASEBOARD_FAB2(SCH_1):M_G_DQ(23)    I13 @BASEBOARD_FAB2_LIB.BASEBOARD_FAB2(SCH_1):PAGE78
    32 M_G_DQ<22> @BASEBOARD_FAB2_LIB.BASEBOARD_FAB2(SCH_1):M_G_DQ(22)    I13 @BASEBOARD_FAB2_LIB.BASEBOARD_FAB2(SCH_1):PAGE78
   170 M_G_DQ<21> @BASEBOARD_FAB2_LIB.BASEBOARD_FAB2(SCH_1):M_G_DQ(21)    I13 @BASEBOARD_FAB2_LIB.BASEBOARD_FAB2(SCH_1):PAGE78
    25 M_G_DQ<20> @BASEBOARD_FAB2_LIB.BASEBOARD_FAB2(SCH_1):M_G_DQ(20)    I13 @BASEBOARD_FAB2_LIB.BASEBOARD_FAB2(SCH_1):PAGE78
   179 M_G_DQ<19> @BASEBOARD_FAB2_LIB.BASEBOARD_FAB2(SCH_1):M_G_DQ(19)    I13 @BASEBOARD_FAB2_LIB.BASEBOARD_FAB2(SCH_1):PAGE78
    34 M_G_DQ<18> @BASEBOARD_FAB2_LIB.BASEBOARD_FAB2(SCH_1):M_G_DQ(18)    I13 @BASEBOARD_FAB2_LIB.BASEBOARD_FAB2(SCH_1):PAGE78
   172 M_G_DQ<17> @BASEBOARD_FAB2_LIB.BASEBOARD_FAB2(SCH_1):M_G_DQ(17)    I13 @BASEBOARD_FAB2_LIB.BASEBOARD_FAB2(SCH_1):PAGE78
    27 M_G_DQ<16> @BASEBOARD_FAB2_LIB.BASEBOARD_FAB2(SCH_1):M_G_DQ(16)    I13 @BASEBOARD_FAB2_LIB.BASEBOARD_FAB2(SCH_1):PAGE78
   166 M_G_DQ<15> @BASEBOARD_FAB2_LIB.BASEBOARD_FAB2(SCH_1):M_G_DQ(15)    I13 @BASEBOARD_FAB2_LIB.BASEBOARD_FAB2(SCH_1):PAGE78
    21 M_G_DQ<14> @BASEBOARD_FAB2_LIB.BASEBOARD_FAB2(SCH_1):M_G_DQ(14)    I13 @BASEBOARD_FAB2_LIB.BASEBOARD_FAB2(SCH_1):PAGE78
   159 M_G_DQ<13> @BASEBOARD_FAB2_LIB.BASEBOARD_FAB2(SCH_1):M_G_DQ(13)    I13 @BASEBOARD_FAB2_LIB.BASEBOARD_FAB2(SCH_1):PAGE78
    14 M_G_DQ<12> @BASEBOARD_FAB2_LIB.BASEBOARD_FAB2(SCH_1):M_G_DQ(12)    I13 @BASEBOARD_FAB2_LIB.BASEBOARD_FAB2(SCH_1):PAGE78
   168 M_G_DQ<11> @BASEBOARD_FAB2_LIB.BASEBOARD_FAB2(SCH_1):M_G_DQ(11)    I13 @BASEBOARD_FAB2_LIB.BASEBOARD_FAB2(SCH_1):PAGE78
    23 M_G_DQ<10> @BASEBOARD_FAB2_LIB.BASEBOARD_FAB2(SCH_1):M_G_DQ(10)    I13 @BASEBOARD_FAB2_LIB.BASEBOARD_FAB2(SCH_1):PAGE78
   161 M_G_DQ<9> @BASEBOARD_FAB2_LIB.BASEBOARD_FAB2(SCH_1):M_G_DQ(9)    I13 @BASEBOARD_FAB2_LIB.BASEBOARD_FAB2(SCH_1):PAGE78
    16 M_G_DQ<8> @BASEBOARD_FAB2_LIB.BASEBOARD_FAB2(SCH_1):M_G_DQ(8)    I13 @BASEBOARD_FAB2_LIB.BASEBOARD_FAB2(SCH_1):PAGE78
   155 M_G_DQ<7> @BASEBOARD_FAB2_LIB.BASEBOARD_FAB2(SCH_1):M_G_DQ(7)    I13 @BASEBOARD_FAB2_LIB.BASEBOARD_FAB2(SCH_1):PAGE78
    10 M_G_DQ<6> @BASEBOARD_FAB2_LIB.BASEBOARD_FAB2(SCH_1):M_G_DQ(6)    I13 @BASEBOARD_FAB2_LIB.BASEBOARD_FAB2(SCH_1):PAGE78
   148 M_G_DQ<5> @BASEBOARD_FAB2_LIB.BASEBOARD_FAB2(SCH_1):M_G_DQ(5)    I13 @BASEBOARD_FAB2_LIB.BASEBOARD_FAB2(SCH_1):PAGE78
     3 M_G_DQ<4> @BASEBOARD_FAB2_LIB.BASEBOARD_FAB2(SCH_1):M_G_DQ(4)    I13 @BASEBOARD_FAB2_LIB.BASEBOARD_FAB2(SCH_1):PAGE78
   157 M_G_DQ<3> @BASEBOARD_FAB2_LIB.BASEBOARD_FAB2(SCH_1):M_G_DQ(3)    I13 @BASEBOARD_FAB2_LIB.BASEBOARD_FAB2(SCH_1):PAGE78
    12 M_G_DQ<2> @BASEBOARD_FAB2_LIB.BASEBOARD_FAB2(SCH_1):M_G_DQ(2)    I13 @BASEBOARD_FAB2_LIB.BASEBOARD_FAB2(SCH_1):PAGE78
   150 M_G_DQ<1> @BASEBOARD_FAB2_LIB.BASEBOARD_FAB2(SCH_1):M_G_DQ(1)    I13 @BASEBOARD_FAB2_LIB.BASEBOARD_FAB2(SCH_1):PAGE78
     5 M_G_DQ<0> @BASEBOARD_FAB2_LIB.BASEBOARD_FAB2(SCH_1):M_G_DQ(0)    I13 @BASEBOARD_FAB2_LIB.BASEBOARD_FAB2(SCH_1):PAGE78
    78 FM_DIMM_EVENT_COD_N @BASEBOARD_FAB2_LIB.BASEBOARD_FAB2(SCH_1):FM_DIMM_EVENT_COD_N    I13 @BASEBOARD_FAB2_LIB.BASEBOARD_FAB2(SCH_1):PAGE78
    91 M_G_ODT<3> @BASEBOARD_FAB2_LIB.BASEBOARD_FAB2(SCH_1):M_G_ODT(3)    I13 @BASEBOARD_FAB2_LIB.BASEBOARD_FAB2(SCH_1):PAGE78
    87 M_G_ODT<2> @BASEBOARD_FAB2_LIB.BASEBOARD_FAB2(SCH_1):M_G_ODT(2)    I13 @BASEBOARD_FAB2_LIB.BASEBOARD_FAB2(SCH_1):PAGE78
   222 M_G_PAR @BASEBOARD_FAB2_LIB.BASEBOARD_FAB2(SCH_1):M_G_PAR    I13 @BASEBOARD_FAB2_LIB.BASEBOARD_FAB2(SCH_1):PAGE78
    58 M_GHJ_RST_N @BASEBOARD_FAB2_LIB.BASEBOARD_FAB2(SCH_1):M_GHJ_RST_N    I13 @BASEBOARD_FAB2_LIB.BASEBOARD_FAB2(SCH_1):PAGE78
   144 TP_CH_G_DIMM0_RFU_2 @BASEBOARD_FAB2_LIB.BASEBOARD_FAB2(SCH_1):TP_CH_G_DIMM0_RFU_2    I13 @BASEBOARD_FAB2_LIB.BASEBOARD_FAB2(SCH_1):PAGE78
   227 TP_CH_G_DIMM0_RFU_1 @BASEBOARD_FAB2_LIB.BASEBOARD_FAB2(SCH_1):TP_CH_G_DIMM0_RFU_1    I13 @BASEBOARD_FAB2_LIB.BASEBOARD_FAB2(SCH_1):PAGE78
   205 TP_CH_G_DIMM0_RFU_0 @BASEBOARD_FAB2_LIB.BASEBOARD_FAB2(SCH_1):TP_CH_G_DIMM0_RFU_0    I13 @BASEBOARD_FAB2_LIB.BASEBOARD_FAB2(SCH_1):PAGE78
    84 M_G_CS_N<4> @BASEBOARD_FAB2_LIB.BASEBOARD_FAB2(SCH_1):M_G_CS_N(4)    I13 @BASEBOARD_FAB2_LIB.BASEBOARD_FAB2(SCH_1):PAGE78
    89 M_G_CS_N<5> @BASEBOARD_FAB2_LIB.BASEBOARD_FAB2(SCH_1):M_G_CS_N(5)    I13 @BASEBOARD_FAB2_LIB.BASEBOARD_FAB2(SCH_1):PAGE78
    93 M_G_CS_N<6> @BASEBOARD_FAB2_LIB.BASEBOARD_FAB2(SCH_1):M_G_CS_N(6)    I13 @BASEBOARD_FAB2_LIB.BASEBOARD_FAB2(SCH_1):PAGE78
   237 M_G_CS_N<7> @BASEBOARD_FAB2_LIB.BASEBOARD_FAB2(SCH_1):M_G_CS_N(7)    I13 @BASEBOARD_FAB2_LIB.BASEBOARD_FAB2(SCH_1):PAGE78
   238    GND @BASEBOARD_FAB2_LIB.BASEBOARD_FAB2(SCH_1):GND    I13 @BASEBOARD_FAB2_LIB.BASEBOARD_FAB2(SCH_1):PAGE78
   140    GND @BASEBOARD_FAB2_LIB.BASEBOARD_FAB2(SCH_1):GND    I13 @BASEBOARD_FAB2_LIB.BASEBOARD_FAB2(SCH_1):PAGE78
   139 PVPP_GHJ @BASEBOARD_FAB2_LIB.BASEBOARD_FAB2(SCH_1):PVPP_GHJ    I13 @BASEBOARD_FAB2_LIB.BASEBOARD_FAB2(SCH_1):PAGE78
   230 FM_ADR_COMPLETE_GHJ_N @BASEBOARD_FAB2_LIB.BASEBOARD_FAB2(SCH_1):FM_ADR_COMPLETE_GHJ_N    I13 @BASEBOARD_FAB2_LIB.BASEBOARD_FAB2(SCH_1):PAGE78
   141 SMB_DDR_GHJ_VPP_SCL @BASEBOARD_FAB2_LIB.BASEBOARD_FAB2(SCH_1):SMB_DDR_GHJ_VPP_SCL    I13 @BASEBOARD_FAB2_LIB.BASEBOARD_FAB2(SCH_1):PAGE78
   285 SMB_DDR_GHJ_VPP_SDA @BASEBOARD_FAB2_LIB.BASEBOARD_FAB2(SCH_1):SMB_DDR_GHJ_VPP_SDA    I13 @BASEBOARD_FAB2_LIB.BASEBOARD_FAB2(SCH_1):PAGE78
   284 PVPP_GHJ @BASEBOARD_FAB2_LIB.BASEBOARD_FAB2(SCH_1):PVPP_GHJ    I13 @BASEBOARD_FAB2_LIB.BASEBOARD_FAB2(SCH_1):PAGE78
   146 M_G_VREF @BASEBOARD_FAB2_LIB.BASEBOARD_FAB2(SCH_1):M_G_VREF    I13 @BASEBOARD_FAB2_LIB.BASEBOARD_FAB2(SCH_1):PAGE78
   152 M_G_DQS_DN<0> @BASEBOARD_FAB2_LIB.BASEBOARD_FAB2(SCH_1):M_G_DQS_DN(0)   I120 @BASEBOARD_FAB2_LIB.BASEBOARD_FAB2(SCH_1):PAGE78
   153 M_G_DQS_DP<0> @BASEBOARD_FAB2_LIB.BASEBOARD_FAB2(SCH_1):M_G_DQS_DP(0)   I120 @BASEBOARD_FAB2_LIB.BASEBOARD_FAB2(SCH_1):PAGE78
    19 M_G_DQS_DN<10> @BASEBOARD_FAB2_LIB.BASEBOARD_FAB2(SCH_1):M_G_DQS_DN(10)   I120 @BASEBOARD_FAB2_LIB.BASEBOARD_FAB2(SCH_1):PAGE78
    18 M_G_DQS_DP<10> @BASEBOARD_FAB2_LIB.BASEBOARD_FAB2(SCH_1):M_G_DQS_DP(10)   I120 @BASEBOARD_FAB2_LIB.BASEBOARD_FAB2(SCH_1):PAGE78
    30 M_G_DQS_DN<11> @BASEBOARD_FAB2_LIB.BASEBOARD_FAB2(SCH_1):M_G_DQS_DN(11)   I120 @BASEBOARD_FAB2_LIB.BASEBOARD_FAB2(SCH_1):PAGE78
    29 M_G_DQS_DP<11> @BASEBOARD_FAB2_LIB.BASEBOARD_FAB2(SCH_1):M_G_DQS_DP(11)   I120 @BASEBOARD_FAB2_LIB.BASEBOARD_FAB2(SCH_1):PAGE78
    41 M_G_DQS_DN<12> @BASEBOARD_FAB2_LIB.BASEBOARD_FAB2(SCH_1):M_G_DQS_DN(12)   I120 @BASEBOARD_FAB2_LIB.BASEBOARD_FAB2(SCH_1):PAGE78
    40 M_G_DQS_DP<12> @BASEBOARD_FAB2_LIB.BASEBOARD_FAB2(SCH_1):M_G_DQS_DP(12)   I120 @BASEBOARD_FAB2_LIB.BASEBOARD_FAB2(SCH_1):PAGE78
   100 M_G_DQS_DN<13> @BASEBOARD_FAB2_LIB.BASEBOARD_FAB2(SCH_1):M_G_DQS_DN(13)   I120 @BASEBOARD_FAB2_LIB.BASEBOARD_FAB2(SCH_1):PAGE78
    99 M_G_DQS_DP<13> @BASEBOARD_FAB2_LIB.BASEBOARD_FAB2(SCH_1):M_G_DQS_DP(13)   I120 @BASEBOARD_FAB2_LIB.BASEBOARD_FAB2(SCH_1):PAGE78
   111 M_G_DQS_DN<14> @BASEBOARD_FAB2_LIB.BASEBOARD_FAB2(SCH_1):M_G_DQS_DN(14)   I120 @BASEBOARD_FAB2_LIB.BASEBOARD_FAB2(SCH_1):PAGE78
   110 M_G_DQS_DP<14> @BASEBOARD_FAB2_LIB.BASEBOARD_FAB2(SCH_1):M_G_DQS_DP(14)   I120 @BASEBOARD_FAB2_LIB.BASEBOARD_FAB2(SCH_1):PAGE78
   122 M_G_DQS_DN<15> @BASEBOARD_FAB2_LIB.BASEBOARD_FAB2(SCH_1):M_G_DQS_DN(15)   I120 @BASEBOARD_FAB2_LIB.BASEBOARD_FAB2(SCH_1):PAGE78
   121 M_G_DQS_DP<15> @BASEBOARD_FAB2_LIB.BASEBOARD_FAB2(SCH_1):M_G_DQS_DP(15)   I120 @BASEBOARD_FAB2_LIB.BASEBOARD_FAB2(SCH_1):PAGE78
   133 M_G_DQS_DN<16> @BASEBOARD_FAB2_LIB.BASEBOARD_FAB2(SCH_1):M_G_DQS_DN(16)   I120 @BASEBOARD_FAB2_LIB.BASEBOARD_FAB2(SCH_1):PAGE78
   132 M_G_DQS_DP<16> @BASEBOARD_FAB2_LIB.BASEBOARD_FAB2(SCH_1):M_G_DQS_DP(16)   I120 @BASEBOARD_FAB2_LIB.BASEBOARD_FAB2(SCH_1):PAGE78
    52 M_G_DQS_DN<17> @BASEBOARD_FAB2_LIB.BASEBOARD_FAB2(SCH_1):M_G_DQS_DN(17)   I120 @BASEBOARD_FAB2_LIB.BASEBOARD_FAB2(SCH_1):PAGE78
    51 M_G_DQS_DP<17> @BASEBOARD_FAB2_LIB.BASEBOARD_FAB2(SCH_1):M_G_DQS_DP(17)   I120 @BASEBOARD_FAB2_LIB.BASEBOARD_FAB2(SCH_1):PAGE78
   163 M_G_DQS_DN<1> @BASEBOARD_FAB2_LIB.BASEBOARD_FAB2(SCH_1):M_G_DQS_DN(1)   I120 @BASEBOARD_FAB2_LIB.BASEBOARD_FAB2(SCH_1):PAGE78
   164 M_G_DQS_DP<1> @BASEBOARD_FAB2_LIB.BASEBOARD_FAB2(SCH_1):M_G_DQS_DP(1)   I120 @BASEBOARD_FAB2_LIB.BASEBOARD_FAB2(SCH_1):PAGE78
   174 M_G_DQS_DN<2> @BASEBOARD_FAB2_LIB.BASEBOARD_FAB2(SCH_1):M_G_DQS_DN(2)   I120 @BASEBOARD_FAB2_LIB.BASEBOARD_FAB2(SCH_1):PAGE78
   175 M_G_DQS_DP<2> @BASEBOARD_FAB2_LIB.BASEBOARD_FAB2(SCH_1):M_G_DQS_DP(2)   I120 @BASEBOARD_FAB2_LIB.BASEBOARD_FAB2(SCH_1):PAGE78
   185 M_G_DQS_DN<3> @BASEBOARD_FAB2_LIB.BASEBOARD_FAB2(SCH_1):M_G_DQS_DN(3)   I120 @BASEBOARD_FAB2_LIB.BASEBOARD_FAB2(SCH_1):PAGE78
   186 M_G_DQS_DP<3> @BASEBOARD_FAB2_LIB.BASEBOARD_FAB2(SCH_1):M_G_DQS_DP(3)   I120 @BASEBOARD_FAB2_LIB.BASEBOARD_FAB2(SCH_1):PAGE78
   244 M_G_DQS_DN<4> @BASEBOARD_FAB2_LIB.BASEBOARD_FAB2(SCH_1):M_G_DQS_DN(4)   I120 @BASEBOARD_FAB2_LIB.BASEBOARD_FAB2(SCH_1):PAGE78
   245 M_G_DQS_DP<4> @BASEBOARD_FAB2_LIB.BASEBOARD_FAB2(SCH_1):M_G_DQS_DP(4)   I120 @BASEBOARD_FAB2_LIB.BASEBOARD_FAB2(SCH_1):PAGE78
   255 M_G_DQS_DN<5> @BASEBOARD_FAB2_LIB.BASEBOARD_FAB2(SCH_1):M_G_DQS_DN(5)   I120 @BASEBOARD_FAB2_LIB.BASEBOARD_FAB2(SCH_1):PAGE78
   256 M_G_DQS_DP<5> @BASEBOARD_FAB2_LIB.BASEBOARD_FAB2(SCH_1):M_G_DQS_DP(5)   I120 @BASEBOARD_FAB2_LIB.BASEBOARD_FAB2(SCH_1):PAGE78
   266 M_G_DQS_DN<6> @BASEBOARD_FAB2_LIB.BASEBOARD_FAB2(SCH_1):M_G_DQS_DN(6)   I120 @BASEBOARD_FAB2_LIB.BASEBOARD_FAB2(SCH_1):PAGE78
   267 M_G_DQS_DP<6> @BASEBOARD_FAB2_LIB.BASEBOARD_FAB2(SCH_1):M_G_DQS_DP(6)   I120 @BASEBOARD_FAB2_LIB.BASEBOARD_FAB2(SCH_1):PAGE78
   277 M_G_DQS_DN<7> @BASEBOARD_FAB2_LIB.BASEBOARD_FAB2(SCH_1):M_G_DQS_DN(7)   I120 @BASEBOARD_FAB2_LIB.BASEBOARD_FAB2(SCH_1):PAGE78
   278 M_G_DQS_DP<7> @BASEBOARD_FAB2_LIB.BASEBOARD_FAB2(SCH_1):M_G_DQS_DP(7)   I120 @BASEBOARD_FAB2_LIB.BASEBOARD_FAB2(SCH_1):PAGE78
   196 M_G_DQS_DN<8> @BASEBOARD_FAB2_LIB.BASEBOARD_FAB2(SCH_1):M_G_DQS_DN(8)   I120 @BASEBOARD_FAB2_LIB.BASEBOARD_FAB2(SCH_1):PAGE78
   197 M_G_DQS_DP<8> @BASEBOARD_FAB2_LIB.BASEBOARD_FAB2(SCH_1):M_G_DQS_DP(8)   I120 @BASEBOARD_FAB2_LIB.BASEBOARD_FAB2(SCH_1):PAGE78
     8 M_G_DQS_DN<9> @BASEBOARD_FAB2_LIB.BASEBOARD_FAB2(SCH_1):M_G_DQS_DN(9)   I120 @BASEBOARD_FAB2_LIB.BASEBOARD_FAB2(SCH_1):PAGE78
     7 M_G_DQS_DP<9> @BASEBOARD_FAB2_LIB.BASEBOARD_FAB2(SCH_1):M_G_DQS_DP(9)   I120 @BASEBOARD_FAB2_LIB.BASEBOARD_FAB2(SCH_1):PAGE78
     2    GND @BASEBOARD_FAB2_LIB.BASEBOARD_FAB2(SCH_1):GND   I144 @BASEBOARD_FAB2_LIB.BASEBOARD_FAB2(SCH_1):PAGE78
     4    GND @BASEBOARD_FAB2_LIB.BASEBOARD_FAB2(SCH_1):GND   I144 @BASEBOARD_FAB2_LIB.BASEBOARD_FAB2(SCH_1):PAGE78
     6    GND @BASEBOARD_FAB2_LIB.BASEBOARD_FAB2(SCH_1):GND   I144 @BASEBOARD_FAB2_LIB.BASEBOARD_FAB2(SCH_1):PAGE78
     9    GND @BASEBOARD_FAB2_LIB.BASEBOARD_FAB2(SCH_1):GND   I144 @BASEBOARD_FAB2_LIB.BASEBOARD_FAB2(SCH_1):PAGE78
    11    GND @BASEBOARD_FAB2_LIB.BASEBOARD_FAB2(SCH_1):GND   I144 @BASEBOARD_FAB2_LIB.BASEBOARD_FAB2(SCH_1):PAGE78
    13    GND @BASEBOARD_FAB2_LIB.BASEBOARD_FAB2(SCH_1):GND   I144 @BASEBOARD_FAB2_LIB.BASEBOARD_FAB2(SCH_1):PAGE78
    15    GND @BASEBOARD_FAB2_LIB.BASEBOARD_FAB2(SCH_1):GND   I144 @BASEBOARD_FAB2_LIB.BASEBOARD_FAB2(SCH_1):PAGE78
    17    GND @BASEBOARD_FAB2_LIB.BASEBOARD_FAB2(SCH_1):GND   I144 @BASEBOARD_FAB2_LIB.BASEBOARD_FAB2(SCH_1):PAGE78
    20    GND @BASEBOARD_FAB2_LIB.BASEBOARD_FAB2(SCH_1):GND   I144 @BASEBOARD_FAB2_LIB.BASEBOARD_FAB2(SCH_1):PAGE78
    22    GND @BASEBOARD_FAB2_LIB.BASEBOARD_FAB2(SCH_1):GND   I144 @BASEBOARD_FAB2_LIB.BASEBOARD_FAB2(SCH_1):PAGE78
    24    GND @BASEBOARD_FAB2_LIB.BASEBOARD_FAB2(SCH_1):GND   I144 @BASEBOARD_FAB2_LIB.BASEBOARD_FAB2(SCH_1):PAGE78
    26    GND @BASEBOARD_FAB2_LIB.BASEBOARD_FAB2(SCH_1):GND   I144 @BASEBOARD_FAB2_LIB.BASEBOARD_FAB2(SCH_1):PAGE78
    28    GND @BASEBOARD_FAB2_LIB.BASEBOARD_FAB2(SCH_1):GND   I144 @BASEBOARD_FAB2_LIB.BASEBOARD_FAB2(SCH_1):PAGE78
    31    GND @BASEBOARD_FAB2_LIB.BASEBOARD_FAB2(SCH_1):GND   I144 @BASEBOARD_FAB2_LIB.BASEBOARD_FAB2(SCH_1):PAGE78
    33    GND @BASEBOARD_FAB2_LIB.BASEBOARD_FAB2(SCH_1):GND   I144 @BASEBOARD_FAB2_LIB.BASEBOARD_FAB2(SCH_1):PAGE78
    35    GND @BASEBOARD_FAB2_LIB.BASEBOARD_FAB2(SCH_1):GND   I144 @BASEBOARD_FAB2_LIB.BASEBOARD_FAB2(SCH_1):PAGE78
    37    GND @BASEBOARD_FAB2_LIB.BASEBOARD_FAB2(SCH_1):GND   I144 @BASEBOARD_FAB2_LIB.BASEBOARD_FAB2(SCH_1):PAGE78
    39    GND @BASEBOARD_FAB2_LIB.BASEBOARD_FAB2(SCH_1):GND   I144 @BASEBOARD_FAB2_LIB.BASEBOARD_FAB2(SCH_1):PAGE78
    42    GND @BASEBOARD_FAB2_LIB.BASEBOARD_FAB2(SCH_1):GND   I144 @BASEBOARD_FAB2_LIB.BASEBOARD_FAB2(SCH_1):PAGE78
    44    GND @BASEBOARD_FAB2_LIB.BASEBOARD_FAB2(SCH_1):GND   I144 @BASEBOARD_FAB2_LIB.BASEBOARD_FAB2(SCH_1):PAGE78
    46    GND @BASEBOARD_FAB2_LIB.BASEBOARD_FAB2(SCH_1):GND   I144 @BASEBOARD_FAB2_LIB.BASEBOARD_FAB2(SCH_1):PAGE78
    48    GND @BASEBOARD_FAB2_LIB.BASEBOARD_FAB2(SCH_1):GND   I144 @BASEBOARD_FAB2_LIB.BASEBOARD_FAB2(SCH_1):PAGE78
    50    GND @BASEBOARD_FAB2_LIB.BASEBOARD_FAB2(SCH_1):GND   I144 @BASEBOARD_FAB2_LIB.BASEBOARD_FAB2(SCH_1):PAGE78
    53    GND @BASEBOARD_FAB2_LIB.BASEBOARD_FAB2(SCH_1):GND   I144 @BASEBOARD_FAB2_LIB.BASEBOARD_FAB2(SCH_1):PAGE78
    55    GND @BASEBOARD_FAB2_LIB.BASEBOARD_FAB2(SCH_1):GND   I144 @BASEBOARD_FAB2_LIB.BASEBOARD_FAB2(SCH_1):PAGE78
    57    GND @BASEBOARD_FAB2_LIB.BASEBOARD_FAB2(SCH_1):GND   I144 @BASEBOARD_FAB2_LIB.BASEBOARD_FAB2(SCH_1):PAGE78
    94    GND @BASEBOARD_FAB2_LIB.BASEBOARD_FAB2(SCH_1):GND   I144 @BASEBOARD_FAB2_LIB.BASEBOARD_FAB2(SCH_1):PAGE78
    96    GND @BASEBOARD_FAB2_LIB.BASEBOARD_FAB2(SCH_1):GND   I144 @BASEBOARD_FAB2_LIB.BASEBOARD_FAB2(SCH_1):PAGE78
    98    GND @BASEBOARD_FAB2_LIB.BASEBOARD_FAB2(SCH_1):GND   I144 @BASEBOARD_FAB2_LIB.BASEBOARD_FAB2(SCH_1):PAGE78
   101    GND @BASEBOARD_FAB2_LIB.BASEBOARD_FAB2(SCH_1):GND   I144 @BASEBOARD_FAB2_LIB.BASEBOARD_FAB2(SCH_1):PAGE78
   103    GND @BASEBOARD_FAB2_LIB.BASEBOARD_FAB2(SCH_1):GND   I144 @BASEBOARD_FAB2_LIB.BASEBOARD_FAB2(SCH_1):PAGE78
   105    GND @BASEBOARD_FAB2_LIB.BASEBOARD_FAB2(SCH_1):GND   I144 @BASEBOARD_FAB2_LIB.BASEBOARD_FAB2(SCH_1):PAGE78
   107    GND @BASEBOARD_FAB2_LIB.BASEBOARD_FAB2(SCH_1):GND   I144 @BASEBOARD_FAB2_LIB.BASEBOARD_FAB2(SCH_1):PAGE78
   109    GND @BASEBOARD_FAB2_LIB.BASEBOARD_FAB2(SCH_1):GND   I144 @BASEBOARD_FAB2_LIB.BASEBOARD_FAB2(SCH_1):PAGE78
   112    GND @BASEBOARD_FAB2_LIB.BASEBOARD_FAB2(SCH_1):GND   I144 @BASEBOARD_FAB2_LIB.BASEBOARD_FAB2(SCH_1):PAGE78
   114    GND @BASEBOARD_FAB2_LIB.BASEBOARD_FAB2(SCH_1):GND   I144 @BASEBOARD_FAB2_LIB.BASEBOARD_FAB2(SCH_1):PAGE78
   116    GND @BASEBOARD_FAB2_LIB.BASEBOARD_FAB2(SCH_1):GND   I144 @BASEBOARD_FAB2_LIB.BASEBOARD_FAB2(SCH_1):PAGE78
   118    GND @BASEBOARD_FAB2_LIB.BASEBOARD_FAB2(SCH_1):GND   I144 @BASEBOARD_FAB2_LIB.BASEBOARD_FAB2(SCH_1):PAGE78
   120    GND @BASEBOARD_FAB2_LIB.BASEBOARD_FAB2(SCH_1):GND   I144 @BASEBOARD_FAB2_LIB.BASEBOARD_FAB2(SCH_1):PAGE78
   123    GND @BASEBOARD_FAB2_LIB.BASEBOARD_FAB2(SCH_1):GND   I144 @BASEBOARD_FAB2_LIB.BASEBOARD_FAB2(SCH_1):PAGE78
   125    GND @BASEBOARD_FAB2_LIB.BASEBOARD_FAB2(SCH_1):GND   I144 @BASEBOARD_FAB2_LIB.BASEBOARD_FAB2(SCH_1):PAGE78
   127    GND @BASEBOARD_FAB2_LIB.BASEBOARD_FAB2(SCH_1):GND   I144 @BASEBOARD_FAB2_LIB.BASEBOARD_FAB2(SCH_1):PAGE78
   129    GND @BASEBOARD_FAB2_LIB.BASEBOARD_FAB2(SCH_1):GND   I144 @BASEBOARD_FAB2_LIB.BASEBOARD_FAB2(SCH_1):PAGE78
   131    GND @BASEBOARD_FAB2_LIB.BASEBOARD_FAB2(SCH_1):GND   I144 @BASEBOARD_FAB2_LIB.BASEBOARD_FAB2(SCH_1):PAGE78
   134    GND @BASEBOARD_FAB2_LIB.BASEBOARD_FAB2(SCH_1):GND   I144 @BASEBOARD_FAB2_LIB.BASEBOARD_FAB2(SCH_1):PAGE78
   136    GND @BASEBOARD_FAB2_LIB.BASEBOARD_FAB2(SCH_1):GND   I144 @BASEBOARD_FAB2_LIB.BASEBOARD_FAB2(SCH_1):PAGE78
   138    GND @BASEBOARD_FAB2_LIB.BASEBOARD_FAB2(SCH_1):GND   I144 @BASEBOARD_FAB2_LIB.BASEBOARD_FAB2(SCH_1):PAGE78
   147    GND @BASEBOARD_FAB2_LIB.BASEBOARD_FAB2(SCH_1):GND   I144 @BASEBOARD_FAB2_LIB.BASEBOARD_FAB2(SCH_1):PAGE78
   149    GND @BASEBOARD_FAB2_LIB.BASEBOARD_FAB2(SCH_1):GND   I144 @BASEBOARD_FAB2_LIB.BASEBOARD_FAB2(SCH_1):PAGE78
   151    GND @BASEBOARD_FAB2_LIB.BASEBOARD_FAB2(SCH_1):GND   I144 @BASEBOARD_FAB2_LIB.BASEBOARD_FAB2(SCH_1):PAGE78
   154    GND @BASEBOARD_FAB2_LIB.BASEBOARD_FAB2(SCH_1):GND   I144 @BASEBOARD_FAB2_LIB.BASEBOARD_FAB2(SCH_1):PAGE78
   156    GND @BASEBOARD_FAB2_LIB.BASEBOARD_FAB2(SCH_1):GND   I144 @BASEBOARD_FAB2_LIB.BASEBOARD_FAB2(SCH_1):PAGE78
   158    GND @BASEBOARD_FAB2_LIB.BASEBOARD_FAB2(SCH_1):GND   I144 @BASEBOARD_FAB2_LIB.BASEBOARD_FAB2(SCH_1):PAGE78
   160    GND @BASEBOARD_FAB2_LIB.BASEBOARD_FAB2(SCH_1):GND   I144 @BASEBOARD_FAB2_LIB.BASEBOARD_FAB2(SCH_1):PAGE78
   162    GND @BASEBOARD_FAB2_LIB.BASEBOARD_FAB2(SCH_1):GND   I144 @BASEBOARD_FAB2_LIB.BASEBOARD_FAB2(SCH_1):PAGE78
   165    GND @BASEBOARD_FAB2_LIB.BASEBOARD_FAB2(SCH_1):GND   I144 @BASEBOARD_FAB2_LIB.BASEBOARD_FAB2(SCH_1):PAGE78
   167    GND @BASEBOARD_FAB2_LIB.BASEBOARD_FAB2(SCH_1):GND   I144 @BASEBOARD_FAB2_LIB.BASEBOARD_FAB2(SCH_1):PAGE78
   169    GND @BASEBOARD_FAB2_LIB.BASEBOARD_FAB2(SCH_1):GND   I144 @BASEBOARD_FAB2_LIB.BASEBOARD_FAB2(SCH_1):PAGE78
   171    GND @BASEBOARD_FAB2_LIB.BASEBOARD_FAB2(SCH_1):GND   I144 @BASEBOARD_FAB2_LIB.BASEBOARD_FAB2(SCH_1):PAGE78
   173    GND @BASEBOARD_FAB2_LIB.BASEBOARD_FAB2(SCH_1):GND   I144 @BASEBOARD_FAB2_LIB.BASEBOARD_FAB2(SCH_1):PAGE78
   176    GND @BASEBOARD_FAB2_LIB.BASEBOARD_FAB2(SCH_1):GND   I144 @BASEBOARD_FAB2_LIB.BASEBOARD_FAB2(SCH_1):PAGE78
   178    GND @BASEBOARD_FAB2_LIB.BASEBOARD_FAB2(SCH_1):GND   I144 @BASEBOARD_FAB2_LIB.BASEBOARD_FAB2(SCH_1):PAGE78
   180    GND @BASEBOARD_FAB2_LIB.BASEBOARD_FAB2(SCH_1):GND   I144 @BASEBOARD_FAB2_LIB.BASEBOARD_FAB2(SCH_1):PAGE78
   182    GND @BASEBOARD_FAB2_LIB.BASEBOARD_FAB2(SCH_1):GND   I144 @BASEBOARD_FAB2_LIB.BASEBOARD_FAB2(SCH_1):PAGE78
   184    GND @BASEBOARD_FAB2_LIB.BASEBOARD_FAB2(SCH_1):GND   I144 @BASEBOARD_FAB2_LIB.BASEBOARD_FAB2(SCH_1):PAGE78
   187    GND @BASEBOARD_FAB2_LIB.BASEBOARD_FAB2(SCH_1):GND   I144 @BASEBOARD_FAB2_LIB.BASEBOARD_FAB2(SCH_1):PAGE78
   189    GND @BASEBOARD_FAB2_LIB.BASEBOARD_FAB2(SCH_1):GND   I144 @BASEBOARD_FAB2_LIB.BASEBOARD_FAB2(SCH_1):PAGE78
   191    GND @BASEBOARD_FAB2_LIB.BASEBOARD_FAB2(SCH_1):GND   I144 @BASEBOARD_FAB2_LIB.BASEBOARD_FAB2(SCH_1):PAGE78
   193    GND @BASEBOARD_FAB2_LIB.BASEBOARD_FAB2(SCH_1):GND   I144 @BASEBOARD_FAB2_LIB.BASEBOARD_FAB2(SCH_1):PAGE78
   195    GND @BASEBOARD_FAB2_LIB.BASEBOARD_FAB2(SCH_1):GND   I144 @BASEBOARD_FAB2_LIB.BASEBOARD_FAB2(SCH_1):PAGE78
   198    GND @BASEBOARD_FAB2_LIB.BASEBOARD_FAB2(SCH_1):GND   I144 @BASEBOARD_FAB2_LIB.BASEBOARD_FAB2(SCH_1):PAGE78
   200    GND @BASEBOARD_FAB2_LIB.BASEBOARD_FAB2(SCH_1):GND   I144 @BASEBOARD_FAB2_LIB.BASEBOARD_FAB2(SCH_1):PAGE78
   202    GND @BASEBOARD_FAB2_LIB.BASEBOARD_FAB2(SCH_1):GND   I144 @BASEBOARD_FAB2_LIB.BASEBOARD_FAB2(SCH_1):PAGE78
   239    GND @BASEBOARD_FAB2_LIB.BASEBOARD_FAB2(SCH_1):GND   I144 @BASEBOARD_FAB2_LIB.BASEBOARD_FAB2(SCH_1):PAGE78
   241    GND @BASEBOARD_FAB2_LIB.BASEBOARD_FAB2(SCH_1):GND   I144 @BASEBOARD_FAB2_LIB.BASEBOARD_FAB2(SCH_1):PAGE78
   243    GND @BASEBOARD_FAB2_LIB.BASEBOARD_FAB2(SCH_1):GND   I144 @BASEBOARD_FAB2_LIB.BASEBOARD_FAB2(SCH_1):PAGE78
   246    GND @BASEBOARD_FAB2_LIB.BASEBOARD_FAB2(SCH_1):GND   I144 @BASEBOARD_FAB2_LIB.BASEBOARD_FAB2(SCH_1):PAGE78
   248    GND @BASEBOARD_FAB2_LIB.BASEBOARD_FAB2(SCH_1):GND   I144 @BASEBOARD_FAB2_LIB.BASEBOARD_FAB2(SCH_1):PAGE78
   250    GND @BASEBOARD_FAB2_LIB.BASEBOARD_FAB2(SCH_1):GND   I144 @BASEBOARD_FAB2_LIB.BASEBOARD_FAB2(SCH_1):PAGE78
   252    GND @BASEBOARD_FAB2_LIB.BASEBOARD_FAB2(SCH_1):GND   I144 @BASEBOARD_FAB2_LIB.BASEBOARD_FAB2(SCH_1):PAGE78
   254    GND @BASEBOARD_FAB2_LIB.BASEBOARD_FAB2(SCH_1):GND   I144 @BASEBOARD_FAB2_LIB.BASEBOARD_FAB2(SCH_1):PAGE78
   257    GND @BASEBOARD_FAB2_LIB.BASEBOARD_FAB2(SCH_1):GND   I144 @BASEBOARD_FAB2_LIB.BASEBOARD_FAB2(SCH_1):PAGE78
   259    GND @BASEBOARD_FAB2_LIB.BASEBOARD_FAB2(SCH_1):GND   I144 @BASEBOARD_FAB2_LIB.BASEBOARD_FAB2(SCH_1):PAGE78
   261    GND @BASEBOARD_FAB2_LIB.BASEBOARD_FAB2(SCH_1):GND   I144 @BASEBOARD_FAB2_LIB.BASEBOARD_FAB2(SCH_1):PAGE78
   263    GND @BASEBOARD_FAB2_LIB.BASEBOARD_FAB2(SCH_1):GND   I144 @BASEBOARD_FAB2_LIB.BASEBOARD_FAB2(SCH_1):PAGE78
   265    GND @BASEBOARD_FAB2_LIB.BASEBOARD_FAB2(SCH_1):GND   I144 @BASEBOARD_FAB2_LIB.BASEBOARD_FAB2(SCH_1):PAGE78
   268    GND @BASEBOARD_FAB2_LIB.BASEBOARD_FAB2(SCH_1):GND   I144 @BASEBOARD_FAB2_LIB.BASEBOARD_FAB2(SCH_1):PAGE78
   270    GND @BASEBOARD_FAB2_LIB.BASEBOARD_FAB2(SCH_1):GND   I144 @BASEBOARD_FAB2_LIB.BASEBOARD_FAB2(SCH_1):PAGE78
   272    GND @BASEBOARD_FAB2_LIB.BASEBOARD_FAB2(SCH_1):GND   I144 @BASEBOARD_FAB2_LIB.BASEBOARD_FAB2(SCH_1):PAGE78
   274    GND @BASEBOARD_FAB2_LIB.BASEBOARD_FAB2(SCH_1):GND   I144 @BASEBOARD_FAB2_LIB.BASEBOARD_FAB2(SCH_1):PAGE78
   276    GND @BASEBOARD_FAB2_LIB.BASEBOARD_FAB2(SCH_1):GND   I144 @BASEBOARD_FAB2_LIB.BASEBOARD_FAB2(SCH_1):PAGE78
   279    GND @BASEBOARD_FAB2_LIB.BASEBOARD_FAB2(SCH_1):GND   I144 @BASEBOARD_FAB2_LIB.BASEBOARD_FAB2(SCH_1):PAGE78
   281    GND @BASEBOARD_FAB2_LIB.BASEBOARD_FAB2(SCH_1):GND   I144 @BASEBOARD_FAB2_LIB.BASEBOARD_FAB2(SCH_1):PAGE78
   283    GND @BASEBOARD_FAB2_LIB.BASEBOARD_FAB2(SCH_1):GND   I144 @BASEBOARD_FAB2_LIB.BASEBOARD_FAB2(SCH_1):PAGE78
     1 P12V_NVDIMM_GHJ @BASEBOARD_FAB2_LIB.BASEBOARD_FAB2(SCH_1):P12V_NVDIMM_GHJ    I75 @BASEBOARD_FAB2_LIB.BASEBOARD_FAB2(SCH_1):PAGE78
   145 P12V_NVDIMM_GHJ @BASEBOARD_FAB2_LIB.BASEBOARD_FAB2(SCH_1):P12V_NVDIMM_GHJ    I75 @BASEBOARD_FAB2_LIB.BASEBOARD_FAB2(SCH_1):PAGE78
    59 PVDDQ_GHJ @BASEBOARD_FAB2_LIB.BASEBOARD_FAB2(SCH_1):PVDDQ_GHJ    I75 @BASEBOARD_FAB2_LIB.BASEBOARD_FAB2(SCH_1):PAGE78
    61 PVDDQ_GHJ @BASEBOARD_FAB2_LIB.BASEBOARD_FAB2(SCH_1):PVDDQ_GHJ    I75 @BASEBOARD_FAB2_LIB.BASEBOARD_FAB2(SCH_1):PAGE78
    64 PVDDQ_GHJ @BASEBOARD_FAB2_LIB.BASEBOARD_FAB2(SCH_1):PVDDQ_GHJ    I75 @BASEBOARD_FAB2_LIB.BASEBOARD_FAB2(SCH_1):PAGE78
    67 PVDDQ_GHJ @BASEBOARD_FAB2_LIB.BASEBOARD_FAB2(SCH_1):PVDDQ_GHJ    I75 @BASEBOARD_FAB2_LIB.BASEBOARD_FAB2(SCH_1):PAGE78
    70 PVDDQ_GHJ @BASEBOARD_FAB2_LIB.BASEBOARD_FAB2(SCH_1):PVDDQ_GHJ    I75 @BASEBOARD_FAB2_LIB.BASEBOARD_FAB2(SCH_1):PAGE78
    73 PVDDQ_GHJ @BASEBOARD_FAB2_LIB.BASEBOARD_FAB2(SCH_1):PVDDQ_GHJ    I75 @BASEBOARD_FAB2_LIB.BASEBOARD_FAB2(SCH_1):PAGE78
    76 PVDDQ_GHJ @BASEBOARD_FAB2_LIB.BASEBOARD_FAB2(SCH_1):PVDDQ_GHJ    I75 @BASEBOARD_FAB2_LIB.BASEBOARD_FAB2(SCH_1):PAGE78
    80 PVDDQ_GHJ @BASEBOARD_FAB2_LIB.BASEBOARD_FAB2(SCH_1):PVDDQ_GHJ    I75 @BASEBOARD_FAB2_LIB.BASEBOARD_FAB2(SCH_1):PAGE78
    83 PVDDQ_GHJ @BASEBOARD_FAB2_LIB.BASEBOARD_FAB2(SCH_1):PVDDQ_GHJ    I75 @BASEBOARD_FAB2_LIB.BASEBOARD_FAB2(SCH_1):PAGE78
    85 PVDDQ_GHJ @BASEBOARD_FAB2_LIB.BASEBOARD_FAB2(SCH_1):PVDDQ_GHJ    I75 @BASEBOARD_FAB2_LIB.BASEBOARD_FAB2(SCH_1):PAGE78
    88 PVDDQ_GHJ @BASEBOARD_FAB2_LIB.BASEBOARD_FAB2(SCH_1):PVDDQ_GHJ    I75 @BASEBOARD_FAB2_LIB.BASEBOARD_FAB2(SCH_1):PAGE78
    90 PVDDQ_GHJ @BASEBOARD_FAB2_LIB.BASEBOARD_FAB2(SCH_1):PVDDQ_GHJ    I75 @BASEBOARD_FAB2_LIB.BASEBOARD_FAB2(SCH_1):PAGE78
    92 PVDDQ_GHJ @BASEBOARD_FAB2_LIB.BASEBOARD_FAB2(SCH_1):PVDDQ_GHJ    I75 @BASEBOARD_FAB2_LIB.BASEBOARD_FAB2(SCH_1):PAGE78
   204 PVDDQ_GHJ @BASEBOARD_FAB2_LIB.BASEBOARD_FAB2(SCH_1):PVDDQ_GHJ    I75 @BASEBOARD_FAB2_LIB.BASEBOARD_FAB2(SCH_1):PAGE78
   206 PVDDQ_GHJ @BASEBOARD_FAB2_LIB.BASEBOARD_FAB2(SCH_1):PVDDQ_GHJ    I75 @BASEBOARD_FAB2_LIB.BASEBOARD_FAB2(SCH_1):PAGE78
   209 PVDDQ_GHJ @BASEBOARD_FAB2_LIB.BASEBOARD_FAB2(SCH_1):PVDDQ_GHJ    I75 @BASEBOARD_FAB2_LIB.BASEBOARD_FAB2(SCH_1):PAGE78
   212 PVDDQ_GHJ @BASEBOARD_FAB2_LIB.BASEBOARD_FAB2(SCH_1):PVDDQ_GHJ    I75 @BASEBOARD_FAB2_LIB.BASEBOARD_FAB2(SCH_1):PAGE78
   215 PVDDQ_GHJ @BASEBOARD_FAB2_LIB.BASEBOARD_FAB2(SCH_1):PVDDQ_GHJ    I75 @BASEBOARD_FAB2_LIB.BASEBOARD_FAB2(SCH_1):PAGE78
   217 PVDDQ_GHJ @BASEBOARD_FAB2_LIB.BASEBOARD_FAB2(SCH_1):PVDDQ_GHJ    I75 @BASEBOARD_FAB2_LIB.BASEBOARD_FAB2(SCH_1):PAGE78
   220 PVDDQ_GHJ @BASEBOARD_FAB2_LIB.BASEBOARD_FAB2(SCH_1):PVDDQ_GHJ    I75 @BASEBOARD_FAB2_LIB.BASEBOARD_FAB2(SCH_1):PAGE78
   223 PVDDQ_GHJ @BASEBOARD_FAB2_LIB.BASEBOARD_FAB2(SCH_1):PVDDQ_GHJ    I75 @BASEBOARD_FAB2_LIB.BASEBOARD_FAB2(SCH_1):PAGE78
   226 PVDDQ_GHJ @BASEBOARD_FAB2_LIB.BASEBOARD_FAB2(SCH_1):PVDDQ_GHJ    I75 @BASEBOARD_FAB2_LIB.BASEBOARD_FAB2(SCH_1):PAGE78
   229 PVDDQ_GHJ @BASEBOARD_FAB2_LIB.BASEBOARD_FAB2(SCH_1):PVDDQ_GHJ    I75 @BASEBOARD_FAB2_LIB.BASEBOARD_FAB2(SCH_1):PAGE78
   231 PVDDQ_GHJ @BASEBOARD_FAB2_LIB.BASEBOARD_FAB2(SCH_1):PVDDQ_GHJ    I75 @BASEBOARD_FAB2_LIB.BASEBOARD_FAB2(SCH_1):PAGE78
   233 PVDDQ_GHJ @BASEBOARD_FAB2_LIB.BASEBOARD_FAB2(SCH_1):PVDDQ_GHJ    I75 @BASEBOARD_FAB2_LIB.BASEBOARD_FAB2(SCH_1):PAGE78
   236 PVDDQ_GHJ @BASEBOARD_FAB2_LIB.BASEBOARD_FAB2(SCH_1):PVDDQ_GHJ    I75 @BASEBOARD_FAB2_LIB.BASEBOARD_FAB2(SCH_1):PAGE78
   142 PVPP_GHJ @BASEBOARD_FAB2_LIB.BASEBOARD_FAB2(SCH_1):PVPP_GHJ    I75 @BASEBOARD_FAB2_LIB.BASEBOARD_FAB2(SCH_1):PAGE78
   143 PVPP_GHJ @BASEBOARD_FAB2_LIB.BASEBOARD_FAB2(SCH_1):PVPP_GHJ    I75 @BASEBOARD_FAB2_LIB.BASEBOARD_FAB2(SCH_1):PAGE78
   288 PVPP_GHJ @BASEBOARD_FAB2_LIB.BASEBOARD_FAB2(SCH_1):PVPP_GHJ    I75 @BASEBOARD_FAB2_LIB.BASEBOARD_FAB2(SCH_1):PAGE78
   286 PVPP_GHJ @BASEBOARD_FAB2_LIB.BASEBOARD_FAB2(SCH_1):PVPP_GHJ    I75 @BASEBOARD_FAB2_LIB.BASEBOARD_FAB2(SCH_1):PAGE78
   287 PVPP_GHJ @BASEBOARD_FAB2_LIB.BASEBOARD_FAB2(SCH_1):PVPP_GHJ    I75 @BASEBOARD_FAB2_LIB.BASEBOARD_FAB2(SCH_1):PAGE78
    77 PVTT_GHJ @BASEBOARD_FAB2_LIB.BASEBOARD_FAB2(SCH_1):PVTT_GHJ    I75 @BASEBOARD_FAB2_LIB.BASEBOARD_FAB2(SCH_1):PAGE78
   221 PVTT_GHJ @BASEBOARD_FAB2_LIB.BASEBOARD_FAB2(SCH_1):PVTT_GHJ    I75 @BASEBOARD_FAB2_LIB.BASEBOARD_FAB2(SCH_1):PAGE78

J9U1 SCONN288_H44441003_PIP-SCONN,HA
    79 M_H_MA<0> @BASEBOARD_FAB2_LIB.BASEBOARD_FAB2(SCH_1):M_H_MA(0)    I24 @BASEBOARD_FAB2_LIB.BASEBOARD_FAB2(SCH_1):PAGE80
    72 M_H_MA<1> @BASEBOARD_FAB2_LIB.BASEBOARD_FAB2(SCH_1):M_H_MA(1)    I24 @BASEBOARD_FAB2_LIB.BASEBOARD_FAB2(SCH_1):PAGE80
   225 M_H_MA<10> @BASEBOARD_FAB2_LIB.BASEBOARD_FAB2(SCH_1):M_H_MA(10)    I24 @BASEBOARD_FAB2_LIB.BASEBOARD_FAB2(SCH_1):PAGE80
   210 M_H_MA<11> @BASEBOARD_FAB2_LIB.BASEBOARD_FAB2(SCH_1):M_H_MA(11)    I24 @BASEBOARD_FAB2_LIB.BASEBOARD_FAB2(SCH_1):PAGE80
    65 M_H_MA<12> @BASEBOARD_FAB2_LIB.BASEBOARD_FAB2(SCH_1):M_H_MA(12)    I24 @BASEBOARD_FAB2_LIB.BASEBOARD_FAB2(SCH_1):PAGE80
   232 M_H_MA<13> @BASEBOARD_FAB2_LIB.BASEBOARD_FAB2(SCH_1):M_H_MA(13)    I24 @BASEBOARD_FAB2_LIB.BASEBOARD_FAB2(SCH_1):PAGE80
   228 M_H_MA<14> @BASEBOARD_FAB2_LIB.BASEBOARD_FAB2(SCH_1):M_H_MA(14)    I24 @BASEBOARD_FAB2_LIB.BASEBOARD_FAB2(SCH_1):PAGE80
    86 M_H_MA<15> @BASEBOARD_FAB2_LIB.BASEBOARD_FAB2(SCH_1):M_H_MA(15)    I24 @BASEBOARD_FAB2_LIB.BASEBOARD_FAB2(SCH_1):PAGE80
    82 M_H_MA<16> @BASEBOARD_FAB2_LIB.BASEBOARD_FAB2(SCH_1):M_H_MA(16)    I24 @BASEBOARD_FAB2_LIB.BASEBOARD_FAB2(SCH_1):PAGE80
   234 M_H_MA<17> @BASEBOARD_FAB2_LIB.BASEBOARD_FAB2(SCH_1):M_H_MA(17)    I24 @BASEBOARD_FAB2_LIB.BASEBOARD_FAB2(SCH_1):PAGE80
   216 M_H_MA<2> @BASEBOARD_FAB2_LIB.BASEBOARD_FAB2(SCH_1):M_H_MA(2)    I24 @BASEBOARD_FAB2_LIB.BASEBOARD_FAB2(SCH_1):PAGE80
    71 M_H_MA<3> @BASEBOARD_FAB2_LIB.BASEBOARD_FAB2(SCH_1):M_H_MA(3)    I24 @BASEBOARD_FAB2_LIB.BASEBOARD_FAB2(SCH_1):PAGE80
   214 M_H_MA<4> @BASEBOARD_FAB2_LIB.BASEBOARD_FAB2(SCH_1):M_H_MA(4)    I24 @BASEBOARD_FAB2_LIB.BASEBOARD_FAB2(SCH_1):PAGE80
   213 M_H_MA<5> @BASEBOARD_FAB2_LIB.BASEBOARD_FAB2(SCH_1):M_H_MA(5)    I24 @BASEBOARD_FAB2_LIB.BASEBOARD_FAB2(SCH_1):PAGE80
    69 M_H_MA<6> @BASEBOARD_FAB2_LIB.BASEBOARD_FAB2(SCH_1):M_H_MA(6)    I24 @BASEBOARD_FAB2_LIB.BASEBOARD_FAB2(SCH_1):PAGE80
   211 M_H_MA<7> @BASEBOARD_FAB2_LIB.BASEBOARD_FAB2(SCH_1):M_H_MA(7)    I24 @BASEBOARD_FAB2_LIB.BASEBOARD_FAB2(SCH_1):PAGE80
    68 M_H_MA<8> @BASEBOARD_FAB2_LIB.BASEBOARD_FAB2(SCH_1):M_H_MA(8)    I24 @BASEBOARD_FAB2_LIB.BASEBOARD_FAB2(SCH_1):PAGE80
    66 M_H_MA<9> @BASEBOARD_FAB2_LIB.BASEBOARD_FAB2(SCH_1):M_H_MA(9)    I24 @BASEBOARD_FAB2_LIB.BASEBOARD_FAB2(SCH_1):PAGE80
    62 M_H_ACT_N @BASEBOARD_FAB2_LIB.BASEBOARD_FAB2(SCH_1):M_H_ACT_N    I24 @BASEBOARD_FAB2_LIB.BASEBOARD_FAB2(SCH_1):PAGE80
   208 M_H_ALERT_N @BASEBOARD_FAB2_LIB.BASEBOARD_FAB2(SCH_1):M_H_ALERT_N    I24 @BASEBOARD_FAB2_LIB.BASEBOARD_FAB2(SCH_1):PAGE80
   224 M_H_BA<1> @BASEBOARD_FAB2_LIB.BASEBOARD_FAB2(SCH_1):M_H_BA(1)    I24 @BASEBOARD_FAB2_LIB.BASEBOARD_FAB2(SCH_1):PAGE80
    81 M_H_BA<0> @BASEBOARD_FAB2_LIB.BASEBOARD_FAB2(SCH_1):M_H_BA(0)    I24 @BASEBOARD_FAB2_LIB.BASEBOARD_FAB2(SCH_1):PAGE80
   207 M_H_BG<1> @BASEBOARD_FAB2_LIB.BASEBOARD_FAB2(SCH_1):M_H_BG(1)    I24 @BASEBOARD_FAB2_LIB.BASEBOARD_FAB2(SCH_1):PAGE80
    63 M_H_BG<0> @BASEBOARD_FAB2_LIB.BASEBOARD_FAB2(SCH_1):M_H_BG(0)    I24 @BASEBOARD_FAB2_LIB.BASEBOARD_FAB2(SCH_1):PAGE80
   235 M_H_C<2> @BASEBOARD_FAB2_LIB.BASEBOARD_FAB2(SCH_1):M_H_C(2)    I24 @BASEBOARD_FAB2_LIB.BASEBOARD_FAB2(SCH_1):PAGE80
   199 M_H_ECC<7> @BASEBOARD_FAB2_LIB.BASEBOARD_FAB2(SCH_1):M_H_ECC(7)    I24 @BASEBOARD_FAB2_LIB.BASEBOARD_FAB2(SCH_1):PAGE80
    54 M_H_ECC<6> @BASEBOARD_FAB2_LIB.BASEBOARD_FAB2(SCH_1):M_H_ECC(6)    I24 @BASEBOARD_FAB2_LIB.BASEBOARD_FAB2(SCH_1):PAGE80
   192 M_H_ECC<5> @BASEBOARD_FAB2_LIB.BASEBOARD_FAB2(SCH_1):M_H_ECC(5)    I24 @BASEBOARD_FAB2_LIB.BASEBOARD_FAB2(SCH_1):PAGE80
    47 M_H_ECC<4> @BASEBOARD_FAB2_LIB.BASEBOARD_FAB2(SCH_1):M_H_ECC(4)    I24 @BASEBOARD_FAB2_LIB.BASEBOARD_FAB2(SCH_1):PAGE80
   201 M_H_ECC<3> @BASEBOARD_FAB2_LIB.BASEBOARD_FAB2(SCH_1):M_H_ECC(3)    I24 @BASEBOARD_FAB2_LIB.BASEBOARD_FAB2(SCH_1):PAGE80
    56 M_H_ECC<2> @BASEBOARD_FAB2_LIB.BASEBOARD_FAB2(SCH_1):M_H_ECC(2)    I24 @BASEBOARD_FAB2_LIB.BASEBOARD_FAB2(SCH_1):PAGE80
   194 M_H_ECC<1> @BASEBOARD_FAB2_LIB.BASEBOARD_FAB2(SCH_1):M_H_ECC(1)    I24 @BASEBOARD_FAB2_LIB.BASEBOARD_FAB2(SCH_1):PAGE80
    49 M_H_ECC<0> @BASEBOARD_FAB2_LIB.BASEBOARD_FAB2(SCH_1):M_H_ECC(0)    I24 @BASEBOARD_FAB2_LIB.BASEBOARD_FAB2(SCH_1):PAGE80
    75 M_H_CLK_DN<2> @BASEBOARD_FAB2_LIB.BASEBOARD_FAB2(SCH_1):M_H_CLK_DN(2)    I24 @BASEBOARD_FAB2_LIB.BASEBOARD_FAB2(SCH_1):PAGE80
    74 M_H_CLK_DP<2> @BASEBOARD_FAB2_LIB.BASEBOARD_FAB2(SCH_1):M_H_CLK_DP(2)    I24 @BASEBOARD_FAB2_LIB.BASEBOARD_FAB2(SCH_1):PAGE80
   219 M_H_CLK_DN<3> @BASEBOARD_FAB2_LIB.BASEBOARD_FAB2(SCH_1):M_H_CLK_DN(3)    I24 @BASEBOARD_FAB2_LIB.BASEBOARD_FAB2(SCH_1):PAGE80
   218 M_H_CLK_DP<3> @BASEBOARD_FAB2_LIB.BASEBOARD_FAB2(SCH_1):M_H_CLK_DP(3)    I24 @BASEBOARD_FAB2_LIB.BASEBOARD_FAB2(SCH_1):PAGE80
   203 M_H_CKE<3> @BASEBOARD_FAB2_LIB.BASEBOARD_FAB2(SCH_1):M_H_CKE(3)    I24 @BASEBOARD_FAB2_LIB.BASEBOARD_FAB2(SCH_1):PAGE80
    60 M_H_CKE<2> @BASEBOARD_FAB2_LIB.BASEBOARD_FAB2(SCH_1):M_H_CKE(2)    I24 @BASEBOARD_FAB2_LIB.BASEBOARD_FAB2(SCH_1):PAGE80
   280 M_H_DQ<63> @BASEBOARD_FAB2_LIB.BASEBOARD_FAB2(SCH_1):M_H_DQ(63)    I24 @BASEBOARD_FAB2_LIB.BASEBOARD_FAB2(SCH_1):PAGE80
   135 M_H_DQ<62> @BASEBOARD_FAB2_LIB.BASEBOARD_FAB2(SCH_1):M_H_DQ(62)    I24 @BASEBOARD_FAB2_LIB.BASEBOARD_FAB2(SCH_1):PAGE80
   273 M_H_DQ<61> @BASEBOARD_FAB2_LIB.BASEBOARD_FAB2(SCH_1):M_H_DQ(61)    I24 @BASEBOARD_FAB2_LIB.BASEBOARD_FAB2(SCH_1):PAGE80
   128 M_H_DQ<60> @BASEBOARD_FAB2_LIB.BASEBOARD_FAB2(SCH_1):M_H_DQ(60)    I24 @BASEBOARD_FAB2_LIB.BASEBOARD_FAB2(SCH_1):PAGE80
   282 M_H_DQ<59> @BASEBOARD_FAB2_LIB.BASEBOARD_FAB2(SCH_1):M_H_DQ(59)    I24 @BASEBOARD_FAB2_LIB.BASEBOARD_FAB2(SCH_1):PAGE80
   137 M_H_DQ<58> @BASEBOARD_FAB2_LIB.BASEBOARD_FAB2(SCH_1):M_H_DQ(58)    I24 @BASEBOARD_FAB2_LIB.BASEBOARD_FAB2(SCH_1):PAGE80
   275 M_H_DQ<57> @BASEBOARD_FAB2_LIB.BASEBOARD_FAB2(SCH_1):M_H_DQ(57)    I24 @BASEBOARD_FAB2_LIB.BASEBOARD_FAB2(SCH_1):PAGE80
   130 M_H_DQ<56> @BASEBOARD_FAB2_LIB.BASEBOARD_FAB2(SCH_1):M_H_DQ(56)    I24 @BASEBOARD_FAB2_LIB.BASEBOARD_FAB2(SCH_1):PAGE80
   269 M_H_DQ<55> @BASEBOARD_FAB2_LIB.BASEBOARD_FAB2(SCH_1):M_H_DQ(55)    I24 @BASEBOARD_FAB2_LIB.BASEBOARD_FAB2(SCH_1):PAGE80
   124 M_H_DQ<54> @BASEBOARD_FAB2_LIB.BASEBOARD_FAB2(SCH_1):M_H_DQ(54)    I24 @BASEBOARD_FAB2_LIB.BASEBOARD_FAB2(SCH_1):PAGE80
   262 M_H_DQ<53> @BASEBOARD_FAB2_LIB.BASEBOARD_FAB2(SCH_1):M_H_DQ(53)    I24 @BASEBOARD_FAB2_LIB.BASEBOARD_FAB2(SCH_1):PAGE80
   117 M_H_DQ<52> @BASEBOARD_FAB2_LIB.BASEBOARD_FAB2(SCH_1):M_H_DQ(52)    I24 @BASEBOARD_FAB2_LIB.BASEBOARD_FAB2(SCH_1):PAGE80
   271 M_H_DQ<51> @BASEBOARD_FAB2_LIB.BASEBOARD_FAB2(SCH_1):M_H_DQ(51)    I24 @BASEBOARD_FAB2_LIB.BASEBOARD_FAB2(SCH_1):PAGE80
   126 M_H_DQ<50> @BASEBOARD_FAB2_LIB.BASEBOARD_FAB2(SCH_1):M_H_DQ(50)    I24 @BASEBOARD_FAB2_LIB.BASEBOARD_FAB2(SCH_1):PAGE80
   264 M_H_DQ<49> @BASEBOARD_FAB2_LIB.BASEBOARD_FAB2(SCH_1):M_H_DQ(49)    I24 @BASEBOARD_FAB2_LIB.BASEBOARD_FAB2(SCH_1):PAGE80
   119 M_H_DQ<48> @BASEBOARD_FAB2_LIB.BASEBOARD_FAB2(SCH_1):M_H_DQ(48)    I24 @BASEBOARD_FAB2_LIB.BASEBOARD_FAB2(SCH_1):PAGE80
   258 M_H_DQ<47> @BASEBOARD_FAB2_LIB.BASEBOARD_FAB2(SCH_1):M_H_DQ(47)    I24 @BASEBOARD_FAB2_LIB.BASEBOARD_FAB2(SCH_1):PAGE80
   113 M_H_DQ<46> @BASEBOARD_FAB2_LIB.BASEBOARD_FAB2(SCH_1):M_H_DQ(46)    I24 @BASEBOARD_FAB2_LIB.BASEBOARD_FAB2(SCH_1):PAGE80
   251 M_H_DQ<45> @BASEBOARD_FAB2_LIB.BASEBOARD_FAB2(SCH_1):M_H_DQ(45)    I24 @BASEBOARD_FAB2_LIB.BASEBOARD_FAB2(SCH_1):PAGE80
   106 M_H_DQ<44> @BASEBOARD_FAB2_LIB.BASEBOARD_FAB2(SCH_1):M_H_DQ(44)    I24 @BASEBOARD_FAB2_LIB.BASEBOARD_FAB2(SCH_1):PAGE80
   260 M_H_DQ<43> @BASEBOARD_FAB2_LIB.BASEBOARD_FAB2(SCH_1):M_H_DQ(43)    I24 @BASEBOARD_FAB2_LIB.BASEBOARD_FAB2(SCH_1):PAGE80
   115 M_H_DQ<42> @BASEBOARD_FAB2_LIB.BASEBOARD_FAB2(SCH_1):M_H_DQ(42)    I24 @BASEBOARD_FAB2_LIB.BASEBOARD_FAB2(SCH_1):PAGE80
   253 M_H_DQ<41> @BASEBOARD_FAB2_LIB.BASEBOARD_FAB2(SCH_1):M_H_DQ(41)    I24 @BASEBOARD_FAB2_LIB.BASEBOARD_FAB2(SCH_1):PAGE80
   108 M_H_DQ<40> @BASEBOARD_FAB2_LIB.BASEBOARD_FAB2(SCH_1):M_H_DQ(40)    I24 @BASEBOARD_FAB2_LIB.BASEBOARD_FAB2(SCH_1):PAGE80
   247 M_H_DQ<39> @BASEBOARD_FAB2_LIB.BASEBOARD_FAB2(SCH_1):M_H_DQ(39)    I24 @BASEBOARD_FAB2_LIB.BASEBOARD_FAB2(SCH_1):PAGE80
   102 M_H_DQ<38> @BASEBOARD_FAB2_LIB.BASEBOARD_FAB2(SCH_1):M_H_DQ(38)    I24 @BASEBOARD_FAB2_LIB.BASEBOARD_FAB2(SCH_1):PAGE80
   240 M_H_DQ<37> @BASEBOARD_FAB2_LIB.BASEBOARD_FAB2(SCH_1):M_H_DQ(37)    I24 @BASEBOARD_FAB2_LIB.BASEBOARD_FAB2(SCH_1):PAGE80
    95 M_H_DQ<36> @BASEBOARD_FAB2_LIB.BASEBOARD_FAB2(SCH_1):M_H_DQ(36)    I24 @BASEBOARD_FAB2_LIB.BASEBOARD_FAB2(SCH_1):PAGE80
   249 M_H_DQ<35> @BASEBOARD_FAB2_LIB.BASEBOARD_FAB2(SCH_1):M_H_DQ(35)    I24 @BASEBOARD_FAB2_LIB.BASEBOARD_FAB2(SCH_1):PAGE80
   104 M_H_DQ<34> @BASEBOARD_FAB2_LIB.BASEBOARD_FAB2(SCH_1):M_H_DQ(34)    I24 @BASEBOARD_FAB2_LIB.BASEBOARD_FAB2(SCH_1):PAGE80
   242 M_H_DQ<33> @BASEBOARD_FAB2_LIB.BASEBOARD_FAB2(SCH_1):M_H_DQ(33)    I24 @BASEBOARD_FAB2_LIB.BASEBOARD_FAB2(SCH_1):PAGE80
    97 M_H_DQ<32> @BASEBOARD_FAB2_LIB.BASEBOARD_FAB2(SCH_1):M_H_DQ(32)    I24 @BASEBOARD_FAB2_LIB.BASEBOARD_FAB2(SCH_1):PAGE80
   188 M_H_DQ<31> @BASEBOARD_FAB2_LIB.BASEBOARD_FAB2(SCH_1):M_H_DQ(31)    I24 @BASEBOARD_FAB2_LIB.BASEBOARD_FAB2(SCH_1):PAGE80
    43 M_H_DQ<30> @BASEBOARD_FAB2_LIB.BASEBOARD_FAB2(SCH_1):M_H_DQ(30)    I24 @BASEBOARD_FAB2_LIB.BASEBOARD_FAB2(SCH_1):PAGE80
   181 M_H_DQ<29> @BASEBOARD_FAB2_LIB.BASEBOARD_FAB2(SCH_1):M_H_DQ(29)    I24 @BASEBOARD_FAB2_LIB.BASEBOARD_FAB2(SCH_1):PAGE80
    36 M_H_DQ<28> @BASEBOARD_FAB2_LIB.BASEBOARD_FAB2(SCH_1):M_H_DQ(28)    I24 @BASEBOARD_FAB2_LIB.BASEBOARD_FAB2(SCH_1):PAGE80
   190 M_H_DQ<27> @BASEBOARD_FAB2_LIB.BASEBOARD_FAB2(SCH_1):M_H_DQ(27)    I24 @BASEBOARD_FAB2_LIB.BASEBOARD_FAB2(SCH_1):PAGE80
    45 M_H_DQ<26> @BASEBOARD_FAB2_LIB.BASEBOARD_FAB2(SCH_1):M_H_DQ(26)    I24 @BASEBOARD_FAB2_LIB.BASEBOARD_FAB2(SCH_1):PAGE80
   183 M_H_DQ<25> @BASEBOARD_FAB2_LIB.BASEBOARD_FAB2(SCH_1):M_H_DQ(25)    I24 @BASEBOARD_FAB2_LIB.BASEBOARD_FAB2(SCH_1):PAGE80
    38 M_H_DQ<24> @BASEBOARD_FAB2_LIB.BASEBOARD_FAB2(SCH_1):M_H_DQ(24)    I24 @BASEBOARD_FAB2_LIB.BASEBOARD_FAB2(SCH_1):PAGE80
   177 M_H_DQ<23> @BASEBOARD_FAB2_LIB.BASEBOARD_FAB2(SCH_1):M_H_DQ(23)    I24 @BASEBOARD_FAB2_LIB.BASEBOARD_FAB2(SCH_1):PAGE80
    32 M_H_DQ<22> @BASEBOARD_FAB2_LIB.BASEBOARD_FAB2(SCH_1):M_H_DQ(22)    I24 @BASEBOARD_FAB2_LIB.BASEBOARD_FAB2(SCH_1):PAGE80
   170 M_H_DQ<21> @BASEBOARD_FAB2_LIB.BASEBOARD_FAB2(SCH_1):M_H_DQ(21)    I24 @BASEBOARD_FAB2_LIB.BASEBOARD_FAB2(SCH_1):PAGE80
    25 M_H_DQ<20> @BASEBOARD_FAB2_LIB.BASEBOARD_FAB2(SCH_1):M_H_DQ(20)    I24 @BASEBOARD_FAB2_LIB.BASEBOARD_FAB2(SCH_1):PAGE80
   179 M_H_DQ<19> @BASEBOARD_FAB2_LIB.BASEBOARD_FAB2(SCH_1):M_H_DQ(19)    I24 @BASEBOARD_FAB2_LIB.BASEBOARD_FAB2(SCH_1):PAGE80
    34 M_H_DQ<18> @BASEBOARD_FAB2_LIB.BASEBOARD_FAB2(SCH_1):M_H_DQ(18)    I24 @BASEBOARD_FAB2_LIB.BASEBOARD_FAB2(SCH_1):PAGE80
   172 M_H_DQ<17> @BASEBOARD_FAB2_LIB.BASEBOARD_FAB2(SCH_1):M_H_DQ(17)    I24 @BASEBOARD_FAB2_LIB.BASEBOARD_FAB2(SCH_1):PAGE80
    27 M_H_DQ<16> @BASEBOARD_FAB2_LIB.BASEBOARD_FAB2(SCH_1):M_H_DQ(16)    I24 @BASEBOARD_FAB2_LIB.BASEBOARD_FAB2(SCH_1):PAGE80
   166 M_H_DQ<15> @BASEBOARD_FAB2_LIB.BASEBOARD_FAB2(SCH_1):M_H_DQ(15)    I24 @BASEBOARD_FAB2_LIB.BASEBOARD_FAB2(SCH_1):PAGE80
    21 M_H_DQ<14> @BASEBOARD_FAB2_LIB.BASEBOARD_FAB2(SCH_1):M_H_DQ(14)    I24 @BASEBOARD_FAB2_LIB.BASEBOARD_FAB2(SCH_1):PAGE80
   159 M_H_DQ<13> @BASEBOARD_FAB2_LIB.BASEBOARD_FAB2(SCH_1):M_H_DQ(13)    I24 @BASEBOARD_FAB2_LIB.BASEBOARD_FAB2(SCH_1):PAGE80
    14 M_H_DQ<12> @BASEBOARD_FAB2_LIB.BASEBOARD_FAB2(SCH_1):M_H_DQ(12)    I24 @BASEBOARD_FAB2_LIB.BASEBOARD_FAB2(SCH_1):PAGE80
   168 M_H_DQ<11> @BASEBOARD_FAB2_LIB.BASEBOARD_FAB2(SCH_1):M_H_DQ(11)    I24 @BASEBOARD_FAB2_LIB.BASEBOARD_FAB2(SCH_1):PAGE80
    23 M_H_DQ<10> @BASEBOARD_FAB2_LIB.BASEBOARD_FAB2(SCH_1):M_H_DQ(10)    I24 @BASEBOARD_FAB2_LIB.BASEBOARD_FAB2(SCH_1):PAGE80
   161 M_H_DQ<9> @BASEBOARD_FAB2_LIB.BASEBOARD_FAB2(SCH_1):M_H_DQ(9)    I24 @BASEBOARD_FAB2_LIB.BASEBOARD_FAB2(SCH_1):PAGE80
    16 M_H_DQ<8> @BASEBOARD_FAB2_LIB.BASEBOARD_FAB2(SCH_1):M_H_DQ(8)    I24 @BASEBOARD_FAB2_LIB.BASEBOARD_FAB2(SCH_1):PAGE80
   155 M_H_DQ<7> @BASEBOARD_FAB2_LIB.BASEBOARD_FAB2(SCH_1):M_H_DQ(7)    I24 @BASEBOARD_FAB2_LIB.BASEBOARD_FAB2(SCH_1):PAGE80
    10 M_H_DQ<6> @BASEBOARD_FAB2_LIB.BASEBOARD_FAB2(SCH_1):M_H_DQ(6)    I24 @BASEBOARD_FAB2_LIB.BASEBOARD_FAB2(SCH_1):PAGE80
   148 M_H_DQ<5> @BASEBOARD_FAB2_LIB.BASEBOARD_FAB2(SCH_1):M_H_DQ(5)    I24 @BASEBOARD_FAB2_LIB.BASEBOARD_FAB2(SCH_1):PAGE80
     3 M_H_DQ<4> @BASEBOARD_FAB2_LIB.BASEBOARD_FAB2(SCH_1):M_H_DQ(4)    I24 @BASEBOARD_FAB2_LIB.BASEBOARD_FAB2(SCH_1):PAGE80
   157 M_H_DQ<3> @BASEBOARD_FAB2_LIB.BASEBOARD_FAB2(SCH_1):M_H_DQ(3)    I24 @BASEBOARD_FAB2_LIB.BASEBOARD_FAB2(SCH_1):PAGE80
    12 M_H_DQ<2> @BASEBOARD_FAB2_LIB.BASEBOARD_FAB2(SCH_1):M_H_DQ(2)    I24 @BASEBOARD_FAB2_LIB.BASEBOARD_FAB2(SCH_1):PAGE80
   150 M_H_DQ<1> @BASEBOARD_FAB2_LIB.BASEBOARD_FAB2(SCH_1):M_H_DQ(1)    I24 @BASEBOARD_FAB2_LIB.BASEBOARD_FAB2(SCH_1):PAGE80
     5 M_H_DQ<0> @BASEBOARD_FAB2_LIB.BASEBOARD_FAB2(SCH_1):M_H_DQ(0)    I24 @BASEBOARD_FAB2_LIB.BASEBOARD_FAB2(SCH_1):PAGE80
    78 FM_DIMM_EVENT_COD_N @BASEBOARD_FAB2_LIB.BASEBOARD_FAB2(SCH_1):FM_DIMM_EVENT_COD_N    I24 @BASEBOARD_FAB2_LIB.BASEBOARD_FAB2(SCH_1):PAGE80
    91 M_H_ODT<3> @BASEBOARD_FAB2_LIB.BASEBOARD_FAB2(SCH_1):M_H_ODT(3)    I24 @BASEBOARD_FAB2_LIB.BASEBOARD_FAB2(SCH_1):PAGE80
    87 M_H_ODT<2> @BASEBOARD_FAB2_LIB.BASEBOARD_FAB2(SCH_1):M_H_ODT(2)    I24 @BASEBOARD_FAB2_LIB.BASEBOARD_FAB2(SCH_1):PAGE80
   222 M_H_PAR @BASEBOARD_FAB2_LIB.BASEBOARD_FAB2(SCH_1):M_H_PAR    I24 @BASEBOARD_FAB2_LIB.BASEBOARD_FAB2(SCH_1):PAGE80
    58 M_GHJ_RST_N @BASEBOARD_FAB2_LIB.BASEBOARD_FAB2(SCH_1):M_GHJ_RST_N    I24 @BASEBOARD_FAB2_LIB.BASEBOARD_FAB2(SCH_1):PAGE80
   144 TP_CH_H_DIMM0_RFU_2 @BASEBOARD_FAB2_LIB.BASEBOARD_FAB2(SCH_1):TP_CH_H_DIMM0_RFU_2    I24 @BASEBOARD_FAB2_LIB.BASEBOARD_FAB2(SCH_1):PAGE80
   227 TP_CH_H_DIMM0_RFU_1 @BASEBOARD_FAB2_LIB.BASEBOARD_FAB2(SCH_1):TP_CH_H_DIMM0_RFU_1    I24 @BASEBOARD_FAB2_LIB.BASEBOARD_FAB2(SCH_1):PAGE80
   205 TP_CH_H_DIMM0_RFU_0 @BASEBOARD_FAB2_LIB.BASEBOARD_FAB2(SCH_1):TP_CH_H_DIMM0_RFU_0    I24 @BASEBOARD_FAB2_LIB.BASEBOARD_FAB2(SCH_1):PAGE80
    84 M_H_CS_N<4> @BASEBOARD_FAB2_LIB.BASEBOARD_FAB2(SCH_1):M_H_CS_N(4)    I24 @BASEBOARD_FAB2_LIB.BASEBOARD_FAB2(SCH_1):PAGE80
    89 M_H_CS_N<5> @BASEBOARD_FAB2_LIB.BASEBOARD_FAB2(SCH_1):M_H_CS_N(5)    I24 @BASEBOARD_FAB2_LIB.BASEBOARD_FAB2(SCH_1):PAGE80
    93 M_H_CS_N<6> @BASEBOARD_FAB2_LIB.BASEBOARD_FAB2(SCH_1):M_H_CS_N(6)    I24 @BASEBOARD_FAB2_LIB.BASEBOARD_FAB2(SCH_1):PAGE80
   237 M_H_CS_N<7> @BASEBOARD_FAB2_LIB.BASEBOARD_FAB2(SCH_1):M_H_CS_N(7)    I24 @BASEBOARD_FAB2_LIB.BASEBOARD_FAB2(SCH_1):PAGE80
   238    GND @BASEBOARD_FAB2_LIB.BASEBOARD_FAB2(SCH_1):GND    I24 @BASEBOARD_FAB2_LIB.BASEBOARD_FAB2(SCH_1):PAGE80
   140 PVPP_GHJ @BASEBOARD_FAB2_LIB.BASEBOARD_FAB2(SCH_1):PVPP_GHJ    I24 @BASEBOARD_FAB2_LIB.BASEBOARD_FAB2(SCH_1):PAGE80
   139 PVPP_GHJ @BASEBOARD_FAB2_LIB.BASEBOARD_FAB2(SCH_1):PVPP_GHJ    I24 @BASEBOARD_FAB2_LIB.BASEBOARD_FAB2(SCH_1):PAGE80
   230 FM_ADR_COMPLETE_GHJ_N @BASEBOARD_FAB2_LIB.BASEBOARD_FAB2(SCH_1):FM_ADR_COMPLETE_GHJ_N    I24 @BASEBOARD_FAB2_LIB.BASEBOARD_FAB2(SCH_1):PAGE80
   141 SMB_DDR_GHJ_VPP_SCL @BASEBOARD_FAB2_LIB.BASEBOARD_FAB2(SCH_1):SMB_DDR_GHJ_VPP_SCL    I24 @BASEBOARD_FAB2_LIB.BASEBOARD_FAB2(SCH_1):PAGE80
   285 SMB_DDR_GHJ_VPP_SDA @BASEBOARD_FAB2_LIB.BASEBOARD_FAB2(SCH_1):SMB_DDR_GHJ_VPP_SDA    I24 @BASEBOARD_FAB2_LIB.BASEBOARD_FAB2(SCH_1):PAGE80
   284 PVPP_GHJ @BASEBOARD_FAB2_LIB.BASEBOARD_FAB2(SCH_1):PVPP_GHJ    I24 @BASEBOARD_FAB2_LIB.BASEBOARD_FAB2(SCH_1):PAGE80
   146 M_H_VREF @BASEBOARD_FAB2_LIB.BASEBOARD_FAB2(SCH_1):M_H_VREF    I24 @BASEBOARD_FAB2_LIB.BASEBOARD_FAB2(SCH_1):PAGE80
   152 M_H_DQS_DN<0> @BASEBOARD_FAB2_LIB.BASEBOARD_FAB2(SCH_1):M_H_DQS_DN(0)   I101 @BASEBOARD_FAB2_LIB.BASEBOARD_FAB2(SCH_1):PAGE80
   153 M_H_DQS_DP<0> @BASEBOARD_FAB2_LIB.BASEBOARD_FAB2(SCH_1):M_H_DQS_DP(0)   I101 @BASEBOARD_FAB2_LIB.BASEBOARD_FAB2(SCH_1):PAGE80
    19 M_H_DQS_DN<10> @BASEBOARD_FAB2_LIB.BASEBOARD_FAB2(SCH_1):M_H_DQS_DN(10)   I101 @BASEBOARD_FAB2_LIB.BASEBOARD_FAB2(SCH_1):PAGE80
    18 M_H_DQS_DP<10> @BASEBOARD_FAB2_LIB.BASEBOARD_FAB2(SCH_1):M_H_DQS_DP(10)   I101 @BASEBOARD_FAB2_LIB.BASEBOARD_FAB2(SCH_1):PAGE80
    30 M_H_DQS_DN<11> @BASEBOARD_FAB2_LIB.BASEBOARD_FAB2(SCH_1):M_H_DQS_DN(11)   I101 @BASEBOARD_FAB2_LIB.BASEBOARD_FAB2(SCH_1):PAGE80
    29 M_H_DQS_DP<11> @BASEBOARD_FAB2_LIB.BASEBOARD_FAB2(SCH_1):M_H_DQS_DP(11)   I101 @BASEBOARD_FAB2_LIB.BASEBOARD_FAB2(SCH_1):PAGE80
    41 M_H_DQS_DN<12> @BASEBOARD_FAB2_LIB.BASEBOARD_FAB2(SCH_1):M_H_DQS_DN(12)   I101 @BASEBOARD_FAB2_LIB.BASEBOARD_FAB2(SCH_1):PAGE80
    40 M_H_DQS_DP<12> @BASEBOARD_FAB2_LIB.BASEBOARD_FAB2(SCH_1):M_H_DQS_DP(12)   I101 @BASEBOARD_FAB2_LIB.BASEBOARD_FAB2(SCH_1):PAGE80
   100 M_H_DQS_DN<13> @BASEBOARD_FAB2_LIB.BASEBOARD_FAB2(SCH_1):M_H_DQS_DN(13)   I101 @BASEBOARD_FAB2_LIB.BASEBOARD_FAB2(SCH_1):PAGE80
    99 M_H_DQS_DP<13> @BASEBOARD_FAB2_LIB.BASEBOARD_FAB2(SCH_1):M_H_DQS_DP(13)   I101 @BASEBOARD_FAB2_LIB.BASEBOARD_FAB2(SCH_1):PAGE80
   111 M_H_DQS_DN<14> @BASEBOARD_FAB2_LIB.BASEBOARD_FAB2(SCH_1):M_H_DQS_DN(14)   I101 @BASEBOARD_FAB2_LIB.BASEBOARD_FAB2(SCH_1):PAGE80
   110 M_H_DQS_DP<14> @BASEBOARD_FAB2_LIB.BASEBOARD_FAB2(SCH_1):M_H_DQS_DP(14)   I101 @BASEBOARD_FAB2_LIB.BASEBOARD_FAB2(SCH_1):PAGE80
   122 M_H_DQS_DN<15> @BASEBOARD_FAB2_LIB.BASEBOARD_FAB2(SCH_1):M_H_DQS_DN(15)   I101 @BASEBOARD_FAB2_LIB.BASEBOARD_FAB2(SCH_1):PAGE80
   121 M_H_DQS_DP<15> @BASEBOARD_FAB2_LIB.BASEBOARD_FAB2(SCH_1):M_H_DQS_DP(15)   I101 @BASEBOARD_FAB2_LIB.BASEBOARD_FAB2(SCH_1):PAGE80
   133 M_H_DQS_DN<16> @BASEBOARD_FAB2_LIB.BASEBOARD_FAB2(SCH_1):M_H_DQS_DN(16)   I101 @BASEBOARD_FAB2_LIB.BASEBOARD_FAB2(SCH_1):PAGE80
   132 M_H_DQS_DP<16> @BASEBOARD_FAB2_LIB.BASEBOARD_FAB2(SCH_1):M_H_DQS_DP(16)   I101 @BASEBOARD_FAB2_LIB.BASEBOARD_FAB2(SCH_1):PAGE80
    52 M_H_DQS_DN<17> @BASEBOARD_FAB2_LIB.BASEBOARD_FAB2(SCH_1):M_H_DQS_DN(17)   I101 @BASEBOARD_FAB2_LIB.BASEBOARD_FAB2(SCH_1):PAGE80
    51 M_H_DQS_DP<17> @BASEBOARD_FAB2_LIB.BASEBOARD_FAB2(SCH_1):M_H_DQS_DP(17)   I101 @BASEBOARD_FAB2_LIB.BASEBOARD_FAB2(SCH_1):PAGE80
   163 M_H_DQS_DN<1> @BASEBOARD_FAB2_LIB.BASEBOARD_FAB2(SCH_1):M_H_DQS_DN(1)   I101 @BASEBOARD_FAB2_LIB.BASEBOARD_FAB2(SCH_1):PAGE80
   164 M_H_DQS_DP<1> @BASEBOARD_FAB2_LIB.BASEBOARD_FAB2(SCH_1):M_H_DQS_DP(1)   I101 @BASEBOARD_FAB2_LIB.BASEBOARD_FAB2(SCH_1):PAGE80
   174 M_H_DQS_DN<2> @BASEBOARD_FAB2_LIB.BASEBOARD_FAB2(SCH_1):M_H_DQS_DN(2)   I101 @BASEBOARD_FAB2_LIB.BASEBOARD_FAB2(SCH_1):PAGE80
   175 M_H_DQS_DP<2> @BASEBOARD_FAB2_LIB.BASEBOARD_FAB2(SCH_1):M_H_DQS_DP(2)   I101 @BASEBOARD_FAB2_LIB.BASEBOARD_FAB2(SCH_1):PAGE80
   185 M_H_DQS_DN<3> @BASEBOARD_FAB2_LIB.BASEBOARD_FAB2(SCH_1):M_H_DQS_DN(3)   I101 @BASEBOARD_FAB2_LIB.BASEBOARD_FAB2(SCH_1):PAGE80
   186 M_H_DQS_DP<3> @BASEBOARD_FAB2_LIB.BASEBOARD_FAB2(SCH_1):M_H_DQS_DP(3)   I101 @BASEBOARD_FAB2_LIB.BASEBOARD_FAB2(SCH_1):PAGE80
   244 M_H_DQS_DN<4> @BASEBOARD_FAB2_LIB.BASEBOARD_FAB2(SCH_1):M_H_DQS_DN(4)   I101 @BASEBOARD_FAB2_LIB.BASEBOARD_FAB2(SCH_1):PAGE80
   245 M_H_DQS_DP<4> @BASEBOARD_FAB2_LIB.BASEBOARD_FAB2(SCH_1):M_H_DQS_DP(4)   I101 @BASEBOARD_FAB2_LIB.BASEBOARD_FAB2(SCH_1):PAGE80
   255 M_H_DQS_DN<5> @BASEBOARD_FAB2_LIB.BASEBOARD_FAB2(SCH_1):M_H_DQS_DN(5)   I101 @BASEBOARD_FAB2_LIB.BASEBOARD_FAB2(SCH_1):PAGE80
   256 M_H_DQS_DP<5> @BASEBOARD_FAB2_LIB.BASEBOARD_FAB2(SCH_1):M_H_DQS_DP(5)   I101 @BASEBOARD_FAB2_LIB.BASEBOARD_FAB2(SCH_1):PAGE80
   266 M_H_DQS_DN<6> @BASEBOARD_FAB2_LIB.BASEBOARD_FAB2(SCH_1):M_H_DQS_DN(6)   I101 @BASEBOARD_FAB2_LIB.BASEBOARD_FAB2(SCH_1):PAGE80
   267 M_H_DQS_DP<6> @BASEBOARD_FAB2_LIB.BASEBOARD_FAB2(SCH_1):M_H_DQS_DP(6)   I101 @BASEBOARD_FAB2_LIB.BASEBOARD_FAB2(SCH_1):PAGE80
   277 M_H_DQS_DN<7> @BASEBOARD_FAB2_LIB.BASEBOARD_FAB2(SCH_1):M_H_DQS_DN(7)   I101 @BASEBOARD_FAB2_LIB.BASEBOARD_FAB2(SCH_1):PAGE80
   278 M_H_DQS_DP<7> @BASEBOARD_FAB2_LIB.BASEBOARD_FAB2(SCH_1):M_H_DQS_DP(7)   I101 @BASEBOARD_FAB2_LIB.BASEBOARD_FAB2(SCH_1):PAGE80
   196 M_H_DQS_DN<8> @BASEBOARD_FAB2_LIB.BASEBOARD_FAB2(SCH_1):M_H_DQS_DN(8)   I101 @BASEBOARD_FAB2_LIB.BASEBOARD_FAB2(SCH_1):PAGE80
   197 M_H_DQS_DP<8> @BASEBOARD_FAB2_LIB.BASEBOARD_FAB2(SCH_1):M_H_DQS_DP(8)   I101 @BASEBOARD_FAB2_LIB.BASEBOARD_FAB2(SCH_1):PAGE80
     8 M_H_DQS_DN<9> @BASEBOARD_FAB2_LIB.BASEBOARD_FAB2(SCH_1):M_H_DQS_DN(9)   I101 @BASEBOARD_FAB2_LIB.BASEBOARD_FAB2(SCH_1):PAGE80
     7 M_H_DQS_DP<9> @BASEBOARD_FAB2_LIB.BASEBOARD_FAB2(SCH_1):M_H_DQS_DP(9)   I101 @BASEBOARD_FAB2_LIB.BASEBOARD_FAB2(SCH_1):PAGE80
     2    GND @BASEBOARD_FAB2_LIB.BASEBOARD_FAB2(SCH_1):GND   I138 @BASEBOARD_FAB2_LIB.BASEBOARD_FAB2(SCH_1):PAGE80
     4    GND @BASEBOARD_FAB2_LIB.BASEBOARD_FAB2(SCH_1):GND   I138 @BASEBOARD_FAB2_LIB.BASEBOARD_FAB2(SCH_1):PAGE80
     6    GND @BASEBOARD_FAB2_LIB.BASEBOARD_FAB2(SCH_1):GND   I138 @BASEBOARD_FAB2_LIB.BASEBOARD_FAB2(SCH_1):PAGE80
     9    GND @BASEBOARD_FAB2_LIB.BASEBOARD_FAB2(SCH_1):GND   I138 @BASEBOARD_FAB2_LIB.BASEBOARD_FAB2(SCH_1):PAGE80
    11    GND @BASEBOARD_FAB2_LIB.BASEBOARD_FAB2(SCH_1):GND   I138 @BASEBOARD_FAB2_LIB.BASEBOARD_FAB2(SCH_1):PAGE80
    13    GND @BASEBOARD_FAB2_LIB.BASEBOARD_FAB2(SCH_1):GND   I138 @BASEBOARD_FAB2_LIB.BASEBOARD_FAB2(SCH_1):PAGE80
    15    GND @BASEBOARD_FAB2_LIB.BASEBOARD_FAB2(SCH_1):GND   I138 @BASEBOARD_FAB2_LIB.BASEBOARD_FAB2(SCH_1):PAGE80
    17    GND @BASEBOARD_FAB2_LIB.BASEBOARD_FAB2(SCH_1):GND   I138 @BASEBOARD_FAB2_LIB.BASEBOARD_FAB2(SCH_1):PAGE80
    20    GND @BASEBOARD_FAB2_LIB.BASEBOARD_FAB2(SCH_1):GND   I138 @BASEBOARD_FAB2_LIB.BASEBOARD_FAB2(SCH_1):PAGE80
    22    GND @BASEBOARD_FAB2_LIB.BASEBOARD_FAB2(SCH_1):GND   I138 @BASEBOARD_FAB2_LIB.BASEBOARD_FAB2(SCH_1):PAGE80
    24    GND @BASEBOARD_FAB2_LIB.BASEBOARD_FAB2(SCH_1):GND   I138 @BASEBOARD_FAB2_LIB.BASEBOARD_FAB2(SCH_1):PAGE80
    26    GND @BASEBOARD_FAB2_LIB.BASEBOARD_FAB2(SCH_1):GND   I138 @BASEBOARD_FAB2_LIB.BASEBOARD_FAB2(SCH_1):PAGE80
    28    GND @BASEBOARD_FAB2_LIB.BASEBOARD_FAB2(SCH_1):GND   I138 @BASEBOARD_FAB2_LIB.BASEBOARD_FAB2(SCH_1):PAGE80
    31    GND @BASEBOARD_FAB2_LIB.BASEBOARD_FAB2(SCH_1):GND   I138 @BASEBOARD_FAB2_LIB.BASEBOARD_FAB2(SCH_1):PAGE80
    33    GND @BASEBOARD_FAB2_LIB.BASEBOARD_FAB2(SCH_1):GND   I138 @BASEBOARD_FAB2_LIB.BASEBOARD_FAB2(SCH_1):PAGE80
    35    GND @BASEBOARD_FAB2_LIB.BASEBOARD_FAB2(SCH_1):GND   I138 @BASEBOARD_FAB2_LIB.BASEBOARD_FAB2(SCH_1):PAGE80
    37    GND @BASEBOARD_FAB2_LIB.BASEBOARD_FAB2(SCH_1):GND   I138 @BASEBOARD_FAB2_LIB.BASEBOARD_FAB2(SCH_1):PAGE80
    39    GND @BASEBOARD_FAB2_LIB.BASEBOARD_FAB2(SCH_1):GND   I138 @BASEBOARD_FAB2_LIB.BASEBOARD_FAB2(SCH_1):PAGE80
    42    GND @BASEBOARD_FAB2_LIB.BASEBOARD_FAB2(SCH_1):GND   I138 @BASEBOARD_FAB2_LIB.BASEBOARD_FAB2(SCH_1):PAGE80
    44    GND @BASEBOARD_FAB2_LIB.BASEBOARD_FAB2(SCH_1):GND   I138 @BASEBOARD_FAB2_LIB.BASEBOARD_FAB2(SCH_1):PAGE80
    46    GND @BASEBOARD_FAB2_LIB.BASEBOARD_FAB2(SCH_1):GND   I138 @BASEBOARD_FAB2_LIB.BASEBOARD_FAB2(SCH_1):PAGE80
    48    GND @BASEBOARD_FAB2_LIB.BASEBOARD_FAB2(SCH_1):GND   I138 @BASEBOARD_FAB2_LIB.BASEBOARD_FAB2(SCH_1):PAGE80
    50    GND @BASEBOARD_FAB2_LIB.BASEBOARD_FAB2(SCH_1):GND   I138 @BASEBOARD_FAB2_LIB.BASEBOARD_FAB2(SCH_1):PAGE80
    53    GND @BASEBOARD_FAB2_LIB.BASEBOARD_FAB2(SCH_1):GND   I138 @BASEBOARD_FAB2_LIB.BASEBOARD_FAB2(SCH_1):PAGE80
    55    GND @BASEBOARD_FAB2_LIB.BASEBOARD_FAB2(SCH_1):GND   I138 @BASEBOARD_FAB2_LIB.BASEBOARD_FAB2(SCH_1):PAGE80
    57    GND @BASEBOARD_FAB2_LIB.BASEBOARD_FAB2(SCH_1):GND   I138 @BASEBOARD_FAB2_LIB.BASEBOARD_FAB2(SCH_1):PAGE80
    94    GND @BASEBOARD_FAB2_LIB.BASEBOARD_FAB2(SCH_1):GND   I138 @BASEBOARD_FAB2_LIB.BASEBOARD_FAB2(SCH_1):PAGE80
    96    GND @BASEBOARD_FAB2_LIB.BASEBOARD_FAB2(SCH_1):GND   I138 @BASEBOARD_FAB2_LIB.BASEBOARD_FAB2(SCH_1):PAGE80
    98    GND @BASEBOARD_FAB2_LIB.BASEBOARD_FAB2(SCH_1):GND   I138 @BASEBOARD_FAB2_LIB.BASEBOARD_FAB2(SCH_1):PAGE80
   101    GND @BASEBOARD_FAB2_LIB.BASEBOARD_FAB2(SCH_1):GND   I138 @BASEBOARD_FAB2_LIB.BASEBOARD_FAB2(SCH_1):PAGE80
   103    GND @BASEBOARD_FAB2_LIB.BASEBOARD_FAB2(SCH_1):GND   I138 @BASEBOARD_FAB2_LIB.BASEBOARD_FAB2(SCH_1):PAGE80
   105    GND @BASEBOARD_FAB2_LIB.BASEBOARD_FAB2(SCH_1):GND   I138 @BASEBOARD_FAB2_LIB.BASEBOARD_FAB2(SCH_1):PAGE80
   107    GND @BASEBOARD_FAB2_LIB.BASEBOARD_FAB2(SCH_1):GND   I138 @BASEBOARD_FAB2_LIB.BASEBOARD_FAB2(SCH_1):PAGE80
   109    GND @BASEBOARD_FAB2_LIB.BASEBOARD_FAB2(SCH_1):GND   I138 @BASEBOARD_FAB2_LIB.BASEBOARD_FAB2(SCH_1):PAGE80
   112    GND @BASEBOARD_FAB2_LIB.BASEBOARD_FAB2(SCH_1):GND   I138 @BASEBOARD_FAB2_LIB.BASEBOARD_FAB2(SCH_1):PAGE80
   114    GND @BASEBOARD_FAB2_LIB.BASEBOARD_FAB2(SCH_1):GND   I138 @BASEBOARD_FAB2_LIB.BASEBOARD_FAB2(SCH_1):PAGE80
   116    GND @BASEBOARD_FAB2_LIB.BASEBOARD_FAB2(SCH_1):GND   I138 @BASEBOARD_FAB2_LIB.BASEBOARD_FAB2(SCH_1):PAGE80
   118    GND @BASEBOARD_FAB2_LIB.BASEBOARD_FAB2(SCH_1):GND   I138 @BASEBOARD_FAB2_LIB.BASEBOARD_FAB2(SCH_1):PAGE80
   120    GND @BASEBOARD_FAB2_LIB.BASEBOARD_FAB2(SCH_1):GND   I138 @BASEBOARD_FAB2_LIB.BASEBOARD_FAB2(SCH_1):PAGE80
   123    GND @BASEBOARD_FAB2_LIB.BASEBOARD_FAB2(SCH_1):GND   I138 @BASEBOARD_FAB2_LIB.BASEBOARD_FAB2(SCH_1):PAGE80
   125    GND @BASEBOARD_FAB2_LIB.BASEBOARD_FAB2(SCH_1):GND   I138 @BASEBOARD_FAB2_LIB.BASEBOARD_FAB2(SCH_1):PAGE80
   127    GND @BASEBOARD_FAB2_LIB.BASEBOARD_FAB2(SCH_1):GND   I138 @BASEBOARD_FAB2_LIB.BASEBOARD_FAB2(SCH_1):PAGE80
   129    GND @BASEBOARD_FAB2_LIB.BASEBOARD_FAB2(SCH_1):GND   I138 @BASEBOARD_FAB2_LIB.BASEBOARD_FAB2(SCH_1):PAGE80
   131    GND @BASEBOARD_FAB2_LIB.BASEBOARD_FAB2(SCH_1):GND   I138 @BASEBOARD_FAB2_LIB.BASEBOARD_FAB2(SCH_1):PAGE80
   134    GND @BASEBOARD_FAB2_LIB.BASEBOARD_FAB2(SCH_1):GND   I138 @BASEBOARD_FAB2_LIB.BASEBOARD_FAB2(SCH_1):PAGE80
   136    GND @BASEBOARD_FAB2_LIB.BASEBOARD_FAB2(SCH_1):GND   I138 @BASEBOARD_FAB2_LIB.BASEBOARD_FAB2(SCH_1):PAGE80
   138    GND @BASEBOARD_FAB2_LIB.BASEBOARD_FAB2(SCH_1):GND   I138 @BASEBOARD_FAB2_LIB.BASEBOARD_FAB2(SCH_1):PAGE80
   147    GND @BASEBOARD_FAB2_LIB.BASEBOARD_FAB2(SCH_1):GND   I138 @BASEBOARD_FAB2_LIB.BASEBOARD_FAB2(SCH_1):PAGE80
   149    GND @BASEBOARD_FAB2_LIB.BASEBOARD_FAB2(SCH_1):GND   I138 @BASEBOARD_FAB2_LIB.BASEBOARD_FAB2(SCH_1):PAGE80
   151    GND @BASEBOARD_FAB2_LIB.BASEBOARD_FAB2(SCH_1):GND   I138 @BASEBOARD_FAB2_LIB.BASEBOARD_FAB2(SCH_1):PAGE80
   154    GND @BASEBOARD_FAB2_LIB.BASEBOARD_FAB2(SCH_1):GND   I138 @BASEBOARD_FAB2_LIB.BASEBOARD_FAB2(SCH_1):PAGE80
   156    GND @BASEBOARD_FAB2_LIB.BASEBOARD_FAB2(SCH_1):GND   I138 @BASEBOARD_FAB2_LIB.BASEBOARD_FAB2(SCH_1):PAGE80
   158    GND @BASEBOARD_FAB2_LIB.BASEBOARD_FAB2(SCH_1):GND   I138 @BASEBOARD_FAB2_LIB.BASEBOARD_FAB2(SCH_1):PAGE80
   160    GND @BASEBOARD_FAB2_LIB.BASEBOARD_FAB2(SCH_1):GND   I138 @BASEBOARD_FAB2_LIB.BASEBOARD_FAB2(SCH_1):PAGE80
   162    GND @BASEBOARD_FAB2_LIB.BASEBOARD_FAB2(SCH_1):GND   I138 @BASEBOARD_FAB2_LIB.BASEBOARD_FAB2(SCH_1):PAGE80
   165    GND @BASEBOARD_FAB2_LIB.BASEBOARD_FAB2(SCH_1):GND   I138 @BASEBOARD_FAB2_LIB.BASEBOARD_FAB2(SCH_1):PAGE80
   167    GND @BASEBOARD_FAB2_LIB.BASEBOARD_FAB2(SCH_1):GND   I138 @BASEBOARD_FAB2_LIB.BASEBOARD_FAB2(SCH_1):PAGE80
   169    GND @BASEBOARD_FAB2_LIB.BASEBOARD_FAB2(SCH_1):GND   I138 @BASEBOARD_FAB2_LIB.BASEBOARD_FAB2(SCH_1):PAGE80
   171    GND @BASEBOARD_FAB2_LIB.BASEBOARD_FAB2(SCH_1):GND   I138 @BASEBOARD_FAB2_LIB.BASEBOARD_FAB2(SCH_1):PAGE80
   173    GND @BASEBOARD_FAB2_LIB.BASEBOARD_FAB2(SCH_1):GND   I138 @BASEBOARD_FAB2_LIB.BASEBOARD_FAB2(SCH_1):PAGE80
   176    GND @BASEBOARD_FAB2_LIB.BASEBOARD_FAB2(SCH_1):GND   I138 @BASEBOARD_FAB2_LIB.BASEBOARD_FAB2(SCH_1):PAGE80
   178    GND @BASEBOARD_FAB2_LIB.BASEBOARD_FAB2(SCH_1):GND   I138 @BASEBOARD_FAB2_LIB.BASEBOARD_FAB2(SCH_1):PAGE80
   180    GND @BASEBOARD_FAB2_LIB.BASEBOARD_FAB2(SCH_1):GND   I138 @BASEBOARD_FAB2_LIB.BASEBOARD_FAB2(SCH_1):PAGE80
   182    GND @BASEBOARD_FAB2_LIB.BASEBOARD_FAB2(SCH_1):GND   I138 @BASEBOARD_FAB2_LIB.BASEBOARD_FAB2(SCH_1):PAGE80
   184    GND @BASEBOARD_FAB2_LIB.BASEBOARD_FAB2(SCH_1):GND   I138 @BASEBOARD_FAB2_LIB.BASEBOARD_FAB2(SCH_1):PAGE80
   187    GND @BASEBOARD_FAB2_LIB.BASEBOARD_FAB2(SCH_1):GND   I138 @BASEBOARD_FAB2_LIB.BASEBOARD_FAB2(SCH_1):PAGE80
   189    GND @BASEBOARD_FAB2_LIB.BASEBOARD_FAB2(SCH_1):GND   I138 @BASEBOARD_FAB2_LIB.BASEBOARD_FAB2(SCH_1):PAGE80
   191    GND @BASEBOARD_FAB2_LIB.BASEBOARD_FAB2(SCH_1):GND   I138 @BASEBOARD_FAB2_LIB.BASEBOARD_FAB2(SCH_1):PAGE80
   193    GND @BASEBOARD_FAB2_LIB.BASEBOARD_FAB2(SCH_1):GND   I138 @BASEBOARD_FAB2_LIB.BASEBOARD_FAB2(SCH_1):PAGE80
   195    GND @BASEBOARD_FAB2_LIB.BASEBOARD_FAB2(SCH_1):GND   I138 @BASEBOARD_FAB2_LIB.BASEBOARD_FAB2(SCH_1):PAGE80
   198    GND @BASEBOARD_FAB2_LIB.BASEBOARD_FAB2(SCH_1):GND   I138 @BASEBOARD_FAB2_LIB.BASEBOARD_FAB2(SCH_1):PAGE80
   200    GND @BASEBOARD_FAB2_LIB.BASEBOARD_FAB2(SCH_1):GND   I138 @BASEBOARD_FAB2_LIB.BASEBOARD_FAB2(SCH_1):PAGE80
   202    GND @BASEBOARD_FAB2_LIB.BASEBOARD_FAB2(SCH_1):GND   I138 @BASEBOARD_FAB2_LIB.BASEBOARD_FAB2(SCH_1):PAGE80
   239    GND @BASEBOARD_FAB2_LIB.BASEBOARD_FAB2(SCH_1):GND   I138 @BASEBOARD_FAB2_LIB.BASEBOARD_FAB2(SCH_1):PAGE80
   241    GND @BASEBOARD_FAB2_LIB.BASEBOARD_FAB2(SCH_1):GND   I138 @BASEBOARD_FAB2_LIB.BASEBOARD_FAB2(SCH_1):PAGE80
   243    GND @BASEBOARD_FAB2_LIB.BASEBOARD_FAB2(SCH_1):GND   I138 @BASEBOARD_FAB2_LIB.BASEBOARD_FAB2(SCH_1):PAGE80
   246    GND @BASEBOARD_FAB2_LIB.BASEBOARD_FAB2(SCH_1):GND   I138 @BASEBOARD_FAB2_LIB.BASEBOARD_FAB2(SCH_1):PAGE80
   248    GND @BASEBOARD_FAB2_LIB.BASEBOARD_FAB2(SCH_1):GND   I138 @BASEBOARD_FAB2_LIB.BASEBOARD_FAB2(SCH_1):PAGE80
   250    GND @BASEBOARD_FAB2_LIB.BASEBOARD_FAB2(SCH_1):GND   I138 @BASEBOARD_FAB2_LIB.BASEBOARD_FAB2(SCH_1):PAGE80
   252    GND @BASEBOARD_FAB2_LIB.BASEBOARD_FAB2(SCH_1):GND   I138 @BASEBOARD_FAB2_LIB.BASEBOARD_FAB2(SCH_1):PAGE80
   254    GND @BASEBOARD_FAB2_LIB.BASEBOARD_FAB2(SCH_1):GND   I138 @BASEBOARD_FAB2_LIB.BASEBOARD_FAB2(SCH_1):PAGE80
   257    GND @BASEBOARD_FAB2_LIB.BASEBOARD_FAB2(SCH_1):GND   I138 @BASEBOARD_FAB2_LIB.BASEBOARD_FAB2(SCH_1):PAGE80
   259    GND @BASEBOARD_FAB2_LIB.BASEBOARD_FAB2(SCH_1):GND   I138 @BASEBOARD_FAB2_LIB.BASEBOARD_FAB2(SCH_1):PAGE80
   261    GND @BASEBOARD_FAB2_LIB.BASEBOARD_FAB2(SCH_1):GND   I138 @BASEBOARD_FAB2_LIB.BASEBOARD_FAB2(SCH_1):PAGE80
   263    GND @BASEBOARD_FAB2_LIB.BASEBOARD_FAB2(SCH_1):GND   I138 @BASEBOARD_FAB2_LIB.BASEBOARD_FAB2(SCH_1):PAGE80
   265    GND @BASEBOARD_FAB2_LIB.BASEBOARD_FAB2(SCH_1):GND   I138 @BASEBOARD_FAB2_LIB.BASEBOARD_FAB2(SCH_1):PAGE80
   268    GND @BASEBOARD_FAB2_LIB.BASEBOARD_FAB2(SCH_1):GND   I138 @BASEBOARD_FAB2_LIB.BASEBOARD_FAB2(SCH_1):PAGE80
   270    GND @BASEBOARD_FAB2_LIB.BASEBOARD_FAB2(SCH_1):GND   I138 @BASEBOARD_FAB2_LIB.BASEBOARD_FAB2(SCH_1):PAGE80
   272    GND @BASEBOARD_FAB2_LIB.BASEBOARD_FAB2(SCH_1):GND   I138 @BASEBOARD_FAB2_LIB.BASEBOARD_FAB2(SCH_1):PAGE80
   274    GND @BASEBOARD_FAB2_LIB.BASEBOARD_FAB2(SCH_1):GND   I138 @BASEBOARD_FAB2_LIB.BASEBOARD_FAB2(SCH_1):PAGE80
   276    GND @BASEBOARD_FAB2_LIB.BASEBOARD_FAB2(SCH_1):GND   I138 @BASEBOARD_FAB2_LIB.BASEBOARD_FAB2(SCH_1):PAGE80
   279    GND @BASEBOARD_FAB2_LIB.BASEBOARD_FAB2(SCH_1):GND   I138 @BASEBOARD_FAB2_LIB.BASEBOARD_FAB2(SCH_1):PAGE80
   281    GND @BASEBOARD_FAB2_LIB.BASEBOARD_FAB2(SCH_1):GND   I138 @BASEBOARD_FAB2_LIB.BASEBOARD_FAB2(SCH_1):PAGE80
   283    GND @BASEBOARD_FAB2_LIB.BASEBOARD_FAB2(SCH_1):GND   I138 @BASEBOARD_FAB2_LIB.BASEBOARD_FAB2(SCH_1):PAGE80
     1 P12V_NVDIMM_GHJ @BASEBOARD_FAB2_LIB.BASEBOARD_FAB2(SCH_1):P12V_NVDIMM_GHJ    I56 @BASEBOARD_FAB2_LIB.BASEBOARD_FAB2(SCH_1):PAGE80
   145 P12V_NVDIMM_GHJ @BASEBOARD_FAB2_LIB.BASEBOARD_FAB2(SCH_1):P12V_NVDIMM_GHJ    I56 @BASEBOARD_FAB2_LIB.BASEBOARD_FAB2(SCH_1):PAGE80
    59 PVDDQ_GHJ @BASEBOARD_FAB2_LIB.BASEBOARD_FAB2(SCH_1):PVDDQ_GHJ    I56 @BASEBOARD_FAB2_LIB.BASEBOARD_FAB2(SCH_1):PAGE80
    61 PVDDQ_GHJ @BASEBOARD_FAB2_LIB.BASEBOARD_FAB2(SCH_1):PVDDQ_GHJ    I56 @BASEBOARD_FAB2_LIB.BASEBOARD_FAB2(SCH_1):PAGE80
    64 PVDDQ_GHJ @BASEBOARD_FAB2_LIB.BASEBOARD_FAB2(SCH_1):PVDDQ_GHJ    I56 @BASEBOARD_FAB2_LIB.BASEBOARD_FAB2(SCH_1):PAGE80
    67 PVDDQ_GHJ @BASEBOARD_FAB2_LIB.BASEBOARD_FAB2(SCH_1):PVDDQ_GHJ    I56 @BASEBOARD_FAB2_LIB.BASEBOARD_FAB2(SCH_1):PAGE80
    70 PVDDQ_GHJ @BASEBOARD_FAB2_LIB.BASEBOARD_FAB2(SCH_1):PVDDQ_GHJ    I56 @BASEBOARD_FAB2_LIB.BASEBOARD_FAB2(SCH_1):PAGE80
    73 PVDDQ_GHJ @BASEBOARD_FAB2_LIB.BASEBOARD_FAB2(SCH_1):PVDDQ_GHJ    I56 @BASEBOARD_FAB2_LIB.BASEBOARD_FAB2(SCH_1):PAGE80
    76 PVDDQ_GHJ @BASEBOARD_FAB2_LIB.BASEBOARD_FAB2(SCH_1):PVDDQ_GHJ    I56 @BASEBOARD_FAB2_LIB.BASEBOARD_FAB2(SCH_1):PAGE80
    80 PVDDQ_GHJ @BASEBOARD_FAB2_LIB.BASEBOARD_FAB2(SCH_1):PVDDQ_GHJ    I56 @BASEBOARD_FAB2_LIB.BASEBOARD_FAB2(SCH_1):PAGE80
    83 PVDDQ_GHJ @BASEBOARD_FAB2_LIB.BASEBOARD_FAB2(SCH_1):PVDDQ_GHJ    I56 @BASEBOARD_FAB2_LIB.BASEBOARD_FAB2(SCH_1):PAGE80
    85 PVDDQ_GHJ @BASEBOARD_FAB2_LIB.BASEBOARD_FAB2(SCH_1):PVDDQ_GHJ    I56 @BASEBOARD_FAB2_LIB.BASEBOARD_FAB2(SCH_1):PAGE80
    88 PVDDQ_GHJ @BASEBOARD_FAB2_LIB.BASEBOARD_FAB2(SCH_1):PVDDQ_GHJ    I56 @BASEBOARD_FAB2_LIB.BASEBOARD_FAB2(SCH_1):PAGE80
    90 PVDDQ_GHJ @BASEBOARD_FAB2_LIB.BASEBOARD_FAB2(SCH_1):PVDDQ_GHJ    I56 @BASEBOARD_FAB2_LIB.BASEBOARD_FAB2(SCH_1):PAGE80
    92 PVDDQ_GHJ @BASEBOARD_FAB2_LIB.BASEBOARD_FAB2(SCH_1):PVDDQ_GHJ    I56 @BASEBOARD_FAB2_LIB.BASEBOARD_FAB2(SCH_1):PAGE80
   204 PVDDQ_GHJ @BASEBOARD_FAB2_LIB.BASEBOARD_FAB2(SCH_1):PVDDQ_GHJ    I56 @BASEBOARD_FAB2_LIB.BASEBOARD_FAB2(SCH_1):PAGE80
   206 PVDDQ_GHJ @BASEBOARD_FAB2_LIB.BASEBOARD_FAB2(SCH_1):PVDDQ_GHJ    I56 @BASEBOARD_FAB2_LIB.BASEBOARD_FAB2(SCH_1):PAGE80
   209 PVDDQ_GHJ @BASEBOARD_FAB2_LIB.BASEBOARD_FAB2(SCH_1):PVDDQ_GHJ    I56 @BASEBOARD_FAB2_LIB.BASEBOARD_FAB2(SCH_1):PAGE80
   212 PVDDQ_GHJ @BASEBOARD_FAB2_LIB.BASEBOARD_FAB2(SCH_1):PVDDQ_GHJ    I56 @BASEBOARD_FAB2_LIB.BASEBOARD_FAB2(SCH_1):PAGE80
   215 PVDDQ_GHJ @BASEBOARD_FAB2_LIB.BASEBOARD_FAB2(SCH_1):PVDDQ_GHJ    I56 @BASEBOARD_FAB2_LIB.BASEBOARD_FAB2(SCH_1):PAGE80
   217 PVDDQ_GHJ @BASEBOARD_FAB2_LIB.BASEBOARD_FAB2(SCH_1):PVDDQ_GHJ    I56 @BASEBOARD_FAB2_LIB.BASEBOARD_FAB2(SCH_1):PAGE80
   220 PVDDQ_GHJ @BASEBOARD_FAB2_LIB.BASEBOARD_FAB2(SCH_1):PVDDQ_GHJ    I56 @BASEBOARD_FAB2_LIB.BASEBOARD_FAB2(SCH_1):PAGE80
   223 PVDDQ_GHJ @BASEBOARD_FAB2_LIB.BASEBOARD_FAB2(SCH_1):PVDDQ_GHJ    I56 @BASEBOARD_FAB2_LIB.BASEBOARD_FAB2(SCH_1):PAGE80
   226 PVDDQ_GHJ @BASEBOARD_FAB2_LIB.BASEBOARD_FAB2(SCH_1):PVDDQ_GHJ    I56 @BASEBOARD_FAB2_LIB.BASEBOARD_FAB2(SCH_1):PAGE80
   229 PVDDQ_GHJ @BASEBOARD_FAB2_LIB.BASEBOARD_FAB2(SCH_1):PVDDQ_GHJ    I56 @BASEBOARD_FAB2_LIB.BASEBOARD_FAB2(SCH_1):PAGE80
   231 PVDDQ_GHJ @BASEBOARD_FAB2_LIB.BASEBOARD_FAB2(SCH_1):PVDDQ_GHJ    I56 @BASEBOARD_FAB2_LIB.BASEBOARD_FAB2(SCH_1):PAGE80
   233 PVDDQ_GHJ @BASEBOARD_FAB2_LIB.BASEBOARD_FAB2(SCH_1):PVDDQ_GHJ    I56 @BASEBOARD_FAB2_LIB.BASEBOARD_FAB2(SCH_1):PAGE80
   236 PVDDQ_GHJ @BASEBOARD_FAB2_LIB.BASEBOARD_FAB2(SCH_1):PVDDQ_GHJ    I56 @BASEBOARD_FAB2_LIB.BASEBOARD_FAB2(SCH_1):PAGE80
   142 PVPP_GHJ @BASEBOARD_FAB2_LIB.BASEBOARD_FAB2(SCH_1):PVPP_GHJ    I56 @BASEBOARD_FAB2_LIB.BASEBOARD_FAB2(SCH_1):PAGE80
   143 PVPP_GHJ @BASEBOARD_FAB2_LIB.BASEBOARD_FAB2(SCH_1):PVPP_GHJ    I56 @BASEBOARD_FAB2_LIB.BASEBOARD_FAB2(SCH_1):PAGE80
   288 PVPP_GHJ @BASEBOARD_FAB2_LIB.BASEBOARD_FAB2(SCH_1):PVPP_GHJ    I56 @BASEBOARD_FAB2_LIB.BASEBOARD_FAB2(SCH_1):PAGE80
   286 PVPP_GHJ @BASEBOARD_FAB2_LIB.BASEBOARD_FAB2(SCH_1):PVPP_GHJ    I56 @BASEBOARD_FAB2_LIB.BASEBOARD_FAB2(SCH_1):PAGE80
   287 PVPP_GHJ @BASEBOARD_FAB2_LIB.BASEBOARD_FAB2(SCH_1):PVPP_GHJ    I56 @BASEBOARD_FAB2_LIB.BASEBOARD_FAB2(SCH_1):PAGE80
    77 PVTT_GHJ @BASEBOARD_FAB2_LIB.BASEBOARD_FAB2(SCH_1):PVTT_GHJ    I56 @BASEBOARD_FAB2_LIB.BASEBOARD_FAB2(SCH_1):PAGE80
   221 PVTT_GHJ @BASEBOARD_FAB2_LIB.BASEBOARD_FAB2(SCH_1):PVTT_GHJ    I56 @BASEBOARD_FAB2_LIB.BASEBOARD_FAB2(SCH_1):PAGE80

J9U2 SCONN288_H44441003_PIP-SCONN,HA
    79 M_J_MA<0> @BASEBOARD_FAB2_LIB.BASEBOARD_FAB2(SCH_1):M_J_MA(0)   I187 @BASEBOARD_FAB2_LIB.BASEBOARD_FAB2(SCH_1):PAGE82
    72 M_J_MA<1> @BASEBOARD_FAB2_LIB.BASEBOARD_FAB2(SCH_1):M_J_MA(1)   I187 @BASEBOARD_FAB2_LIB.BASEBOARD_FAB2(SCH_1):PAGE82
   225 M_J_MA<10> @BASEBOARD_FAB2_LIB.BASEBOARD_FAB2(SCH_1):M_J_MA(10)   I187 @BASEBOARD_FAB2_LIB.BASEBOARD_FAB2(SCH_1):PAGE82
   210 M_J_MA<11> @BASEBOARD_FAB2_LIB.BASEBOARD_FAB2(SCH_1):M_J_MA(11)   I187 @BASEBOARD_FAB2_LIB.BASEBOARD_FAB2(SCH_1):PAGE82
    65 M_J_MA<12> @BASEBOARD_FAB2_LIB.BASEBOARD_FAB2(SCH_1):M_J_MA(12)   I187 @BASEBOARD_FAB2_LIB.BASEBOARD_FAB2(SCH_1):PAGE82
   232 M_J_MA<13> @BASEBOARD_FAB2_LIB.BASEBOARD_FAB2(SCH_1):M_J_MA(13)   I187 @BASEBOARD_FAB2_LIB.BASEBOARD_FAB2(SCH_1):PAGE82
   228 M_J_MA<14> @BASEBOARD_FAB2_LIB.BASEBOARD_FAB2(SCH_1):M_J_MA(14)   I187 @BASEBOARD_FAB2_LIB.BASEBOARD_FAB2(SCH_1):PAGE82
    86 M_J_MA<15> @BASEBOARD_FAB2_LIB.BASEBOARD_FAB2(SCH_1):M_J_MA(15)   I187 @BASEBOARD_FAB2_LIB.BASEBOARD_FAB2(SCH_1):PAGE82
    82 M_J_MA<16> @BASEBOARD_FAB2_LIB.BASEBOARD_FAB2(SCH_1):M_J_MA(16)   I187 @BASEBOARD_FAB2_LIB.BASEBOARD_FAB2(SCH_1):PAGE82
   234 M_J_MA<17> @BASEBOARD_FAB2_LIB.BASEBOARD_FAB2(SCH_1):M_J_MA(17)   I187 @BASEBOARD_FAB2_LIB.BASEBOARD_FAB2(SCH_1):PAGE82
   216 M_J_MA<2> @BASEBOARD_FAB2_LIB.BASEBOARD_FAB2(SCH_1):M_J_MA(2)   I187 @BASEBOARD_FAB2_LIB.BASEBOARD_FAB2(SCH_1):PAGE82
    71 M_J_MA<3> @BASEBOARD_FAB2_LIB.BASEBOARD_FAB2(SCH_1):M_J_MA(3)   I187 @BASEBOARD_FAB2_LIB.BASEBOARD_FAB2(SCH_1):PAGE82
   214 M_J_MA<4> @BASEBOARD_FAB2_LIB.BASEBOARD_FAB2(SCH_1):M_J_MA(4)   I187 @BASEBOARD_FAB2_LIB.BASEBOARD_FAB2(SCH_1):PAGE82
   213 M_J_MA<5> @BASEBOARD_FAB2_LIB.BASEBOARD_FAB2(SCH_1):M_J_MA(5)   I187 @BASEBOARD_FAB2_LIB.BASEBOARD_FAB2(SCH_1):PAGE82
    69 M_J_MA<6> @BASEBOARD_FAB2_LIB.BASEBOARD_FAB2(SCH_1):M_J_MA(6)   I187 @BASEBOARD_FAB2_LIB.BASEBOARD_FAB2(SCH_1):PAGE82
   211 M_J_MA<7> @BASEBOARD_FAB2_LIB.BASEBOARD_FAB2(SCH_1):M_J_MA(7)   I187 @BASEBOARD_FAB2_LIB.BASEBOARD_FAB2(SCH_1):PAGE82
    68 M_J_MA<8> @BASEBOARD_FAB2_LIB.BASEBOARD_FAB2(SCH_1):M_J_MA(8)   I187 @BASEBOARD_FAB2_LIB.BASEBOARD_FAB2(SCH_1):PAGE82
    66 M_J_MA<9> @BASEBOARD_FAB2_LIB.BASEBOARD_FAB2(SCH_1):M_J_MA(9)   I187 @BASEBOARD_FAB2_LIB.BASEBOARD_FAB2(SCH_1):PAGE82
    62 M_J_ACT_N @BASEBOARD_FAB2_LIB.BASEBOARD_FAB2(SCH_1):M_J_ACT_N   I187 @BASEBOARD_FAB2_LIB.BASEBOARD_FAB2(SCH_1):PAGE82
   208 M_J_ALERT_N @BASEBOARD_FAB2_LIB.BASEBOARD_FAB2(SCH_1):M_J_ALERT_N   I187 @BASEBOARD_FAB2_LIB.BASEBOARD_FAB2(SCH_1):PAGE82
   224 M_J_BA<1> @BASEBOARD_FAB2_LIB.BASEBOARD_FAB2(SCH_1):M_J_BA(1)   I187 @BASEBOARD_FAB2_LIB.BASEBOARD_FAB2(SCH_1):PAGE82
    81 M_J_BA<0> @BASEBOARD_FAB2_LIB.BASEBOARD_FAB2(SCH_1):M_J_BA(0)   I187 @BASEBOARD_FAB2_LIB.BASEBOARD_FAB2(SCH_1):PAGE82
   207 M_J_BG<1> @BASEBOARD_FAB2_LIB.BASEBOARD_FAB2(SCH_1):M_J_BG(1)   I187 @BASEBOARD_FAB2_LIB.BASEBOARD_FAB2(SCH_1):PAGE82
    63 M_J_BG<0> @BASEBOARD_FAB2_LIB.BASEBOARD_FAB2(SCH_1):M_J_BG(0)   I187 @BASEBOARD_FAB2_LIB.BASEBOARD_FAB2(SCH_1):PAGE82
   235 M_J_C<2> @BASEBOARD_FAB2_LIB.BASEBOARD_FAB2(SCH_1):M_J_C(2)   I187 @BASEBOARD_FAB2_LIB.BASEBOARD_FAB2(SCH_1):PAGE82
   199 M_J_ECC<7> @BASEBOARD_FAB2_LIB.BASEBOARD_FAB2(SCH_1):M_J_ECC(7)   I187 @BASEBOARD_FAB2_LIB.BASEBOARD_FAB2(SCH_1):PAGE82
    54 M_J_ECC<6> @BASEBOARD_FAB2_LIB.BASEBOARD_FAB2(SCH_1):M_J_ECC(6)   I187 @BASEBOARD_FAB2_LIB.BASEBOARD_FAB2(SCH_1):PAGE82
   192 M_J_ECC<5> @BASEBOARD_FAB2_LIB.BASEBOARD_FAB2(SCH_1):M_J_ECC(5)   I187 @BASEBOARD_FAB2_LIB.BASEBOARD_FAB2(SCH_1):PAGE82
    47 M_J_ECC<4> @BASEBOARD_FAB2_LIB.BASEBOARD_FAB2(SCH_1):M_J_ECC(4)   I187 @BASEBOARD_FAB2_LIB.BASEBOARD_FAB2(SCH_1):PAGE82
   201 M_J_ECC<3> @BASEBOARD_FAB2_LIB.BASEBOARD_FAB2(SCH_1):M_J_ECC(3)   I187 @BASEBOARD_FAB2_LIB.BASEBOARD_FAB2(SCH_1):PAGE82
    56 M_J_ECC<2> @BASEBOARD_FAB2_LIB.BASEBOARD_FAB2(SCH_1):M_J_ECC(2)   I187 @BASEBOARD_FAB2_LIB.BASEBOARD_FAB2(SCH_1):PAGE82
   194 M_J_ECC<1> @BASEBOARD_FAB2_LIB.BASEBOARD_FAB2(SCH_1):M_J_ECC(1)   I187 @BASEBOARD_FAB2_LIB.BASEBOARD_FAB2(SCH_1):PAGE82
    49 M_J_ECC<0> @BASEBOARD_FAB2_LIB.BASEBOARD_FAB2(SCH_1):M_J_ECC(0)   I187 @BASEBOARD_FAB2_LIB.BASEBOARD_FAB2(SCH_1):PAGE82
    75 M_J_CLK_DN<2> @BASEBOARD_FAB2_LIB.BASEBOARD_FAB2(SCH_1):M_J_CLK_DN(2)   I187 @BASEBOARD_FAB2_LIB.BASEBOARD_FAB2(SCH_1):PAGE82
    74 M_J_CLK_DP<2> @BASEBOARD_FAB2_LIB.BASEBOARD_FAB2(SCH_1):M_J_CLK_DP(2)   I187 @BASEBOARD_FAB2_LIB.BASEBOARD_FAB2(SCH_1):PAGE82
   219 M_J_CLK_DN<3> @BASEBOARD_FAB2_LIB.BASEBOARD_FAB2(SCH_1):M_J_CLK_DN(3)   I187 @BASEBOARD_FAB2_LIB.BASEBOARD_FAB2(SCH_1):PAGE82
   218 M_J_CLK_DP<3> @BASEBOARD_FAB2_LIB.BASEBOARD_FAB2(SCH_1):M_J_CLK_DP(3)   I187 @BASEBOARD_FAB2_LIB.BASEBOARD_FAB2(SCH_1):PAGE82
   203 M_J_CKE<3> @BASEBOARD_FAB2_LIB.BASEBOARD_FAB2(SCH_1):M_J_CKE(3)   I187 @BASEBOARD_FAB2_LIB.BASEBOARD_FAB2(SCH_1):PAGE82
    60 M_J_CKE<2> @BASEBOARD_FAB2_LIB.BASEBOARD_FAB2(SCH_1):M_J_CKE(2)   I187 @BASEBOARD_FAB2_LIB.BASEBOARD_FAB2(SCH_1):PAGE82
   280 M_J_DQ<63> @BASEBOARD_FAB2_LIB.BASEBOARD_FAB2(SCH_1):M_J_DQ(63)   I187 @BASEBOARD_FAB2_LIB.BASEBOARD_FAB2(SCH_1):PAGE82
   135 M_J_DQ<62> @BASEBOARD_FAB2_LIB.BASEBOARD_FAB2(SCH_1):M_J_DQ(62)   I187 @BASEBOARD_FAB2_LIB.BASEBOARD_FAB2(SCH_1):PAGE82
   273 M_J_DQ<61> @BASEBOARD_FAB2_LIB.BASEBOARD_FAB2(SCH_1):M_J_DQ(61)   I187 @BASEBOARD_FAB2_LIB.BASEBOARD_FAB2(SCH_1):PAGE82
   128 M_J_DQ<60> @BASEBOARD_FAB2_LIB.BASEBOARD_FAB2(SCH_1):M_J_DQ(60)   I187 @BASEBOARD_FAB2_LIB.BASEBOARD_FAB2(SCH_1):PAGE82
   282 M_J_DQ<59> @BASEBOARD_FAB2_LIB.BASEBOARD_FAB2(SCH_1):M_J_DQ(59)   I187 @BASEBOARD_FAB2_LIB.BASEBOARD_FAB2(SCH_1):PAGE82
   137 M_J_DQ<58> @BASEBOARD_FAB2_LIB.BASEBOARD_FAB2(SCH_1):M_J_DQ(58)   I187 @BASEBOARD_FAB2_LIB.BASEBOARD_FAB2(SCH_1):PAGE82
   275 M_J_DQ<57> @BASEBOARD_FAB2_LIB.BASEBOARD_FAB2(SCH_1):M_J_DQ(57)   I187 @BASEBOARD_FAB2_LIB.BASEBOARD_FAB2(SCH_1):PAGE82
   130 M_J_DQ<56> @BASEBOARD_FAB2_LIB.BASEBOARD_FAB2(SCH_1):M_J_DQ(56)   I187 @BASEBOARD_FAB2_LIB.BASEBOARD_FAB2(SCH_1):PAGE82
   269 M_J_DQ<55> @BASEBOARD_FAB2_LIB.BASEBOARD_FAB2(SCH_1):M_J_DQ(55)   I187 @BASEBOARD_FAB2_LIB.BASEBOARD_FAB2(SCH_1):PAGE82
   124 M_J_DQ<54> @BASEBOARD_FAB2_LIB.BASEBOARD_FAB2(SCH_1):M_J_DQ(54)   I187 @BASEBOARD_FAB2_LIB.BASEBOARD_FAB2(SCH_1):PAGE82
   262 M_J_DQ<53> @BASEBOARD_FAB2_LIB.BASEBOARD_FAB2(SCH_1):M_J_DQ(53)   I187 @BASEBOARD_FAB2_LIB.BASEBOARD_FAB2(SCH_1):PAGE82
   117 M_J_DQ<52> @BASEBOARD_FAB2_LIB.BASEBOARD_FAB2(SCH_1):M_J_DQ(52)   I187 @BASEBOARD_FAB2_LIB.BASEBOARD_FAB2(SCH_1):PAGE82
   271 M_J_DQ<51> @BASEBOARD_FAB2_LIB.BASEBOARD_FAB2(SCH_1):M_J_DQ(51)   I187 @BASEBOARD_FAB2_LIB.BASEBOARD_FAB2(SCH_1):PAGE82
   126 M_J_DQ<50> @BASEBOARD_FAB2_LIB.BASEBOARD_FAB2(SCH_1):M_J_DQ(50)   I187 @BASEBOARD_FAB2_LIB.BASEBOARD_FAB2(SCH_1):PAGE82
   264 M_J_DQ<49> @BASEBOARD_FAB2_LIB.BASEBOARD_FAB2(SCH_1):M_J_DQ(49)   I187 @BASEBOARD_FAB2_LIB.BASEBOARD_FAB2(SCH_1):PAGE82
   119 M_J_DQ<48> @BASEBOARD_FAB2_LIB.BASEBOARD_FAB2(SCH_1):M_J_DQ(48)   I187 @BASEBOARD_FAB2_LIB.BASEBOARD_FAB2(SCH_1):PAGE82
   258 M_J_DQ<47> @BASEBOARD_FAB2_LIB.BASEBOARD_FAB2(SCH_1):M_J_DQ(47)   I187 @BASEBOARD_FAB2_LIB.BASEBOARD_FAB2(SCH_1):PAGE82
   113 M_J_DQ<46> @BASEBOARD_FAB2_LIB.BASEBOARD_FAB2(SCH_1):M_J_DQ(46)   I187 @BASEBOARD_FAB2_LIB.BASEBOARD_FAB2(SCH_1):PAGE82
   251 M_J_DQ<45> @BASEBOARD_FAB2_LIB.BASEBOARD_FAB2(SCH_1):M_J_DQ(45)   I187 @BASEBOARD_FAB2_LIB.BASEBOARD_FAB2(SCH_1):PAGE82
   106 M_J_DQ<44> @BASEBOARD_FAB2_LIB.BASEBOARD_FAB2(SCH_1):M_J_DQ(44)   I187 @BASEBOARD_FAB2_LIB.BASEBOARD_FAB2(SCH_1):PAGE82
   260 M_J_DQ<43> @BASEBOARD_FAB2_LIB.BASEBOARD_FAB2(SCH_1):M_J_DQ(43)   I187 @BASEBOARD_FAB2_LIB.BASEBOARD_FAB2(SCH_1):PAGE82
   115 M_J_DQ<42> @BASEBOARD_FAB2_LIB.BASEBOARD_FAB2(SCH_1):M_J_DQ(42)   I187 @BASEBOARD_FAB2_LIB.BASEBOARD_FAB2(SCH_1):PAGE82
   253 M_J_DQ<41> @BASEBOARD_FAB2_LIB.BASEBOARD_FAB2(SCH_1):M_J_DQ(41)   I187 @BASEBOARD_FAB2_LIB.BASEBOARD_FAB2(SCH_1):PAGE82
   108 M_J_DQ<40> @BASEBOARD_FAB2_LIB.BASEBOARD_FAB2(SCH_1):M_J_DQ(40)   I187 @BASEBOARD_FAB2_LIB.BASEBOARD_FAB2(SCH_1):PAGE82
   247 M_J_DQ<39> @BASEBOARD_FAB2_LIB.BASEBOARD_FAB2(SCH_1):M_J_DQ(39)   I187 @BASEBOARD_FAB2_LIB.BASEBOARD_FAB2(SCH_1):PAGE82
   102 M_J_DQ<38> @BASEBOARD_FAB2_LIB.BASEBOARD_FAB2(SCH_1):M_J_DQ(38)   I187 @BASEBOARD_FAB2_LIB.BASEBOARD_FAB2(SCH_1):PAGE82
   240 M_J_DQ<37> @BASEBOARD_FAB2_LIB.BASEBOARD_FAB2(SCH_1):M_J_DQ(37)   I187 @BASEBOARD_FAB2_LIB.BASEBOARD_FAB2(SCH_1):PAGE82
    95 M_J_DQ<36> @BASEBOARD_FAB2_LIB.BASEBOARD_FAB2(SCH_1):M_J_DQ(36)   I187 @BASEBOARD_FAB2_LIB.BASEBOARD_FAB2(SCH_1):PAGE82
   249 M_J_DQ<35> @BASEBOARD_FAB2_LIB.BASEBOARD_FAB2(SCH_1):M_J_DQ(35)   I187 @BASEBOARD_FAB2_LIB.BASEBOARD_FAB2(SCH_1):PAGE82
   104 M_J_DQ<34> @BASEBOARD_FAB2_LIB.BASEBOARD_FAB2(SCH_1):M_J_DQ(34)   I187 @BASEBOARD_FAB2_LIB.BASEBOARD_FAB2(SCH_1):PAGE82
   242 M_J_DQ<33> @BASEBOARD_FAB2_LIB.BASEBOARD_FAB2(SCH_1):M_J_DQ(33)   I187 @BASEBOARD_FAB2_LIB.BASEBOARD_FAB2(SCH_1):PAGE82
    97 M_J_DQ<32> @BASEBOARD_FAB2_LIB.BASEBOARD_FAB2(SCH_1):M_J_DQ(32)   I187 @BASEBOARD_FAB2_LIB.BASEBOARD_FAB2(SCH_1):PAGE82
   188 M_J_DQ<31> @BASEBOARD_FAB2_LIB.BASEBOARD_FAB2(SCH_1):M_J_DQ(31)   I187 @BASEBOARD_FAB2_LIB.BASEBOARD_FAB2(SCH_1):PAGE82
    43 M_J_DQ<30> @BASEBOARD_FAB2_LIB.BASEBOARD_FAB2(SCH_1):M_J_DQ(30)   I187 @BASEBOARD_FAB2_LIB.BASEBOARD_FAB2(SCH_1):PAGE82
   181 M_J_DQ<29> @BASEBOARD_FAB2_LIB.BASEBOARD_FAB2(SCH_1):M_J_DQ(29)   I187 @BASEBOARD_FAB2_LIB.BASEBOARD_FAB2(SCH_1):PAGE82
    36 M_J_DQ<28> @BASEBOARD_FAB2_LIB.BASEBOARD_FAB2(SCH_1):M_J_DQ(28)   I187 @BASEBOARD_FAB2_LIB.BASEBOARD_FAB2(SCH_1):PAGE82
   190 M_J_DQ<27> @BASEBOARD_FAB2_LIB.BASEBOARD_FAB2(SCH_1):M_J_DQ(27)   I187 @BASEBOARD_FAB2_LIB.BASEBOARD_FAB2(SCH_1):PAGE82
    45 M_J_DQ<26> @BASEBOARD_FAB2_LIB.BASEBOARD_FAB2(SCH_1):M_J_DQ(26)   I187 @BASEBOARD_FAB2_LIB.BASEBOARD_FAB2(SCH_1):PAGE82
   183 M_J_DQ<25> @BASEBOARD_FAB2_LIB.BASEBOARD_FAB2(SCH_1):M_J_DQ(25)   I187 @BASEBOARD_FAB2_LIB.BASEBOARD_FAB2(SCH_1):PAGE82
    38 M_J_DQ<24> @BASEBOARD_FAB2_LIB.BASEBOARD_FAB2(SCH_1):M_J_DQ(24)   I187 @BASEBOARD_FAB2_LIB.BASEBOARD_FAB2(SCH_1):PAGE82
   177 M_J_DQ<23> @BASEBOARD_FAB2_LIB.BASEBOARD_FAB2(SCH_1):M_J_DQ(23)   I187 @BASEBOARD_FAB2_LIB.BASEBOARD_FAB2(SCH_1):PAGE82
    32 M_J_DQ<22> @BASEBOARD_FAB2_LIB.BASEBOARD_FAB2(SCH_1):M_J_DQ(22)   I187 @BASEBOARD_FAB2_LIB.BASEBOARD_FAB2(SCH_1):PAGE82
   170 M_J_DQ<21> @BASEBOARD_FAB2_LIB.BASEBOARD_FAB2(SCH_1):M_J_DQ(21)   I187 @BASEBOARD_FAB2_LIB.BASEBOARD_FAB2(SCH_1):PAGE82
    25 M_J_DQ<20> @BASEBOARD_FAB2_LIB.BASEBOARD_FAB2(SCH_1):M_J_DQ(20)   I187 @BASEBOARD_FAB2_LIB.BASEBOARD_FAB2(SCH_1):PAGE82
   179 M_J_DQ<19> @BASEBOARD_FAB2_LIB.BASEBOARD_FAB2(SCH_1):M_J_DQ(19)   I187 @BASEBOARD_FAB2_LIB.BASEBOARD_FAB2(SCH_1):PAGE82
    34 M_J_DQ<18> @BASEBOARD_FAB2_LIB.BASEBOARD_FAB2(SCH_1):M_J_DQ(18)   I187 @BASEBOARD_FAB2_LIB.BASEBOARD_FAB2(SCH_1):PAGE82
   172 M_J_DQ<17> @BASEBOARD_FAB2_LIB.BASEBOARD_FAB2(SCH_1):M_J_DQ(17)   I187 @BASEBOARD_FAB2_LIB.BASEBOARD_FAB2(SCH_1):PAGE82
    27 M_J_DQ<16> @BASEBOARD_FAB2_LIB.BASEBOARD_FAB2(SCH_1):M_J_DQ(16)   I187 @BASEBOARD_FAB2_LIB.BASEBOARD_FAB2(SCH_1):PAGE82
   166 M_J_DQ<15> @BASEBOARD_FAB2_LIB.BASEBOARD_FAB2(SCH_1):M_J_DQ(15)   I187 @BASEBOARD_FAB2_LIB.BASEBOARD_FAB2(SCH_1):PAGE82
    21 M_J_DQ<14> @BASEBOARD_FAB2_LIB.BASEBOARD_FAB2(SCH_1):M_J_DQ(14)   I187 @BASEBOARD_FAB2_LIB.BASEBOARD_FAB2(SCH_1):PAGE82
   159 M_J_DQ<13> @BASEBOARD_FAB2_LIB.BASEBOARD_FAB2(SCH_1):M_J_DQ(13)   I187 @BASEBOARD_FAB2_LIB.BASEBOARD_FAB2(SCH_1):PAGE82
    14 M_J_DQ<12> @BASEBOARD_FAB2_LIB.BASEBOARD_FAB2(SCH_1):M_J_DQ(12)   I187 @BASEBOARD_FAB2_LIB.BASEBOARD_FAB2(SCH_1):PAGE82
   168 M_J_DQ<11> @BASEBOARD_FAB2_LIB.BASEBOARD_FAB2(SCH_1):M_J_DQ(11)   I187 @BASEBOARD_FAB2_LIB.BASEBOARD_FAB2(SCH_1):PAGE82
    23 M_J_DQ<10> @BASEBOARD_FAB2_LIB.BASEBOARD_FAB2(SCH_1):M_J_DQ(10)   I187 @BASEBOARD_FAB2_LIB.BASEBOARD_FAB2(SCH_1):PAGE82
   161 M_J_DQ<9> @BASEBOARD_FAB2_LIB.BASEBOARD_FAB2(SCH_1):M_J_DQ(9)   I187 @BASEBOARD_FAB2_LIB.BASEBOARD_FAB2(SCH_1):PAGE82
    16 M_J_DQ<8> @BASEBOARD_FAB2_LIB.BASEBOARD_FAB2(SCH_1):M_J_DQ(8)   I187 @BASEBOARD_FAB2_LIB.BASEBOARD_FAB2(SCH_1):PAGE82
   155 M_J_DQ<7> @BASEBOARD_FAB2_LIB.BASEBOARD_FAB2(SCH_1):M_J_DQ(7)   I187 @BASEBOARD_FAB2_LIB.BASEBOARD_FAB2(SCH_1):PAGE82
    10 M_J_DQ<6> @BASEBOARD_FAB2_LIB.BASEBOARD_FAB2(SCH_1):M_J_DQ(6)   I187 @BASEBOARD_FAB2_LIB.BASEBOARD_FAB2(SCH_1):PAGE82
   148 M_J_DQ<5> @BASEBOARD_FAB2_LIB.BASEBOARD_FAB2(SCH_1):M_J_DQ(5)   I187 @BASEBOARD_FAB2_LIB.BASEBOARD_FAB2(SCH_1):PAGE82
     3 M_J_DQ<4> @BASEBOARD_FAB2_LIB.BASEBOARD_FAB2(SCH_1):M_J_DQ(4)   I187 @BASEBOARD_FAB2_LIB.BASEBOARD_FAB2(SCH_1):PAGE82
   157 M_J_DQ<3> @BASEBOARD_FAB2_LIB.BASEBOARD_FAB2(SCH_1):M_J_DQ(3)   I187 @BASEBOARD_FAB2_LIB.BASEBOARD_FAB2(SCH_1):PAGE82
    12 M_J_DQ<2> @BASEBOARD_FAB2_LIB.BASEBOARD_FAB2(SCH_1):M_J_DQ(2)   I187 @BASEBOARD_FAB2_LIB.BASEBOARD_FAB2(SCH_1):PAGE82
   150 M_J_DQ<1> @BASEBOARD_FAB2_LIB.BASEBOARD_FAB2(SCH_1):M_J_DQ(1)   I187 @BASEBOARD_FAB2_LIB.BASEBOARD_FAB2(SCH_1):PAGE82
     5 M_J_DQ<0> @BASEBOARD_FAB2_LIB.BASEBOARD_FAB2(SCH_1):M_J_DQ(0)   I187 @BASEBOARD_FAB2_LIB.BASEBOARD_FAB2(SCH_1):PAGE82
    78 FM_DIMM_EVENT_COD_N @BASEBOARD_FAB2_LIB.BASEBOARD_FAB2(SCH_1):FM_DIMM_EVENT_COD_N   I187 @BASEBOARD_FAB2_LIB.BASEBOARD_FAB2(SCH_1):PAGE82
    91 M_J_ODT<3> @BASEBOARD_FAB2_LIB.BASEBOARD_FAB2(SCH_1):M_J_ODT(3)   I187 @BASEBOARD_FAB2_LIB.BASEBOARD_FAB2(SCH_1):PAGE82
    87 M_J_ODT<2> @BASEBOARD_FAB2_LIB.BASEBOARD_FAB2(SCH_1):M_J_ODT(2)   I187 @BASEBOARD_FAB2_LIB.BASEBOARD_FAB2(SCH_1):PAGE82
   222 M_J_PAR @BASEBOARD_FAB2_LIB.BASEBOARD_FAB2(SCH_1):M_J_PAR   I187 @BASEBOARD_FAB2_LIB.BASEBOARD_FAB2(SCH_1):PAGE82
    58 M_GHJ_RST_N @BASEBOARD_FAB2_LIB.BASEBOARD_FAB2(SCH_1):M_GHJ_RST_N   I187 @BASEBOARD_FAB2_LIB.BASEBOARD_FAB2(SCH_1):PAGE82
   144 TP_CH_J_DIMM_J1_RFU_2 @BASEBOARD_FAB2_LIB.BASEBOARD_FAB2(SCH_1):TP_CH_J_DIMM_J1_RFU_2   I187 @BASEBOARD_FAB2_LIB.BASEBOARD_FAB2(SCH_1):PAGE82
   227 TP_CH_J_DIMM_J1_RFU_1 @BASEBOARD_FAB2_LIB.BASEBOARD_FAB2(SCH_1):TP_CH_J_DIMM_J1_RFU_1   I187 @BASEBOARD_FAB2_LIB.BASEBOARD_FAB2(SCH_1):PAGE82
   205 TP_CH_J_DIMM_J1_RFU_0 @BASEBOARD_FAB2_LIB.BASEBOARD_FAB2(SCH_1):TP_CH_J_DIMM_J1_RFU_0   I187 @BASEBOARD_FAB2_LIB.BASEBOARD_FAB2(SCH_1):PAGE82
    84 M_J_CS_N<4> @BASEBOARD_FAB2_LIB.BASEBOARD_FAB2(SCH_1):M_J_CS_N(4)   I187 @BASEBOARD_FAB2_LIB.BASEBOARD_FAB2(SCH_1):PAGE82
    89 M_J_CS_N<5> @BASEBOARD_FAB2_LIB.BASEBOARD_FAB2(SCH_1):M_J_CS_N(5)   I187 @BASEBOARD_FAB2_LIB.BASEBOARD_FAB2(SCH_1):PAGE82
    93 M_J_CS_N<6> @BASEBOARD_FAB2_LIB.BASEBOARD_FAB2(SCH_1):M_J_CS_N(6)   I187 @BASEBOARD_FAB2_LIB.BASEBOARD_FAB2(SCH_1):PAGE82
   237 M_J_CS_N<7> @BASEBOARD_FAB2_LIB.BASEBOARD_FAB2(SCH_1):M_J_CS_N(7)   I187 @BASEBOARD_FAB2_LIB.BASEBOARD_FAB2(SCH_1):PAGE82
   238 PVPP_GHJ @BASEBOARD_FAB2_LIB.BASEBOARD_FAB2(SCH_1):PVPP_GHJ   I187 @BASEBOARD_FAB2_LIB.BASEBOARD_FAB2(SCH_1):PAGE82
   140    GND @BASEBOARD_FAB2_LIB.BASEBOARD_FAB2(SCH_1):GND   I187 @BASEBOARD_FAB2_LIB.BASEBOARD_FAB2(SCH_1):PAGE82
   139 PVPP_GHJ @BASEBOARD_FAB2_LIB.BASEBOARD_FAB2(SCH_1):PVPP_GHJ   I187 @BASEBOARD_FAB2_LIB.BASEBOARD_FAB2(SCH_1):PAGE82
   230 FM_ADR_COMPLETE_GHJ_N @BASEBOARD_FAB2_LIB.BASEBOARD_FAB2(SCH_1):FM_ADR_COMPLETE_GHJ_N   I187 @BASEBOARD_FAB2_LIB.BASEBOARD_FAB2(SCH_1):PAGE82
   141 SMB_DDR_GHJ_VPP_SCL @BASEBOARD_FAB2_LIB.BASEBOARD_FAB2(SCH_1):SMB_DDR_GHJ_VPP_SCL   I187 @BASEBOARD_FAB2_LIB.BASEBOARD_FAB2(SCH_1):PAGE82
   285 SMB_DDR_GHJ_VPP_SDA @BASEBOARD_FAB2_LIB.BASEBOARD_FAB2(SCH_1):SMB_DDR_GHJ_VPP_SDA   I187 @BASEBOARD_FAB2_LIB.BASEBOARD_FAB2(SCH_1):PAGE82
   284 PVPP_GHJ @BASEBOARD_FAB2_LIB.BASEBOARD_FAB2(SCH_1):PVPP_GHJ   I187 @BASEBOARD_FAB2_LIB.BASEBOARD_FAB2(SCH_1):PAGE82
   146 M_J_VREF @BASEBOARD_FAB2_LIB.BASEBOARD_FAB2(SCH_1):M_J_VREF   I187 @BASEBOARD_FAB2_LIB.BASEBOARD_FAB2(SCH_1):PAGE82
   152 M_J_DQS_DN<0> @BASEBOARD_FAB2_LIB.BASEBOARD_FAB2(SCH_1):M_J_DQS_DN(0)    I64 @BASEBOARD_FAB2_LIB.BASEBOARD_FAB2(SCH_1):PAGE82
   153 M_J_DQS_DP<0> @BASEBOARD_FAB2_LIB.BASEBOARD_FAB2(SCH_1):M_J_DQS_DP(0)    I64 @BASEBOARD_FAB2_LIB.BASEBOARD_FAB2(SCH_1):PAGE82
    19 M_J_DQS_DN<10> @BASEBOARD_FAB2_LIB.BASEBOARD_FAB2(SCH_1):M_J_DQS_DN(10)    I64 @BASEBOARD_FAB2_LIB.BASEBOARD_FAB2(SCH_1):PAGE82
    18 M_J_DQS_DP<10> @BASEBOARD_FAB2_LIB.BASEBOARD_FAB2(SCH_1):M_J_DQS_DP(10)    I64 @BASEBOARD_FAB2_LIB.BASEBOARD_FAB2(SCH_1):PAGE82
    30 M_J_DQS_DN<11> @BASEBOARD_FAB2_LIB.BASEBOARD_FAB2(SCH_1):M_J_DQS_DN(11)    I64 @BASEBOARD_FAB2_LIB.BASEBOARD_FAB2(SCH_1):PAGE82
    29 M_J_DQS_DP<11> @BASEBOARD_FAB2_LIB.BASEBOARD_FAB2(SCH_1):M_J_DQS_DP(11)    I64 @BASEBOARD_FAB2_LIB.BASEBOARD_FAB2(SCH_1):PAGE82
    41 M_J_DQS_DN<12> @BASEBOARD_FAB2_LIB.BASEBOARD_FAB2(SCH_1):M_J_DQS_DN(12)    I64 @BASEBOARD_FAB2_LIB.BASEBOARD_FAB2(SCH_1):PAGE82
    40 M_J_DQS_DP<12> @BASEBOARD_FAB2_LIB.BASEBOARD_FAB2(SCH_1):M_J_DQS_DP(12)    I64 @BASEBOARD_FAB2_LIB.BASEBOARD_FAB2(SCH_1):PAGE82
   100 M_J_DQS_DN<13> @BASEBOARD_FAB2_LIB.BASEBOARD_FAB2(SCH_1):M_J_DQS_DN(13)    I64 @BASEBOARD_FAB2_LIB.BASEBOARD_FAB2(SCH_1):PAGE82
    99 M_J_DQS_DP<13> @BASEBOARD_FAB2_LIB.BASEBOARD_FAB2(SCH_1):M_J_DQS_DP(13)    I64 @BASEBOARD_FAB2_LIB.BASEBOARD_FAB2(SCH_1):PAGE82
   111 M_J_DQS_DN<14> @BASEBOARD_FAB2_LIB.BASEBOARD_FAB2(SCH_1):M_J_DQS_DN(14)    I64 @BASEBOARD_FAB2_LIB.BASEBOARD_FAB2(SCH_1):PAGE82
   110 M_J_DQS_DP<14> @BASEBOARD_FAB2_LIB.BASEBOARD_FAB2(SCH_1):M_J_DQS_DP(14)    I64 @BASEBOARD_FAB2_LIB.BASEBOARD_FAB2(SCH_1):PAGE82
   122 M_J_DQS_DN<15> @BASEBOARD_FAB2_LIB.BASEBOARD_FAB2(SCH_1):M_J_DQS_DN(15)    I64 @BASEBOARD_FAB2_LIB.BASEBOARD_FAB2(SCH_1):PAGE82
   121 M_J_DQS_DP<15> @BASEBOARD_FAB2_LIB.BASEBOARD_FAB2(SCH_1):M_J_DQS_DP(15)    I64 @BASEBOARD_FAB2_LIB.BASEBOARD_FAB2(SCH_1):PAGE82
   133 M_J_DQS_DN<16> @BASEBOARD_FAB2_LIB.BASEBOARD_FAB2(SCH_1):M_J_DQS_DN(16)    I64 @BASEBOARD_FAB2_LIB.BASEBOARD_FAB2(SCH_1):PAGE82
   132 M_J_DQS_DP<16> @BASEBOARD_FAB2_LIB.BASEBOARD_FAB2(SCH_1):M_J_DQS_DP(16)    I64 @BASEBOARD_FAB2_LIB.BASEBOARD_FAB2(SCH_1):PAGE82
    52 M_J_DQS_DN<17> @BASEBOARD_FAB2_LIB.BASEBOARD_FAB2(SCH_1):M_J_DQS_DN(17)    I64 @BASEBOARD_FAB2_LIB.BASEBOARD_FAB2(SCH_1):PAGE82
    51 M_J_DQS_DP<17> @BASEBOARD_FAB2_LIB.BASEBOARD_FAB2(SCH_1):M_J_DQS_DP(17)    I64 @BASEBOARD_FAB2_LIB.BASEBOARD_FAB2(SCH_1):PAGE82
   163 M_J_DQS_DN<1> @BASEBOARD_FAB2_LIB.BASEBOARD_FAB2(SCH_1):M_J_DQS_DN(1)    I64 @BASEBOARD_FAB2_LIB.BASEBOARD_FAB2(SCH_1):PAGE82
   164 M_J_DQS_DP<1> @BASEBOARD_FAB2_LIB.BASEBOARD_FAB2(SCH_1):M_J_DQS_DP(1)    I64 @BASEBOARD_FAB2_LIB.BASEBOARD_FAB2(SCH_1):PAGE82
   174 M_J_DQS_DN<2> @BASEBOARD_FAB2_LIB.BASEBOARD_FAB2(SCH_1):M_J_DQS_DN(2)    I64 @BASEBOARD_FAB2_LIB.BASEBOARD_FAB2(SCH_1):PAGE82
   175 M_J_DQS_DP<2> @BASEBOARD_FAB2_LIB.BASEBOARD_FAB2(SCH_1):M_J_DQS_DP(2)    I64 @BASEBOARD_FAB2_LIB.BASEBOARD_FAB2(SCH_1):PAGE82
   185 M_J_DQS_DN<3> @BASEBOARD_FAB2_LIB.BASEBOARD_FAB2(SCH_1):M_J_DQS_DN(3)    I64 @BASEBOARD_FAB2_LIB.BASEBOARD_FAB2(SCH_1):PAGE82
   186 M_J_DQS_DP<3> @BASEBOARD_FAB2_LIB.BASEBOARD_FAB2(SCH_1):M_J_DQS_DP(3)    I64 @BASEBOARD_FAB2_LIB.BASEBOARD_FAB2(SCH_1):PAGE82
   244 M_J_DQS_DN<4> @BASEBOARD_FAB2_LIB.BASEBOARD_FAB2(SCH_1):M_J_DQS_DN(4)    I64 @BASEBOARD_FAB2_LIB.BASEBOARD_FAB2(SCH_1):PAGE82
   245 M_J_DQS_DP<4> @BASEBOARD_FAB2_LIB.BASEBOARD_FAB2(SCH_1):M_J_DQS_DP(4)    I64 @BASEBOARD_FAB2_LIB.BASEBOARD_FAB2(SCH_1):PAGE82
   255 M_J_DQS_DN<5> @BASEBOARD_FAB2_LIB.BASEBOARD_FAB2(SCH_1):M_J_DQS_DN(5)    I64 @BASEBOARD_FAB2_LIB.BASEBOARD_FAB2(SCH_1):PAGE82
   256 M_J_DQS_DP<5> @BASEBOARD_FAB2_LIB.BASEBOARD_FAB2(SCH_1):M_J_DQS_DP(5)    I64 @BASEBOARD_FAB2_LIB.BASEBOARD_FAB2(SCH_1):PAGE82
   266 M_J_DQS_DN<6> @BASEBOARD_FAB2_LIB.BASEBOARD_FAB2(SCH_1):M_J_DQS_DN(6)    I64 @BASEBOARD_FAB2_LIB.BASEBOARD_FAB2(SCH_1):PAGE82
   267 M_J_DQS_DP<6> @BASEBOARD_FAB2_LIB.BASEBOARD_FAB2(SCH_1):M_J_DQS_DP(6)    I64 @BASEBOARD_FAB2_LIB.BASEBOARD_FAB2(SCH_1):PAGE82
   277 M_J_DQS_DN<7> @BASEBOARD_FAB2_LIB.BASEBOARD_FAB2(SCH_1):M_J_DQS_DN(7)    I64 @BASEBOARD_FAB2_LIB.BASEBOARD_FAB2(SCH_1):PAGE82
   278 M_J_DQS_DP<7> @BASEBOARD_FAB2_LIB.BASEBOARD_FAB2(SCH_1):M_J_DQS_DP(7)    I64 @BASEBOARD_FAB2_LIB.BASEBOARD_FAB2(SCH_1):PAGE82
   196 M_J_DQS_DN<8> @BASEBOARD_FAB2_LIB.BASEBOARD_FAB2(SCH_1):M_J_DQS_DN(8)    I64 @BASEBOARD_FAB2_LIB.BASEBOARD_FAB2(SCH_1):PAGE82
   197 M_J_DQS_DP<8> @BASEBOARD_FAB2_LIB.BASEBOARD_FAB2(SCH_1):M_J_DQS_DP(8)    I64 @BASEBOARD_FAB2_LIB.BASEBOARD_FAB2(SCH_1):PAGE82
     8 M_J_DQS_DN<9> @BASEBOARD_FAB2_LIB.BASEBOARD_FAB2(SCH_1):M_J_DQS_DN(9)    I64 @BASEBOARD_FAB2_LIB.BASEBOARD_FAB2(SCH_1):PAGE82
     7 M_J_DQS_DP<9> @BASEBOARD_FAB2_LIB.BASEBOARD_FAB2(SCH_1):M_J_DQS_DP(9)    I64 @BASEBOARD_FAB2_LIB.BASEBOARD_FAB2(SCH_1):PAGE82
     2    GND @BASEBOARD_FAB2_LIB.BASEBOARD_FAB2(SCH_1):GND   I188 @BASEBOARD_FAB2_LIB.BASEBOARD_FAB2(SCH_1):PAGE82
     4    GND @BASEBOARD_FAB2_LIB.BASEBOARD_FAB2(SCH_1):GND   I188 @BASEBOARD_FAB2_LIB.BASEBOARD_FAB2(SCH_1):PAGE82
     6    GND @BASEBOARD_FAB2_LIB.BASEBOARD_FAB2(SCH_1):GND   I188 @BASEBOARD_FAB2_LIB.BASEBOARD_FAB2(SCH_1):PAGE82
     9    GND @BASEBOARD_FAB2_LIB.BASEBOARD_FAB2(SCH_1):GND   I188 @BASEBOARD_FAB2_LIB.BASEBOARD_FAB2(SCH_1):PAGE82
    11    GND @BASEBOARD_FAB2_LIB.BASEBOARD_FAB2(SCH_1):GND   I188 @BASEBOARD_FAB2_LIB.BASEBOARD_FAB2(SCH_1):PAGE82
    13    GND @BASEBOARD_FAB2_LIB.BASEBOARD_FAB2(SCH_1):GND   I188 @BASEBOARD_FAB2_LIB.BASEBOARD_FAB2(SCH_1):PAGE82
    15    GND @BASEBOARD_FAB2_LIB.BASEBOARD_FAB2(SCH_1):GND   I188 @BASEBOARD_FAB2_LIB.BASEBOARD_FAB2(SCH_1):PAGE82
    17    GND @BASEBOARD_FAB2_LIB.BASEBOARD_FAB2(SCH_1):GND   I188 @BASEBOARD_FAB2_LIB.BASEBOARD_FAB2(SCH_1):PAGE82
    20    GND @BASEBOARD_FAB2_LIB.BASEBOARD_FAB2(SCH_1):GND   I188 @BASEBOARD_FAB2_LIB.BASEBOARD_FAB2(SCH_1):PAGE82
    22    GND @BASEBOARD_FAB2_LIB.BASEBOARD_FAB2(SCH_1):GND   I188 @BASEBOARD_FAB2_LIB.BASEBOARD_FAB2(SCH_1):PAGE82
    24    GND @BASEBOARD_FAB2_LIB.BASEBOARD_FAB2(SCH_1):GND   I188 @BASEBOARD_FAB2_LIB.BASEBOARD_FAB2(SCH_1):PAGE82
    26    GND @BASEBOARD_FAB2_LIB.BASEBOARD_FAB2(SCH_1):GND   I188 @BASEBOARD_FAB2_LIB.BASEBOARD_FAB2(SCH_1):PAGE82
    28    GND @BASEBOARD_FAB2_LIB.BASEBOARD_FAB2(SCH_1):GND   I188 @BASEBOARD_FAB2_LIB.BASEBOARD_FAB2(SCH_1):PAGE82
    31    GND @BASEBOARD_FAB2_LIB.BASEBOARD_FAB2(SCH_1):GND   I188 @BASEBOARD_FAB2_LIB.BASEBOARD_FAB2(SCH_1):PAGE82
    33    GND @BASEBOARD_FAB2_LIB.BASEBOARD_FAB2(SCH_1):GND   I188 @BASEBOARD_FAB2_LIB.BASEBOARD_FAB2(SCH_1):PAGE82
    35    GND @BASEBOARD_FAB2_LIB.BASEBOARD_FAB2(SCH_1):GND   I188 @BASEBOARD_FAB2_LIB.BASEBOARD_FAB2(SCH_1):PAGE82
    37    GND @BASEBOARD_FAB2_LIB.BASEBOARD_FAB2(SCH_1):GND   I188 @BASEBOARD_FAB2_LIB.BASEBOARD_FAB2(SCH_1):PAGE82
    39    GND @BASEBOARD_FAB2_LIB.BASEBOARD_FAB2(SCH_1):GND   I188 @BASEBOARD_FAB2_LIB.BASEBOARD_FAB2(SCH_1):PAGE82
    42    GND @BASEBOARD_FAB2_LIB.BASEBOARD_FAB2(SCH_1):GND   I188 @BASEBOARD_FAB2_LIB.BASEBOARD_FAB2(SCH_1):PAGE82
    44    GND @BASEBOARD_FAB2_LIB.BASEBOARD_FAB2(SCH_1):GND   I188 @BASEBOARD_FAB2_LIB.BASEBOARD_FAB2(SCH_1):PAGE82
    46    GND @BASEBOARD_FAB2_LIB.BASEBOARD_FAB2(SCH_1):GND   I188 @BASEBOARD_FAB2_LIB.BASEBOARD_FAB2(SCH_1):PAGE82
    48    GND @BASEBOARD_FAB2_LIB.BASEBOARD_FAB2(SCH_1):GND   I188 @BASEBOARD_FAB2_LIB.BASEBOARD_FAB2(SCH_1):PAGE82
    50    GND @BASEBOARD_FAB2_LIB.BASEBOARD_FAB2(SCH_1):GND   I188 @BASEBOARD_FAB2_LIB.BASEBOARD_FAB2(SCH_1):PAGE82
    53    GND @BASEBOARD_FAB2_LIB.BASEBOARD_FAB2(SCH_1):GND   I188 @BASEBOARD_FAB2_LIB.BASEBOARD_FAB2(SCH_1):PAGE82
    55    GND @BASEBOARD_FAB2_LIB.BASEBOARD_FAB2(SCH_1):GND   I188 @BASEBOARD_FAB2_LIB.BASEBOARD_FAB2(SCH_1):PAGE82
    57    GND @BASEBOARD_FAB2_LIB.BASEBOARD_FAB2(SCH_1):GND   I188 @BASEBOARD_FAB2_LIB.BASEBOARD_FAB2(SCH_1):PAGE82
    94    GND @BASEBOARD_FAB2_LIB.BASEBOARD_FAB2(SCH_1):GND   I188 @BASEBOARD_FAB2_LIB.BASEBOARD_FAB2(SCH_1):PAGE82
    96    GND @BASEBOARD_FAB2_LIB.BASEBOARD_FAB2(SCH_1):GND   I188 @BASEBOARD_FAB2_LIB.BASEBOARD_FAB2(SCH_1):PAGE82
    98    GND @BASEBOARD_FAB2_LIB.BASEBOARD_FAB2(SCH_1):GND   I188 @BASEBOARD_FAB2_LIB.BASEBOARD_FAB2(SCH_1):PAGE82
   101    GND @BASEBOARD_FAB2_LIB.BASEBOARD_FAB2(SCH_1):GND   I188 @BASEBOARD_FAB2_LIB.BASEBOARD_FAB2(SCH_1):PAGE82
   103    GND @BASEBOARD_FAB2_LIB.BASEBOARD_FAB2(SCH_1):GND   I188 @BASEBOARD_FAB2_LIB.BASEBOARD_FAB2(SCH_1):PAGE82
   105    GND @BASEBOARD_FAB2_LIB.BASEBOARD_FAB2(SCH_1):GND   I188 @BASEBOARD_FAB2_LIB.BASEBOARD_FAB2(SCH_1):PAGE82
   107    GND @BASEBOARD_FAB2_LIB.BASEBOARD_FAB2(SCH_1):GND   I188 @BASEBOARD_FAB2_LIB.BASEBOARD_FAB2(SCH_1):PAGE82
   109    GND @BASEBOARD_FAB2_LIB.BASEBOARD_FAB2(SCH_1):GND   I188 @BASEBOARD_FAB2_LIB.BASEBOARD_FAB2(SCH_1):PAGE82
   112    GND @BASEBOARD_FAB2_LIB.BASEBOARD_FAB2(SCH_1):GND   I188 @BASEBOARD_FAB2_LIB.BASEBOARD_FAB2(SCH_1):PAGE82
   114    GND @BASEBOARD_FAB2_LIB.BASEBOARD_FAB2(SCH_1):GND   I188 @BASEBOARD_FAB2_LIB.BASEBOARD_FAB2(SCH_1):PAGE82
   116    GND @BASEBOARD_FAB2_LIB.BASEBOARD_FAB2(SCH_1):GND   I188 @BASEBOARD_FAB2_LIB.BASEBOARD_FAB2(SCH_1):PAGE82
   118    GND @BASEBOARD_FAB2_LIB.BASEBOARD_FAB2(SCH_1):GND   I188 @BASEBOARD_FAB2_LIB.BASEBOARD_FAB2(SCH_1):PAGE82
   120    GND @BASEBOARD_FAB2_LIB.BASEBOARD_FAB2(SCH_1):GND   I188 @BASEBOARD_FAB2_LIB.BASEBOARD_FAB2(SCH_1):PAGE82
   123    GND @BASEBOARD_FAB2_LIB.BASEBOARD_FAB2(SCH_1):GND   I188 @BASEBOARD_FAB2_LIB.BASEBOARD_FAB2(SCH_1):PAGE82
   125    GND @BASEBOARD_FAB2_LIB.BASEBOARD_FAB2(SCH_1):GND   I188 @BASEBOARD_FAB2_LIB.BASEBOARD_FAB2(SCH_1):PAGE82
   127    GND @BASEBOARD_FAB2_LIB.BASEBOARD_FAB2(SCH_1):GND   I188 @BASEBOARD_FAB2_LIB.BASEBOARD_FAB2(SCH_1):PAGE82
   129    GND @BASEBOARD_FAB2_LIB.BASEBOARD_FAB2(SCH_1):GND   I188 @BASEBOARD_FAB2_LIB.BASEBOARD_FAB2(SCH_1):PAGE82
   131    GND @BASEBOARD_FAB2_LIB.BASEBOARD_FAB2(SCH_1):GND   I188 @BASEBOARD_FAB2_LIB.BASEBOARD_FAB2(SCH_1):PAGE82
   134    GND @BASEBOARD_FAB2_LIB.BASEBOARD_FAB2(SCH_1):GND   I188 @BASEBOARD_FAB2_LIB.BASEBOARD_FAB2(SCH_1):PAGE82
   136    GND @BASEBOARD_FAB2_LIB.BASEBOARD_FAB2(SCH_1):GND   I188 @BASEBOARD_FAB2_LIB.BASEBOARD_FAB2(SCH_1):PAGE82
   138    GND @BASEBOARD_FAB2_LIB.BASEBOARD_FAB2(SCH_1):GND   I188 @BASEBOARD_FAB2_LIB.BASEBOARD_FAB2(SCH_1):PAGE82
   147    GND @BASEBOARD_FAB2_LIB.BASEBOARD_FAB2(SCH_1):GND   I188 @BASEBOARD_FAB2_LIB.BASEBOARD_FAB2(SCH_1):PAGE82
   149    GND @BASEBOARD_FAB2_LIB.BASEBOARD_FAB2(SCH_1):GND   I188 @BASEBOARD_FAB2_LIB.BASEBOARD_FAB2(SCH_1):PAGE82
   151    GND @BASEBOARD_FAB2_LIB.BASEBOARD_FAB2(SCH_1):GND   I188 @BASEBOARD_FAB2_LIB.BASEBOARD_FAB2(SCH_1):PAGE82
   154    GND @BASEBOARD_FAB2_LIB.BASEBOARD_FAB2(SCH_1):GND   I188 @BASEBOARD_FAB2_LIB.BASEBOARD_FAB2(SCH_1):PAGE82
   156    GND @BASEBOARD_FAB2_LIB.BASEBOARD_FAB2(SCH_1):GND   I188 @BASEBOARD_FAB2_LIB.BASEBOARD_FAB2(SCH_1):PAGE82
   158    GND @BASEBOARD_FAB2_LIB.BASEBOARD_FAB2(SCH_1):GND   I188 @BASEBOARD_FAB2_LIB.BASEBOARD_FAB2(SCH_1):PAGE82
   160    GND @BASEBOARD_FAB2_LIB.BASEBOARD_FAB2(SCH_1):GND   I188 @BASEBOARD_FAB2_LIB.BASEBOARD_FAB2(SCH_1):PAGE82
   162    GND @BASEBOARD_FAB2_LIB.BASEBOARD_FAB2(SCH_1):GND   I188 @BASEBOARD_FAB2_LIB.BASEBOARD_FAB2(SCH_1):PAGE82
   165    GND @BASEBOARD_FAB2_LIB.BASEBOARD_FAB2(SCH_1):GND   I188 @BASEBOARD_FAB2_LIB.BASEBOARD_FAB2(SCH_1):PAGE82
   167    GND @BASEBOARD_FAB2_LIB.BASEBOARD_FAB2(SCH_1):GND   I188 @BASEBOARD_FAB2_LIB.BASEBOARD_FAB2(SCH_1):PAGE82
   169    GND @BASEBOARD_FAB2_LIB.BASEBOARD_FAB2(SCH_1):GND   I188 @BASEBOARD_FAB2_LIB.BASEBOARD_FAB2(SCH_1):PAGE82
   171    GND @BASEBOARD_FAB2_LIB.BASEBOARD_FAB2(SCH_1):GND   I188 @BASEBOARD_FAB2_LIB.BASEBOARD_FAB2(SCH_1):PAGE82
   173    GND @BASEBOARD_FAB2_LIB.BASEBOARD_FAB2(SCH_1):GND   I188 @BASEBOARD_FAB2_LIB.BASEBOARD_FAB2(SCH_1):PAGE82
   176    GND @BASEBOARD_FAB2_LIB.BASEBOARD_FAB2(SCH_1):GND   I188 @BASEBOARD_FAB2_LIB.BASEBOARD_FAB2(SCH_1):PAGE82
   178    GND @BASEBOARD_FAB2_LIB.BASEBOARD_FAB2(SCH_1):GND   I188 @BASEBOARD_FAB2_LIB.BASEBOARD_FAB2(SCH_1):PAGE82
   180    GND @BASEBOARD_FAB2_LIB.BASEBOARD_FAB2(SCH_1):GND   I188 @BASEBOARD_FAB2_LIB.BASEBOARD_FAB2(SCH_1):PAGE82
   182    GND @BASEBOARD_FAB2_LIB.BASEBOARD_FAB2(SCH_1):GND   I188 @BASEBOARD_FAB2_LIB.BASEBOARD_FAB2(SCH_1):PAGE82
   184    GND @BASEBOARD_FAB2_LIB.BASEBOARD_FAB2(SCH_1):GND   I188 @BASEBOARD_FAB2_LIB.BASEBOARD_FAB2(SCH_1):PAGE82
   187    GND @BASEBOARD_FAB2_LIB.BASEBOARD_FAB2(SCH_1):GND   I188 @BASEBOARD_FAB2_LIB.BASEBOARD_FAB2(SCH_1):PAGE82
   189    GND @BASEBOARD_FAB2_LIB.BASEBOARD_FAB2(SCH_1):GND   I188 @BASEBOARD_FAB2_LIB.BASEBOARD_FAB2(SCH_1):PAGE82
   191    GND @BASEBOARD_FAB2_LIB.BASEBOARD_FAB2(SCH_1):GND   I188 @BASEBOARD_FAB2_LIB.BASEBOARD_FAB2(SCH_1):PAGE82
   193    GND @BASEBOARD_FAB2_LIB.BASEBOARD_FAB2(SCH_1):GND   I188 @BASEBOARD_FAB2_LIB.BASEBOARD_FAB2(SCH_1):PAGE82
   195    GND @BASEBOARD_FAB2_LIB.BASEBOARD_FAB2(SCH_1):GND   I188 @BASEBOARD_FAB2_LIB.BASEBOARD_FAB2(SCH_1):PAGE82
   198    GND @BASEBOARD_FAB2_LIB.BASEBOARD_FAB2(SCH_1):GND   I188 @BASEBOARD_FAB2_LIB.BASEBOARD_FAB2(SCH_1):PAGE82
   200    GND @BASEBOARD_FAB2_LIB.BASEBOARD_FAB2(SCH_1):GND   I188 @BASEBOARD_FAB2_LIB.BASEBOARD_FAB2(SCH_1):PAGE82
   202    GND @BASEBOARD_FAB2_LIB.BASEBOARD_FAB2(SCH_1):GND   I188 @BASEBOARD_FAB2_LIB.BASEBOARD_FAB2(SCH_1):PAGE82
   239    GND @BASEBOARD_FAB2_LIB.BASEBOARD_FAB2(SCH_1):GND   I188 @BASEBOARD_FAB2_LIB.BASEBOARD_FAB2(SCH_1):PAGE82
   241    GND @BASEBOARD_FAB2_LIB.BASEBOARD_FAB2(SCH_1):GND   I188 @BASEBOARD_FAB2_LIB.BASEBOARD_FAB2(SCH_1):PAGE82
   243    GND @BASEBOARD_FAB2_LIB.BASEBOARD_FAB2(SCH_1):GND   I188 @BASEBOARD_FAB2_LIB.BASEBOARD_FAB2(SCH_1):PAGE82
   246    GND @BASEBOARD_FAB2_LIB.BASEBOARD_FAB2(SCH_1):GND   I188 @BASEBOARD_FAB2_LIB.BASEBOARD_FAB2(SCH_1):PAGE82
   248    GND @BASEBOARD_FAB2_LIB.BASEBOARD_FAB2(SCH_1):GND   I188 @BASEBOARD_FAB2_LIB.BASEBOARD_FAB2(SCH_1):PAGE82
   250    GND @BASEBOARD_FAB2_LIB.BASEBOARD_FAB2(SCH_1):GND   I188 @BASEBOARD_FAB2_LIB.BASEBOARD_FAB2(SCH_1):PAGE82
   252    GND @BASEBOARD_FAB2_LIB.BASEBOARD_FAB2(SCH_1):GND   I188 @BASEBOARD_FAB2_LIB.BASEBOARD_FAB2(SCH_1):PAGE82
   254    GND @BASEBOARD_FAB2_LIB.BASEBOARD_FAB2(SCH_1):GND   I188 @BASEBOARD_FAB2_LIB.BASEBOARD_FAB2(SCH_1):PAGE82
   257    GND @BASEBOARD_FAB2_LIB.BASEBOARD_FAB2(SCH_1):GND   I188 @BASEBOARD_FAB2_LIB.BASEBOARD_FAB2(SCH_1):PAGE82
   259    GND @BASEBOARD_FAB2_LIB.BASEBOARD_FAB2(SCH_1):GND   I188 @BASEBOARD_FAB2_LIB.BASEBOARD_FAB2(SCH_1):PAGE82
   261    GND @BASEBOARD_FAB2_LIB.BASEBOARD_FAB2(SCH_1):GND   I188 @BASEBOARD_FAB2_LIB.BASEBOARD_FAB2(SCH_1):PAGE82
   263    GND @BASEBOARD_FAB2_LIB.BASEBOARD_FAB2(SCH_1):GND   I188 @BASEBOARD_FAB2_LIB.BASEBOARD_FAB2(SCH_1):PAGE82
   265    GND @BASEBOARD_FAB2_LIB.BASEBOARD_FAB2(SCH_1):GND   I188 @BASEBOARD_FAB2_LIB.BASEBOARD_FAB2(SCH_1):PAGE82
   268    GND @BASEBOARD_FAB2_LIB.BASEBOARD_FAB2(SCH_1):GND   I188 @BASEBOARD_FAB2_LIB.BASEBOARD_FAB2(SCH_1):PAGE82
   270    GND @BASEBOARD_FAB2_LIB.BASEBOARD_FAB2(SCH_1):GND   I188 @BASEBOARD_FAB2_LIB.BASEBOARD_FAB2(SCH_1):PAGE82
   272    GND @BASEBOARD_FAB2_LIB.BASEBOARD_FAB2(SCH_1):GND   I188 @BASEBOARD_FAB2_LIB.BASEBOARD_FAB2(SCH_1):PAGE82
   274    GND @BASEBOARD_FAB2_LIB.BASEBOARD_FAB2(SCH_1):GND   I188 @BASEBOARD_FAB2_LIB.BASEBOARD_FAB2(SCH_1):PAGE82
   276    GND @BASEBOARD_FAB2_LIB.BASEBOARD_FAB2(SCH_1):GND   I188 @BASEBOARD_FAB2_LIB.BASEBOARD_FAB2(SCH_1):PAGE82
   279    GND @BASEBOARD_FAB2_LIB.BASEBOARD_FAB2(SCH_1):GND   I188 @BASEBOARD_FAB2_LIB.BASEBOARD_FAB2(SCH_1):PAGE82
   281    GND @BASEBOARD_FAB2_LIB.BASEBOARD_FAB2(SCH_1):GND   I188 @BASEBOARD_FAB2_LIB.BASEBOARD_FAB2(SCH_1):PAGE82
   283    GND @BASEBOARD_FAB2_LIB.BASEBOARD_FAB2(SCH_1):GND   I188 @BASEBOARD_FAB2_LIB.BASEBOARD_FAB2(SCH_1):PAGE82
     1 P12V_NVDIMM_GHJ @BASEBOARD_FAB2_LIB.BASEBOARD_FAB2(SCH_1):P12V_NVDIMM_GHJ   I171 @BASEBOARD_FAB2_LIB.BASEBOARD_FAB2(SCH_1):PAGE82
   145 P12V_NVDIMM_GHJ @BASEBOARD_FAB2_LIB.BASEBOARD_FAB2(SCH_1):P12V_NVDIMM_GHJ   I171 @BASEBOARD_FAB2_LIB.BASEBOARD_FAB2(SCH_1):PAGE82
    59 PVDDQ_GHJ @BASEBOARD_FAB2_LIB.BASEBOARD_FAB2(SCH_1):PVDDQ_GHJ   I171 @BASEBOARD_FAB2_LIB.BASEBOARD_FAB2(SCH_1):PAGE82
    61 PVDDQ_GHJ @BASEBOARD_FAB2_LIB.BASEBOARD_FAB2(SCH_1):PVDDQ_GHJ   I171 @BASEBOARD_FAB2_LIB.BASEBOARD_FAB2(SCH_1):PAGE82
    64 PVDDQ_GHJ @BASEBOARD_FAB2_LIB.BASEBOARD_FAB2(SCH_1):PVDDQ_GHJ   I171 @BASEBOARD_FAB2_LIB.BASEBOARD_FAB2(SCH_1):PAGE82
    67 PVDDQ_GHJ @BASEBOARD_FAB2_LIB.BASEBOARD_FAB2(SCH_1):PVDDQ_GHJ   I171 @BASEBOARD_FAB2_LIB.BASEBOARD_FAB2(SCH_1):PAGE82
    70 PVDDQ_GHJ @BASEBOARD_FAB2_LIB.BASEBOARD_FAB2(SCH_1):PVDDQ_GHJ   I171 @BASEBOARD_FAB2_LIB.BASEBOARD_FAB2(SCH_1):PAGE82
    73 PVDDQ_GHJ @BASEBOARD_FAB2_LIB.BASEBOARD_FAB2(SCH_1):PVDDQ_GHJ   I171 @BASEBOARD_FAB2_LIB.BASEBOARD_FAB2(SCH_1):PAGE82
    76 PVDDQ_GHJ @BASEBOARD_FAB2_LIB.BASEBOARD_FAB2(SCH_1):PVDDQ_GHJ   I171 @BASEBOARD_FAB2_LIB.BASEBOARD_FAB2(SCH_1):PAGE82
    80 PVDDQ_GHJ @BASEBOARD_FAB2_LIB.BASEBOARD_FAB2(SCH_1):PVDDQ_GHJ   I171 @BASEBOARD_FAB2_LIB.BASEBOARD_FAB2(SCH_1):PAGE82
    83 PVDDQ_GHJ @BASEBOARD_FAB2_LIB.BASEBOARD_FAB2(SCH_1):PVDDQ_GHJ   I171 @BASEBOARD_FAB2_LIB.BASEBOARD_FAB2(SCH_1):PAGE82
    85 PVDDQ_GHJ @BASEBOARD_FAB2_LIB.BASEBOARD_FAB2(SCH_1):PVDDQ_GHJ   I171 @BASEBOARD_FAB2_LIB.BASEBOARD_FAB2(SCH_1):PAGE82
    88 PVDDQ_GHJ @BASEBOARD_FAB2_LIB.BASEBOARD_FAB2(SCH_1):PVDDQ_GHJ   I171 @BASEBOARD_FAB2_LIB.BASEBOARD_FAB2(SCH_1):PAGE82
    90 PVDDQ_GHJ @BASEBOARD_FAB2_LIB.BASEBOARD_FAB2(SCH_1):PVDDQ_GHJ   I171 @BASEBOARD_FAB2_LIB.BASEBOARD_FAB2(SCH_1):PAGE82
    92 PVDDQ_GHJ @BASEBOARD_FAB2_LIB.BASEBOARD_FAB2(SCH_1):PVDDQ_GHJ   I171 @BASEBOARD_FAB2_LIB.BASEBOARD_FAB2(SCH_1):PAGE82
   204 PVDDQ_GHJ @BASEBOARD_FAB2_LIB.BASEBOARD_FAB2(SCH_1):PVDDQ_GHJ   I171 @BASEBOARD_FAB2_LIB.BASEBOARD_FAB2(SCH_1):PAGE82
   206 PVDDQ_GHJ @BASEBOARD_FAB2_LIB.BASEBOARD_FAB2(SCH_1):PVDDQ_GHJ   I171 @BASEBOARD_FAB2_LIB.BASEBOARD_FAB2(SCH_1):PAGE82
   209 PVDDQ_GHJ @BASEBOARD_FAB2_LIB.BASEBOARD_FAB2(SCH_1):PVDDQ_GHJ   I171 @BASEBOARD_FAB2_LIB.BASEBOARD_FAB2(SCH_1):PAGE82
   212 PVDDQ_GHJ @BASEBOARD_FAB2_LIB.BASEBOARD_FAB2(SCH_1):PVDDQ_GHJ   I171 @BASEBOARD_FAB2_LIB.BASEBOARD_FAB2(SCH_1):PAGE82
   215 PVDDQ_GHJ @BASEBOARD_FAB2_LIB.BASEBOARD_FAB2(SCH_1):PVDDQ_GHJ   I171 @BASEBOARD_FAB2_LIB.BASEBOARD_FAB2(SCH_1):PAGE82
   217 PVDDQ_GHJ @BASEBOARD_FAB2_LIB.BASEBOARD_FAB2(SCH_1):PVDDQ_GHJ   I171 @BASEBOARD_FAB2_LIB.BASEBOARD_FAB2(SCH_1):PAGE82
   220 PVDDQ_GHJ @BASEBOARD_FAB2_LIB.BASEBOARD_FAB2(SCH_1):PVDDQ_GHJ   I171 @BASEBOARD_FAB2_LIB.BASEBOARD_FAB2(SCH_1):PAGE82
   223 PVDDQ_GHJ @BASEBOARD_FAB2_LIB.BASEBOARD_FAB2(SCH_1):PVDDQ_GHJ   I171 @BASEBOARD_FAB2_LIB.BASEBOARD_FAB2(SCH_1):PAGE82
   226 PVDDQ_GHJ @BASEBOARD_FAB2_LIB.BASEBOARD_FAB2(SCH_1):PVDDQ_GHJ   I171 @BASEBOARD_FAB2_LIB.BASEBOARD_FAB2(SCH_1):PAGE82
   229 PVDDQ_GHJ @BASEBOARD_FAB2_LIB.BASEBOARD_FAB2(SCH_1):PVDDQ_GHJ   I171 @BASEBOARD_FAB2_LIB.BASEBOARD_FAB2(SCH_1):PAGE82
   231 PVDDQ_GHJ @BASEBOARD_FAB2_LIB.BASEBOARD_FAB2(SCH_1):PVDDQ_GHJ   I171 @BASEBOARD_FAB2_LIB.BASEBOARD_FAB2(SCH_1):PAGE82
   233 PVDDQ_GHJ @BASEBOARD_FAB2_LIB.BASEBOARD_FAB2(SCH_1):PVDDQ_GHJ   I171 @BASEBOARD_FAB2_LIB.BASEBOARD_FAB2(SCH_1):PAGE82
   236 PVDDQ_GHJ @BASEBOARD_FAB2_LIB.BASEBOARD_FAB2(SCH_1):PVDDQ_GHJ   I171 @BASEBOARD_FAB2_LIB.BASEBOARD_FAB2(SCH_1):PAGE82
   142 PVPP_GHJ @BASEBOARD_FAB2_LIB.BASEBOARD_FAB2(SCH_1):PVPP_GHJ   I171 @BASEBOARD_FAB2_LIB.BASEBOARD_FAB2(SCH_1):PAGE82
   143 PVPP_GHJ @BASEBOARD_FAB2_LIB.BASEBOARD_FAB2(SCH_1):PVPP_GHJ   I171 @BASEBOARD_FAB2_LIB.BASEBOARD_FAB2(SCH_1):PAGE82
   288 PVPP_GHJ @BASEBOARD_FAB2_LIB.BASEBOARD_FAB2(SCH_1):PVPP_GHJ   I171 @BASEBOARD_FAB2_LIB.BASEBOARD_FAB2(SCH_1):PAGE82
   286 PVPP_GHJ @BASEBOARD_FAB2_LIB.BASEBOARD_FAB2(SCH_1):PVPP_GHJ   I171 @BASEBOARD_FAB2_LIB.BASEBOARD_FAB2(SCH_1):PAGE82
   287 PVPP_GHJ @BASEBOARD_FAB2_LIB.BASEBOARD_FAB2(SCH_1):PVPP_GHJ   I171 @BASEBOARD_FAB2_LIB.BASEBOARD_FAB2(SCH_1):PAGE82
    77 PVTT_GHJ @BASEBOARD_FAB2_LIB.BASEBOARD_FAB2(SCH_1):PVTT_GHJ   I171 @BASEBOARD_FAB2_LIB.BASEBOARD_FAB2(SCH_1):PAGE82
   221 PVTT_GHJ @BASEBOARD_FAB2_LIB.BASEBOARD_FAB2(SCH_1):PVTT_GHJ   I171 @BASEBOARD_FAB2_LIB.BASEBOARD_FAB2(SCH_1):PAGE82

J10W1 LOTES-CON4-S1-GP_CONN-G7-LOTESA
     1    GND @BASEBOARD_FAB2_LIB.BASEBOARD_FAB2(SCH_1):GND   I140 @BASEBOARD_FAB2_LIB.BASEBOARD_FAB2(SCH_1):PAGE161
     2 P12V_FAN @BASEBOARD_FAB2_LIB.BASEBOARD_FAB2(SCH_1):P12V_FAN   I140 @BASEBOARD_FAB2_LIB.BASEBOARD_FAB2(SCH_1):PAGE161
     3 FAN_TACH2_CPU1_D1 @BASEBOARD_FAB2_LIB.BASEBOARD_FAB2(SCH_1):FAN_TACH2_CPU1_D1   I140 @BASEBOARD_FAB2_LIB.BASEBOARD_FAB2(SCH_1):PAGE161
     4 FAN_PWM_OUT_SYS1_R @BASEBOARD_FAB2_LIB.BASEBOARD_FAB2(SCH_1):FAN_PWM_OUT_SYS1_R   I140 @BASEBOARD_FAB2_LIB.BASEBOARD_FAB2(SCH_1):PAGE161
   NP1     NC     NC   I140 @BASEBOARD_FAB2_LIB.BASEBOARD_FAB2(SCH_1):PAGE161

J25W1 SMC-CON13-GP_CONN-GC2-SMC-CON1A
     1 V_IO_R_J @BASEBOARD_FAB2_LIB.BASEBOARD_FAB2(SCH_1):V_IO_R_J   I136 @BASEBOARD_FAB2_LIB.BASEBOARD_FAB2(SCH_1):PAGE255
     2    GND @BASEBOARD_FAB2_LIB.BASEBOARD_FAB2(SCH_1):GND   I136 @BASEBOARD_FAB2_LIB.BASEBOARD_FAB2(SCH_1):PAGE255
     3 V_IO_G_J @BASEBOARD_FAB2_LIB.BASEBOARD_FAB2(SCH_1):V_IO_G_J   I136 @BASEBOARD_FAB2_LIB.BASEBOARD_FAB2(SCH_1):PAGE255
     4    GND @BASEBOARD_FAB2_LIB.BASEBOARD_FAB2(SCH_1):GND   I136 @BASEBOARD_FAB2_LIB.BASEBOARD_FAB2(SCH_1):PAGE255
     5 V_IO_B_J @BASEBOARD_FAB2_LIB.BASEBOARD_FAB2(SCH_1):V_IO_B_J   I136 @BASEBOARD_FAB2_LIB.BASEBOARD_FAB2(SCH_1):PAGE255
     6    GND @BASEBOARD_FAB2_LIB.BASEBOARD_FAB2(SCH_1):GND   I136 @BASEBOARD_FAB2_LIB.BASEBOARD_FAB2(SCH_1):PAGE255
     7 V_IO_VSYNC_J @BASEBOARD_FAB2_LIB.BASEBOARD_FAB2(SCH_1):V_IO_VSYNC_J   I136 @BASEBOARD_FAB2_LIB.BASEBOARD_FAB2(SCH_1):PAGE255
     8    GND @BASEBOARD_FAB2_LIB.BASEBOARD_FAB2(SCH_1):GND   I136 @BASEBOARD_FAB2_LIB.BASEBOARD_FAB2(SCH_1):PAGE255
     9 V_IO_HSYNC_J @BASEBOARD_FAB2_LIB.BASEBOARD_FAB2(SCH_1):V_IO_HSYNC_J   I136 @BASEBOARD_FAB2_LIB.BASEBOARD_FAB2(SCH_1):PAGE255
    10    GND @BASEBOARD_FAB2_LIB.BASEBOARD_FAB2(SCH_1):GND   I136 @BASEBOARD_FAB2_LIB.BASEBOARD_FAB2(SCH_1):PAGE255
    11 V_IBMC_5V_DDC_SDA_J @BASEBOARD_FAB2_LIB.BASEBOARD_FAB2(SCH_1):V_IBMC_5V_DDC_SDA_J   I136 @BASEBOARD_FAB2_LIB.BASEBOARD_FAB2(SCH_1):PAGE255
    12 V_IBMC_5V_DDC_SCL_J @BASEBOARD_FAB2_LIB.BASEBOARD_FAB2(SCH_1):V_IBMC_5V_DDC_SCL_J   I136 @BASEBOARD_FAB2_LIB.BASEBOARD_FAB2(SCH_1):PAGE255
    13 P5V_VGA @BASEBOARD_FAB2_LIB.BASEBOARD_FAB2(SCH_1):P5V_VGA   I136 @BASEBOARD_FAB2_LIB.BASEBOARD_FAB2(SCH_1):PAGE255
  PTH1    GND @BASEBOARD_FAB2_LIB.BASEBOARD_FAB2(SCH_1):GND   I136 @BASEBOARD_FAB2_LIB.BASEBOARD_FAB2(SCH_1):PAGE255
  PTH2    GND @BASEBOARD_FAB2_LIB.BASEBOARD_FAB2(SCH_1):GND   I136 @BASEBOARD_FAB2_LIB.BASEBOARD_FAB2(SCH_1):PAGE255

J30W1 SKT-USB32-8-GP_SOCKET-G4-SKT-UA
    A2 USB3_P01_FB_TXP @BASEBOARD_FAB2_LIB.BASEBOARD_FAB2(SCH_1):USB3_P01_FB_TXP    I26 @BASEBOARD_FAB2_LIB.BASEBOARD_FAB2(SCH_1):PAGE253
    A3 USB3_P01_FB_TXN @BASEBOARD_FAB2_LIB.BASEBOARD_FAB2(SCH_1):USB3_P01_FB_TXN    I26 @BASEBOARD_FAB2_LIB.BASEBOARD_FAB2(SCH_1):PAGE253
    A5     NC     NC    I26 @BASEBOARD_FAB2_LIB.BASEBOARD_FAB2(SCH_1):PAGE253
    A6     NC     NC    I26 @BASEBOARD_FAB2_LIB.BASEBOARD_FAB2(SCH_1):PAGE253
    A7     NC     NC    I26 @BASEBOARD_FAB2_LIB.BASEBOARD_FAB2(SCH_1):PAGE253
    B5     NC     NC    I26 @BASEBOARD_FAB2_LIB.BASEBOARD_FAB2(SCH_1):PAGE253
    B6     NC     NC    I26 @BASEBOARD_FAB2_LIB.BASEBOARD_FAB2(SCH_1):PAGE253
    B7     NC     NC    I26 @BASEBOARD_FAB2_LIB.BASEBOARD_FAB2(SCH_1):PAGE253
   B10 USB3_P01_FB_RXN @BASEBOARD_FAB2_LIB.BASEBOARD_FAB2(SCH_1):USB3_P01_FB_RXN    I26 @BASEBOARD_FAB2_LIB.BASEBOARD_FAB2(SCH_1):PAGE253
   B11 USB3_P01_FB_RXP @BASEBOARD_FAB2_LIB.BASEBOARD_FAB2(SCH_1):USB3_P01_FB_RXP    I26 @BASEBOARD_FAB2_LIB.BASEBOARD_FAB2(SCH_1):PAGE253
    A4 P5V_STBY_USBC @BASEBOARD_FAB2_LIB.BASEBOARD_FAB2(SCH_1):P5V_STBY_USBC    I26 @BASEBOARD_FAB2_LIB.BASEBOARD_FAB2(SCH_1):PAGE253
    A9 P5V_STBY_USBC @BASEBOARD_FAB2_LIB.BASEBOARD_FAB2(SCH_1):P5V_STBY_USBC    I26 @BASEBOARD_FAB2_LIB.BASEBOARD_FAB2(SCH_1):PAGE253
    B4 P5V_STBY_USBC @BASEBOARD_FAB2_LIB.BASEBOARD_FAB2(SCH_1):P5V_STBY_USBC    I26 @BASEBOARD_FAB2_LIB.BASEBOARD_FAB2(SCH_1):PAGE253
    B9 P5V_STBY_USBC @BASEBOARD_FAB2_LIB.BASEBOARD_FAB2(SCH_1):P5V_STBY_USBC    I26 @BASEBOARD_FAB2_LIB.BASEBOARD_FAB2(SCH_1):PAGE253
   A11     NC     NC    I26 @BASEBOARD_FAB2_LIB.BASEBOARD_FAB2(SCH_1):PAGE253
   A10     NC     NC    I26 @BASEBOARD_FAB2_LIB.BASEBOARD_FAB2(SCH_1):PAGE253
    B2     NC     NC    I26 @BASEBOARD_FAB2_LIB.BASEBOARD_FAB2(SCH_1):PAGE253
    B3     NC     NC    I26 @BASEBOARD_FAB2_LIB.BASEBOARD_FAB2(SCH_1):PAGE253
   NP1     NC     NC    I26 @BASEBOARD_FAB2_LIB.BASEBOARD_FAB2(SCH_1):PAGE253
   NP2     NC     NC    I26 @BASEBOARD_FAB2_LIB.BASEBOARD_FAB2(SCH_1):PAGE253
    A8     NC     NC    I26 @BASEBOARD_FAB2_LIB.BASEBOARD_FAB2(SCH_1):PAGE253
    B8     NC     NC    I26 @BASEBOARD_FAB2_LIB.BASEBOARD_FAB2(SCH_1):PAGE253
  PTH1    GND @BASEBOARD_FAB2_LIB.BASEBOARD_FAB2(SCH_1):GND    I26 @BASEBOARD_FAB2_LIB.BASEBOARD_FAB2(SCH_1):PAGE253
  PTH2    GND @BASEBOARD_FAB2_LIB.BASEBOARD_FAB2(SCH_1):GND    I26 @BASEBOARD_FAB2_LIB.BASEBOARD_FAB2(SCH_1):PAGE253
  PTH3    GND @BASEBOARD_FAB2_LIB.BASEBOARD_FAB2(SCH_1):GND    I26 @BASEBOARD_FAB2_LIB.BASEBOARD_FAB2(SCH_1):PAGE253
  PTH4    GND @BASEBOARD_FAB2_LIB.BASEBOARD_FAB2(SCH_1):GND    I26 @BASEBOARD_FAB2_LIB.BASEBOARD_FAB2(SCH_1):PAGE253
  PTH5    GND @BASEBOARD_FAB2_LIB.BASEBOARD_FAB2(SCH_1):GND    I26 @BASEBOARD_FAB2_LIB.BASEBOARD_FAB2(SCH_1):PAGE253
  PTH6    GND @BASEBOARD_FAB2_LIB.BASEBOARD_FAB2(SCH_1):GND    I26 @BASEBOARD_FAB2_LIB.BASEBOARD_FAB2(SCH_1):PAGE253
  PTH7    GND @BASEBOARD_FAB2_LIB.BASEBOARD_FAB2(SCH_1):GND    I26 @BASEBOARD_FAB2_LIB.BASEBOARD_FAB2(SCH_1):PAGE253
  PTH8    GND @BASEBOARD_FAB2_LIB.BASEBOARD_FAB2(SCH_1):GND    I26 @BASEBOARD_FAB2_LIB.BASEBOARD_FAB2(SCH_1):PAGE253
    A1    GND @BASEBOARD_FAB2_LIB.BASEBOARD_FAB2(SCH_1):GND    I26 @BASEBOARD_FAB2_LIB.BASEBOARD_FAB2(SCH_1):PAGE253
   A12    GND @BASEBOARD_FAB2_LIB.BASEBOARD_FAB2(SCH_1):GND    I26 @BASEBOARD_FAB2_LIB.BASEBOARD_FAB2(SCH_1):PAGE253
    B1    GND @BASEBOARD_FAB2_LIB.BASEBOARD_FAB2(SCH_1):GND    I26 @BASEBOARD_FAB2_LIB.BASEBOARD_FAB2(SCH_1):PAGE253
   B12    GND @BASEBOARD_FAB2_LIB.BASEBOARD_FAB2(SCH_1):GND    I26 @BASEBOARD_FAB2_LIB.BASEBOARD_FAB2(SCH_1):PAGE253

JA9G1 SKT-RJ45-LED-XFOR-1-GP_SOCKET-A
    L1 LED_LAN_2_R_N @BASEBOARD_FAB2_LIB.BASEBOARD_FAB2(SCH_1):LED_LAN_2_R_N   I129 @BASEBOARD_FAB2_LIB.BASEBOARD_FAB2(SCH_1):PAGE141
    L2 LED_LAN_0_R_N @BASEBOARD_FAB2_LIB.BASEBOARD_FAB2(SCH_1):LED_LAN_0_R_N   I129 @BASEBOARD_FAB2_LIB.BASEBOARD_FAB2(SCH_1):PAGE141
    L3 LED_LAN_1_R_N @BASEBOARD_FAB2_LIB.BASEBOARD_FAB2(SCH_1):LED_LAN_1_R_N   I129 @BASEBOARD_FAB2_LIB.BASEBOARD_FAB2(SCH_1):PAGE141
    L4 NIC_LED_ACT_ANODE_R @BASEBOARD_FAB2_LIB.BASEBOARD_FAB2(SCH_1):NIC_LED_ACT_ANODE_R   I129 @BASEBOARD_FAB2_LIB.BASEBOARD_FAB2(SCH_1):PAGE141
    R1 GND_LAN_TRCT1234_C @BASEBOARD_FAB2_LIB.BASEBOARD_FAB2(SCH_1):GND_LAN_TRCT1234_C   I129 @BASEBOARD_FAB2_LIB.BASEBOARD_FAB2(SCH_1):PAGE141
    R2 NIC_MDI_SPRV_RJ45_0_R_DP @BASEBOARD_FAB2_LIB.BASEBOARD_FAB2(SCH_1):NIC_MDI_SPRV_RJ45_0_R_DP   I129 @BASEBOARD_FAB2_LIB.BASEBOARD_FAB2(SCH_1):PAGE141
    R3 NIC_MDI_SPRV_RJ45_0_R_DN @BASEBOARD_FAB2_LIB.BASEBOARD_FAB2(SCH_1):NIC_MDI_SPRV_RJ45_0_R_DN   I129 @BASEBOARD_FAB2_LIB.BASEBOARD_FAB2(SCH_1):PAGE141
    R4 NIC_MDI_SPRV_RJ45_1_R_DP @BASEBOARD_FAB2_LIB.BASEBOARD_FAB2(SCH_1):NIC_MDI_SPRV_RJ45_1_R_DP   I129 @BASEBOARD_FAB2_LIB.BASEBOARD_FAB2(SCH_1):PAGE141
    R5 NIC_MDI_SPRV_RJ45_1_R_DN @BASEBOARD_FAB2_LIB.BASEBOARD_FAB2(SCH_1):NIC_MDI_SPRV_RJ45_1_R_DN   I129 @BASEBOARD_FAB2_LIB.BASEBOARD_FAB2(SCH_1):PAGE141
    R6    GND @BASEBOARD_FAB2_LIB.BASEBOARD_FAB2(SCH_1):GND   I129 @BASEBOARD_FAB2_LIB.BASEBOARD_FAB2(SCH_1):PAGE141
    R7 NIC_MDI_SPRV_RJ45_2_R_DP @BASEBOARD_FAB2_LIB.BASEBOARD_FAB2(SCH_1):NIC_MDI_SPRV_RJ45_2_R_DP   I129 @BASEBOARD_FAB2_LIB.BASEBOARD_FAB2(SCH_1):PAGE141
    R8 NIC_MDI_SPRV_RJ45_2_R_DN @BASEBOARD_FAB2_LIB.BASEBOARD_FAB2(SCH_1):NIC_MDI_SPRV_RJ45_2_R_DN   I129 @BASEBOARD_FAB2_LIB.BASEBOARD_FAB2(SCH_1):PAGE141
    R9 NIC_MDI_SPRV_RJ45_3_R_DP @BASEBOARD_FAB2_LIB.BASEBOARD_FAB2(SCH_1):NIC_MDI_SPRV_RJ45_3_R_DP   I129 @BASEBOARD_FAB2_LIB.BASEBOARD_FAB2(SCH_1):PAGE141
   R10 NIC_MDI_SPRV_RJ45_3_R_DN @BASEBOARD_FAB2_LIB.BASEBOARD_FAB2(SCH_1):NIC_MDI_SPRV_RJ45_3_R_DN   I129 @BASEBOARD_FAB2_LIB.BASEBOARD_FAB2(SCH_1):PAGE141
   R11 GND_LAN_TRCT1234_C @BASEBOARD_FAB2_LIB.BASEBOARD_FAB2(SCH_1):GND_LAN_TRCT1234_C   I129 @BASEBOARD_FAB2_LIB.BASEBOARD_FAB2(SCH_1):PAGE141
     1    GND @BASEBOARD_FAB2_LIB.BASEBOARD_FAB2(SCH_1):GND   I129 @BASEBOARD_FAB2_LIB.BASEBOARD_FAB2(SCH_1):PAGE141
     2    GND @BASEBOARD_FAB2_LIB.BASEBOARD_FAB2(SCH_1):GND   I129 @BASEBOARD_FAB2_LIB.BASEBOARD_FAB2(SCH_1):PAGE141

L1A1 IND-120NH-30-GP_DISCRET-GB2-INA
     1 VR_PVDDQ_KLM_PH2_SW @BASEBOARD_FAB2_LIB.BASEBOARD_FAB2(SCH_1):VR_PVDDQ_KLM_PH2_SW   I153 @BASEBOARD_FAB2_LIB.BASEBOARD_FAB2(SCH_1):PAGE227
     2 PVDDQ_KLM @BASEBOARD_FAB2_LIB.BASEBOARD_FAB2(SCH_1):PVDDQ_KLM   I153 @BASEBOARD_FAB2_LIB.BASEBOARD_FAB2(SCH_1):PAGE227

L1A2 IND-120NH-30-GP_DISCRET-GB2-INA
     1 VR_PVDDQ_KLM_PH1_SW @BASEBOARD_FAB2_LIB.BASEBOARD_FAB2(SCH_1):VR_PVDDQ_KLM_PH1_SW   I152 @BASEBOARD_FAB2_LIB.BASEBOARD_FAB2(SCH_1):PAGE227
     2 PVDDQ_KLM @BASEBOARD_FAB2_LIB.BASEBOARD_FAB2(SCH_1):PVDDQ_KLM   I152 @BASEBOARD_FAB2_LIB.BASEBOARD_FAB2(SCH_1):PAGE227

L1B1 IND-100NH-35-GP_DISCRET-G8-INDA
     1 P12V_STBY @BASEBOARD_FAB2_LIB.BASEBOARD_FAB2(SCH_1):P12V_STBY   I247 @BASEBOARD_FAB2_LIB.BASEBOARD_FAB2(SCH_1):PAGE228
     2 VR_FET_SW_P12V_STBY_PVDDQ_KLM @BASEBOARD_FAB2_LIB.BASEBOARD_FAB2(SCH_1):VR_FET_SW_P12V_STBY_PVDDQ_KLM   I247 @BASEBOARD_FAB2_LIB.BASEBOARD_FAB2(SCH_1):PAGE228

L1B2 IND-80NH-1-GP_DISCRET-GC2-IND-A
     1 P12V_STBY @BASEBOARD_FAB2_LIB.BASEBOARD_FAB2(SCH_1):P12V_STBY    I81 @BASEBOARD_FAB2_LIB.BASEBOARD_FAB2(SCH_1):PAGE209
     2 VR_FET_SW_P12V_STBY_PVCCIN_CPU1 @BASEBOARD_FAB2_LIB.BASEBOARD_FAB2(SCH_1):VR_FET_SW_P12V_STBY_PVCCIN_CPU1    I81 @BASEBOARD_FAB2_LIB.BASEBOARD_FAB2(SCH_1):PAGE209

L1C1 IND-300NH-20-GP_DISCRET-GB1-INA
     1 VR_PVSA_CPU1_PHASE_SW @BASEBOARD_FAB2_LIB.BASEBOARD_FAB2(SCH_1):VR_PVSA_CPU1_PHASE_SW    I72 @BASEBOARD_FAB2_LIB.BASEBOARD_FAB2(SCH_1):PAGE210
     2 PVSA_CPU1 @BASEBOARD_FAB2_LIB.BASEBOARD_FAB2(SCH_1):PVSA_CPU1    I72 @BASEBOARD_FAB2_LIB.BASEBOARD_FAB2(SCH_1):PAGE210

L1C2 IND-120NH-30-GP_DISCRET-GB2-INA
     1 VR_PVCCIN_CPU1_PHASE5 @BASEBOARD_FAB2_LIB.BASEBOARD_FAB2(SCH_1):VR_PVCCIN_CPU1_PHASE5    I80 @BASEBOARD_FAB2_LIB.BASEBOARD_FAB2(SCH_1):PAGE209
     2 PVCCIN_CPU1 @BASEBOARD_FAB2_LIB.BASEBOARD_FAB2(SCH_1):PVCCIN_CPU1    I80 @BASEBOARD_FAB2_LIB.BASEBOARD_FAB2(SCH_1):PAGE209

L1D1 IND-120NH-30-GP_DISCRET-GB2-INA
     1 VR_PVCCIN_CPU1_PHASE4 @BASEBOARD_FAB2_LIB.BASEBOARD_FAB2(SCH_1):VR_PVCCIN_CPU1_PHASE4   I117 @BASEBOARD_FAB2_LIB.BASEBOARD_FAB2(SCH_1):PAGE208
     2 PVCCIN_CPU1 @BASEBOARD_FAB2_LIB.BASEBOARD_FAB2(SCH_1):PVCCIN_CPU1   I117 @BASEBOARD_FAB2_LIB.BASEBOARD_FAB2(SCH_1):PAGE208

L1D2 IND-120NH-30-GP_DISCRET-GB2-INA
     1 VR_PVCCIN_CPU1_PHASE3 @BASEBOARD_FAB2_LIB.BASEBOARD_FAB2(SCH_1):VR_PVCCIN_CPU1_PHASE3   I116 @BASEBOARD_FAB2_LIB.BASEBOARD_FAB2(SCH_1):PAGE208
     2 PVCCIN_CPU1 @BASEBOARD_FAB2_LIB.BASEBOARD_FAB2(SCH_1):PVCCIN_CPU1   I116 @BASEBOARD_FAB2_LIB.BASEBOARD_FAB2(SCH_1):PAGE208

L1D3 IND-120NH-30-GP_DISCRET-GB2-INA
     1 VR_PVCCIN_CPU1_PHASE2 @BASEBOARD_FAB2_LIB.BASEBOARD_FAB2(SCH_1):VR_PVCCIN_CPU1_PHASE2   I108 @BASEBOARD_FAB2_LIB.BASEBOARD_FAB2(SCH_1):PAGE207
     2 PVCCIN_CPU1 @BASEBOARD_FAB2_LIB.BASEBOARD_FAB2(SCH_1):PVCCIN_CPU1   I108 @BASEBOARD_FAB2_LIB.BASEBOARD_FAB2(SCH_1):PAGE207

L1E1 IND-120NH-30-GP_DISCRET-GB2-INA
     1 VR_PVCCIN_CPU1_PHASE1 @BASEBOARD_FAB2_LIB.BASEBOARD_FAB2(SCH_1):VR_PVCCIN_CPU1_PHASE1   I107 @BASEBOARD_FAB2_LIB.BASEBOARD_FAB2(SCH_1):PAGE207
     2 PVCCIN_CPU1 @BASEBOARD_FAB2_LIB.BASEBOARD_FAB2(SCH_1):PVCCIN_CPU1   I107 @BASEBOARD_FAB2_LIB.BASEBOARD_FAB2(SCH_1):PAGE207

L1F1 IND-100NH-35-GP_DISCRET-G8-INDA
     1 P12V_STBY @BASEBOARD_FAB2_LIB.BASEBOARD_FAB2(SCH_1):P12V_STBY   I253 @BASEBOARD_FAB2_LIB.BASEBOARD_FAB2(SCH_1):PAGE225
     2 VR_FET_SW_P12V_STBY_PVDDQ_GHJ @BASEBOARD_FAB2_LIB.BASEBOARD_FAB2(SCH_1):VR_FET_SW_P12V_STBY_PVDDQ_GHJ   I253 @BASEBOARD_FAB2_LIB.BASEBOARD_FAB2(SCH_1):PAGE225

L1F2 IND-120NH-30-GP_DISCRET-GB2-INA
     1 VR_PVDDQ_GHJ_PH2_SW @BASEBOARD_FAB2_LIB.BASEBOARD_FAB2(SCH_1):VR_PVDDQ_GHJ_PH2_SW   I161 @BASEBOARD_FAB2_LIB.BASEBOARD_FAB2(SCH_1):PAGE224
     2 PVDDQ_GHJ @BASEBOARD_FAB2_LIB.BASEBOARD_FAB2(SCH_1):PVDDQ_GHJ   I161 @BASEBOARD_FAB2_LIB.BASEBOARD_FAB2(SCH_1):PAGE224

L1G1 IND-120NH-30-GP_DISCRET-GB2-INA
     1 VR_PVDDQ_GHJ_PH1_SW @BASEBOARD_FAB2_LIB.BASEBOARD_FAB2(SCH_1):VR_PVDDQ_GHJ_PH1_SW   I160 @BASEBOARD_FAB2_LIB.BASEBOARD_FAB2(SCH_1):PAGE224
     2 PVDDQ_GHJ @BASEBOARD_FAB2_LIB.BASEBOARD_FAB2(SCH_1):PVDDQ_GHJ   I160 @BASEBOARD_FAB2_LIB.BASEBOARD_FAB2(SCH_1):PAGE224

L1M2 CHOKE_4PIN_SMLF-90 OHM,IND,752A
     1 USB2_P01_DN @BASEBOARD_FAB2_LIB.BASEBOARD_FAB2(SCH_1):USB2_P01_DN   I181 @BASEBOARD_FAB2_LIB.BASEBOARD_FAB2(SCH_1):PAGE176
     2 USB2_P01_DP @BASEBOARD_FAB2_LIB.BASEBOARD_FAB2(SCH_1):USB2_P01_DP   I181 @BASEBOARD_FAB2_LIB.BASEBOARD_FAB2(SCH_1):PAGE176
     3 USB2_P01_ESD_DP @BASEBOARD_FAB2_LIB.BASEBOARD_FAB2(SCH_1):USB2_P01_ESD_DP   I181 @BASEBOARD_FAB2_LIB.BASEBOARD_FAB2(SCH_1):PAGE176
     4 USB2_P01_ESD_DN @BASEBOARD_FAB2_LIB.BASEBOARD_FAB2(SCH_1):USB2_P01_ESD_DN   I181 @BASEBOARD_FAB2_LIB.BASEBOARD_FAB2(SCH_1):PAGE176

L2M1 INDUCTOR_SMT-0.022UH,IND,72189A
     1 P1V05_PCH_STBY @BASEBOARD_FAB2_LIB.BASEBOARD_FAB2(SCH_1):P1V05_PCH_STBY    I71 @BASEBOARD_FAB2_LIB.BASEBOARD_FAB2(SCH_1):PAGE127
     2 P1V05_PCH_STBY_KR_PLL @BASEBOARD_FAB2_LIB.BASEBOARD_FAB2(SCH_1):P1V05_PCH_STBY_KR_PLL    I71 @BASEBOARD_FAB2_LIB.BASEBOARD_FAB2(SCH_1):PAGE127

L4A1 INDUCTOR_SM-0.47UH,IND,E13358-A
     1 VR_PVPP_KLM_PHASE @BASEBOARD_FAB2_LIB.BASEBOARD_FAB2(SCH_1):VR_PVPP_KLM_PHASE   I164 @BASEBOARD_FAB2_LIB.BASEBOARD_FAB2(SCH_1):PAGE234
     2 PVPP_KLM @BASEBOARD_FAB2_LIB.BASEBOARD_FAB2(SCH_1):PVPP_KLM   I164 @BASEBOARD_FAB2_LIB.BASEBOARD_FAB2(SCH_1):PAGE234

L4C1 IND-80NH-1-GP_DISCRET-GC2-IND-A
     1 P12V_STBY @BASEBOARD_FAB2_LIB.BASEBOARD_FAB2(SCH_1):P12V_STBY   I105 @BASEBOARD_FAB2_LIB.BASEBOARD_FAB2(SCH_1):PAGE204
     2 VR_FET_SW_P12V_STBY_PVCCIN_CPU0 @BASEBOARD_FAB2_LIB.BASEBOARD_FAB2(SCH_1):VR_FET_SW_P12V_STBY_PVCCIN_CPU0   I105 @BASEBOARD_FAB2_LIB.BASEBOARD_FAB2(SCH_1):PAGE204

L4C2 IND-300NH-20-GP_DISCRET-GB1-INA
     1 VR_PVSA_CPU0_PHASE_SW @BASEBOARD_FAB2_LIB.BASEBOARD_FAB2(SCH_1):VR_PVSA_CPU0_PHASE_SW    I82 @BASEBOARD_FAB2_LIB.BASEBOARD_FAB2(SCH_1):PAGE205
     2 PVSA_CPU0 @BASEBOARD_FAB2_LIB.BASEBOARD_FAB2(SCH_1):PVSA_CPU0    I82 @BASEBOARD_FAB2_LIB.BASEBOARD_FAB2(SCH_1):PAGE205

L4C3 IND-120NH-30-GP_DISCRET-GB2-INA
     1 VR_PVCCIN_CPU0_PHASE5 @BASEBOARD_FAB2_LIB.BASEBOARD_FAB2(SCH_1):VR_PVCCIN_CPU0_PHASE5   I104 @BASEBOARD_FAB2_LIB.BASEBOARD_FAB2(SCH_1):PAGE204
     2 PVCCIN_CPU0 @BASEBOARD_FAB2_LIB.BASEBOARD_FAB2(SCH_1):PVCCIN_CPU0   I104 @BASEBOARD_FAB2_LIB.BASEBOARD_FAB2(SCH_1):PAGE204

L4D1 IND-120NH-30-GP_DISCRET-GB2-INA
     1 VR_PVCCIN_CPU0_PHASE4 @BASEBOARD_FAB2_LIB.BASEBOARD_FAB2(SCH_1):VR_PVCCIN_CPU0_PHASE4   I131 @BASEBOARD_FAB2_LIB.BASEBOARD_FAB2(SCH_1):PAGE203
     2 PVCCIN_CPU0 @BASEBOARD_FAB2_LIB.BASEBOARD_FAB2(SCH_1):PVCCIN_CPU0   I131 @BASEBOARD_FAB2_LIB.BASEBOARD_FAB2(SCH_1):PAGE203

L4D2 IND-120NH-30-GP_DISCRET-GB2-INA
     1 VR_PVCCIN_CPU0_PHASE3 @BASEBOARD_FAB2_LIB.BASEBOARD_FAB2(SCH_1):VR_PVCCIN_CPU0_PHASE3   I130 @BASEBOARD_FAB2_LIB.BASEBOARD_FAB2(SCH_1):PAGE203
     2 PVCCIN_CPU0 @BASEBOARD_FAB2_LIB.BASEBOARD_FAB2(SCH_1):PVCCIN_CPU0   I130 @BASEBOARD_FAB2_LIB.BASEBOARD_FAB2(SCH_1):PAGE203

L4D3 IND-120NH-30-GP_DISCRET-GB2-INA
     1 VR_PVCCIN_CPU0_PHASE2 @BASEBOARD_FAB2_LIB.BASEBOARD_FAB2(SCH_1):VR_PVCCIN_CPU0_PHASE2   I110 @BASEBOARD_FAB2_LIB.BASEBOARD_FAB2(SCH_1):PAGE202
     2 PVCCIN_CPU0 @BASEBOARD_FAB2_LIB.BASEBOARD_FAB2(SCH_1):PVCCIN_CPU0   I110 @BASEBOARD_FAB2_LIB.BASEBOARD_FAB2(SCH_1):PAGE202

L4E1 IND-120NH-30-GP_DISCRET-GB2-INA
     1 VR_PVCCIN_CPU0_PHASE1 @BASEBOARD_FAB2_LIB.BASEBOARD_FAB2(SCH_1):VR_PVCCIN_CPU0_PHASE1   I109 @BASEBOARD_FAB2_LIB.BASEBOARD_FAB2(SCH_1):PAGE202
     2 PVCCIN_CPU0 @BASEBOARD_FAB2_LIB.BASEBOARD_FAB2(SCH_1):PVCCIN_CPU0   I109 @BASEBOARD_FAB2_LIB.BASEBOARD_FAB2(SCH_1):PAGE202

L4E2 IND-150NH-56-GP_DISCRET-GA1-INA
     1 VR_PVCCIO_CPU1_PH1_SW @BASEBOARD_FAB2_LIB.BASEBOARD_FAB2(SCH_1):VR_PVCCIO_CPU1_PH1_SW   I174 @BASEBOARD_FAB2_LIB.BASEBOARD_FAB2(SCH_1):PAGE214
     2 PVCCIO_CPU1 @BASEBOARD_FAB2_LIB.BASEBOARD_FAB2(SCH_1):PVCCIO_CPU1   I174 @BASEBOARD_FAB2_LIB.BASEBOARD_FAB2(SCH_1):PAGE214

L4G1 INDUCTOR_SM-0.47UH,IND,E13358-A
     1 VR_PVPP_GHJ_PHASE @BASEBOARD_FAB2_LIB.BASEBOARD_FAB2(SCH_1):VR_PVPP_GHJ_PHASE   I277 @BASEBOARD_FAB2_LIB.BASEBOARD_FAB2(SCH_1):PAGE233
     2 PVPP_GHJ @BASEBOARD_FAB2_LIB.BASEBOARD_FAB2(SCH_1):PVPP_GHJ   I277 @BASEBOARD_FAB2_LIB.BASEBOARD_FAB2(SCH_1):PAGE233

L7A1 IND-120NH-30-GP_DISCRET-GB2-INA
     1 VR_PVDDQ_DEF_PH1_SW @BASEBOARD_FAB2_LIB.BASEBOARD_FAB2(SCH_1):VR_PVDDQ_DEF_PH1_SW   I157 @BASEBOARD_FAB2_LIB.BASEBOARD_FAB2(SCH_1):PAGE219
     2 PVDDQ_DEF @BASEBOARD_FAB2_LIB.BASEBOARD_FAB2(SCH_1):PVDDQ_DEF   I157 @BASEBOARD_FAB2_LIB.BASEBOARD_FAB2(SCH_1):PAGE219

L7A2 IND-300NH-20-GP_DISCRET-GB1-INA
     1 VR_PVNN_PCH_PH1_PHASE_SW @BASEBOARD_FAB2_LIB.BASEBOARD_FAB2(SCH_1):VR_PVNN_PCH_PH1_PHASE_SW   I178 @BASEBOARD_FAB2_LIB.BASEBOARD_FAB2(SCH_1):PAGE236
     2 PVNN_PCH_STBY @BASEBOARD_FAB2_LIB.BASEBOARD_FAB2(SCH_1):PVNN_PCH_STBY   I178 @BASEBOARD_FAB2_LIB.BASEBOARD_FAB2(SCH_1):PAGE236

L7A3 IND-120NH-30-GP_DISCRET-GB2-INA
     1 VR_PVDDQ_DEF_PH2_SW @BASEBOARD_FAB2_LIB.BASEBOARD_FAB2(SCH_1):VR_PVDDQ_DEF_PH2_SW   I158 @BASEBOARD_FAB2_LIB.BASEBOARD_FAB2(SCH_1):PAGE219
     2 PVDDQ_DEF @BASEBOARD_FAB2_LIB.BASEBOARD_FAB2(SCH_1):PVDDQ_DEF   I158 @BASEBOARD_FAB2_LIB.BASEBOARD_FAB2(SCH_1):PAGE219

L7A4 IND-300NH-20-GP_DISCRET-GB1-INA
     1 VR_P1V05_PCH_STBY_PH1_PHASE_SW @BASEBOARD_FAB2_LIB.BASEBOARD_FAB2(SCH_1):VR_P1V05_PCH_STBY_PH1_PHASE_SW   I179 @BASEBOARD_FAB2_LIB.BASEBOARD_FAB2(SCH_1):PAGE236
     2 P1V05_PCH_STBY @BASEBOARD_FAB2_LIB.BASEBOARD_FAB2(SCH_1):P1V05_PCH_STBY   I179 @BASEBOARD_FAB2_LIB.BASEBOARD_FAB2(SCH_1):PAGE236

L7A5 IND-100NH-35-GP_DISCRET-G8-INDA
     1 P12V_STBY @BASEBOARD_FAB2_LIB.BASEBOARD_FAB2(SCH_1):P12V_STBY   I241 @BASEBOARD_FAB2_LIB.BASEBOARD_FAB2(SCH_1):PAGE220
     2 VR_FET_SW_P12V_STBY_PVDDQ_DEF @BASEBOARD_FAB2_LIB.BASEBOARD_FAB2(SCH_1):VR_FET_SW_P12V_STBY_PVDDQ_DEF   I241 @BASEBOARD_FAB2_LIB.BASEBOARD_FAB2(SCH_1):PAGE220

L7B1 INDUCTOR_SM-0.47UH,IND,E13358-A
     1 VR_PVPP_DEF_PHASE @BASEBOARD_FAB2_LIB.BASEBOARD_FAB2(SCH_1):VR_PVPP_DEF_PHASE   I239 @BASEBOARD_FAB2_LIB.BASEBOARD_FAB2(SCH_1):PAGE232
     2 PVPP_DEF @BASEBOARD_FAB2_LIB.BASEBOARD_FAB2(SCH_1):PVPP_DEF   I239 @BASEBOARD_FAB2_LIB.BASEBOARD_FAB2(SCH_1):PAGE232

L7C1 IND-100NH-35-GP_DISCRET-G8-INDA
     1 P12V_STBY @BASEBOARD_FAB2_LIB.BASEBOARD_FAB2(SCH_1):P12V_STBY   I142 @BASEBOARD_FAB2_LIB.BASEBOARD_FAB2(SCH_1):PAGE212
     2 VR_FET_SW_P12V_STBY_PVCCIO_CPU0 @BASEBOARD_FAB2_LIB.BASEBOARD_FAB2(SCH_1):VR_FET_SW_P12V_STBY_PVCCIO_CPU0   I142 @BASEBOARD_FAB2_LIB.BASEBOARD_FAB2(SCH_1):PAGE212

L7C2 IND-150NH-56-GP_DISCRET-GA1-INA
     1 VR_PVCCIO_CPU0_PH1_SW @BASEBOARD_FAB2_LIB.BASEBOARD_FAB2(SCH_1):VR_PVCCIO_CPU0_PH1_SW   I141 @BASEBOARD_FAB2_LIB.BASEBOARD_FAB2(SCH_1):PAGE212
     2 PVCCIO_CPU0 @BASEBOARD_FAB2_LIB.BASEBOARD_FAB2(SCH_1):PVCCIO_CPU0   I141 @BASEBOARD_FAB2_LIB.BASEBOARD_FAB2(SCH_1):PAGE212

L7F1 INDUCTOR_SM-0.47UH,IND,E13358-A
     1 VR_PVPP_ABC_PHASE @BASEBOARD_FAB2_LIB.BASEBOARD_FAB2(SCH_1):VR_PVPP_ABC_PHASE   I178 @BASEBOARD_FAB2_LIB.BASEBOARD_FAB2(SCH_1):PAGE231
     2 PVPP_ABC @BASEBOARD_FAB2_LIB.BASEBOARD_FAB2(SCH_1):PVPP_ABC   I178 @BASEBOARD_FAB2_LIB.BASEBOARD_FAB2(SCH_1):PAGE231

L7F2 IND-100NH-35-GP_DISCRET-G8-INDA
     1 P12V_STBY @BASEBOARD_FAB2_LIB.BASEBOARD_FAB2(SCH_1):P12V_STBY   I261 @BASEBOARD_FAB2_LIB.BASEBOARD_FAB2(SCH_1):PAGE217
     2 VR_FET_SW_P12V_STBY_PVDDQ_ABC @BASEBOARD_FAB2_LIB.BASEBOARD_FAB2(SCH_1):VR_FET_SW_P12V_STBY_PVDDQ_ABC   I261 @BASEBOARD_FAB2_LIB.BASEBOARD_FAB2(SCH_1):PAGE217

L7G1 IND-120NH-30-GP_DISCRET-GB2-INA
     1 VR_PVDDQ_ABC_PH1_SW @BASEBOARD_FAB2_LIB.BASEBOARD_FAB2(SCH_1):VR_PVDDQ_ABC_PH1_SW   I153 @BASEBOARD_FAB2_LIB.BASEBOARD_FAB2(SCH_1):PAGE216
     2 PVDDQ_ABC @BASEBOARD_FAB2_LIB.BASEBOARD_FAB2(SCH_1):PVDDQ_ABC   I153 @BASEBOARD_FAB2_LIB.BASEBOARD_FAB2(SCH_1):PAGE216

L7G2 IND-120NH-30-GP_DISCRET-GB2-INA
     1 VR_PVDDQ_ABC_PH2_SW @BASEBOARD_FAB2_LIB.BASEBOARD_FAB2(SCH_1):VR_PVDDQ_ABC_PH2_SW   I155 @BASEBOARD_FAB2_LIB.BASEBOARD_FAB2(SCH_1):PAGE216
     2 PVDDQ_ABC @BASEBOARD_FAB2_LIB.BASEBOARD_FAB2(SCH_1):PVDDQ_ABC   I155 @BASEBOARD_FAB2_LIB.BASEBOARD_FAB2(SCH_1):PAGE216

L8E1 INDUCTOR_SM-2.2UH,IND,E98761-0A
     1 VR_P5V_STBY_PHASE @BASEBOARD_FAB2_LIB.BASEBOARD_FAB2(SCH_1):VR_P5V_STBY_PHASE    I90 @BASEBOARD_FAB2_LIB.BASEBOARD_FAB2(SCH_1):PAGE241
     2 P5V_STBY @BASEBOARD_FAB2_LIB.BASEBOARD_FAB2(SCH_1):P5V_STBY    I90 @BASEBOARD_FAB2_LIB.BASEBOARD_FAB2(SCH_1):PAGE241

L8F1 IND-1UH-361-GP_DISCRET-GC1-INDA
     1 VR_P3V3_STBY_PHASE @BASEBOARD_FAB2_LIB.BASEBOARD_FAB2(SCH_1):VR_P3V3_STBY_PHASE   I188 @BASEBOARD_FAB2_LIB.BASEBOARD_FAB2(SCH_1):PAGE240
     2 P3V3_STBY @BASEBOARD_FAB2_LIB.BASEBOARD_FAB2(SCH_1):P3V3_STBY   I188 @BASEBOARD_FAB2_LIB.BASEBOARD_FAB2(SCH_1):PAGE240

L25W1 IND-68NH-15-GP_DISCRET-GC1-INDA
     1 BMC_VGA_BLUE @BASEBOARD_FAB2_LIB.BASEBOARD_FAB2(SCH_1):BMC_VGA_BLUE    I76 @BASEBOARD_FAB2_LIB.BASEBOARD_FAB2(SCH_1):PAGE255
     2 V_IO_B_J @BASEBOARD_FAB2_LIB.BASEBOARD_FAB2(SCH_1):V_IO_B_J    I76 @BASEBOARD_FAB2_LIB.BASEBOARD_FAB2(SCH_1):PAGE255

L25W2 IND-68NH-15-GP_DISCRET-GC1-INDA
     1 BMC_VGA_GREEN @BASEBOARD_FAB2_LIB.BASEBOARD_FAB2(SCH_1):BMC_VGA_GREEN    I77 @BASEBOARD_FAB2_LIB.BASEBOARD_FAB2(SCH_1):PAGE255
     2 V_IO_G_J @BASEBOARD_FAB2_LIB.BASEBOARD_FAB2(SCH_1):V_IO_G_J    I77 @BASEBOARD_FAB2_LIB.BASEBOARD_FAB2(SCH_1):PAGE255

L25W3 IND-68NH-15-GP_DISCRET-GC1-INDA
     1 BMC_VGA_RED @BASEBOARD_FAB2_LIB.BASEBOARD_FAB2(SCH_1):BMC_VGA_RED    I78 @BASEBOARD_FAB2_LIB.BASEBOARD_FAB2(SCH_1):PAGE255
     2 V_IO_R_J @BASEBOARD_FAB2_LIB.BASEBOARD_FAB2(SCH_1):V_IO_R_J    I78 @BASEBOARD_FAB2_LIB.BASEBOARD_FAB2(SCH_1):PAGE255

L30W1 CHOKE_4PIN_SM_B-67 OHM,EMPTY,7A
     1 USB3_P01_RXP @BASEBOARD_FAB2_LIB.BASEBOARD_FAB2(SCH_1):USB3_P01_RXP    I16 @BASEBOARD_FAB2_LIB.BASEBOARD_FAB2(SCH_1):PAGE253
     2 USB3_P01_FB_RXP @BASEBOARD_FAB2_LIB.BASEBOARD_FAB2(SCH_1):USB3_P01_FB_RXP    I16 @BASEBOARD_FAB2_LIB.BASEBOARD_FAB2(SCH_1):PAGE253
     3 USB3_P01_FB_RXN @BASEBOARD_FAB2_LIB.BASEBOARD_FAB2(SCH_1):USB3_P01_FB_RXN    I16 @BASEBOARD_FAB2_LIB.BASEBOARD_FAB2(SCH_1):PAGE253
     4 USB3_P01_RXN @BASEBOARD_FAB2_LIB.BASEBOARD_FAB2(SCH_1):USB3_P01_RXN    I16 @BASEBOARD_FAB2_LIB.BASEBOARD_FAB2(SCH_1):PAGE253

L30W2 CHOKE_4PIN_SM_B-67 OHM,EMPTY,7A
     1 USB3_P01_C_TXP @BASEBOARD_FAB2_LIB.BASEBOARD_FAB2(SCH_1):USB3_P01_C_TXP    I11 @BASEBOARD_FAB2_LIB.BASEBOARD_FAB2(SCH_1):PAGE253
     2 USB3_P01_FB_TXP @BASEBOARD_FAB2_LIB.BASEBOARD_FAB2(SCH_1):USB3_P01_FB_TXP    I11 @BASEBOARD_FAB2_LIB.BASEBOARD_FAB2(SCH_1):PAGE253
     3 USB3_P01_FB_TXN @BASEBOARD_FAB2_LIB.BASEBOARD_FAB2(SCH_1):USB3_P01_FB_TXN    I11 @BASEBOARD_FAB2_LIB.BASEBOARD_FAB2(SCH_1):PAGE253
     4 USB3_P01_C_TXN @BASEBOARD_FAB2_LIB.BASEBOARD_FAB2(SCH_1):USB3_P01_C_TXN    I11 @BASEBOARD_FAB2_LIB.BASEBOARD_FAB2(SCH_1):PAGE253

Q1B1 MOSFET_N_LCC3-BSZ019N03LS,NFETA
     4 P12V_FAN_SWITCH_G @BASEBOARD_FAB2_LIB.BASEBOARD_FAB2(SCH_1):P12V_FAN_SWITCH_G    I86 @BASEBOARD_FAB2_LIB.BASEBOARD_FAB2(SCH_1):PAGE198
     1 P12V_FAN @BASEBOARD_FAB2_LIB.BASEBOARD_FAB2(SCH_1):P12V_FAN    I86 @BASEBOARD_FAB2_LIB.BASEBOARD_FAB2(SCH_1):PAGE198
     5 P12V_STBY @BASEBOARD_FAB2_LIB.BASEBOARD_FAB2(SCH_1):P12V_STBY    I86 @BASEBOARD_FAB2_LIB.BASEBOARD_FAB2(SCH_1):PAGE198

Q1D1 FET_N_DUAL_SMLF-2N7002DW,FET,DA
     2 A_HSC_LOW_EN @BASEBOARD_FAB2_LIB.BASEBOARD_FAB2(SCH_1):A_HSC_LOW_EN    I86 @BASEBOARD_FAB2_LIB.BASEBOARD_FAB2(SCH_1):PAGE199
     1 AGND_HSC @BASEBOARD_FAB2_LIB.BASEBOARD_FAB2(SCH_1):AGND_HSC    I86 @BASEBOARD_FAB2_LIB.BASEBOARD_FAB2(SCH_1):PAGE199
     6 A_HSC_ISET_S2 @BASEBOARD_FAB2_LIB.BASEBOARD_FAB2(SCH_1):A_HSC_ISET_S2    I86 @BASEBOARD_FAB2_LIB.BASEBOARD_FAB2(SCH_1):PAGE199
     5 A_HSC_HIGH_EN @BASEBOARD_FAB2_LIB.BASEBOARD_FAB2(SCH_1):A_HSC_HIGH_EN    I82 @BASEBOARD_FAB2_LIB.BASEBOARD_FAB2(SCH_1):PAGE199
     4 AGND_HSC @BASEBOARD_FAB2_LIB.BASEBOARD_FAB2(SCH_1):AGND_HSC    I82 @BASEBOARD_FAB2_LIB.BASEBOARD_FAB2(SCH_1):PAGE199
     3 A_HSC_ISET_S @BASEBOARD_FAB2_LIB.BASEBOARD_FAB2(SCH_1):A_HSC_ISET_S    I82 @BASEBOARD_FAB2_LIB.BASEBOARD_FAB2(SCH_1):PAGE199

Q1D2 FET_N_SOT23LF-2N7002,FET,C7925A
     1 FM_OC_DETECT_EN_N @BASEBOARD_FAB2_LIB.BASEBOARD_FAB2(SCH_1):FM_OC_DETECT_EN_N   I203 @BASEBOARD_FAB2_LIB.BASEBOARD_FAB2(SCH_1):PAGE200
     2    GND @BASEBOARD_FAB2_LIB.BASEBOARD_FAB2(SCH_1):GND   I203 @BASEBOARD_FAB2_LIB.BASEBOARD_FAB2(SCH_1):PAGE200
     3 FM_OC_DETECT_EN @BASEBOARD_FAB2_LIB.BASEBOARD_FAB2(SCH_1):FM_OC_DETECT_EN   I203 @BASEBOARD_FAB2_LIB.BASEBOARD_FAB2(SCH_1):PAGE200

Q1D3 NPN_SM-MMBT3904,IC,C52245-001
     1 TEMP_SENSOR_B @BASEBOARD_FAB2_LIB.BASEBOARD_FAB2(SCH_1):TEMP_SENSOR_B    I58 @BASEBOARD_FAB2_LIB.BASEBOARD_FAB2(SCH_1):PAGE199
     3 TEMP_SENSOR_B @BASEBOARD_FAB2_LIB.BASEBOARD_FAB2(SCH_1):TEMP_SENSOR_B    I58 @BASEBOARD_FAB2_LIB.BASEBOARD_FAB2(SCH_1):PAGE199
     2 TEMP_SENSOR_E @BASEBOARD_FAB2_LIB.BASEBOARD_FAB2(SCH_1):TEMP_SENSOR_E    I58 @BASEBOARD_FAB2_LIB.BASEBOARD_FAB2(SCH_1):PAGE199

Q1E1 2SB2907A-B0-00001-GP_DISCRET-GA
     C ISENSE_TMP421_2_BC @BASEBOARD_FAB2_LIB.BASEBOARD_FAB2(SCH_1):ISENSE_TMP421_2_BC    I94 @BASEBOARD_FAB2_LIB.BASEBOARD_FAB2(SCH_1):PAGE167
     B ISENSE_TMP421_2_BC @BASEBOARD_FAB2_LIB.BASEBOARD_FAB2(SCH_1):ISENSE_TMP421_2_BC    I94 @BASEBOARD_FAB2_LIB.BASEBOARD_FAB2(SCH_1):PAGE167
     E ISENSE_TMP421_2_E @BASEBOARD_FAB2_LIB.BASEBOARD_FAB2(SCH_1):ISENSE_TMP421_2_E    I94 @BASEBOARD_FAB2_LIB.BASEBOARD_FAB2(SCH_1):PAGE167

Q1F1 NPN_SM-MMBT3904,IC,C52245-001
     1 FM_ADR_COMPLETE_CPU0_R @BASEBOARD_FAB2_LIB.BASEBOARD_FAB2(SCH_1):FM_ADR_COMPLETE_CPU0_R    I53 @BASEBOARD_FAB2_LIB.BASEBOARD_FAB2(SCH_1):PAGE89
     3 IRQ_DIMM_SAVE_N @BASEBOARD_FAB2_LIB.BASEBOARD_FAB2(SCH_1):IRQ_DIMM_SAVE_N    I53 @BASEBOARD_FAB2_LIB.BASEBOARD_FAB2(SCH_1):PAGE89
     2    GND @BASEBOARD_FAB2_LIB.BASEBOARD_FAB2(SCH_1):GND    I53 @BASEBOARD_FAB2_LIB.BASEBOARD_FAB2(SCH_1):PAGE89

Q1L2 FET_N_DUAL_SMLF-NTJD4001N,FET,A
     2 FM_CPLD_DBG_PWR_EN @BASEBOARD_FAB2_LIB.BASEBOARD_FAB2(SCH_1):FM_CPLD_DBG_PWR_EN   I188 @BASEBOARD_FAB2_LIB.BASEBOARD_FAB2(SCH_1):PAGE155
     1 P5V_STBY_DBG @BASEBOARD_FAB2_LIB.BASEBOARD_FAB2(SCH_1):P5V_STBY_DBG   I188 @BASEBOARD_FAB2_LIB.BASEBOARD_FAB2(SCH_1):PAGE155
     6 P5V_STBY @BASEBOARD_FAB2_LIB.BASEBOARD_FAB2(SCH_1):P5V_STBY   I188 @BASEBOARD_FAB2_LIB.BASEBOARD_FAB2(SCH_1):PAGE155
     5 FM_CPLD_DBG_PWR_EN_R_N @BASEBOARD_FAB2_LIB.BASEBOARD_FAB2(SCH_1):FM_CPLD_DBG_PWR_EN_R_N   I187 @BASEBOARD_FAB2_LIB.BASEBOARD_FAB2(SCH_1):PAGE155
     4    GND @BASEBOARD_FAB2_LIB.BASEBOARD_FAB2(SCH_1):GND   I187 @BASEBOARD_FAB2_LIB.BASEBOARD_FAB2(SCH_1):PAGE155
     3 FM_CPLD_DBG_PWR_EN @BASEBOARD_FAB2_LIB.BASEBOARD_FAB2(SCH_1):FM_CPLD_DBG_PWR_EN   I187 @BASEBOARD_FAB2_LIB.BASEBOARD_FAB2(SCH_1):PAGE155

Q1L3 NPN_SM-MMBT3904,IC,C52245-001
     1 FM_DB_UART_SEL4_N @BASEBOARD_FAB2_LIB.BASEBOARD_FAB2(SCH_1):FM_DB_UART_SEL4_N     I8 @BASEBOARD_FAB2_LIB.BASEBOARD_FAB2(SCH_1):PAGE168
     3 FM_DB_PRESENT @BASEBOARD_FAB2_LIB.BASEBOARD_FAB2(SCH_1):FM_DB_PRESENT     I8 @BASEBOARD_FAB2_LIB.BASEBOARD_FAB2(SCH_1):PAGE168
     2    GND @BASEBOARD_FAB2_LIB.BASEBOARD_FAB2(SCH_1):GND     I8 @BASEBOARD_FAB2_LIB.BASEBOARD_FAB2(SCH_1):PAGE168

Q1L4 FET_N_DUAL_SMLF-2N7002DW,FET,DA
     2 FM_DB_PRESENT @BASEBOARD_FAB2_LIB.BASEBOARD_FAB2(SCH_1):FM_DB_PRESENT    I19 @BASEBOARD_FAB2_LIB.BASEBOARD_FAB2(SCH_1):PAGE168
     1    GND @BASEBOARD_FAB2_LIB.BASEBOARD_FAB2(SCH_1):GND    I19 @BASEBOARD_FAB2_LIB.BASEBOARD_FAB2(SCH_1):PAGE168
     6 FM_POST_CARD_PRES_BMC_N @BASEBOARD_FAB2_LIB.BASEBOARD_FAB2(SCH_1):FM_POST_CARD_PRES_BMC_N    I19 @BASEBOARD_FAB2_LIB.BASEBOARD_FAB2(SCH_1):PAGE168
     5 TP_FET_Q56_4 @BASEBOARD_FAB2_LIB.BASEBOARD_FAB2(SCH_1):TP_FET_Q56_4    I18 @BASEBOARD_FAB2_LIB.BASEBOARD_FAB2(SCH_1):PAGE168
     4 TP_FET_Q56_4 @BASEBOARD_FAB2_LIB.BASEBOARD_FAB2(SCH_1):TP_FET_Q56_4    I18 @BASEBOARD_FAB2_LIB.BASEBOARD_FAB2(SCH_1):PAGE168
     3 TP_FET_Q56_3 @BASEBOARD_FAB2_LIB.BASEBOARD_FAB2(SCH_1):TP_FET_Q56_3    I18 @BASEBOARD_FAB2_LIB.BASEBOARD_FAB2(SCH_1):PAGE168

Q1P2 FET_N_SOT23LF-2N7002,FET,C7925A
     1 PWRGD_P5V_N @BASEBOARD_FAB2_LIB.BASEBOARD_FAB2(SCH_1):PWRGD_P5V_N   I129 @BASEBOARD_FAB2_LIB.BASEBOARD_FAB2(SCH_1):PAGE196
     2    GND @BASEBOARD_FAB2_LIB.BASEBOARD_FAB2(SCH_1):GND   I129 @BASEBOARD_FAB2_LIB.BASEBOARD_FAB2(SCH_1):PAGE196
     3 PWRGD_P5V_R @BASEBOARD_FAB2_LIB.BASEBOARD_FAB2(SCH_1):PWRGD_P5V_R   I129 @BASEBOARD_FAB2_LIB.BASEBOARD_FAB2(SCH_1):PAGE196

Q1W1 FET_N_SOT23LF-2N7002,FET,C7925A
     1 FM_OCP_MEZZA_PRES_N @BASEBOARD_FAB2_LIB.BASEBOARD_FAB2(SCH_1):FM_OCP_MEZZA_PRES_N    I29 @BASEBOARD_FAB2_LIB.BASEBOARD_FAB2(SCH_1):PAGE250
     2    GND @BASEBOARD_FAB2_LIB.BASEBOARD_FAB2(SCH_1):GND    I29 @BASEBOARD_FAB2_LIB.BASEBOARD_FAB2(SCH_1):PAGE250
     3 FM_OCP_MEZZA_PRES @BASEBOARD_FAB2_LIB.BASEBOARD_FAB2(SCH_1):FM_OCP_MEZZA_PRES    I29 @BASEBOARD_FAB2_LIB.BASEBOARD_FAB2(SCH_1):PAGE250

Q1W2 FET_N_DUAL_SMLF-2N7002DW,FET,DA
     2 FM_OCP_MEZZB_PRES_N @BASEBOARD_FAB2_LIB.BASEBOARD_FAB2(SCH_1):FM_OCP_MEZZB_PRES_N    I24 @BASEBOARD_FAB2_LIB.BASEBOARD_FAB2(SCH_1):PAGE250
     1    GND @BASEBOARD_FAB2_LIB.BASEBOARD_FAB2(SCH_1):GND    I24 @BASEBOARD_FAB2_LIB.BASEBOARD_FAB2(SCH_1):PAGE250
     6 FM_OCP_MEZZB_PRES_LVT3_BMC @BASEBOARD_FAB2_LIB.BASEBOARD_FAB2(SCH_1):FM_OCP_MEZZB_PRES_LVT3_BMC    I24 @BASEBOARD_FAB2_LIB.BASEBOARD_FAB2(SCH_1):PAGE250
     5 FM_OCP_MEZZB_PRES_LVT3_BMC @BASEBOARD_FAB2_LIB.BASEBOARD_FAB2(SCH_1):FM_OCP_MEZZB_PRES_LVT3_BMC    I12 @BASEBOARD_FAB2_LIB.BASEBOARD_FAB2(SCH_1):PAGE250
     4    GND @BASEBOARD_FAB2_LIB.BASEBOARD_FAB2(SCH_1):GND    I12 @BASEBOARD_FAB2_LIB.BASEBOARD_FAB2(SCH_1):PAGE250
     3 FM_OCP_MEZZB_PRES_1V05_PCH_N @BASEBOARD_FAB2_LIB.BASEBOARD_FAB2(SCH_1):FM_OCP_MEZZB_PRES_1V05_PCH_N    I12 @BASEBOARD_FAB2_LIB.BASEBOARD_FAB2(SCH_1):PAGE250

Q1W4 FET_N_DUAL_SMLF-2N7002DW,FET,DA
     2 FM_OCP_MEZZC_PRES_N @BASEBOARD_FAB2_LIB.BASEBOARD_FAB2(SCH_1):FM_OCP_MEZZC_PRES_N     I3 @BASEBOARD_FAB2_LIB.BASEBOARD_FAB2(SCH_1):PAGE250
     1    GND @BASEBOARD_FAB2_LIB.BASEBOARD_FAB2(SCH_1):GND     I3 @BASEBOARD_FAB2_LIB.BASEBOARD_FAB2(SCH_1):PAGE250
     6 FM_OCP_MEZZC_PRES_LVT3_BMC @BASEBOARD_FAB2_LIB.BASEBOARD_FAB2(SCH_1):FM_OCP_MEZZC_PRES_LVT3_BMC     I3 @BASEBOARD_FAB2_LIB.BASEBOARD_FAB2(SCH_1):PAGE250
     5 FM_OCP_MEZZC_PRES_LVT3_BMC @BASEBOARD_FAB2_LIB.BASEBOARD_FAB2(SCH_1):FM_OCP_MEZZC_PRES_LVT3_BMC     I8 @BASEBOARD_FAB2_LIB.BASEBOARD_FAB2(SCH_1):PAGE250
     4    GND @BASEBOARD_FAB2_LIB.BASEBOARD_FAB2(SCH_1):GND     I8 @BASEBOARD_FAB2_LIB.BASEBOARD_FAB2(SCH_1):PAGE250
     3 FM_OCP_MEZZC_PRES_1V05_PCH_N @BASEBOARD_FAB2_LIB.BASEBOARD_FAB2(SCH_1):FM_OCP_MEZZC_PRES_1V05_PCH_N     I8 @BASEBOARD_FAB2_LIB.BASEBOARD_FAB2(SCH_1):PAGE250

Q1W5 FET_N_SOT23LF-2N7002,FET,C7925A
     1 A_HSC_HIGH_EN @BASEBOARD_FAB2_LIB.BASEBOARD_FAB2(SCH_1):A_HSC_HIGH_EN   I130 @BASEBOARD_FAB2_LIB.BASEBOARD_FAB2(SCH_1):PAGE199
     2    GND @BASEBOARD_FAB2_LIB.BASEBOARD_FAB2(SCH_1):GND   I130 @BASEBOARD_FAB2_LIB.BASEBOARD_FAB2(SCH_1):PAGE199
     3 A_HSC_LOW_GATE @BASEBOARD_FAB2_LIB.BASEBOARD_FAB2(SCH_1):A_HSC_LOW_GATE   I130 @BASEBOARD_FAB2_LIB.BASEBOARD_FAB2(SCH_1):PAGE199

Q1W6 NPN_SM-MMBT3904,IC,C52245-001
     1 FM_ADR_COMPLETE_CPU1_R @BASEBOARD_FAB2_LIB.BASEBOARD_FAB2(SCH_1):FM_ADR_COMPLETE_CPU1_R    I55 @BASEBOARD_FAB2_LIB.BASEBOARD_FAB2(SCH_1):PAGE89
     3 FM_ADR_COMPLETE_CPU1_N @BASEBOARD_FAB2_LIB.BASEBOARD_FAB2(SCH_1):FM_ADR_COMPLETE_CPU1_N    I55 @BASEBOARD_FAB2_LIB.BASEBOARD_FAB2(SCH_1):PAGE89
     2    GND @BASEBOARD_FAB2_LIB.BASEBOARD_FAB2(SCH_1):GND    I55 @BASEBOARD_FAB2_LIB.BASEBOARD_FAB2(SCH_1):PAGE89

Q2P1 FET_N_SOT23LF-2N7002,FET,C7925A
     1 FM_PMBUS_ALERT_BUF_EN_N @BASEBOARD_FAB2_LIB.BASEBOARD_FAB2(SCH_1):FM_PMBUS_ALERT_BUF_EN_N    I58 @BASEBOARD_FAB2_LIB.BASEBOARD_FAB2(SCH_1):PAGE170
     2    GND @BASEBOARD_FAB2_LIB.BASEBOARD_FAB2(SCH_1):GND    I58 @BASEBOARD_FAB2_LIB.BASEBOARD_FAB2(SCH_1):PAGE170
     3 FM_PMBUS_ALERT_BUF_EN @BASEBOARD_FAB2_LIB.BASEBOARD_FAB2(SCH_1):FM_PMBUS_ALERT_BUF_EN    I58 @BASEBOARD_FAB2_LIB.BASEBOARD_FAB2(SCH_1):PAGE170

Q2T1 NPN_SM-MMBT3904,IC,C52245-001
     1 H_CPU0_FAST_WAKE_B_N @BASEBOARD_FAB2_LIB.BASEBOARD_FAB2(SCH_1):H_CPU0_FAST_WAKE_B_N   I330 @BASEBOARD_FAB2_LIB.BASEBOARD_FAB2(SCH_1):PAGE157
     3 H_CPU0_FAST_WAKE @BASEBOARD_FAB2_LIB.BASEBOARD_FAB2(SCH_1):H_CPU0_FAST_WAKE   I330 @BASEBOARD_FAB2_LIB.BASEBOARD_FAB2(SCH_1):PAGE157
     2    GND @BASEBOARD_FAB2_LIB.BASEBOARD_FAB2(SCH_1):GND   I330 @BASEBOARD_FAB2_LIB.BASEBOARD_FAB2(SCH_1):PAGE157

Q2T2 FET_N_SOT23LF-2N7002,FET,C7925A
     1 H_CPU0_FAST_WAKE @BASEBOARD_FAB2_LIB.BASEBOARD_FAB2(SCH_1):H_CPU0_FAST_WAKE   I340 @BASEBOARD_FAB2_LIB.BASEBOARD_FAB2(SCH_1):PAGE157
     2    GND @BASEBOARD_FAB2_LIB.BASEBOARD_FAB2(SCH_1):GND   I340 @BASEBOARD_FAB2_LIB.BASEBOARD_FAB2(SCH_1):PAGE157
     3 H_CPU0_FAST_WAKE_LVT3_N @BASEBOARD_FAB2_LIB.BASEBOARD_FAB2(SCH_1):H_CPU0_FAST_WAKE_LVT3_N   I340 @BASEBOARD_FAB2_LIB.BASEBOARD_FAB2(SCH_1):PAGE157

Q2U1 FET_N_DUAL_SMLF-NTJD4001N,FET,A
     2 FM_SYS_THROTTLE_LVC3 @BASEBOARD_FAB2_LIB.BASEBOARD_FAB2(SCH_1):FM_SYS_THROTTLE_LVC3    I28 @BASEBOARD_FAB2_LIB.BASEBOARD_FAB2(SCH_1):PAGE95
     1    GND @BASEBOARD_FAB2_LIB.BASEBOARD_FAB2(SCH_1):GND    I28 @BASEBOARD_FAB2_LIB.BASEBOARD_FAB2(SCH_1):PAGE95
     6 H_CPU0_MEMABC_MEMHOT_G_N @BASEBOARD_FAB2_LIB.BASEBOARD_FAB2(SCH_1):H_CPU0_MEMABC_MEMHOT_G_N    I28 @BASEBOARD_FAB2_LIB.BASEBOARD_FAB2(SCH_1):PAGE95
     5 FM_SYS_THROTTLE_LVC3 @BASEBOARD_FAB2_LIB.BASEBOARD_FAB2(SCH_1):FM_SYS_THROTTLE_LVC3   I113 @BASEBOARD_FAB2_LIB.BASEBOARD_FAB2(SCH_1):PAGE95
     4    GND @BASEBOARD_FAB2_LIB.BASEBOARD_FAB2(SCH_1):GND   I113 @BASEBOARD_FAB2_LIB.BASEBOARD_FAB2(SCH_1):PAGE95
     3 H_CPU0_MEMDEF_MEMHOT_G_N @BASEBOARD_FAB2_LIB.BASEBOARD_FAB2(SCH_1):H_CPU0_MEMDEF_MEMHOT_G_N   I113 @BASEBOARD_FAB2_LIB.BASEBOARD_FAB2(SCH_1):PAGE95

Q3U1 FET_N_DUAL_SMLF-NTJD4001N,FET,A
     2 IRQ_PVDDQ_ABC_VRHOT_LVT3_N @BASEBOARD_FAB2_LIB.BASEBOARD_FAB2(SCH_1):IRQ_PVDDQ_ABC_VRHOT_LVT3_N    I49 @BASEBOARD_FAB2_LIB.BASEBOARD_FAB2(SCH_1):PAGE94
     1    GND @BASEBOARD_FAB2_LIB.BASEBOARD_FAB2(SCH_1):GND    I49 @BASEBOARD_FAB2_LIB.BASEBOARD_FAB2(SCH_1):PAGE94
     6 H_CPU0_MEMABC_MEMHOT @BASEBOARD_FAB2_LIB.BASEBOARD_FAB2(SCH_1):H_CPU0_MEMABC_MEMHOT    I49 @BASEBOARD_FAB2_LIB.BASEBOARD_FAB2(SCH_1):PAGE94
     5 H_CPU0_MEMABC_MEMHOT @BASEBOARD_FAB2_LIB.BASEBOARD_FAB2(SCH_1):H_CPU0_MEMABC_MEMHOT    I89 @BASEBOARD_FAB2_LIB.BASEBOARD_FAB2(SCH_1):PAGE94
     4    GND @BASEBOARD_FAB2_LIB.BASEBOARD_FAB2(SCH_1):GND    I89 @BASEBOARD_FAB2_LIB.BASEBOARD_FAB2(SCH_1):PAGE94
     3 H_CPU0_MEMABC_MEMHOT_G_N @BASEBOARD_FAB2_LIB.BASEBOARD_FAB2(SCH_1):H_CPU0_MEMABC_MEMHOT_G_N    I89 @BASEBOARD_FAB2_LIB.BASEBOARD_FAB2(SCH_1):PAGE94

Q4B1 FET_N_DUAL_SMLF-NTJD4001N,FET,A
     2 IRQ_PVDDQ_KLM_VRHOT_LVT3_N @BASEBOARD_FAB2_LIB.BASEBOARD_FAB2(SCH_1):IRQ_PVDDQ_KLM_VRHOT_LVT3_N    I84 @BASEBOARD_FAB2_LIB.BASEBOARD_FAB2(SCH_1):PAGE94
     1    GND @BASEBOARD_FAB2_LIB.BASEBOARD_FAB2(SCH_1):GND    I84 @BASEBOARD_FAB2_LIB.BASEBOARD_FAB2(SCH_1):PAGE94
     6 H_CPU1_MEMKLM_MEMHOT @BASEBOARD_FAB2_LIB.BASEBOARD_FAB2(SCH_1):H_CPU1_MEMKLM_MEMHOT    I84 @BASEBOARD_FAB2_LIB.BASEBOARD_FAB2(SCH_1):PAGE94
     5 H_CPU1_MEMKLM_MEMHOT @BASEBOARD_FAB2_LIB.BASEBOARD_FAB2(SCH_1):H_CPU1_MEMKLM_MEMHOT    I77 @BASEBOARD_FAB2_LIB.BASEBOARD_FAB2(SCH_1):PAGE94
     4    GND @BASEBOARD_FAB2_LIB.BASEBOARD_FAB2(SCH_1):GND    I77 @BASEBOARD_FAB2_LIB.BASEBOARD_FAB2(SCH_1):PAGE94
     3 H_CPU1_MEMKLM_MEMHOT_G_N @BASEBOARD_FAB2_LIB.BASEBOARD_FAB2(SCH_1):H_CPU1_MEMKLM_MEMHOT_G_N    I77 @BASEBOARD_FAB2_LIB.BASEBOARD_FAB2(SCH_1):PAGE94

Q4B2 FET_N_DUAL_SMLF-NTJD4001N,FET,A
     2 FM_SYS_THROTTLE_LVC3 @BASEBOARD_FAB2_LIB.BASEBOARD_FAB2(SCH_1):FM_SYS_THROTTLE_LVC3    I32 @BASEBOARD_FAB2_LIB.BASEBOARD_FAB2(SCH_1):PAGE95
     1    GND @BASEBOARD_FAB2_LIB.BASEBOARD_FAB2(SCH_1):GND    I32 @BASEBOARD_FAB2_LIB.BASEBOARD_FAB2(SCH_1):PAGE95
     6 H_CPU1_MEMGHJ_MEMHOT_G_N @BASEBOARD_FAB2_LIB.BASEBOARD_FAB2(SCH_1):H_CPU1_MEMGHJ_MEMHOT_G_N    I32 @BASEBOARD_FAB2_LIB.BASEBOARD_FAB2(SCH_1):PAGE95
     5 FM_SYS_THROTTLE_LVC3 @BASEBOARD_FAB2_LIB.BASEBOARD_FAB2(SCH_1):FM_SYS_THROTTLE_LVC3    I33 @BASEBOARD_FAB2_LIB.BASEBOARD_FAB2(SCH_1):PAGE95
     4    GND @BASEBOARD_FAB2_LIB.BASEBOARD_FAB2(SCH_1):GND    I33 @BASEBOARD_FAB2_LIB.BASEBOARD_FAB2(SCH_1):PAGE95
     3 H_CPU1_MEMKLM_MEMHOT_G_N @BASEBOARD_FAB2_LIB.BASEBOARD_FAB2(SCH_1):H_CPU1_MEMKLM_MEMHOT_G_N    I33 @BASEBOARD_FAB2_LIB.BASEBOARD_FAB2(SCH_1):PAGE95

Q4U1 FET_N_DUAL_SMLF-NTJD4001N,FET,A
     2 FM_DIMM_EVENT_COD_N @BASEBOARD_FAB2_LIB.BASEBOARD_FAB2(SCH_1):FM_DIMM_EVENT_COD_N    I98 @BASEBOARD_FAB2_LIB.BASEBOARD_FAB2(SCH_1):PAGE94
     1    GND @BASEBOARD_FAB2_LIB.BASEBOARD_FAB2(SCH_1):GND    I98 @BASEBOARD_FAB2_LIB.BASEBOARD_FAB2(SCH_1):PAGE94
     6 FM_DIMM_EVENT_FET @BASEBOARD_FAB2_LIB.BASEBOARD_FAB2(SCH_1):FM_DIMM_EVENT_FET    I98 @BASEBOARD_FAB2_LIB.BASEBOARD_FAB2(SCH_1):PAGE94
     5 FM_DIMM_EVENT_FET @BASEBOARD_FAB2_LIB.BASEBOARD_FAB2(SCH_1):FM_DIMM_EVENT_FET   I102 @BASEBOARD_FAB2_LIB.BASEBOARD_FAB2(SCH_1):PAGE94
     4    GND @BASEBOARD_FAB2_LIB.BASEBOARD_FAB2(SCH_1):GND   I102 @BASEBOARD_FAB2_LIB.BASEBOARD_FAB2(SCH_1):PAGE94
     3 FM_MEM_THERM_EVENT_LVT3_N @BASEBOARD_FAB2_LIB.BASEBOARD_FAB2(SCH_1):FM_MEM_THERM_EVENT_LVT3_N   I102 @BASEBOARD_FAB2_LIB.BASEBOARD_FAB2(SCH_1):PAGE94

Q4W1 FET_N_DUAL_SMLF-2N7002DW,FET,DA
     2 P3V3_DB1200_R1 @BASEBOARD_FAB2_LIB.BASEBOARD_FAB2(SCH_1):P3V3_DB1200_R1   I102 @BASEBOARD_FAB2_LIB.BASEBOARD_FAB2(SCH_1):PAGE102
     1 SMB_HOST_STBY_LVC3_SDA_R2 @BASEBOARD_FAB2_LIB.BASEBOARD_FAB2(SCH_1):SMB_HOST_STBY_LVC3_SDA_R2   I102 @BASEBOARD_FAB2_LIB.BASEBOARD_FAB2(SCH_1):PAGE102
     6 SMB_HOST_STBY_LVC3_SDA @BASEBOARD_FAB2_LIB.BASEBOARD_FAB2(SCH_1):SMB_HOST_STBY_LVC3_SDA   I102 @BASEBOARD_FAB2_LIB.BASEBOARD_FAB2(SCH_1):PAGE102
     5 P3V3_DB1200_R1 @BASEBOARD_FAB2_LIB.BASEBOARD_FAB2(SCH_1):P3V3_DB1200_R1   I101 @BASEBOARD_FAB2_LIB.BASEBOARD_FAB2(SCH_1):PAGE102
     4 SMB_HOST_STBY_LVC3_SCL_R2 @BASEBOARD_FAB2_LIB.BASEBOARD_FAB2(SCH_1):SMB_HOST_STBY_LVC3_SCL_R2   I101 @BASEBOARD_FAB2_LIB.BASEBOARD_FAB2(SCH_1):PAGE102
     3 SMB_HOST_STBY_LVC3_SCL @BASEBOARD_FAB2_LIB.BASEBOARD_FAB2(SCH_1):SMB_HOST_STBY_LVC3_SCL   I101 @BASEBOARD_FAB2_LIB.BASEBOARD_FAB2(SCH_1):PAGE102

Q4W2 FET_N_SOT23LF-2N7002,FET,C7925A
     1 FM_DB1200_PWRGD @BASEBOARD_FAB2_LIB.BASEBOARD_FAB2(SCH_1):FM_DB1200_PWRGD   I112 @BASEBOARD_FAB2_LIB.BASEBOARD_FAB2(SCH_1):PAGE102
     2    GND @BASEBOARD_FAB2_LIB.BASEBOARD_FAB2(SCH_1):GND   I112 @BASEBOARD_FAB2_LIB.BASEBOARD_FAB2(SCH_1):PAGE102
     3 FM_DB1200_PWRGD_R @BASEBOARD_FAB2_LIB.BASEBOARD_FAB2(SCH_1):FM_DB1200_PWRGD_R   I112 @BASEBOARD_FAB2_LIB.BASEBOARD_FAB2(SCH_1):PAGE102

Q6W1 FET_N_SOT23LF-2N7002,FET,C7925A
     1 UV_HIGH_SET @BASEBOARD_FAB2_LIB.BASEBOARD_FAB2(SCH_1):UV_HIGH_SET   I225 @BASEBOARD_FAB2_LIB.BASEBOARD_FAB2(SCH_1):PAGE200
     2    GND @BASEBOARD_FAB2_LIB.BASEBOARD_FAB2(SCH_1):GND   I225 @BASEBOARD_FAB2_LIB.BASEBOARD_FAB2(SCH_1):PAGE200
     3 UV_HIGH_SET_N @BASEBOARD_FAB2_LIB.BASEBOARD_FAB2(SCH_1):UV_HIGH_SET_N   I225 @BASEBOARD_FAB2_LIB.BASEBOARD_FAB2(SCH_1):PAGE200

Q6W2 NPN_SM-MMBT3904,IC,C52245-001
     1 FM_UART_SEL_N @BASEBOARD_FAB2_LIB.BASEBOARD_FAB2(SCH_1):FM_UART_SEL_N    I47 @BASEBOARD_FAB2_LIB.BASEBOARD_FAB2(SCH_1):PAGE168
     3 FM_SOL_UART_CH_SEL @BASEBOARD_FAB2_LIB.BASEBOARD_FAB2(SCH_1):FM_SOL_UART_CH_SEL    I47 @BASEBOARD_FAB2_LIB.BASEBOARD_FAB2(SCH_1):PAGE168
     2    GND @BASEBOARD_FAB2_LIB.BASEBOARD_FAB2(SCH_1):GND    I47 @BASEBOARD_FAB2_LIB.BASEBOARD_FAB2(SCH_1):PAGE168

Q6W4 FET_N_SOT23LF-2N7002,FET,C7925A
     1 DEBUG_CARD2_PRSNT @BASEBOARD_FAB2_LIB.BASEBOARD_FAB2(SCH_1):DEBUG_CARD2_PRSNT    I43 @BASEBOARD_FAB2_LIB.BASEBOARD_FAB2(SCH_1):PAGE168
     2    GND @BASEBOARD_FAB2_LIB.BASEBOARD_FAB2(SCH_1):GND    I43 @BASEBOARD_FAB2_LIB.BASEBOARD_FAB2(SCH_1):PAGE168
     3 FM_POST_CARD_PRES_BMC_N @BASEBOARD_FAB2_LIB.BASEBOARD_FAB2(SCH_1):FM_POST_CARD_PRES_BMC_N    I43 @BASEBOARD_FAB2_LIB.BASEBOARD_FAB2(SCH_1):PAGE168

Q7D1 FET_N_SOT23LF-2N7002,FET,C7925A
     1 FM_THERMTRIP_DLY_R @BASEBOARD_FAB2_LIB.BASEBOARD_FAB2(SCH_1):FM_THERMTRIP_DLY_R    I14 @BASEBOARD_FAB2_LIB.BASEBOARD_FAB2(SCH_1):PAGE134
     2    GND @BASEBOARD_FAB2_LIB.BASEBOARD_FAB2(SCH_1):GND    I14 @BASEBOARD_FAB2_LIB.BASEBOARD_FAB2(SCH_1):PAGE134
     3 FM_PCH_LVC1_THERMTRIP_N @BASEBOARD_FAB2_LIB.BASEBOARD_FAB2(SCH_1):FM_PCH_LVC1_THERMTRIP_N    I14 @BASEBOARD_FAB2_LIB.BASEBOARD_FAB2(SCH_1):PAGE134

Q7E1 FET_N_DUAL_SMLF-NTJD4001N,FET,A
     2 IRQ_PVDDQ_DEF_VRHOT_LVT3_N @BASEBOARD_FAB2_LIB.BASEBOARD_FAB2(SCH_1):IRQ_PVDDQ_DEF_VRHOT_LVT3_N    I60 @BASEBOARD_FAB2_LIB.BASEBOARD_FAB2(SCH_1):PAGE94
     1    GND @BASEBOARD_FAB2_LIB.BASEBOARD_FAB2(SCH_1):GND    I60 @BASEBOARD_FAB2_LIB.BASEBOARD_FAB2(SCH_1):PAGE94
     6 H_CPU0_MEMDEF_MEMHOT @BASEBOARD_FAB2_LIB.BASEBOARD_FAB2(SCH_1):H_CPU0_MEMDEF_MEMHOT    I60 @BASEBOARD_FAB2_LIB.BASEBOARD_FAB2(SCH_1):PAGE94
     5 H_CPU0_MEMDEF_MEMHOT @BASEBOARD_FAB2_LIB.BASEBOARD_FAB2(SCH_1):H_CPU0_MEMDEF_MEMHOT    I64 @BASEBOARD_FAB2_LIB.BASEBOARD_FAB2(SCH_1):PAGE94
     4    GND @BASEBOARD_FAB2_LIB.BASEBOARD_FAB2(SCH_1):GND    I64 @BASEBOARD_FAB2_LIB.BASEBOARD_FAB2(SCH_1):PAGE94
     3 H_CPU0_MEMDEF_MEMHOT_G_N @BASEBOARD_FAB2_LIB.BASEBOARD_FAB2(SCH_1):H_CPU0_MEMDEF_MEMHOT_G_N    I64 @BASEBOARD_FAB2_LIB.BASEBOARD_FAB2(SCH_1):PAGE94

Q7E2 FET_N_DUAL_SMLF-NTJD4001N,FET,A
     2 IRQ_PVDDQ_GHJ_VRHOT_LVT3_N @BASEBOARD_FAB2_LIB.BASEBOARD_FAB2(SCH_1):IRQ_PVDDQ_GHJ_VRHOT_LVT3_N    I69 @BASEBOARD_FAB2_LIB.BASEBOARD_FAB2(SCH_1):PAGE94
     1    GND @BASEBOARD_FAB2_LIB.BASEBOARD_FAB2(SCH_1):GND    I69 @BASEBOARD_FAB2_LIB.BASEBOARD_FAB2(SCH_1):PAGE94
     6 H_CPU1_MEMGHJ_MEMHOT @BASEBOARD_FAB2_LIB.BASEBOARD_FAB2(SCH_1):H_CPU1_MEMGHJ_MEMHOT    I69 @BASEBOARD_FAB2_LIB.BASEBOARD_FAB2(SCH_1):PAGE94
     5 H_CPU1_MEMGHJ_MEMHOT @BASEBOARD_FAB2_LIB.BASEBOARD_FAB2(SCH_1):H_CPU1_MEMGHJ_MEMHOT    I75 @BASEBOARD_FAB2_LIB.BASEBOARD_FAB2(SCH_1):PAGE94
     4    GND @BASEBOARD_FAB2_LIB.BASEBOARD_FAB2(SCH_1):GND    I75 @BASEBOARD_FAB2_LIB.BASEBOARD_FAB2(SCH_1):PAGE94
     3 H_CPU1_MEMGHJ_MEMHOT_G_N @BASEBOARD_FAB2_LIB.BASEBOARD_FAB2(SCH_1):H_CPU1_MEMGHJ_MEMHOT_G_N    I75 @BASEBOARD_FAB2_LIB.BASEBOARD_FAB2(SCH_1):PAGE94

Q7E3 FET_N_DUAL_SMLF-NTJD4001N,FET,A
     2 FM_SYS_THROTTLE_LVC3 @BASEBOARD_FAB2_LIB.BASEBOARD_FAB2(SCH_1):FM_SYS_THROTTLE_LVC3    I52 @BASEBOARD_FAB2_LIB.BASEBOARD_FAB2(SCH_1):PAGE95
     1    GND @BASEBOARD_FAB2_LIB.BASEBOARD_FAB2(SCH_1):GND    I52 @BASEBOARD_FAB2_LIB.BASEBOARD_FAB2(SCH_1):PAGE95
     6 H_CPU0_PROCHOT_G_N @BASEBOARD_FAB2_LIB.BASEBOARD_FAB2(SCH_1):H_CPU0_PROCHOT_G_N    I52 @BASEBOARD_FAB2_LIB.BASEBOARD_FAB2(SCH_1):PAGE95
     5 FM_SYS_THROTTLE_LVC3 @BASEBOARD_FAB2_LIB.BASEBOARD_FAB2(SCH_1):FM_SYS_THROTTLE_LVC3    I51 @BASEBOARD_FAB2_LIB.BASEBOARD_FAB2(SCH_1):PAGE95
     4    GND @BASEBOARD_FAB2_LIB.BASEBOARD_FAB2(SCH_1):GND    I51 @BASEBOARD_FAB2_LIB.BASEBOARD_FAB2(SCH_1):PAGE95
     3 H_CPU1_PROCHOT_G_N @BASEBOARD_FAB2_LIB.BASEBOARD_FAB2(SCH_1):H_CPU1_PROCHOT_G_N    I51 @BASEBOARD_FAB2_LIB.BASEBOARD_FAB2(SCH_1):PAGE95

Q7E4 FET_N_SOT23LF-2N7002,FET,C7925A
     1 FM_THROTTLE_R_N @BASEBOARD_FAB2_LIB.BASEBOARD_FAB2(SCH_1):FM_THROTTLE_R_N   I122 @BASEBOARD_FAB2_LIB.BASEBOARD_FAB2(SCH_1):PAGE95
     2    GND @BASEBOARD_FAB2_LIB.BASEBOARD_FAB2(SCH_1):GND   I122 @BASEBOARD_FAB2_LIB.BASEBOARD_FAB2(SCH_1):PAGE95
     3 FM_SYS_THROTTLE_LVC3 @BASEBOARD_FAB2_LIB.BASEBOARD_FAB2(SCH_1):FM_SYS_THROTTLE_LVC3   I122 @BASEBOARD_FAB2_LIB.BASEBOARD_FAB2(SCH_1):PAGE95

Q7E5 FET_N_DUAL_SMLF-NTJD4001N,FET,A
     2 IRQ_CPU0_PROCHOT_G_N @BASEBOARD_FAB2_LIB.BASEBOARD_FAB2(SCH_1):IRQ_CPU0_PROCHOT_G_N   I111 @BASEBOARD_FAB2_LIB.BASEBOARD_FAB2(SCH_1):PAGE95
     1    GND @BASEBOARD_FAB2_LIB.BASEBOARD_FAB2(SCH_1):GND   I111 @BASEBOARD_FAB2_LIB.BASEBOARD_FAB2(SCH_1):PAGE95
     6 IRQ_CPU0_VRHOT @BASEBOARD_FAB2_LIB.BASEBOARD_FAB2(SCH_1):IRQ_CPU0_VRHOT   I111 @BASEBOARD_FAB2_LIB.BASEBOARD_FAB2(SCH_1):PAGE95
     5 IRQ_CPU0_VRHOT @BASEBOARD_FAB2_LIB.BASEBOARD_FAB2(SCH_1):IRQ_CPU0_VRHOT    I59 @BASEBOARD_FAB2_LIB.BASEBOARD_FAB2(SCH_1):PAGE95
     4    GND @BASEBOARD_FAB2_LIB.BASEBOARD_FAB2(SCH_1):GND    I59 @BASEBOARD_FAB2_LIB.BASEBOARD_FAB2(SCH_1):PAGE95
     3 H_CPU0_PROCHOT_G_N @BASEBOARD_FAB2_LIB.BASEBOARD_FAB2(SCH_1):H_CPU0_PROCHOT_G_N    I59 @BASEBOARD_FAB2_LIB.BASEBOARD_FAB2(SCH_1):PAGE95

Q7E6 FET_N_DUAL_SMLF-NTJD4001N,FET,A
     2 IRQ_CPU1_PROCHOT_G_N @BASEBOARD_FAB2_LIB.BASEBOARD_FAB2(SCH_1):IRQ_CPU1_PROCHOT_G_N   I112 @BASEBOARD_FAB2_LIB.BASEBOARD_FAB2(SCH_1):PAGE95
     1    GND @BASEBOARD_FAB2_LIB.BASEBOARD_FAB2(SCH_1):GND   I112 @BASEBOARD_FAB2_LIB.BASEBOARD_FAB2(SCH_1):PAGE95
     6 IRQ_CPU1_VRHOT @BASEBOARD_FAB2_LIB.BASEBOARD_FAB2(SCH_1):IRQ_CPU1_VRHOT   I112 @BASEBOARD_FAB2_LIB.BASEBOARD_FAB2(SCH_1):PAGE95
     5 IRQ_CPU1_VRHOT @BASEBOARD_FAB2_LIB.BASEBOARD_FAB2(SCH_1):IRQ_CPU1_VRHOT    I69 @BASEBOARD_FAB2_LIB.BASEBOARD_FAB2(SCH_1):PAGE95
     4    GND @BASEBOARD_FAB2_LIB.BASEBOARD_FAB2(SCH_1):GND    I69 @BASEBOARD_FAB2_LIB.BASEBOARD_FAB2(SCH_1):PAGE95
     3 H_CPU1_PROCHOT_G_N @BASEBOARD_FAB2_LIB.BASEBOARD_FAB2(SCH_1):H_CPU1_PROCHOT_G_N    I69 @BASEBOARD_FAB2_LIB.BASEBOARD_FAB2(SCH_1):PAGE95

Q7E7 MOSFET_N_LCC3-BSZ019N03LS,NFETA
     4 P12V_SWITCH_G @BASEBOARD_FAB2_LIB.BASEBOARD_FAB2(SCH_1):P12V_SWITCH_G    I88 @BASEBOARD_FAB2_LIB.BASEBOARD_FAB2(SCH_1):PAGE198
     1   P12V @BASEBOARD_FAB2_LIB.BASEBOARD_FAB2(SCH_1):P12V    I88 @BASEBOARD_FAB2_LIB.BASEBOARD_FAB2(SCH_1):PAGE198
     5 P12V_STBY @BASEBOARD_FAB2_LIB.BASEBOARD_FAB2(SCH_1):P12V_STBY    I88 @BASEBOARD_FAB2_LIB.BASEBOARD_FAB2(SCH_1):PAGE198

Q7E8 FET_N_SOT23LF-2N7002,FET,C7925A
     1 FM_SYS_THROTTLE_LVC3 @BASEBOARD_FAB2_LIB.BASEBOARD_FAB2(SCH_1):FM_SYS_THROTTLE_LVC3   I123 @BASEBOARD_FAB2_LIB.BASEBOARD_FAB2(SCH_1):PAGE95
     2    GND @BASEBOARD_FAB2_LIB.BASEBOARD_FAB2(SCH_1):GND   I123 @BASEBOARD_FAB2_LIB.BASEBOARD_FAB2(SCH_1):PAGE95
     3 FM_PWRBRK_N @BASEBOARD_FAB2_LIB.BASEBOARD_FAB2(SCH_1):FM_PWRBRK_N   I123 @BASEBOARD_FAB2_LIB.BASEBOARD_FAB2(SCH_1):PAGE95

Q8B1 MOSFET_N_LCC3-BSZ019N03LS,NFETA
     4 P5V_SWITCH_G @BASEBOARD_FAB2_LIB.BASEBOARD_FAB2(SCH_1):P5V_SWITCH_G    I87 @BASEBOARD_FAB2_LIB.BASEBOARD_FAB2(SCH_1):PAGE198
     1    P5V @BASEBOARD_FAB2_LIB.BASEBOARD_FAB2(SCH_1):P5V    I87 @BASEBOARD_FAB2_LIB.BASEBOARD_FAB2(SCH_1):PAGE198
     5 P5V_STBY @BASEBOARD_FAB2_LIB.BASEBOARD_FAB2(SCH_1):P5V_STBY    I87 @BASEBOARD_FAB2_LIB.BASEBOARD_FAB2(SCH_1):PAGE198

Q8D1 NPN_DUAL_SSOPLF-MBT3904,XSTR,CA
     5 IRQ_DIMM_SAVE_R_N @BASEBOARD_FAB2_LIB.BASEBOARD_FAB2(SCH_1):IRQ_DIMM_SAVE_R_N    I35 @BASEBOARD_FAB2_LIB.BASEBOARD_FAB2(SCH_1):PAGE89
     3 IRQ_DIMM_SAVE_LVT3 @BASEBOARD_FAB2_LIB.BASEBOARD_FAB2(SCH_1):IRQ_DIMM_SAVE_LVT3    I35 @BASEBOARD_FAB2_LIB.BASEBOARD_FAB2(SCH_1):PAGE89
     4    GND @BASEBOARD_FAB2_LIB.BASEBOARD_FAB2(SCH_1):GND    I35 @BASEBOARD_FAB2_LIB.BASEBOARD_FAB2(SCH_1):PAGE89
     2 IRQ_DIMM_SAVE_LVT3 @BASEBOARD_FAB2_LIB.BASEBOARD_FAB2(SCH_1):IRQ_DIMM_SAVE_LVT3    I46 @BASEBOARD_FAB2_LIB.BASEBOARD_FAB2(SCH_1):PAGE89
     6 IRQ_DIMM_SAVE_LVT3_N @BASEBOARD_FAB2_LIB.BASEBOARD_FAB2(SCH_1):IRQ_DIMM_SAVE_LVT3_N    I46 @BASEBOARD_FAB2_LIB.BASEBOARD_FAB2(SCH_1):PAGE89
     1    GND @BASEBOARD_FAB2_LIB.BASEBOARD_FAB2(SCH_1):GND    I46 @BASEBOARD_FAB2_LIB.BASEBOARD_FAB2(SCH_1):PAGE89

Q8D2 FET_N_SOT23LF-2N7002,FET,C7925A
     1 RST_PLTRST_BUF_N @BASEBOARD_FAB2_LIB.BASEBOARD_FAB2(SCH_1):RST_PLTRST_BUF_N    I15 @BASEBOARD_FAB2_LIB.BASEBOARD_FAB2(SCH_1):PAGE134
     2 FM_PCH_BMC_THERMTRIP_EXI_STRAP_ @BASEBOARD_FAB2_LIB.BASEBOARD_FAB2(SCH_1):FM_PCH_BMC_THERMTRIP_EXI_STRAP_N    I15 @BASEBOARD_FAB2_LIB.BASEBOARD_FAB2(SCH_1):PAGE134
     3 FM_PCH_BMC_THERMTRIP_N @BASEBOARD_FAB2_LIB.BASEBOARD_FAB2(SCH_1):FM_PCH_BMC_THERMTRIP_N    I15 @BASEBOARD_FAB2_LIB.BASEBOARD_FAB2(SCH_1):PAGE134

Q8E1 FET_N_SOT23LF-2N7002,FET,C7925A
     1 RST_PLTRST_N @BASEBOARD_FAB2_LIB.BASEBOARD_FAB2(SCH_1):RST_PLTRST_N   I134 @BASEBOARD_FAB2_LIB.BASEBOARD_FAB2(SCH_1):PAGE136
     2    GND @BASEBOARD_FAB2_LIB.BASEBOARD_FAB2(SCH_1):GND   I134 @BASEBOARD_FAB2_LIB.BASEBOARD_FAB2(SCH_1):PAGE136
     3 RST_PLTRST_TOP_SWAP @BASEBOARD_FAB2_LIB.BASEBOARD_FAB2(SCH_1):RST_PLTRST_TOP_SWAP   I134 @BASEBOARD_FAB2_LIB.BASEBOARD_FAB2(SCH_1):PAGE136

Q8E2 FET_N_SOT23LF-2N7002,FET,C7925A
     1 RST_RSMRST_DLY @BASEBOARD_FAB2_LIB.BASEBOARD_FAB2(SCH_1):RST_RSMRST_DLY    I13 @BASEBOARD_FAB2_LIB.BASEBOARD_FAB2(SCH_1):PAGE126
     2    GND @BASEBOARD_FAB2_LIB.BASEBOARD_FAB2(SCH_1):GND    I13 @BASEBOARD_FAB2_LIB.BASEBOARD_FAB2(SCH_1):PAGE126
     3 IRQ_SML0_ALERT_N @BASEBOARD_FAB2_LIB.BASEBOARD_FAB2(SCH_1):IRQ_SML0_ALERT_N    I13 @BASEBOARD_FAB2_LIB.BASEBOARD_FAB2(SCH_1):PAGE126

Q8F1 FET_N_SOT23LF-2N7002,FET,C7925A
     1 FM_BACKUP_BIOS_SEL_N @BASEBOARD_FAB2_LIB.BASEBOARD_FAB2(SCH_1):FM_BACKUP_BIOS_SEL_N   I126 @BASEBOARD_FAB2_LIB.BASEBOARD_FAB2(SCH_1):PAGE154
     2    GND @BASEBOARD_FAB2_LIB.BASEBOARD_FAB2(SCH_1):GND   I126 @BASEBOARD_FAB2_LIB.BASEBOARD_FAB2(SCH_1):PAGE154
     3 FM_DUAL_BIOS_SEL_N @BASEBOARD_FAB2_LIB.BASEBOARD_FAB2(SCH_1):FM_DUAL_BIOS_SEL_N   I126 @BASEBOARD_FAB2_LIB.BASEBOARD_FAB2(SCH_1):PAGE154

Q8F2 FET_N_SOT23LF-2N7002,FET,C7925A
     1 FM_FAST_PROCHOT_EN_N @BASEBOARD_FAB2_LIB.BASEBOARD_FAB2(SCH_1):FM_FAST_PROCHOT_EN_N    I67 @BASEBOARD_FAB2_LIB.BASEBOARD_FAB2(SCH_1):PAGE170
     2    GND @BASEBOARD_FAB2_LIB.BASEBOARD_FAB2(SCH_1):GND    I67 @BASEBOARD_FAB2_LIB.BASEBOARD_FAB2(SCH_1):PAGE170
     3 FM_FAST_PROCHOT_EN @BASEBOARD_FAB2_LIB.BASEBOARD_FAB2(SCH_1):FM_FAST_PROCHOT_EN    I67 @BASEBOARD_FAB2_LIB.BASEBOARD_FAB2(SCH_1):PAGE170

Q8G1 MOSFET_N_LCC3-BSZ019N03LS,NFETA
     4 P3V3_SWITCH_G @BASEBOARD_FAB2_LIB.BASEBOARD_FAB2(SCH_1):P3V3_SWITCH_G    I85 @BASEBOARD_FAB2_LIB.BASEBOARD_FAB2(SCH_1):PAGE198
     1   P3V3 @BASEBOARD_FAB2_LIB.BASEBOARD_FAB2(SCH_1):P3V3    I85 @BASEBOARD_FAB2_LIB.BASEBOARD_FAB2(SCH_1):PAGE198
     5 P3V3_STBY @BASEBOARD_FAB2_LIB.BASEBOARD_FAB2(SCH_1):P3V3_STBY    I85 @BASEBOARD_FAB2_LIB.BASEBOARD_FAB2(SCH_1):PAGE198

Q8W1 NPN_DUAL_SSOPLF-MBT3904,XSTR,CA
     5 IRQ_DIMM_SAVE_CPU1_R_N @BASEBOARD_FAB2_LIB.BASEBOARD_FAB2(SCH_1):IRQ_DIMM_SAVE_CPU1_R_N    I52 @BASEBOARD_FAB2_LIB.BASEBOARD_FAB2(SCH_1):PAGE89
     3 IRQ_DIMM_SAVE_LVT3_CPU1 @BASEBOARD_FAB2_LIB.BASEBOARD_FAB2(SCH_1):IRQ_DIMM_SAVE_LVT3_CPU1    I52 @BASEBOARD_FAB2_LIB.BASEBOARD_FAB2(SCH_1):PAGE89
     4    GND @BASEBOARD_FAB2_LIB.BASEBOARD_FAB2(SCH_1):GND    I52 @BASEBOARD_FAB2_LIB.BASEBOARD_FAB2(SCH_1):PAGE89
     2 IRQ_DIMM_SAVE_LVT3_CPU1 @BASEBOARD_FAB2_LIB.BASEBOARD_FAB2(SCH_1):IRQ_DIMM_SAVE_LVT3_CPU1    I51 @BASEBOARD_FAB2_LIB.BASEBOARD_FAB2(SCH_1):PAGE89
     6 IRQ_DIMM_SAVE_LVT3_N @BASEBOARD_FAB2_LIB.BASEBOARD_FAB2(SCH_1):IRQ_DIMM_SAVE_LVT3_N    I51 @BASEBOARD_FAB2_LIB.BASEBOARD_FAB2(SCH_1):PAGE89
     1    GND @BASEBOARD_FAB2_LIB.BASEBOARD_FAB2(SCH_1):GND    I51 @BASEBOARD_FAB2_LIB.BASEBOARD_FAB2(SCH_1):PAGE89

Q9A1 NPN_DUAL_SSOPLF-MBT3904,EMPTY,A
     5 XDP_CPU_TCK_BUF @BASEBOARD_FAB2_LIB.BASEBOARD_FAB2(SCH_1):XDP_CPU_TCK_BUF    I94 @BASEBOARD_FAB2_LIB.BASEBOARD_FAB2(SCH_1):PAGE111
     3   P3V3 @BASEBOARD_FAB2_LIB.BASEBOARD_FAB2(SCH_1):P3V3    I94 @BASEBOARD_FAB2_LIB.BASEBOARD_FAB2(SCH_1):PAGE111
     4 XDP_CPU_TCK0 @BASEBOARD_FAB2_LIB.BASEBOARD_FAB2(SCH_1):XDP_CPU_TCK0    I94 @BASEBOARD_FAB2_LIB.BASEBOARD_FAB2(SCH_1):PAGE111
     2 XDP_CPU_TCK_BUF @BASEBOARD_FAB2_LIB.BASEBOARD_FAB2(SCH_1):XDP_CPU_TCK_BUF    I93 @BASEBOARD_FAB2_LIB.BASEBOARD_FAB2(SCH_1):PAGE111
     6 XDP_CPU_TCK_BUF @BASEBOARD_FAB2_LIB.BASEBOARD_FAB2(SCH_1):XDP_CPU_TCK_BUF    I93 @BASEBOARD_FAB2_LIB.BASEBOARD_FAB2(SCH_1):PAGE111
     1 XDP_CPU_GTL_TCK_R2 @BASEBOARD_FAB2_LIB.BASEBOARD_FAB2(SCH_1):XDP_CPU_GTL_TCK_R2    I93 @BASEBOARD_FAB2_LIB.BASEBOARD_FAB2(SCH_1):PAGE111

Q9A2 FET_N_DUAL_SMLF-NTJD4001N,FET,A
     2 FM_PWR_LED_N @BASEBOARD_FAB2_LIB.BASEBOARD_FAB2(SCH_1):FM_PWR_LED_N   I175 @BASEBOARD_FAB2_LIB.BASEBOARD_FAB2(SCH_1):PAGE119
     1    GND @BASEBOARD_FAB2_LIB.BASEBOARD_FAB2(SCH_1):GND   I175 @BASEBOARD_FAB2_LIB.BASEBOARD_FAB2(SCH_1):PAGE119
     6 FM_PWR_LED @BASEBOARD_FAB2_LIB.BASEBOARD_FAB2(SCH_1):FM_PWR_LED   I175 @BASEBOARD_FAB2_LIB.BASEBOARD_FAB2(SCH_1):PAGE119
     5 FM_PWR_LED @BASEBOARD_FAB2_LIB.BASEBOARD_FAB2(SCH_1):FM_PWR_LED   I180 @BASEBOARD_FAB2_LIB.BASEBOARD_FAB2(SCH_1):PAGE119
     4    GND @BASEBOARD_FAB2_LIB.BASEBOARD_FAB2(SCH_1):GND   I180 @BASEBOARD_FAB2_LIB.BASEBOARD_FAB2(SCH_1):PAGE119
     3 FM_PWR_LED_K @BASEBOARD_FAB2_LIB.BASEBOARD_FAB2(SCH_1):FM_PWR_LED_K   I180 @BASEBOARD_FAB2_LIB.BASEBOARD_FAB2(SCH_1):PAGE119

Q9A3 FET_N_SOT23LF-2N7002,FET,C7925A
     1 FM_BIOS_TOP_SWAP_SPKR @BASEBOARD_FAB2_LIB.BASEBOARD_FAB2(SCH_1):FM_BIOS_TOP_SWAP_SPKR    I49 @BASEBOARD_FAB2_LIB.BASEBOARD_FAB2(SCH_1):PAGE175
     2    GND @BASEBOARD_FAB2_LIB.BASEBOARD_FAB2(SCH_1):GND    I49 @BASEBOARD_FAB2_LIB.BASEBOARD_FAB2(SCH_1):PAGE175
     3 FM_SPEAKER_PCH_N @BASEBOARD_FAB2_LIB.BASEBOARD_FAB2(SCH_1):FM_SPEAKER_PCH_N    I49 @BASEBOARD_FAB2_LIB.BASEBOARD_FAB2(SCH_1):PAGE175

Q9B1 2SB2907A-B0-00001-GP_DISCRET-GA
     C ISENSE_TMP421_1_BC @BASEBOARD_FAB2_LIB.BASEBOARD_FAB2(SCH_1):ISENSE_TMP421_1_BC    I93 @BASEBOARD_FAB2_LIB.BASEBOARD_FAB2(SCH_1):PAGE167
     B ISENSE_TMP421_1_BC @BASEBOARD_FAB2_LIB.BASEBOARD_FAB2(SCH_1):ISENSE_TMP421_1_BC    I93 @BASEBOARD_FAB2_LIB.BASEBOARD_FAB2(SCH_1):PAGE167
     E ISENSE_TMP421_1_E @BASEBOARD_FAB2_LIB.BASEBOARD_FAB2(SCH_1):ISENSE_TMP421_1_E    I93 @BASEBOARD_FAB2_LIB.BASEBOARD_FAB2(SCH_1):PAGE167

Q9E1 FET_N_DUAL_SMLF-NTJD4001N,FET,A
     2 FM_BMC_HEARTBEAT_N @BASEBOARD_FAB2_LIB.BASEBOARD_FAB2(SCH_1):FM_BMC_HEARTBEAT_N   I198 @BASEBOARD_FAB2_LIB.BASEBOARD_FAB2(SCH_1):PAGE151
     1    GND @BASEBOARD_FAB2_LIB.BASEBOARD_FAB2(SCH_1):GND   I198 @BASEBOARD_FAB2_LIB.BASEBOARD_FAB2(SCH_1):PAGE151
     6 FM_HEARTBEAT_LED @BASEBOARD_FAB2_LIB.BASEBOARD_FAB2(SCH_1):FM_HEARTBEAT_LED   I198 @BASEBOARD_FAB2_LIB.BASEBOARD_FAB2(SCH_1):PAGE151
     5 FM_HEARTBEAT_LED @BASEBOARD_FAB2_LIB.BASEBOARD_FAB2(SCH_1):FM_HEARTBEAT_LED   I145 @BASEBOARD_FAB2_LIB.BASEBOARD_FAB2(SCH_1):PAGE151
     4    GND @BASEBOARD_FAB2_LIB.BASEBOARD_FAB2(SCH_1):GND   I145 @BASEBOARD_FAB2_LIB.BASEBOARD_FAB2(SCH_1):PAGE151
     3 FM_HEARTBEAT_LED_K @BASEBOARD_FAB2_LIB.BASEBOARD_FAB2(SCH_1):FM_HEARTBEAT_LED_K   I145 @BASEBOARD_FAB2_LIB.BASEBOARD_FAB2(SCH_1):PAGE151

Q9F1 FET_N_DUAL_SMLF-NTJD4001N,FET,A
     2 FM_BMC_FAULT_LED_N @BASEBOARD_FAB2_LIB.BASEBOARD_FAB2(SCH_1):FM_BMC_FAULT_LED_N    I80 @BASEBOARD_FAB2_LIB.BASEBOARD_FAB2(SCH_1):PAGE177
     1    GND @BASEBOARD_FAB2_LIB.BASEBOARD_FAB2(SCH_1):GND    I80 @BASEBOARD_FAB2_LIB.BASEBOARD_FAB2(SCH_1):PAGE177
     6 FM_BMC_FAULT_LED @BASEBOARD_FAB2_LIB.BASEBOARD_FAB2(SCH_1):FM_BMC_FAULT_LED    I80 @BASEBOARD_FAB2_LIB.BASEBOARD_FAB2(SCH_1):PAGE177
     5 FM_BMC_FAULT_LED @BASEBOARD_FAB2_LIB.BASEBOARD_FAB2(SCH_1):FM_BMC_FAULT_LED    I79 @BASEBOARD_FAB2_LIB.BASEBOARD_FAB2(SCH_1):PAGE177
     4    GND @BASEBOARD_FAB2_LIB.BASEBOARD_FAB2(SCH_1):GND    I79 @BASEBOARD_FAB2_LIB.BASEBOARD_FAB2(SCH_1):PAGE177
     3 FM_RED_LED_CATHODE @BASEBOARD_FAB2_LIB.BASEBOARD_FAB2(SCH_1):FM_RED_LED_CATHODE    I79 @BASEBOARD_FAB2_LIB.BASEBOARD_FAB2(SCH_1):PAGE177

Q9G1 FET_N_DUAL_SMLF-NTJD4001N,FET,A
     2 FM_BATTERY_SENSE_EN_N @BASEBOARD_FAB2_LIB.BASEBOARD_FAB2(SCH_1):FM_BATTERY_SENSE_EN_N   I162 @BASEBOARD_FAB2_LIB.BASEBOARD_FAB2(SCH_1):PAGE169
     1    GND @BASEBOARD_FAB2_LIB.BASEBOARD_FAB2(SCH_1):GND   I162 @BASEBOARD_FAB2_LIB.BASEBOARD_FAB2(SCH_1):PAGE169
     6 FM_BATTERY_SENSE_EN @BASEBOARD_FAB2_LIB.BASEBOARD_FAB2(SCH_1):FM_BATTERY_SENSE_EN   I162 @BASEBOARD_FAB2_LIB.BASEBOARD_FAB2(SCH_1):PAGE169
     5 FM_BATTERY_SENSE_EN @BASEBOARD_FAB2_LIB.BASEBOARD_FAB2(SCH_1):FM_BATTERY_SENSE_EN   I157 @BASEBOARD_FAB2_LIB.BASEBOARD_FAB2(SCH_1):PAGE169
     4 A_P3V_BAT_SCALED @BASEBOARD_FAB2_LIB.BASEBOARD_FAB2(SCH_1):A_P3V_BAT_SCALED   I157 @BASEBOARD_FAB2_LIB.BASEBOARD_FAB2(SCH_1):PAGE169
     3 P3V_BAT_SOURCE_R @BASEBOARD_FAB2_LIB.BASEBOARD_FAB2(SCH_1):P3V_BAT_SOURCE_R   I157 @BASEBOARD_FAB2_LIB.BASEBOARD_FAB2(SCH_1):PAGE169

Q9P1 FET_N_DUAL_SMLF-2N7002DW,FET,DA
     2 A_HSC_LOW_GATE @BASEBOARD_FAB2_LIB.BASEBOARD_FAB2(SCH_1):A_HSC_LOW_GATE   I196 @BASEBOARD_FAB2_LIB.BASEBOARD_FAB2(SCH_1):PAGE200
     1    GND @BASEBOARD_FAB2_LIB.BASEBOARD_FAB2(SCH_1):GND   I196 @BASEBOARD_FAB2_LIB.BASEBOARD_FAB2(SCH_1):PAGE200
     6 A_HSC_LOW_DRAIN @BASEBOARD_FAB2_LIB.BASEBOARD_FAB2(SCH_1):A_HSC_LOW_DRAIN   I196 @BASEBOARD_FAB2_LIB.BASEBOARD_FAB2(SCH_1):PAGE200
     5 A_P12V_STBY_FPH_GATE @BASEBOARD_FAB2_LIB.BASEBOARD_FAB2(SCH_1):A_P12V_STBY_FPH_GATE   I199 @BASEBOARD_FAB2_LIB.BASEBOARD_FAB2(SCH_1):PAGE200
     4    GND @BASEBOARD_FAB2_LIB.BASEBOARD_FAB2(SCH_1):GND   I199 @BASEBOARD_FAB2_LIB.BASEBOARD_FAB2(SCH_1):PAGE200
     3 IRQ_UV_DETECT_N @BASEBOARD_FAB2_LIB.BASEBOARD_FAB2(SCH_1):IRQ_UV_DETECT_N   I199 @BASEBOARD_FAB2_LIB.BASEBOARD_FAB2(SCH_1):PAGE200

Q9T1 NPN_SM-MMBT3904,IC,C52245-001
     1 FM_MATED_IN_D2_N @BASEBOARD_FAB2_LIB.BASEBOARD_FAB2(SCH_1):FM_MATED_IN_D2_N    I42 @BASEBOARD_FAB2_LIB.BASEBOARD_FAB2(SCH_1):PAGE181
     3 FM_P12V_HOTSWAP0_EN @BASEBOARD_FAB2_LIB.BASEBOARD_FAB2(SCH_1):FM_P12V_HOTSWAP0_EN    I42 @BASEBOARD_FAB2_LIB.BASEBOARD_FAB2(SCH_1):PAGE181
     2    GND @BASEBOARD_FAB2_LIB.BASEBOARD_FAB2(SCH_1):GND    I42 @BASEBOARD_FAB2_LIB.BASEBOARD_FAB2(SCH_1):PAGE181

Q9W1 FET_N_SOT23LF-2N7002,FET,C7925A
     1 BMC_TPM_HW_C_RST @BASEBOARD_FAB2_LIB.BASEBOARD_FAB2(SCH_1):BMC_TPM_HW_C_RST    I30 @BASEBOARD_FAB2_LIB.BASEBOARD_FAB2(SCH_1):PAGE249
     2    GND @BASEBOARD_FAB2_LIB.BASEBOARD_FAB2(SCH_1):GND    I30 @BASEBOARD_FAB2_LIB.BASEBOARD_FAB2(SCH_1):PAGE249
     3 FM_TPM_PRES_RST_N @BASEBOARD_FAB2_LIB.BASEBOARD_FAB2(SCH_1):FM_TPM_PRES_RST_N    I30 @BASEBOARD_FAB2_LIB.BASEBOARD_FAB2(SCH_1):PAGE249

Q9W2 NPN_SM-MMBT3904,IC,C52245-001
     1 FM_TPM_PRES_RST_N_R @BASEBOARD_FAB2_LIB.BASEBOARD_FAB2(SCH_1):FM_TPM_PRES_RST_N_R    I29 @BASEBOARD_FAB2_LIB.BASEBOARD_FAB2(SCH_1):PAGE249
     3 FM_TPM_PRES_RST @BASEBOARD_FAB2_LIB.BASEBOARD_FAB2(SCH_1):FM_TPM_PRES_RST    I29 @BASEBOARD_FAB2_LIB.BASEBOARD_FAB2(SCH_1):PAGE249
     2    GND @BASEBOARD_FAB2_LIB.BASEBOARD_FAB2(SCH_1):GND    I29 @BASEBOARD_FAB2_LIB.BASEBOARD_FAB2(SCH_1):PAGE249

Q9W3 NPN_SM-MMBT3904,IC,C52245-001
     1 FM_TPM_PRES_RST @BASEBOARD_FAB2_LIB.BASEBOARD_FAB2(SCH_1):FM_TPM_PRES_RST    I49 @BASEBOARD_FAB2_LIB.BASEBOARD_FAB2(SCH_1):PAGE249
     3 RST_BMC_EXTRST_N @BASEBOARD_FAB2_LIB.BASEBOARD_FAB2(SCH_1):RST_BMC_EXTRST_N    I49 @BASEBOARD_FAB2_LIB.BASEBOARD_FAB2(SCH_1):PAGE249
     2    GND @BASEBOARD_FAB2_LIB.BASEBOARD_FAB2(SCH_1):GND    I49 @BASEBOARD_FAB2_LIB.BASEBOARD_FAB2(SCH_1):PAGE249

Q9W4 LMV331IDCKRG4-GP_DISCRET-G-LMVA
     1 FM_TPM_PRES_RST_N @BASEBOARD_FAB2_LIB.BASEBOARD_FAB2(SCH_1):FM_TPM_PRES_RST_N    I15 @BASEBOARD_FAB2_LIB.BASEBOARD_FAB2(SCH_1):PAGE249
     3 VREF_2V2 @BASEBOARD_FAB2_LIB.BASEBOARD_FAB2(SCH_1):VREF_2V2    I15 @BASEBOARD_FAB2_LIB.BASEBOARD_FAB2(SCH_1):PAGE249
     4 FM_TPM_PRES_N @BASEBOARD_FAB2_LIB.BASEBOARD_FAB2(SCH_1):FM_TPM_PRES_N    I15 @BASEBOARD_FAB2_LIB.BASEBOARD_FAB2(SCH_1):PAGE249
     5 P5V_STBY @BASEBOARD_FAB2_LIB.BASEBOARD_FAB2(SCH_1):P5V_STBY    I15 @BASEBOARD_FAB2_LIB.BASEBOARD_FAB2(SCH_1):PAGE249
     2    GND @BASEBOARD_FAB2_LIB.BASEBOARD_FAB2(SCH_1):GND    I15 @BASEBOARD_FAB2_LIB.BASEBOARD_FAB2(SCH_1):PAGE249

Q12W1 BSL308C-H6327-GP_DISCRET-GB1-BA
     1 PWRGD_PVDDQ_ABC @BASEBOARD_FAB2_LIB.BASEBOARD_FAB2(SCH_1):PWRGD_PVDDQ_ABC    I43 @BASEBOARD_FAB2_LIB.BASEBOARD_FAB2(SCH_1):PAGE197
     2 P12V_NVDIMM_ABC @BASEBOARD_FAB2_LIB.BASEBOARD_FAB2(SCH_1):P12V_NVDIMM_ABC    I43 @BASEBOARD_FAB2_LIB.BASEBOARD_FAB2(SCH_1):PAGE197
     6 PWRGD_PVDDQ_ABC_N @BASEBOARD_FAB2_LIB.BASEBOARD_FAB2(SCH_1):PWRGD_PVDDQ_ABC_N    I43 @BASEBOARD_FAB2_LIB.BASEBOARD_FAB2(SCH_1):PAGE197
     5    GND @BASEBOARD_FAB2_LIB.BASEBOARD_FAB2(SCH_1):GND    I43 @BASEBOARD_FAB2_LIB.BASEBOARD_FAB2(SCH_1):PAGE197
     3 PWRGD_PVDDQ_ABC_N @BASEBOARD_FAB2_LIB.BASEBOARD_FAB2(SCH_1):PWRGD_PVDDQ_ABC_N    I43 @BASEBOARD_FAB2_LIB.BASEBOARD_FAB2(SCH_1):PAGE197
     4 P12V_NVDIMM_ABC_D @BASEBOARD_FAB2_LIB.BASEBOARD_FAB2(SCH_1):P12V_NVDIMM_ABC_D    I43 @BASEBOARD_FAB2_LIB.BASEBOARD_FAB2(SCH_1):PAGE197

Q12W2 BSL308C-H6327-GP_DISCRET-GB1-BA
     1 PWRGD_PVDDQ_DEF @BASEBOARD_FAB2_LIB.BASEBOARD_FAB2(SCH_1):PWRGD_PVDDQ_DEF    I19 @BASEBOARD_FAB2_LIB.BASEBOARD_FAB2(SCH_1):PAGE197
     2 P12V_NVDIMM_DEF @BASEBOARD_FAB2_LIB.BASEBOARD_FAB2(SCH_1):P12V_NVDIMM_DEF    I19 @BASEBOARD_FAB2_LIB.BASEBOARD_FAB2(SCH_1):PAGE197
     6 PWRGD_PVDDQ_DEF_N @BASEBOARD_FAB2_LIB.BASEBOARD_FAB2(SCH_1):PWRGD_PVDDQ_DEF_N    I19 @BASEBOARD_FAB2_LIB.BASEBOARD_FAB2(SCH_1):PAGE197
     5    GND @BASEBOARD_FAB2_LIB.BASEBOARD_FAB2(SCH_1):GND    I19 @BASEBOARD_FAB2_LIB.BASEBOARD_FAB2(SCH_1):PAGE197
     3 PWRGD_PVDDQ_DEF_N @BASEBOARD_FAB2_LIB.BASEBOARD_FAB2(SCH_1):PWRGD_PVDDQ_DEF_N    I19 @BASEBOARD_FAB2_LIB.BASEBOARD_FAB2(SCH_1):PAGE197
     4 P12V_NVDIMM_DEF_D @BASEBOARD_FAB2_LIB.BASEBOARD_FAB2(SCH_1):P12V_NVDIMM_DEF_D    I19 @BASEBOARD_FAB2_LIB.BASEBOARD_FAB2(SCH_1):PAGE197

Q12W3 BSL308C-H6327-GP_DISCRET-GB1-BA
     1 PWRGD_PVDDQ_GHJ @BASEBOARD_FAB2_LIB.BASEBOARD_FAB2(SCH_1):PWRGD_PVDDQ_GHJ    I91 @BASEBOARD_FAB2_LIB.BASEBOARD_FAB2(SCH_1):PAGE197
     2 P12V_NVDIMM_GHJ @BASEBOARD_FAB2_LIB.BASEBOARD_FAB2(SCH_1):P12V_NVDIMM_GHJ    I91 @BASEBOARD_FAB2_LIB.BASEBOARD_FAB2(SCH_1):PAGE197
     6 PWRGD_PVDDQ_GHJ_N @BASEBOARD_FAB2_LIB.BASEBOARD_FAB2(SCH_1):PWRGD_PVDDQ_GHJ_N    I91 @BASEBOARD_FAB2_LIB.BASEBOARD_FAB2(SCH_1):PAGE197
     5    GND @BASEBOARD_FAB2_LIB.BASEBOARD_FAB2(SCH_1):GND    I91 @BASEBOARD_FAB2_LIB.BASEBOARD_FAB2(SCH_1):PAGE197
     3 PWRGD_PVDDQ_GHJ_N @BASEBOARD_FAB2_LIB.BASEBOARD_FAB2(SCH_1):PWRGD_PVDDQ_GHJ_N    I91 @BASEBOARD_FAB2_LIB.BASEBOARD_FAB2(SCH_1):PAGE197
     4 P12V_NVDIMM_GHJ_D @BASEBOARD_FAB2_LIB.BASEBOARD_FAB2(SCH_1):P12V_NVDIMM_GHJ_D    I91 @BASEBOARD_FAB2_LIB.BASEBOARD_FAB2(SCH_1):PAGE197

Q12W4 BSL308C-H6327-GP_DISCRET-GB1-BA
     1 PWRGD_PVDDQ_KLM @BASEBOARD_FAB2_LIB.BASEBOARD_FAB2(SCH_1):PWRGD_PVDDQ_KLM    I35 @BASEBOARD_FAB2_LIB.BASEBOARD_FAB2(SCH_1):PAGE197
     2 P12V_NVDIMM_KLM @BASEBOARD_FAB2_LIB.BASEBOARD_FAB2(SCH_1):P12V_NVDIMM_KLM    I35 @BASEBOARD_FAB2_LIB.BASEBOARD_FAB2(SCH_1):PAGE197
     6 PWRGD_PVDDQ_KLM_N @BASEBOARD_FAB2_LIB.BASEBOARD_FAB2(SCH_1):PWRGD_PVDDQ_KLM_N    I35 @BASEBOARD_FAB2_LIB.BASEBOARD_FAB2(SCH_1):PAGE197
     5    GND @BASEBOARD_FAB2_LIB.BASEBOARD_FAB2(SCH_1):GND    I35 @BASEBOARD_FAB2_LIB.BASEBOARD_FAB2(SCH_1):PAGE197
     3 PWRGD_PVDDQ_KLM_N @BASEBOARD_FAB2_LIB.BASEBOARD_FAB2(SCH_1):PWRGD_PVDDQ_KLM_N    I35 @BASEBOARD_FAB2_LIB.BASEBOARD_FAB2(SCH_1):PAGE197
     4 P12V_NVDIMM_KLM_D @BASEBOARD_FAB2_LIB.BASEBOARD_FAB2(SCH_1):P12V_NVDIMM_KLM_D    I35 @BASEBOARD_FAB2_LIB.BASEBOARD_FAB2(SCH_1):PAGE197

Q25W4 FET_N_DUAL_SMLF-2N7002DW,FET,DA
     2 Q25W1_GATE @BASEBOARD_FAB2_LIB.BASEBOARD_FAB2(SCH_1):Q25W1_GATE    I95 @BASEBOARD_FAB2_LIB.BASEBOARD_FAB2(SCH_1):PAGE255
     1 I2C_BMC_VGA_DDC_SCL @BASEBOARD_FAB2_LIB.BASEBOARD_FAB2(SCH_1):I2C_BMC_VGA_DDC_SCL    I95 @BASEBOARD_FAB2_LIB.BASEBOARD_FAB2(SCH_1):PAGE255
     6 I2C_BMC_VGA_DDC_SCL_G @BASEBOARD_FAB2_LIB.BASEBOARD_FAB2(SCH_1):I2C_BMC_VGA_DDC_SCL_G    I95 @BASEBOARD_FAB2_LIB.BASEBOARD_FAB2(SCH_1):PAGE255
     5 Q25W2_GATE @BASEBOARD_FAB2_LIB.BASEBOARD_FAB2(SCH_1):Q25W2_GATE    I96 @BASEBOARD_FAB2_LIB.BASEBOARD_FAB2(SCH_1):PAGE255
     4 I2C_BMC_VGA_DDC_SDA @BASEBOARD_FAB2_LIB.BASEBOARD_FAB2(SCH_1):I2C_BMC_VGA_DDC_SDA    I96 @BASEBOARD_FAB2_LIB.BASEBOARD_FAB2(SCH_1):PAGE255
     3 I2C_BMC_VGA_DDC_SDA_G @BASEBOARD_FAB2_LIB.BASEBOARD_FAB2(SCH_1):I2C_BMC_VGA_DDC_SDA_G    I96 @BASEBOARD_FAB2_LIB.BASEBOARD_FAB2(SCH_1):PAGE255

Q25W5 FET_N_SOT23LF-2N7002,FET,C7925A
     1 BMC_JTAG_SEL_N @BASEBOARD_FAB2_LIB.BASEBOARD_FAB2(SCH_1):BMC_JTAG_SEL_N    I51 @BASEBOARD_FAB2_LIB.BASEBOARD_FAB2(SCH_1):PAGE268
     2    GND @BASEBOARD_FAB2_LIB.BASEBOARD_FAB2(SCH_1):GND    I51 @BASEBOARD_FAB2_LIB.BASEBOARD_FAB2(SCH_1):PAGE268
     3 BMC_JTAG_SEL @BASEBOARD_FAB2_LIB.BASEBOARD_FAB2(SCH_1):BMC_JTAG_SEL    I51 @BASEBOARD_FAB2_LIB.BASEBOARD_FAB2(SCH_1):PAGE268

R1A1 RES_0603-120.0,1%,1/10W,CHIP,GA
     1 PVDDQ_KLM @BASEBOARD_FAB2_LIB.BASEBOARD_FAB2(SCH_1):PVDDQ_KLM    I58 @BASEBOARD_FAB2_LIB.BASEBOARD_FAB2(SCH_1):PAGE228
     2    GND @BASEBOARD_FAB2_LIB.BASEBOARD_FAB2(SCH_1):GND    I58 @BASEBOARD_FAB2_LIB.BASEBOARD_FAB2(SCH_1):PAGE228

R1A2 RES_0402-68.1K,1%,1/16W,EMPTY,A
     1 VR_PVDDQ_KLM_PH2_OCSET @BASEBOARD_FAB2_LIB.BASEBOARD_FAB2(SCH_1):VR_PVDDQ_KLM_PH2_OCSET   I105 @BASEBOARD_FAB2_LIB.BASEBOARD_FAB2(SCH_1):PAGE227
     2    GND @BASEBOARD_FAB2_LIB.BASEBOARD_FAB2(SCH_1):GND   I105 @BASEBOARD_FAB2_LIB.BASEBOARD_FAB2(SCH_1):PAGE227

R1A3 RES_0402-68.1K,1%,1/16W,EMPTY,A
     1 VR_PVDDQ_KLM_PH1_OCSET @BASEBOARD_FAB2_LIB.BASEBOARD_FAB2(SCH_1):VR_PVDDQ_KLM_PH1_OCSET   I103 @BASEBOARD_FAB2_LIB.BASEBOARD_FAB2(SCH_1):PAGE227
     2    GND @BASEBOARD_FAB2_LIB.BASEBOARD_FAB2(SCH_1):GND   I103 @BASEBOARD_FAB2_LIB.BASEBOARD_FAB2(SCH_1):PAGE227

R1B1 RES_0402-1.00K,1%,1/16W,CHIP,GA
     1 P3V3_STBY @BASEBOARD_FAB2_LIB.BASEBOARD_FAB2(SCH_1):P3V3_STBY    I49 @BASEBOARD_FAB2_LIB.BASEBOARD_FAB2(SCH_1):PAGE226
     2 IRQ_PVDDQ_KLM_VRHOT_LVT3_R_N @BASEBOARD_FAB2_LIB.BASEBOARD_FAB2(SCH_1):IRQ_PVDDQ_KLM_VRHOT_LVT3_R_N    I49 @BASEBOARD_FAB2_LIB.BASEBOARD_FAB2(SCH_1):PAGE226

R1B2 RES_0402-1.00K,1%,1/16W,CHIP,GA
     1 P3V3_STBY @BASEBOARD_FAB2_LIB.BASEBOARD_FAB2(SCH_1):P3V3_STBY    I50 @BASEBOARD_FAB2_LIB.BASEBOARD_FAB2(SCH_1):PAGE226
     2 PWRGD_PVDDQ_KLM_R @BASEBOARD_FAB2_LIB.BASEBOARD_FAB2(SCH_1):PWRGD_PVDDQ_KLM_R    I50 @BASEBOARD_FAB2_LIB.BASEBOARD_FAB2(SCH_1):PAGE226

R1B4 RES_0402-33.2,1%,1/16W,CHIP,G2A
     1 IRQ_PVDDQ_KLM_VRHOT_LVT3_R_N @BASEBOARD_FAB2_LIB.BASEBOARD_FAB2(SCH_1):IRQ_PVDDQ_KLM_VRHOT_LVT3_R_N    I54 @BASEBOARD_FAB2_LIB.BASEBOARD_FAB2(SCH_1):PAGE226
     2 IRQ_PVDDQ_KLM_VRHOT_LVT3_N @BASEBOARD_FAB2_LIB.BASEBOARD_FAB2(SCH_1):IRQ_PVDDQ_KLM_VRHOT_LVT3_N    I54 @BASEBOARD_FAB2_LIB.BASEBOARD_FAB2(SCH_1):PAGE226

R1B5 RES_0402-22.1,1.0%,1/16W,CHIP,A
     1 PWRGD_PVDDQ_KLM_R @BASEBOARD_FAB2_LIB.BASEBOARD_FAB2(SCH_1):PWRGD_PVDDQ_KLM_R    I55 @BASEBOARD_FAB2_LIB.BASEBOARD_FAB2(SCH_1):PAGE226
     2 PWRGD_PVDDQ_KLM @BASEBOARD_FAB2_LIB.BASEBOARD_FAB2(SCH_1):PWRGD_PVDDQ_KLM    I55 @BASEBOARD_FAB2_LIB.BASEBOARD_FAB2(SCH_1):PAGE226

R1B8 RES_0402-150.0,1%,1/16W,CHIP,GA
     1 SVID_CLK1_CPU1_R @BASEBOARD_FAB2_LIB.BASEBOARD_FAB2(SCH_1):SVID_CLK1_CPU1_R    I19 @BASEBOARD_FAB2_LIB.BASEBOARD_FAB2(SCH_1):PAGE226
     2 SVID_CLK_PVDDQ_KLM @BASEBOARD_FAB2_LIB.BASEBOARD_FAB2(SCH_1):SVID_CLK_PVDDQ_KLM    I19 @BASEBOARD_FAB2_LIB.BASEBOARD_FAB2(SCH_1):PAGE226

R1B10 RES_0402-0.0,5%,1/16W,CHIP,G21A
     1 SVID_VDIO_PVDDQ_KLM @BASEBOARD_FAB2_LIB.BASEBOARD_FAB2(SCH_1):SVID_VDIO_PVDDQ_KLM    I41 @BASEBOARD_FAB2_LIB.BASEBOARD_FAB2(SCH_1):PAGE226
     2 SVID_DIO1_CPU1_R @BASEBOARD_FAB2_LIB.BASEBOARD_FAB2(SCH_1):SVID_DIO1_CPU1_R    I41 @BASEBOARD_FAB2_LIB.BASEBOARD_FAB2(SCH_1):PAGE226

R1B11 RES_0402-0.0,5%,1/16W,CHIP,G21A
     1 SVID_ALERT_PVDDQ_KLM @BASEBOARD_FAB2_LIB.BASEBOARD_FAB2(SCH_1):SVID_ALERT_PVDDQ_KLM    I48 @BASEBOARD_FAB2_LIB.BASEBOARD_FAB2(SCH_1):PAGE226
     2 SVID_ALERT1_CPU1_R_N @BASEBOARD_FAB2_LIB.BASEBOARD_FAB2(SCH_1):SVID_ALERT1_CPU1_R_N    I48 @BASEBOARD_FAB2_LIB.BASEBOARD_FAB2(SCH_1):PAGE226

R1B12 RES_0402-16K,1.0%,1/16W,CHIP,GA
     1 VR_PVDDQ_KLM_XADDR1 @BASEBOARD_FAB2_LIB.BASEBOARD_FAB2(SCH_1):VR_PVDDQ_KLM_XADDR1    I72 @BASEBOARD_FAB2_LIB.BASEBOARD_FAB2(SCH_1):PAGE226
     2    GND @BASEBOARD_FAB2_LIB.BASEBOARD_FAB2(SCH_1):GND    I72 @BASEBOARD_FAB2_LIB.BASEBOARD_FAB2(SCH_1):PAGE226

R1B13 RES_0402-2.26K,1.0%,1/16W,CHIPA
     1 P3V3_STBY @BASEBOARD_FAB2_LIB.BASEBOARD_FAB2(SCH_1):P3V3_STBY    I75 @BASEBOARD_FAB2_LIB.BASEBOARD_FAB2(SCH_1):PAGE226
     2 PWRGD_PVDDQ_KLM @BASEBOARD_FAB2_LIB.BASEBOARD_FAB2(SCH_1):PWRGD_PVDDQ_KLM    I75 @BASEBOARD_FAB2_LIB.BASEBOARD_FAB2(SCH_1):PAGE226

R1B15 RES_0402-3.16K,1%,1/16W,CHIP,GA
     1 VR_PVDDQ_KLM_XADDR2 @BASEBOARD_FAB2_LIB.BASEBOARD_FAB2(SCH_1):VR_PVDDQ_KLM_XADDR2    I73 @BASEBOARD_FAB2_LIB.BASEBOARD_FAB2(SCH_1):PAGE226
     2    GND @BASEBOARD_FAB2_LIB.BASEBOARD_FAB2(SCH_1):GND    I73 @BASEBOARD_FAB2_LIB.BASEBOARD_FAB2(SCH_1):PAGE226

R1B16 RES_0402-10.0,1%,1/16W,CHIP,G2A
     1 VSENSE_PVDDQ_KLM_P @BASEBOARD_FAB2_LIB.BASEBOARD_FAB2(SCH_1):VSENSE_PVDDQ_KLM_P    I13 @BASEBOARD_FAB2_LIB.BASEBOARD_FAB2(SCH_1):PAGE226
     2 VR_PVDDQ_KLM_AVSP @BASEBOARD_FAB2_LIB.BASEBOARD_FAB2(SCH_1):VR_PVDDQ_KLM_AVSP    I13 @BASEBOARD_FAB2_LIB.BASEBOARD_FAB2(SCH_1):PAGE226

R1B21 RES_0402-4.75K,1%,1/16W,CHIP,GA
     1 P3V3_STBY @BASEBOARD_FAB2_LIB.BASEBOARD_FAB2(SCH_1):P3V3_STBY    I70 @BASEBOARD_FAB2_LIB.BASEBOARD_FAB2(SCH_1):PAGE161
     2 FAN_TACH2 @BASEBOARD_FAB2_LIB.BASEBOARD_FAB2(SCH_1):FAN_TACH2    I70 @BASEBOARD_FAB2_LIB.BASEBOARD_FAB2(SCH_1):PAGE161

R1B22 RES_0402-100.0,1%,1/16W,CHIP,GA
     1 FAN_TACH2 @BASEBOARD_FAB2_LIB.BASEBOARD_FAB2(SCH_1):FAN_TACH2    I67 @BASEBOARD_FAB2_LIB.BASEBOARD_FAB2(SCH_1):PAGE161
     2 FAN_TACH2_CPU1_D2 @BASEBOARD_FAB2_LIB.BASEBOARD_FAB2(SCH_1):FAN_TACH2_CPU1_D2    I67 @BASEBOARD_FAB2_LIB.BASEBOARD_FAB2(SCH_1):PAGE161

R1C1 RES_0402-221,1.0%,1/16W,CHIP,GA
     1 SVID_ALERT1_CPU1_N @BASEBOARD_FAB2_LIB.BASEBOARD_FAB2(SCH_1):SVID_ALERT1_CPU1_N    I26 @BASEBOARD_FAB2_LIB.BASEBOARD_FAB2(SCH_1):PAGE55
     2 SVID_ALERT1_CPU1_R_N @BASEBOARD_FAB2_LIB.BASEBOARD_FAB2(SCH_1):SVID_ALERT1_CPU1_R_N    I26 @BASEBOARD_FAB2_LIB.BASEBOARD_FAB2(SCH_1):PAGE55

R1C2 RES_0402-0.0,5%,1/16W,CHIP,G21A
     1 SVID_DIO1_CPU1 @BASEBOARD_FAB2_LIB.BASEBOARD_FAB2(SCH_1):SVID_DIO1_CPU1    I24 @BASEBOARD_FAB2_LIB.BASEBOARD_FAB2(SCH_1):PAGE55
     2 SVID_DIO1_CPU1_R @BASEBOARD_FAB2_LIB.BASEBOARD_FAB2(SCH_1):SVID_DIO1_CPU1_R    I24 @BASEBOARD_FAB2_LIB.BASEBOARD_FAB2(SCH_1):PAGE55

R1C3 RES_0402-0.0,5%,1/16W,CHIP,G21A
     1 SVID_CLK1_CPU1 @BASEBOARD_FAB2_LIB.BASEBOARD_FAB2(SCH_1):SVID_CLK1_CPU1    I25 @BASEBOARD_FAB2_LIB.BASEBOARD_FAB2(SCH_1):PAGE55
     2 SVID_CLK1_CPU1_R @BASEBOARD_FAB2_LIB.BASEBOARD_FAB2(SCH_1):SVID_CLK1_CPU1_R    I25 @BASEBOARD_FAB2_LIB.BASEBOARD_FAB2(SCH_1):PAGE55

R1C4 RES_0402-100.0,1%,1/16W,CHIP,GA
     1 VSENSE_PVSA_CPU1_N @BASEBOARD_FAB2_LIB.BASEBOARD_FAB2(SCH_1):VSENSE_PVSA_CPU1_N    I33 @BASEBOARD_FAB2_LIB.BASEBOARD_FAB2(SCH_1):PAGE210
     2    GND @BASEBOARD_FAB2_LIB.BASEBOARD_FAB2(SCH_1):GND    I33 @BASEBOARD_FAB2_LIB.BASEBOARD_FAB2(SCH_1):PAGE210

R1C5 RES_0402-0.0,5%,1/16W,CHIP,G21A
     1 VSENSE_PVSA_CPU1_N @BASEBOARD_FAB2_LIB.BASEBOARD_FAB2(SCH_1):VSENSE_PVSA_CPU1_N    I32 @BASEBOARD_FAB2_LIB.BASEBOARD_FAB2(SCH_1):PAGE210
     2 VSENSE_PVSA_CPU1_SKT_VRTN @BASEBOARD_FAB2_LIB.BASEBOARD_FAB2(SCH_1):VSENSE_PVSA_CPU1_SKT_VRTN    I32 @BASEBOARD_FAB2_LIB.BASEBOARD_FAB2(SCH_1):PAGE210

R1C6 RES_0402-1.00K,1%,1/16W,EMPTY,A
     1 VSENSE_PVSA_CPU1_P @BASEBOARD_FAB2_LIB.BASEBOARD_FAB2(SCH_1):VSENSE_PVSA_CPU1_P    I34 @BASEBOARD_FAB2_LIB.BASEBOARD_FAB2(SCH_1):PAGE210
     2 VSENSE_PVSA_CPU1_N @BASEBOARD_FAB2_LIB.BASEBOARD_FAB2(SCH_1):VSENSE_PVSA_CPU1_N    I34 @BASEBOARD_FAB2_LIB.BASEBOARD_FAB2(SCH_1):PAGE210

R1C7 RES_0402-0.0,5%,1/16W,CHIP,G21A
     1 VSENSE_PVSA_CPU1_P @BASEBOARD_FAB2_LIB.BASEBOARD_FAB2(SCH_1):VSENSE_PVSA_CPU1_P    I31 @BASEBOARD_FAB2_LIB.BASEBOARD_FAB2(SCH_1):PAGE210
     2 VSENSE_PVSA_CPU1_SKT_VSEN @BASEBOARD_FAB2_LIB.BASEBOARD_FAB2(SCH_1):VSENSE_PVSA_CPU1_SKT_VSEN    I31 @BASEBOARD_FAB2_LIB.BASEBOARD_FAB2(SCH_1):PAGE210

R1C9 RES_0402-0.0,5%,1/16W,EMPTY,G2A
     1 IRQ_BOARD_BMC_ALERT_N @BASEBOARD_FAB2_LIB.BASEBOARD_FAB2(SCH_1):IRQ_BOARD_BMC_ALERT_N     I8 @BASEBOARD_FAB2_LIB.BASEBOARD_FAB2(SCH_1):PAGE182
     2 FAN_TACH2_R @BASEBOARD_FAB2_LIB.BASEBOARD_FAB2(SCH_1):FAN_TACH2_R     I8 @BASEBOARD_FAB2_LIB.BASEBOARD_FAB2(SCH_1):PAGE182

R1C10 RES_0402-0.0,5%,1/16W,EMPTY,G2A
     1 SMB_LAN_STBY_LVC3_SDA @BASEBOARD_FAB2_LIB.BASEBOARD_FAB2(SCH_1):SMB_LAN_STBY_LVC3_SDA     I9 @BASEBOARD_FAB2_LIB.BASEBOARD_FAB2(SCH_1):PAGE182
     2 FAN_TACH3_R @BASEBOARD_FAB2_LIB.BASEBOARD_FAB2(SCH_1):FAN_TACH3_R     I9 @BASEBOARD_FAB2_LIB.BASEBOARD_FAB2(SCH_1):PAGE182

R1C11 RES_0402-0.0,5%,1/16W,EMPTY,G2A
     1 SMB_LAN_STBY_LVC3_SCL @BASEBOARD_FAB2_LIB.BASEBOARD_FAB2(SCH_1):SMB_LAN_STBY_LVC3_SCL    I10 @BASEBOARD_FAB2_LIB.BASEBOARD_FAB2(SCH_1):PAGE182
     2 FAN_TACH1_R @BASEBOARD_FAB2_LIB.BASEBOARD_FAB2(SCH_1):FAN_TACH1_R    I10 @BASEBOARD_FAB2_LIB.BASEBOARD_FAB2(SCH_1):PAGE182

R1C12 RES_0402-100.0,1%,1/16W,CHIP,GA
     1 VSENSE_PVSA_CPU1_P @BASEBOARD_FAB2_LIB.BASEBOARD_FAB2(SCH_1):VSENSE_PVSA_CPU1_P    I29 @BASEBOARD_FAB2_LIB.BASEBOARD_FAB2(SCH_1):PAGE210
     2 PVSA_CPU1 @BASEBOARD_FAB2_LIB.BASEBOARD_FAB2(SCH_1):PVSA_CPU1    I29 @BASEBOARD_FAB2_LIB.BASEBOARD_FAB2(SCH_1):PAGE210

R1C13 RES_0402-100.0K,1%,1/16W,CHIP,B
     1 VR_FET_SW_P12V_STBY_PVCCIN_CPU1 @BASEBOARD_FAB2_LIB.BASEBOARD_FAB2(SCH_1):VR_FET_SW_P12V_STBY_PVCCIN_CPU1    I49 @BASEBOARD_FAB2_LIB.BASEBOARD_FAB2(SCH_1):PAGE206
     2 VR_PVCCIN_CPU1_AVINSEN @BASEBOARD_FAB2_LIB.BASEBOARD_FAB2(SCH_1):VR_PVCCIN_CPU1_AVINSEN    I49 @BASEBOARD_FAB2_LIB.BASEBOARD_FAB2(SCH_1):PAGE206

R1C14 RES_0402-0.0,5%,1/16W,CHIP,G21A
     1 P3V3_STBY @BASEBOARD_FAB2_LIB.BASEBOARD_FAB2(SCH_1):P3V3_STBY    I46 @BASEBOARD_FAB2_LIB.BASEBOARD_FAB2(SCH_1):PAGE206
     2 VR_PVCCIN_CPU1_VDD @BASEBOARD_FAB2_LIB.BASEBOARD_FAB2(SCH_1):VR_PVCCIN_CPU1_VDD    I46 @BASEBOARD_FAB2_LIB.BASEBOARD_FAB2(SCH_1):PAGE206

R1C16 RES_0402-1.5K,1%,1/16W,CHIP,G2A
     1 VR_PVCCIN_CPU1_AVINSEN @BASEBOARD_FAB2_LIB.BASEBOARD_FAB2(SCH_1):VR_PVCCIN_CPU1_AVINSEN    I56 @BASEBOARD_FAB2_LIB.BASEBOARD_FAB2(SCH_1):PAGE206
     2    GND @BASEBOARD_FAB2_LIB.BASEBOARD_FAB2(SCH_1):GND    I56 @BASEBOARD_FAB2_LIB.BASEBOARD_FAB2(SCH_1):PAGE206

R1C18 RES_0402-2.26K,1.0%,1/16W,EMPTA
     1 P3V3_STBY @BASEBOARD_FAB2_LIB.BASEBOARD_FAB2(SCH_1):P3V3_STBY    I34 @BASEBOARD_FAB2_LIB.BASEBOARD_FAB2(SCH_1):PAGE206
     2 PU_VR_PVCCIN_CPU1_IMON @BASEBOARD_FAB2_LIB.BASEBOARD_FAB2(SCH_1):PU_VR_PVCCIN_CPU1_IMON    I34 @BASEBOARD_FAB2_LIB.BASEBOARD_FAB2(SCH_1):PAGE206

R1C21 RES_0402-10.0,1%,1/16W,CHIP,G2A
     1 VSENSE_PVSA_CPU1_P @BASEBOARD_FAB2_LIB.BASEBOARD_FAB2(SCH_1):VSENSE_PVSA_CPU1_P    I77 @BASEBOARD_FAB2_LIB.BASEBOARD_FAB2(SCH_1):PAGE206
     2 VSENSE_PVSA_CPU1_BVSP @BASEBOARD_FAB2_LIB.BASEBOARD_FAB2(SCH_1):VSENSE_PVSA_CPU1_BVSP    I77 @BASEBOARD_FAB2_LIB.BASEBOARD_FAB2(SCH_1):PAGE206

R1C28 RES_0402-1.00K,1%,1/16W,CHIP,GA
     1 P3V3_STBY @BASEBOARD_FAB2_LIB.BASEBOARD_FAB2(SCH_1):P3V3_STBY    I35 @BASEBOARD_FAB2_LIB.BASEBOARD_FAB2(SCH_1):PAGE206
     2 VR_VRRDY_PVCCIN_CPU1 @BASEBOARD_FAB2_LIB.BASEBOARD_FAB2(SCH_1):VR_VRRDY_PVCCIN_CPU1    I35 @BASEBOARD_FAB2_LIB.BASEBOARD_FAB2(SCH_1):PAGE206

R1C30 RES_0402-22.1,1.0%,1/16W,CHIP,A
     1 VR_VRRDY_PVCCIN_CPU1 @BASEBOARD_FAB2_LIB.BASEBOARD_FAB2(SCH_1):VR_VRRDY_PVCCIN_CPU1   I113 @BASEBOARD_FAB2_LIB.BASEBOARD_FAB2(SCH_1):PAGE206
     2 PWRGD_PVCCIN_CPU1 @BASEBOARD_FAB2_LIB.BASEBOARD_FAB2(SCH_1):PWRGD_PVCCIN_CPU1   I113 @BASEBOARD_FAB2_LIB.BASEBOARD_FAB2(SCH_1):PAGE206

R1C31 RES_0402-0.0,5%,1/16W,EMPTY,G2A
     1 FM_XRC_READY_N @BASEBOARD_FAB2_LIB.BASEBOARD_FAB2(SCH_1):FM_XRC_READY_N     I6 @BASEBOARD_FAB2_LIB.BASEBOARD_FAB2(SCH_1):PAGE182
     2 FAN_TACH0_R @BASEBOARD_FAB2_LIB.BASEBOARD_FAB2(SCH_1):FAN_TACH0_R     I6 @BASEBOARD_FAB2_LIB.BASEBOARD_FAB2(SCH_1):PAGE182

R1C32 RES_0402-1.00K,1%,1/16W,CHIP,GA
     1    GND @BASEBOARD_FAB2_LIB.BASEBOARD_FAB2(SCH_1):GND   I312 @BASEBOARD_FAB2_LIB.BASEBOARD_FAB2(SCH_1):PAGE156
     2 PD_PIROM_CPU1_ADDR2 @BASEBOARD_FAB2_LIB.BASEBOARD_FAB2(SCH_1):PD_PIROM_CPU1_ADDR2   I312 @BASEBOARD_FAB2_LIB.BASEBOARD_FAB2(SCH_1):PAGE156

R1C33 RES_0402-1.00K,1%,1/16W,CHIP,GA
     1    GND @BASEBOARD_FAB2_LIB.BASEBOARD_FAB2(SCH_1):GND   I313 @BASEBOARD_FAB2_LIB.BASEBOARD_FAB2(SCH_1):PAGE156
     2 PD_PIROM_CPU1_ADDR1 @BASEBOARD_FAB2_LIB.BASEBOARD_FAB2(SCH_1):PD_PIROM_CPU1_ADDR1   I313 @BASEBOARD_FAB2_LIB.BASEBOARD_FAB2(SCH_1):PAGE156

R1C34 RES_0402-10.0K,1%,1/16W,CHIP,GA
     1 P3V3_STBY @BASEBOARD_FAB2_LIB.BASEBOARD_FAB2(SCH_1):P3V3_STBY   I320 @BASEBOARD_FAB2_LIB.BASEBOARD_FAB2(SCH_1):PAGE156
     2 PU_PIROM_CPU1_ADDR0 @BASEBOARD_FAB2_LIB.BASEBOARD_FAB2(SCH_1):PU_PIROM_CPU1_ADDR0   I320 @BASEBOARD_FAB2_LIB.BASEBOARD_FAB2(SCH_1):PAGE156

R1C35 RES_0402-3.32K,1%,1/16W,EMPTY,A
     1 P3V3_STBY @BASEBOARD_FAB2_LIB.BASEBOARD_FAB2(SCH_1):P3V3_STBY   I336 @BASEBOARD_FAB2_LIB.BASEBOARD_FAB2(SCH_1):PAGE156
     2 FM_CPU1_SM_WP @BASEBOARD_FAB2_LIB.BASEBOARD_FAB2(SCH_1):FM_CPU1_SM_WP   I336 @BASEBOARD_FAB2_LIB.BASEBOARD_FAB2(SCH_1):PAGE156

R1C36 RES_0402-1.00K,1%,1/16W,CHIP,GA
     1 FM_CPU1_SM_WP @BASEBOARD_FAB2_LIB.BASEBOARD_FAB2(SCH_1):FM_CPU1_SM_WP   I337 @BASEBOARD_FAB2_LIB.BASEBOARD_FAB2(SCH_1):PAGE156
     2    GND @BASEBOARD_FAB2_LIB.BASEBOARD_FAB2(SCH_1):GND   I337 @BASEBOARD_FAB2_LIB.BASEBOARD_FAB2(SCH_1):PAGE156

R1C37 RES_0402-68.1K,1%,1/16W,EMPTY,A
     1 VR_PVSA_CPU1_OCSET @BASEBOARD_FAB2_LIB.BASEBOARD_FAB2(SCH_1):VR_PVSA_CPU1_OCSET    I52 @BASEBOARD_FAB2_LIB.BASEBOARD_FAB2(SCH_1):PAGE210
     2    GND @BASEBOARD_FAB2_LIB.BASEBOARD_FAB2(SCH_1):GND    I52 @BASEBOARD_FAB2_LIB.BASEBOARD_FAB2(SCH_1):PAGE210

R1D1 RES_0402-33.2,1%,1/16W,CHIP,G2A
     1 PWRGD_PVSA_CPU1_R @BASEBOARD_FAB2_LIB.BASEBOARD_FAB2(SCH_1):PWRGD_PVSA_CPU1_R   I116 @BASEBOARD_FAB2_LIB.BASEBOARD_FAB2(SCH_1):PAGE206
     2 PWRGD_PVSA_CPU1 @BASEBOARD_FAB2_LIB.BASEBOARD_FAB2(SCH_1):PWRGD_PVSA_CPU1   I116 @BASEBOARD_FAB2_LIB.BASEBOARD_FAB2(SCH_1):PAGE206

R1D2 RES_0402-0.0,5%,1/16W,CHIP,G21A
     1 SVID_VDIO_PVCCIN_CPU1 @BASEBOARD_FAB2_LIB.BASEBOARD_FAB2(SCH_1):SVID_VDIO_PVCCIN_CPU1    I38 @BASEBOARD_FAB2_LIB.BASEBOARD_FAB2(SCH_1):PAGE206
     2 SVID_DIO0_CPU1_R @BASEBOARD_FAB2_LIB.BASEBOARD_FAB2(SCH_1):SVID_DIO0_CPU1_R    I38 @BASEBOARD_FAB2_LIB.BASEBOARD_FAB2(SCH_1):PAGE206

R1D3 RES_0402-0.0,5%,1/16W,CHIP,G21A
     1 SVID_VALERT_VCCIN_CPU1 @BASEBOARD_FAB2_LIB.BASEBOARD_FAB2(SCH_1):SVID_VALERT_VCCIN_CPU1    I37 @BASEBOARD_FAB2_LIB.BASEBOARD_FAB2(SCH_1):PAGE206
     2 SVID_ALERT0_CPU1_R_N @BASEBOARD_FAB2_LIB.BASEBOARD_FAB2(SCH_1):SVID_ALERT0_CPU1_R_N    I37 @BASEBOARD_FAB2_LIB.BASEBOARD_FAB2(SCH_1):PAGE206

R1D4 RES_0402-10.0,1%,1/16W,CHIP,G2A
     1 VSENSE_PVCCIN_CPU1_P @BASEBOARD_FAB2_LIB.BASEBOARD_FAB2(SCH_1):VSENSE_PVCCIN_CPU1_P    I79 @BASEBOARD_FAB2_LIB.BASEBOARD_FAB2(SCH_1):PAGE206
     2 VSENSE_PVCCIN_CPU1_AVSP @BASEBOARD_FAB2_LIB.BASEBOARD_FAB2(SCH_1):VSENSE_PVCCIN_CPU1_AVSP    I79 @BASEBOARD_FAB2_LIB.BASEBOARD_FAB2(SCH_1):PAGE206

R1D6 RES_0402-1.00K,1%,1/16W,CHIP,GA
     1 P3V3_STBY @BASEBOARD_FAB2_LIB.BASEBOARD_FAB2(SCH_1):P3V3_STBY     I6 @BASEBOARD_FAB2_LIB.BASEBOARD_FAB2(SCH_1):PAGE206
     2 IRQ_PVCCIN_CPU1_VRHOT_LVC3_R_N @BASEBOARD_FAB2_LIB.BASEBOARD_FAB2(SCH_1):IRQ_PVCCIN_CPU1_VRHOT_LVC3_R_N     I6 @BASEBOARD_FAB2_LIB.BASEBOARD_FAB2(SCH_1):PAGE206

R1D7 RES_0402-1.00K,1%,1/16W,CHIP,GA
     1 P3V3_STBY @BASEBOARD_FAB2_LIB.BASEBOARD_FAB2(SCH_1):P3V3_STBY   I155 @BASEBOARD_FAB2_LIB.BASEBOARD_FAB2(SCH_1):PAGE206
     2 FM_PVCCIN_CPU1_PWR_IN_ALERT_N @BASEBOARD_FAB2_LIB.BASEBOARD_FAB2(SCH_1):FM_PVCCIN_CPU1_PWR_IN_ALERT_N   I155 @BASEBOARD_FAB2_LIB.BASEBOARD_FAB2(SCH_1):PAGE206

R1D8 RES_0402-1.00K,1%,1/16W,CHIP,GA
     1 P3V3_STBY @BASEBOARD_FAB2_LIB.BASEBOARD_FAB2(SCH_1):P3V3_STBY    I36 @BASEBOARD_FAB2_LIB.BASEBOARD_FAB2(SCH_1):PAGE206
     2 PWRGD_PVSA_CPU1_R @BASEBOARD_FAB2_LIB.BASEBOARD_FAB2(SCH_1):PWRGD_PVSA_CPU1_R    I36 @BASEBOARD_FAB2_LIB.BASEBOARD_FAB2(SCH_1):PAGE206

R1D9 RES_0402-150.0,1%,1/16W,CHIP,GA
     1 SVID_CLK0_CPU1_R @BASEBOARD_FAB2_LIB.BASEBOARD_FAB2(SCH_1):SVID_CLK0_CPU1_R    I54 @BASEBOARD_FAB2_LIB.BASEBOARD_FAB2(SCH_1):PAGE206
     2 SVID_VCLK_PVCCIN_CPU1 @BASEBOARD_FAB2_LIB.BASEBOARD_FAB2(SCH_1):SVID_VCLK_PVCCIN_CPU1    I54 @BASEBOARD_FAB2_LIB.BASEBOARD_FAB2(SCH_1):PAGE206

R1D10 RES_0402-10.0K,1%,1/16W,CHIP,GA
     1 P3V3_STBY @BASEBOARD_FAB2_LIB.BASEBOARD_FAB2(SCH_1):P3V3_STBY   I244 @BASEBOARD_FAB2_LIB.BASEBOARD_FAB2(SCH_1):PAGE200
     2 A_HSC_LOW_GATE @BASEBOARD_FAB2_LIB.BASEBOARD_FAB2(SCH_1):A_HSC_LOW_GATE   I244 @BASEBOARD_FAB2_LIB.BASEBOARD_FAB2(SCH_1):PAGE200

R1D11 RES_0402-100.0K,1%,1/16W,CHIP,A
     1 A_HSC_LOW_EN @BASEBOARD_FAB2_LIB.BASEBOARD_FAB2(SCH_1):A_HSC_LOW_EN    I88 @BASEBOARD_FAB2_LIB.BASEBOARD_FAB2(SCH_1):PAGE199
     2 AGND_HSC @BASEBOARD_FAB2_LIB.BASEBOARD_FAB2(SCH_1):AGND_HSC    I88 @BASEBOARD_FAB2_LIB.BASEBOARD_FAB2(SCH_1):PAGE199

R1D12 RES_0402-10.0K,1%,1/16W,CHIP,GA
     1 A_HSC_LOW @BASEBOARD_FAB2_LIB.BASEBOARD_FAB2(SCH_1):A_HSC_LOW   I174 @BASEBOARD_FAB2_LIB.BASEBOARD_FAB2(SCH_1):PAGE200
     2 AGND_HSC @BASEBOARD_FAB2_LIB.BASEBOARD_FAB2(SCH_1):AGND_HSC   I174 @BASEBOARD_FAB2_LIB.BASEBOARD_FAB2(SCH_1):PAGE200

R1D13 RES_0402-90.9K,1%,1/16W,CHIP,GA
     1 A_HSC_ISET_S @BASEBOARD_FAB2_LIB.BASEBOARD_FAB2(SCH_1):A_HSC_ISET_S    I84 @BASEBOARD_FAB2_LIB.BASEBOARD_FAB2(SCH_1):PAGE199
     2 A_HSC_ISET @BASEBOARD_FAB2_LIB.BASEBOARD_FAB2(SCH_1):A_HSC_ISET    I84 @BASEBOARD_FAB2_LIB.BASEBOARD_FAB2(SCH_1):PAGE199

R1D14 RES_0402-105.0K,1%,1/16W,CHIP,A
     1 A_HSC_CSOUT @BASEBOARD_FAB2_LIB.BASEBOARD_FAB2(SCH_1):A_HSC_CSOUT   I246 @BASEBOARD_FAB2_LIB.BASEBOARD_FAB2(SCH_1):PAGE200
     2 A_HSC_LOW @BASEBOARD_FAB2_LIB.BASEBOARD_FAB2(SCH_1):A_HSC_LOW   I246 @BASEBOARD_FAB2_LIB.BASEBOARD_FAB2(SCH_1):PAGE200

R1D15 RES_0402-100.0K,1%,1/16W,CHIP,A
     1 P12V_PSU @BASEBOARD_FAB2_LIB.BASEBOARD_FAB2(SCH_1):P12V_PSU    I92 @BASEBOARD_FAB2_LIB.BASEBOARD_FAB2(SCH_1):PAGE199
     2 A_HSC_OCP_SEL @BASEBOARD_FAB2_LIB.BASEBOARD_FAB2(SCH_1):A_HSC_OCP_SEL    I92 @BASEBOARD_FAB2_LIB.BASEBOARD_FAB2(SCH_1):PAGE199

R1D16 RES_0402-69.8K,1%,1/16W,CHIP,GA
     1 A_HSC_ISET @BASEBOARD_FAB2_LIB.BASEBOARD_FAB2(SCH_1):A_HSC_ISET    I85 @BASEBOARD_FAB2_LIB.BASEBOARD_FAB2(SCH_1):PAGE199
     2 A_HSC_ISET_S2 @BASEBOARD_FAB2_LIB.BASEBOARD_FAB2(SCH_1):A_HSC_ISET_S2    I85 @BASEBOARD_FAB2_LIB.BASEBOARD_FAB2(SCH_1):PAGE199

R1D18 RES_0402-100.0K,1%,1/16W,CHIP,A
     1 A_HSC_HIGH_EN @BASEBOARD_FAB2_LIB.BASEBOARD_FAB2(SCH_1):A_HSC_HIGH_EN    I87 @BASEBOARD_FAB2_LIB.BASEBOARD_FAB2(SCH_1):PAGE199
     2 AGND_HSC @BASEBOARD_FAB2_LIB.BASEBOARD_FAB2(SCH_1):AGND_HSC    I87 @BASEBOARD_FAB2_LIB.BASEBOARD_FAB2(SCH_1):PAGE199

R1D19 RES_0402-10.0K,1%,1/16W,CHIP,GA
     1 A_HSC_HIGH @BASEBOARD_FAB2_LIB.BASEBOARD_FAB2(SCH_1):A_HSC_HIGH   I175 @BASEBOARD_FAB2_LIB.BASEBOARD_FAB2(SCH_1):PAGE200
     2 AGND_HSC @BASEBOARD_FAB2_LIB.BASEBOARD_FAB2(SCH_1):AGND_HSC   I175 @BASEBOARD_FAB2_LIB.BASEBOARD_FAB2(SCH_1):PAGE200

R1D20 RES_0402-200.0K,1%,1/16W,CHIP,A
     1 A_HSC_CSOUT @BASEBOARD_FAB2_LIB.BASEBOARD_FAB2(SCH_1):A_HSC_CSOUT   I253 @BASEBOARD_FAB2_LIB.BASEBOARD_FAB2(SCH_1):PAGE200
     2 A_HSC_HIGH @BASEBOARD_FAB2_LIB.BASEBOARD_FAB2(SCH_1):A_HSC_HIGH   I253 @BASEBOARD_FAB2_LIB.BASEBOARD_FAB2(SCH_1):PAGE200

R1D21 RES_0402-4.75K,1%,1/16W,CHIP,GA
     1 P3V3_STBY @BASEBOARD_FAB2_LIB.BASEBOARD_FAB2(SCH_1):P3V3_STBY   I204 @BASEBOARD_FAB2_LIB.BASEBOARD_FAB2(SCH_1):PAGE200
     2 FM_OC_DETECT_EN @BASEBOARD_FAB2_LIB.BASEBOARD_FAB2(SCH_1):FM_OC_DETECT_EN   I204 @BASEBOARD_FAB2_LIB.BASEBOARD_FAB2(SCH_1):PAGE200

R1D22 RES_0402-10.0K,1%,1/16W,CHIP,GA
     1 P3V3_STBY @BASEBOARD_FAB2_LIB.BASEBOARD_FAB2(SCH_1):P3V3_STBY   I158 @BASEBOARD_FAB2_LIB.BASEBOARD_FAB2(SCH_1):PAGE200
     2 FM_OC_DETECT_N @BASEBOARD_FAB2_LIB.BASEBOARD_FAB2(SCH_1):FM_OC_DETECT_N   I158 @BASEBOARD_FAB2_LIB.BASEBOARD_FAB2(SCH_1):PAGE200

R1D23 RES_0402-10.0K,1%,1/16W,CHIP,GA
     1 P3V3_STBY @BASEBOARD_FAB2_LIB.BASEBOARD_FAB2(SCH_1):P3V3_STBY   I191 @BASEBOARD_FAB2_LIB.BASEBOARD_FAB2(SCH_1):PAGE200
     2 IRQ_OC_DETECT_N @BASEBOARD_FAB2_LIB.BASEBOARD_FAB2(SCH_1):IRQ_OC_DETECT_N   I191 @BASEBOARD_FAB2_LIB.BASEBOARD_FAB2(SCH_1):PAGE200

R1D24 RES_0402-0.0,5%,1/16W,CHIP,G21A
     1 SMB_BMC_PMBUS_STBY_LVC3_SCL @BASEBOARD_FAB2_LIB.BASEBOARD_FAB2(SCH_1):SMB_BMC_PMBUS_STBY_LVC3_SCL    I27 @BASEBOARD_FAB2_LIB.BASEBOARD_FAB2(SCH_1):PAGE199
     2 SMB_3V3SB_HSC_SCL_R @BASEBOARD_FAB2_LIB.BASEBOARD_FAB2(SCH_1):SMB_3V3SB_HSC_SCL_R    I27 @BASEBOARD_FAB2_LIB.BASEBOARD_FAB2(SCH_1):PAGE199

R1D25 RES_0402-0.0,5%,1/16W,CHIP,G21A
     1 SMB_BMC_PMBUS_STBY_LVC3_SDA @BASEBOARD_FAB2_LIB.BASEBOARD_FAB2(SCH_1):SMB_BMC_PMBUS_STBY_LVC3_SDA    I28 @BASEBOARD_FAB2_LIB.BASEBOARD_FAB2(SCH_1):PAGE199
     2 SMB_3V3SB_HSC_SDA_R @BASEBOARD_FAB2_LIB.BASEBOARD_FAB2(SCH_1):SMB_3V3SB_HSC_SDA_R    I28 @BASEBOARD_FAB2_LIB.BASEBOARD_FAB2(SCH_1):PAGE199

R1D26 RES_0402-33.2,1%,1/16W,CHIP,G2A
     1 IRQ_SML1_PMBUS_ALERT_R_N @BASEBOARD_FAB2_LIB.BASEBOARD_FAB2(SCH_1):IRQ_SML1_PMBUS_ALERT_R_N   I109 @BASEBOARD_FAB2_LIB.BASEBOARD_FAB2(SCH_1):PAGE199
     2 IRQ_SML1_PMBUS_ALERT_N @BASEBOARD_FAB2_LIB.BASEBOARD_FAB2(SCH_1):IRQ_SML1_PMBUS_ALERT_N   I109 @BASEBOARD_FAB2_LIB.BASEBOARD_FAB2(SCH_1):PAGE199

R1D27 RES_0402-4.75K,1%,1/16W,EMPTY,A
     1 A_HSC_VCAP @BASEBOARD_FAB2_LIB.BASEBOARD_FAB2(SCH_1):A_HSC_VCAP    I38 @BASEBOARD_FAB2_LIB.BASEBOARD_FAB2(SCH_1):PAGE199
     2 FM_P12V_HSC_ADR2 @BASEBOARD_FAB2_LIB.BASEBOARD_FAB2(SCH_1):FM_P12V_HSC_ADR2    I38 @BASEBOARD_FAB2_LIB.BASEBOARD_FAB2(SCH_1):PAGE199

R1D28 RES_0402-100.0,1%,1/16W,EMPTY,A
     1 PD_HSC_RETRY_N @BASEBOARD_FAB2_LIB.BASEBOARD_FAB2(SCH_1):PD_HSC_RETRY_N    I26 @BASEBOARD_FAB2_LIB.BASEBOARD_FAB2(SCH_1):PAGE199
     2 AGND_HSC @BASEBOARD_FAB2_LIB.BASEBOARD_FAB2(SCH_1):AGND_HSC    I26 @BASEBOARD_FAB2_LIB.BASEBOARD_FAB2(SCH_1):PAGE199

R1D29 RES_0402-4.75K,1%,1/16W,CHIP,GA
     1 A_HSC_VCAP @BASEBOARD_FAB2_LIB.BASEBOARD_FAB2(SCH_1):A_HSC_VCAP   I137 @BASEBOARD_FAB2_LIB.BASEBOARD_FAB2(SCH_1):PAGE199
     2 FM_P12V_HSC_ADR1 @BASEBOARD_FAB2_LIB.BASEBOARD_FAB2(SCH_1):FM_P12V_HSC_ADR1   I137 @BASEBOARD_FAB2_LIB.BASEBOARD_FAB2(SCH_1):PAGE199

R1D30 RES_0402-33.2,1%,1/16W,CHIP,G2A
     1 IRQ_HSC_FAULT_R_N @BASEBOARD_FAB2_LIB.BASEBOARD_FAB2(SCH_1):IRQ_HSC_FAULT_R_N   I110 @BASEBOARD_FAB2_LIB.BASEBOARD_FAB2(SCH_1):PAGE199
     2 IRQ_HSC_FAULT_N @BASEBOARD_FAB2_LIB.BASEBOARD_FAB2(SCH_1):IRQ_HSC_FAULT_N   I110 @BASEBOARD_FAB2_LIB.BASEBOARD_FAB2(SCH_1):PAGE199

R1D31 RES_0402-6.19K,1%,1/16W,CHIP,GA
     1 PWRGD_P12V_R @BASEBOARD_FAB2_LIB.BASEBOARD_FAB2(SCH_1):PWRGD_P12V_R    I43 @BASEBOARD_FAB2_LIB.BASEBOARD_FAB2(SCH_1):PAGE199
     2    GND @BASEBOARD_FAB2_LIB.BASEBOARD_FAB2(SCH_1):GND    I43 @BASEBOARD_FAB2_LIB.BASEBOARD_FAB2(SCH_1):PAGE199

R1D32 RES_0402-100.0K,1%,1/16W,CHIP,A
     1 A_HSC_VCAP @BASEBOARD_FAB2_LIB.BASEBOARD_FAB2(SCH_1):A_HSC_VCAP    I17 @BASEBOARD_FAB2_LIB.BASEBOARD_FAB2(SCH_1):PAGE199
     2 A_HSC_ISTART @BASEBOARD_FAB2_LIB.BASEBOARD_FAB2(SCH_1):A_HSC_ISTART    I17 @BASEBOARD_FAB2_LIB.BASEBOARD_FAB2(SCH_1):PAGE199

R1D33 RES_0402-33.2,1%,1/16W,CHIP,G2A
     1 PWRGD_P12V_R @BASEBOARD_FAB2_LIB.BASEBOARD_FAB2(SCH_1):PWRGD_P12V_R   I108 @BASEBOARD_FAB2_LIB.BASEBOARD_FAB2(SCH_1):PAGE199
     2 PWRGD_P12V_HSC @BASEBOARD_FAB2_LIB.BASEBOARD_FAB2(SCH_1):PWRGD_P12V_HSC   I108 @BASEBOARD_FAB2_LIB.BASEBOARD_FAB2(SCH_1):PAGE199

R1D34 RES_0402-16K,1.0%,1/16W,CHIP,GA
     1 A_HSC_ISTART @BASEBOARD_FAB2_LIB.BASEBOARD_FAB2(SCH_1):A_HSC_ISTART   I102 @BASEBOARD_FAB2_LIB.BASEBOARD_FAB2(SCH_1):PAGE199
     2 AGND_HSC @BASEBOARD_FAB2_LIB.BASEBOARD_FAB2(SCH_1):AGND_HSC   I102 @BASEBOARD_FAB2_LIB.BASEBOARD_FAB2(SCH_1):PAGE199

R1D35 RES_0402-4.75K,1%,1/16W,CHIP,GA
     1 P3V3_STBY @BASEBOARD_FAB2_LIB.BASEBOARD_FAB2(SCH_1):P3V3_STBY    I12 @BASEBOARD_FAB2_LIB.BASEBOARD_FAB2(SCH_1):PAGE126
     2 FM_OC_DETECT_EN_N @BASEBOARD_FAB2_LIB.BASEBOARD_FAB2(SCH_1):FM_OC_DETECT_EN_N    I12 @BASEBOARD_FAB2_LIB.BASEBOARD_FAB2(SCH_1):PAGE126

R1D36 RES_0402-1.00K,1%,1/16W,CHIP,GA
     1 P12V_STBY @BASEBOARD_FAB2_LIB.BASEBOARD_FAB2(SCH_1):P12V_STBY    I65 @BASEBOARD_FAB2_LIB.BASEBOARD_FAB2(SCH_1):PAGE199
     2 A_HSC_VOUT @BASEBOARD_FAB2_LIB.BASEBOARD_FAB2(SCH_1):A_HSC_VOUT    I65 @BASEBOARD_FAB2_LIB.BASEBOARD_FAB2(SCH_1):PAGE199

R1D37 RES_0402-100.0K,1%,1/16W,CHIP,A
     1 A_HSC_VCAP @BASEBOARD_FAB2_LIB.BASEBOARD_FAB2(SCH_1):A_HSC_VCAP    I15 @BASEBOARD_FAB2_LIB.BASEBOARD_FAB2(SCH_1):PAGE199
     2 A_HSC_ISET @BASEBOARD_FAB2_LIB.BASEBOARD_FAB2(SCH_1):A_HSC_ISET    I15 @BASEBOARD_FAB2_LIB.BASEBOARD_FAB2(SCH_1):PAGE199

R1D39 RES_0402-100.0K,1%,1/16W,CHIP,A
     1 A_HSC_VCAP @BASEBOARD_FAB2_LIB.BASEBOARD_FAB2(SCH_1):A_HSC_VCAP    I16 @BASEBOARD_FAB2_LIB.BASEBOARD_FAB2(SCH_1):PAGE199
     2 A_HSC_PSET @BASEBOARD_FAB2_LIB.BASEBOARD_FAB2(SCH_1):A_HSC_PSET    I16 @BASEBOARD_FAB2_LIB.BASEBOARD_FAB2(SCH_1):PAGE199

R1D40 RES_0402-40.2K,1%,1/16W,CHIP,GA
     1 A_HSC_PSET @BASEBOARD_FAB2_LIB.BASEBOARD_FAB2(SCH_1):A_HSC_PSET   I100 @BASEBOARD_FAB2_LIB.BASEBOARD_FAB2(SCH_1):PAGE199
     2 AGND_HSC @BASEBOARD_FAB2_LIB.BASEBOARD_FAB2(SCH_1):AGND_HSC   I100 @BASEBOARD_FAB2_LIB.BASEBOARD_FAB2(SCH_1):PAGE199

R1D41 RES_0805-0.0,5%,1/8W,CHIP,G221A
     1    GND @BASEBOARD_FAB2_LIB.BASEBOARD_FAB2(SCH_1):GND    I19 @BASEBOARD_FAB2_LIB.BASEBOARD_FAB2(SCH_1):PAGE199
     2 AGND_HSC @BASEBOARD_FAB2_LIB.BASEBOARD_FAB2(SCH_1):AGND_HSC    I19 @BASEBOARD_FAB2_LIB.BASEBOARD_FAB2(SCH_1):PAGE199

R1D42 RES_0402-11K,1%,1/16W,CHIP,G21A
     1 A_HSC_UV @BASEBOARD_FAB2_LIB.BASEBOARD_FAB2(SCH_1):A_HSC_UV    I13 @BASEBOARD_FAB2_LIB.BASEBOARD_FAB2(SCH_1):PAGE199
     2 AGND_HSC @BASEBOARD_FAB2_LIB.BASEBOARD_FAB2(SCH_1):AGND_HSC    I13 @BASEBOARD_FAB2_LIB.BASEBOARD_FAB2(SCH_1):PAGE199

R1D43 RES_0402-7.5K,1%,1/16W,CHIP,G2A
     1 A_HSC_OV @BASEBOARD_FAB2_LIB.BASEBOARD_FAB2(SCH_1):A_HSC_OV     I9 @BASEBOARD_FAB2_LIB.BASEBOARD_FAB2(SCH_1):PAGE199
     2 AGND_HSC @BASEBOARD_FAB2_LIB.BASEBOARD_FAB2(SCH_1):AGND_HSC     I9 @BASEBOARD_FAB2_LIB.BASEBOARD_FAB2(SCH_1):PAGE199

R1D44 RES_0402-0.0,5%,1/16W,CHIP,G21A
     1 A_HSC_MOP @BASEBOARD_FAB2_LIB.BASEBOARD_FAB2(SCH_1):A_HSC_MOP    I44 @BASEBOARD_FAB2_LIB.BASEBOARD_FAB2(SCH_1):PAGE200
     2 A_HSC_HSP @BASEBOARD_FAB2_LIB.BASEBOARD_FAB2(SCH_1):A_HSC_HSP    I44 @BASEBOARD_FAB2_LIB.BASEBOARD_FAB2(SCH_1):PAGE200

R1D45 RES_0402-0.0,5%,1/16W,CHIP,G21A
     1 A_HSC_MON @BASEBOARD_FAB2_LIB.BASEBOARD_FAB2(SCH_1):A_HSC_MON    I43 @BASEBOARD_FAB2_LIB.BASEBOARD_FAB2(SCH_1):PAGE200
     2 A_HSC_HSN @BASEBOARD_FAB2_LIB.BASEBOARD_FAB2(SCH_1):A_HSC_HSN    I43 @BASEBOARD_FAB2_LIB.BASEBOARD_FAB2(SCH_1):PAGE200

R1D46 RES_0402-10.0,1%,1/16W,CHIP,G2A
     1 P12V_HSC_SENP0 @BASEBOARD_FAB2_LIB.BASEBOARD_FAB2(SCH_1):P12V_HSC_SENP0    I48 @BASEBOARD_FAB2_LIB.BASEBOARD_FAB2(SCH_1):PAGE200
     2 A_HSC_HSP @BASEBOARD_FAB2_LIB.BASEBOARD_FAB2(SCH_1):A_HSC_HSP    I48 @BASEBOARD_FAB2_LIB.BASEBOARD_FAB2(SCH_1):PAGE200

R1D47 RES_0402-10.0,1%,1/16W,CHIP,G2A
     1 P12V_HSC_SENN0 @BASEBOARD_FAB2_LIB.BASEBOARD_FAB2(SCH_1):P12V_HSC_SENN0    I52 @BASEBOARD_FAB2_LIB.BASEBOARD_FAB2(SCH_1):PAGE200
     2 A_HSC_HSN @BASEBOARD_FAB2_LIB.BASEBOARD_FAB2(SCH_1):A_HSC_HSN    I52 @BASEBOARD_FAB2_LIB.BASEBOARD_FAB2(SCH_1):PAGE200

R1D48 RES_0402-10.0,1%,1/16W,CHIP,G2A
     1 A_HSC_GATE @BASEBOARD_FAB2_LIB.BASEBOARD_FAB2(SCH_1):A_HSC_GATE    I60 @BASEBOARD_FAB2_LIB.BASEBOARD_FAB2(SCH_1):PAGE200
     2 A_HSC_GATE3_R @BASEBOARD_FAB2_LIB.BASEBOARD_FAB2(SCH_1):A_HSC_GATE3_R    I60 @BASEBOARD_FAB2_LIB.BASEBOARD_FAB2(SCH_1):PAGE200

R1D49 RES_PWR_6PAD-0.001,1%,3W,CHIP,A
     1 P12V_PSU @BASEBOARD_FAB2_LIB.BASEBOARD_FAB2(SCH_1):P12V_PSU    I50 @BASEBOARD_FAB2_LIB.BASEBOARD_FAB2(SCH_1):PAGE200
     2 P12V_MB0_SW @BASEBOARD_FAB2_LIB.BASEBOARD_FAB2(SCH_1):P12V_MB0_SW    I50 @BASEBOARD_FAB2_LIB.BASEBOARD_FAB2(SCH_1):PAGE200
     3 P12V_HSC_SENP0 @BASEBOARD_FAB2_LIB.BASEBOARD_FAB2(SCH_1):P12V_HSC_SENP0    I50 @BASEBOARD_FAB2_LIB.BASEBOARD_FAB2(SCH_1):PAGE200
     4 P12V_HSC_SENN0 @BASEBOARD_FAB2_LIB.BASEBOARD_FAB2(SCH_1):P12V_HSC_SENN0    I50 @BASEBOARD_FAB2_LIB.BASEBOARD_FAB2(SCH_1):PAGE200
     5 P12V_PSU @BASEBOARD_FAB2_LIB.BASEBOARD_FAB2(SCH_1):P12V_PSU    I50 @BASEBOARD_FAB2_LIB.BASEBOARD_FAB2(SCH_1):PAGE200
     6 P12V_MB0_SW @BASEBOARD_FAB2_LIB.BASEBOARD_FAB2(SCH_1):P12V_MB0_SW    I50 @BASEBOARD_FAB2_LIB.BASEBOARD_FAB2(SCH_1):PAGE200

R1D51 RES_0402-10.0,1%,1/16W,CHIP,G2A
     1 A_HSC_C @BASEBOARD_FAB2_LIB.BASEBOARD_FAB2(SCH_1):A_HSC_C   I154 @BASEBOARD_FAB2_LIB.BASEBOARD_FAB2(SCH_1):PAGE200
     2 A_HSC_GATE @BASEBOARD_FAB2_LIB.BASEBOARD_FAB2(SCH_1):A_HSC_GATE   I154 @BASEBOARD_FAB2_LIB.BASEBOARD_FAB2(SCH_1):PAGE200

R1D52 RES_0402-68.1K,1%,1/16W,EMPTY,A
     1 VR_PVCCIN_CPU1_PH5_OCSET @BASEBOARD_FAB2_LIB.BASEBOARD_FAB2(SCH_1):VR_PVCCIN_CPU1_PH5_OCSET    I59 @BASEBOARD_FAB2_LIB.BASEBOARD_FAB2(SCH_1):PAGE209
     2    GND @BASEBOARD_FAB2_LIB.BASEBOARD_FAB2(SCH_1):GND    I59 @BASEBOARD_FAB2_LIB.BASEBOARD_FAB2(SCH_1):PAGE209

R1D53 RES_0402-2.26K,1.0%,1/16W,EMPTA
     1 P3V3_STBY @BASEBOARD_FAB2_LIB.BASEBOARD_FAB2(SCH_1):P3V3_STBY    I33 @BASEBOARD_FAB2_LIB.BASEBOARD_FAB2(SCH_1):PAGE206
     2 PU_VR_PVCCIN_CPU1_FLT1_SMBALT_N @BASEBOARD_FAB2_LIB.BASEBOARD_FAB2(SCH_1):PU_VR_PVCCIN_CPU1_FLT1_SMBALT_N_IMON    I33 @BASEBOARD_FAB2_LIB.BASEBOARD_FAB2(SCH_1):PAGE206

R1D54 RES_0402-68.1K,1%,1/16W,EMPTY,A
     1 VR_PVCCIN_CPU1_PH4_OCSET @BASEBOARD_FAB2_LIB.BASEBOARD_FAB2(SCH_1):VR_PVCCIN_CPU1_PH4_OCSET    I75 @BASEBOARD_FAB2_LIB.BASEBOARD_FAB2(SCH_1):PAGE208
     2    GND @BASEBOARD_FAB2_LIB.BASEBOARD_FAB2(SCH_1):GND    I75 @BASEBOARD_FAB2_LIB.BASEBOARD_FAB2(SCH_1):PAGE208

R1D55 RES_0402-68.1K,1%,1/16W,EMPTY,A
     1 VR_PVCCIN_CPU1_PH3_OCSET @BASEBOARD_FAB2_LIB.BASEBOARD_FAB2(SCH_1):VR_PVCCIN_CPU1_PH3_OCSET    I76 @BASEBOARD_FAB2_LIB.BASEBOARD_FAB2(SCH_1):PAGE208
     2    GND @BASEBOARD_FAB2_LIB.BASEBOARD_FAB2(SCH_1):GND    I76 @BASEBOARD_FAB2_LIB.BASEBOARD_FAB2(SCH_1):PAGE208

R1E1 RES_0402-10.0,1%,1/16W,CHIP,G2A
     1 A_HSC_GATE @BASEBOARD_FAB2_LIB.BASEBOARD_FAB2(SCH_1):A_HSC_GATE    I56 @BASEBOARD_FAB2_LIB.BASEBOARD_FAB2(SCH_1):PAGE200
     2 A_HSC_GATE1_R @BASEBOARD_FAB2_LIB.BASEBOARD_FAB2(SCH_1):A_HSC_GATE1_R    I56 @BASEBOARD_FAB2_LIB.BASEBOARD_FAB2(SCH_1):PAGE200

R1E3 RES_0603-100.0,1%,1/10W,CHIP,GA
     1 PVCCIN_CPU1 @BASEBOARD_FAB2_LIB.BASEBOARD_FAB2(SCH_1):PVCCIN_CPU1     I7 @BASEBOARD_FAB2_LIB.BASEBOARD_FAB2(SCH_1):PAGE208
     2    GND @BASEBOARD_FAB2_LIB.BASEBOARD_FAB2(SCH_1):GND     I7 @BASEBOARD_FAB2_LIB.BASEBOARD_FAB2(SCH_1):PAGE208

R1E4 RES_0402-100.0,1%,1/16W,CHIP,GA
     1 VSENSE_PVCCIN_CPU1_P @BASEBOARD_FAB2_LIB.BASEBOARD_FAB2(SCH_1):VSENSE_PVCCIN_CPU1_P    I15 @BASEBOARD_FAB2_LIB.BASEBOARD_FAB2(SCH_1):PAGE209
     2 PVCCIN_CPU1 @BASEBOARD_FAB2_LIB.BASEBOARD_FAB2(SCH_1):PVCCIN_CPU1    I15 @BASEBOARD_FAB2_LIB.BASEBOARD_FAB2(SCH_1):PAGE209

R1E5 RES_0402-1.00K,1%,1/16W,EMPTY,A
     1 VSENSE_PVCCIN_CPU1_P @BASEBOARD_FAB2_LIB.BASEBOARD_FAB2(SCH_1):VSENSE_PVCCIN_CPU1_P     I3 @BASEBOARD_FAB2_LIB.BASEBOARD_FAB2(SCH_1):PAGE209
     2 VSENSE_PVCCIN_CPU1_N @BASEBOARD_FAB2_LIB.BASEBOARD_FAB2(SCH_1):VSENSE_PVCCIN_CPU1_N     I3 @BASEBOARD_FAB2_LIB.BASEBOARD_FAB2(SCH_1):PAGE209

R1E6 RES_0402-0.0,5%,1/16W,CHIP,G21A
     1 VSENSE_PVCCIN_CPU1_P @BASEBOARD_FAB2_LIB.BASEBOARD_FAB2(SCH_1):VSENSE_PVCCIN_CPU1_P    I11 @BASEBOARD_FAB2_LIB.BASEBOARD_FAB2(SCH_1):PAGE209
     2 VSENSE_PVCCIN_CPU1_SKT_VSEN @BASEBOARD_FAB2_LIB.BASEBOARD_FAB2(SCH_1):VSENSE_PVCCIN_CPU1_SKT_VSEN    I11 @BASEBOARD_FAB2_LIB.BASEBOARD_FAB2(SCH_1):PAGE209

R1E7 RES_0402-0.0,5%,1/16W,CHIP,G21A
     1 VSENSE_PVCCIN_CPU1_N @BASEBOARD_FAB2_LIB.BASEBOARD_FAB2(SCH_1):VSENSE_PVCCIN_CPU1_N    I10 @BASEBOARD_FAB2_LIB.BASEBOARD_FAB2(SCH_1):PAGE209
     2 VSENSE_PVCCIN_CPU1_SKT_VRTN @BASEBOARD_FAB2_LIB.BASEBOARD_FAB2(SCH_1):VSENSE_PVCCIN_CPU1_SKT_VRTN    I10 @BASEBOARD_FAB2_LIB.BASEBOARD_FAB2(SCH_1):PAGE209

R1E8 RES_0402-100.0,1%,1/16W,CHIP,GA
     1 VSENSE_PVCCIN_CPU1_N @BASEBOARD_FAB2_LIB.BASEBOARD_FAB2(SCH_1):VSENSE_PVCCIN_CPU1_N     I9 @BASEBOARD_FAB2_LIB.BASEBOARD_FAB2(SCH_1):PAGE209
     2    GND @BASEBOARD_FAB2_LIB.BASEBOARD_FAB2(SCH_1):GND     I9 @BASEBOARD_FAB2_LIB.BASEBOARD_FAB2(SCH_1):PAGE209

R1E9 RES_0402-1.00K,1%,1/16W,CHIP,GA
     1 P3V3_STBY @BASEBOARD_FAB2_LIB.BASEBOARD_FAB2(SCH_1):P3V3_STBY    I34 @BASEBOARD_FAB2_LIB.BASEBOARD_FAB2(SCH_1):PAGE167
     2 PU_TMP421_2_A0 @BASEBOARD_FAB2_LIB.BASEBOARD_FAB2(SCH_1):PU_TMP421_2_A0    I34 @BASEBOARD_FAB2_LIB.BASEBOARD_FAB2(SCH_1):PAGE167

R1E10 RES_0402-1.00K,1%,1/16W,CHIP,GA
     1 P3V3_STBY @BASEBOARD_FAB2_LIB.BASEBOARD_FAB2(SCH_1):P3V3_STBY    I38 @BASEBOARD_FAB2_LIB.BASEBOARD_FAB2(SCH_1):PAGE167
     2 PD_TMP421_2_A1 @BASEBOARD_FAB2_LIB.BASEBOARD_FAB2(SCH_1):PD_TMP421_2_A1    I38 @BASEBOARD_FAB2_LIB.BASEBOARD_FAB2(SCH_1):PAGE167

R1E11 RES_0402-10.0K,1%,1/16W,EMPTY,A
     1 P3V3_STBY @BASEBOARD_FAB2_LIB.BASEBOARD_FAB2(SCH_1):P3V3_STBY   I120 @BASEBOARD_FAB2_LIB.BASEBOARD_FAB2(SCH_1):PAGE161
     2 FM_ENABLE_FAN_POWER @BASEBOARD_FAB2_LIB.BASEBOARD_FAB2(SCH_1):FM_ENABLE_FAN_POWER   I120 @BASEBOARD_FAB2_LIB.BASEBOARD_FAB2(SCH_1):PAGE161

R1E12 RES_0402-4.75K,1%,1/16W,CHIP,GA
     1 P5V_STBY @BASEBOARD_FAB2_LIB.BASEBOARD_FAB2(SCH_1):P5V_STBY    I51 @BASEBOARD_FAB2_LIB.BASEBOARD_FAB2(SCH_1):PAGE161
     2 FAN_PWM_OUT_SYS0_R @BASEBOARD_FAB2_LIB.BASEBOARD_FAB2(SCH_1):FAN_PWM_OUT_SYS0_R    I51 @BASEBOARD_FAB2_LIB.BASEBOARD_FAB2(SCH_1):PAGE161

R1E13 RES_0402-68.1K,1%,1/16W,EMPTY,A
     1 VR_PVCCIN_CPU1_PH2_OCSET @BASEBOARD_FAB2_LIB.BASEBOARD_FAB2(SCH_1):VR_PVCCIN_CPU1_PH2_OCSET    I67 @BASEBOARD_FAB2_LIB.BASEBOARD_FAB2(SCH_1):PAGE207
     2    GND @BASEBOARD_FAB2_LIB.BASEBOARD_FAB2(SCH_1):GND    I67 @BASEBOARD_FAB2_LIB.BASEBOARD_FAB2(SCH_1):PAGE207

R1E14 RES_0402-68.1K,1%,1/16W,EMPTY,A
     1 VR_PVCCIN_CPU1_PH1_OCSET @BASEBOARD_FAB2_LIB.BASEBOARD_FAB2(SCH_1):VR_PVCCIN_CPU1_PH1_OCSET    I68 @BASEBOARD_FAB2_LIB.BASEBOARD_FAB2(SCH_1):PAGE207
     2    GND @BASEBOARD_FAB2_LIB.BASEBOARD_FAB2(SCH_1):GND    I68 @BASEBOARD_FAB2_LIB.BASEBOARD_FAB2(SCH_1):PAGE207

R1F1 RES_0402-4.75K,1%,1/16W,CHIP,GA
     1 P3V3_STBY @BASEBOARD_FAB2_LIB.BASEBOARD_FAB2(SCH_1):P3V3_STBY    I45 @BASEBOARD_FAB2_LIB.BASEBOARD_FAB2(SCH_1):PAGE161
     2 FAN_TACH0 @BASEBOARD_FAB2_LIB.BASEBOARD_FAB2(SCH_1):FAN_TACH0    I45 @BASEBOARD_FAB2_LIB.BASEBOARD_FAB2(SCH_1):PAGE161

R1F2 RES_0402-100.0,1%,1/16W,CHIP,GA
     1 FAN_TACH0 @BASEBOARD_FAB2_LIB.BASEBOARD_FAB2(SCH_1):FAN_TACH0    I43 @BASEBOARD_FAB2_LIB.BASEBOARD_FAB2(SCH_1):PAGE161
     2 FAN_TACH0_CPU0_D2 @BASEBOARD_FAB2_LIB.BASEBOARD_FAB2(SCH_1):FAN_TACH0_CPU0_D2    I43 @BASEBOARD_FAB2_LIB.BASEBOARD_FAB2(SCH_1):PAGE161

R1F3 RES_1206-0.002,1%,1W,CHIP,G521A
     1 P12V_STBY @BASEBOARD_FAB2_LIB.BASEBOARD_FAB2(SCH_1):P12V_STBY    I50 @BASEBOARD_FAB2_LIB.BASEBOARD_FAB2(SCH_1):PAGE197
     2 P12V_NVDIMM_GHJ @BASEBOARD_FAB2_LIB.BASEBOARD_FAB2(SCH_1):P12V_NVDIMM_GHJ    I50 @BASEBOARD_FAB2_LIB.BASEBOARD_FAB2(SCH_1):PAGE197

R1F4 RES_0402-2,1.0%,1/16W,CHIP,G21A
     1 M_G_CPU_VREF @BASEBOARD_FAB2_LIB.BASEBOARD_FAB2(SCH_1):M_G_CPU_VREF     I7 @BASEBOARD_FAB2_LIB.BASEBOARD_FAB2(SCH_1):PAGE100
     2 M_G_VREF @BASEBOARD_FAB2_LIB.BASEBOARD_FAB2(SCH_1):M_G_VREF     I7 @BASEBOARD_FAB2_LIB.BASEBOARD_FAB2(SCH_1):PAGE100

R1F5 RES_0402-1.00K,1%,1/16W,CHIP,GA
     1 PVDDQ_GHJ @BASEBOARD_FAB2_LIB.BASEBOARD_FAB2(SCH_1):PVDDQ_GHJ     I6 @BASEBOARD_FAB2_LIB.BASEBOARD_FAB2(SCH_1):PAGE100
     2 M_G_VREF @BASEBOARD_FAB2_LIB.BASEBOARD_FAB2(SCH_1):M_G_VREF     I6 @BASEBOARD_FAB2_LIB.BASEBOARD_FAB2(SCH_1):PAGE100

R1F6 RES_0402-1.00K,1%,1/16W,CHIP,GA
     1 M_G_VREF @BASEBOARD_FAB2_LIB.BASEBOARD_FAB2(SCH_1):M_G_VREF     I2 @BASEBOARD_FAB2_LIB.BASEBOARD_FAB2(SCH_1):PAGE100
     2    GND @BASEBOARD_FAB2_LIB.BASEBOARD_FAB2(SCH_1):GND     I2 @BASEBOARD_FAB2_LIB.BASEBOARD_FAB2(SCH_1):PAGE100

R1F8 RES_0402-0.0,5%,1/16W,CHIP,G21A
     1 FAN_TACH0 @BASEBOARD_FAB2_LIB.BASEBOARD_FAB2(SCH_1):FAN_TACH0    I22 @BASEBOARD_FAB2_LIB.BASEBOARD_FAB2(SCH_1):PAGE181
     2 FAN_TACH0_R @BASEBOARD_FAB2_LIB.BASEBOARD_FAB2(SCH_1):FAN_TACH0_R    I22 @BASEBOARD_FAB2_LIB.BASEBOARD_FAB2(SCH_1):PAGE181

R1F9 RES_0402-0.0,5%,1/16W,EMPTY,G2A
     1 FM_BMC_READY_N @BASEBOARD_FAB2_LIB.BASEBOARD_FAB2(SCH_1):FM_BMC_READY_N     I7 @BASEBOARD_FAB2_LIB.BASEBOARD_FAB2(SCH_1):PAGE182
     2 FAN_PWM_OUT_SYS0_R1 @BASEBOARD_FAB2_LIB.BASEBOARD_FAB2(SCH_1):FAN_PWM_OUT_SYS0_R1     I7 @BASEBOARD_FAB2_LIB.BASEBOARD_FAB2(SCH_1):PAGE182

R1G1 RES_0402-2,1.0%,1/16W,CHIP,G21A
     1 M_H_CPU_VREF @BASEBOARD_FAB2_LIB.BASEBOARD_FAB2(SCH_1):M_H_CPU_VREF    I25 @BASEBOARD_FAB2_LIB.BASEBOARD_FAB2(SCH_1):PAGE100
     2 M_H_VREF @BASEBOARD_FAB2_LIB.BASEBOARD_FAB2(SCH_1):M_H_VREF    I25 @BASEBOARD_FAB2_LIB.BASEBOARD_FAB2(SCH_1):PAGE100

R1G2 RES_0402-1.00K,1%,1/16W,CHIP,GA
     1 PVDDQ_GHJ @BASEBOARD_FAB2_LIB.BASEBOARD_FAB2(SCH_1):PVDDQ_GHJ    I19 @BASEBOARD_FAB2_LIB.BASEBOARD_FAB2(SCH_1):PAGE100
     2 M_H_VREF @BASEBOARD_FAB2_LIB.BASEBOARD_FAB2(SCH_1):M_H_VREF    I19 @BASEBOARD_FAB2_LIB.BASEBOARD_FAB2(SCH_1):PAGE100

R1G3 RES_0402-1.00K,1%,1/16W,CHIP,GA
     1 M_H_VREF @BASEBOARD_FAB2_LIB.BASEBOARD_FAB2(SCH_1):M_H_VREF    I20 @BASEBOARD_FAB2_LIB.BASEBOARD_FAB2(SCH_1):PAGE100
     2    GND @BASEBOARD_FAB2_LIB.BASEBOARD_FAB2(SCH_1):GND    I20 @BASEBOARD_FAB2_LIB.BASEBOARD_FAB2(SCH_1):PAGE100

R1G5 RES_0402-10.0,1%,1/16W,CHIP,G2A
     1 VSENSE_PVDDQ_GHJ_P @BASEBOARD_FAB2_LIB.BASEBOARD_FAB2(SCH_1):VSENSE_PVDDQ_GHJ_P    I13 @BASEBOARD_FAB2_LIB.BASEBOARD_FAB2(SCH_1):PAGE223
     2 VR_PVDDQ_GHJ_AVSP @BASEBOARD_FAB2_LIB.BASEBOARD_FAB2(SCH_1):VR_PVDDQ_GHJ_AVSP    I13 @BASEBOARD_FAB2_LIB.BASEBOARD_FAB2(SCH_1):PAGE223

R1G6 RES_0402-2.26K,1.0%,1/16W,CHIPA
     1 P3V3_STBY @BASEBOARD_FAB2_LIB.BASEBOARD_FAB2(SCH_1):P3V3_STBY    I76 @BASEBOARD_FAB2_LIB.BASEBOARD_FAB2(SCH_1):PAGE223
     2 PWRGD_PVDDQ_GHJ @BASEBOARD_FAB2_LIB.BASEBOARD_FAB2(SCH_1):PWRGD_PVDDQ_GHJ    I76 @BASEBOARD_FAB2_LIB.BASEBOARD_FAB2(SCH_1):PAGE223

R1G7 RES_0402-150.0,1%,1/16W,CHIP,GA
     1 SVID_CLK1_CPU1_R @BASEBOARD_FAB2_LIB.BASEBOARD_FAB2(SCH_1):SVID_CLK1_CPU1_R    I18 @BASEBOARD_FAB2_LIB.BASEBOARD_FAB2(SCH_1):PAGE223
     2 SVID_CLK_PVDDQ_GHJ @BASEBOARD_FAB2_LIB.BASEBOARD_FAB2(SCH_1):SVID_CLK_PVDDQ_GHJ    I18 @BASEBOARD_FAB2_LIB.BASEBOARD_FAB2(SCH_1):PAGE223

R1G8 RES_0402-33.2,1%,1/16W,CHIP,G2A
     1 IRQ_PVDDQ_GHJ_VRHOT_LVT3_R_N @BASEBOARD_FAB2_LIB.BASEBOARD_FAB2(SCH_1):IRQ_PVDDQ_GHJ_VRHOT_LVT3_R_N    I55 @BASEBOARD_FAB2_LIB.BASEBOARD_FAB2(SCH_1):PAGE223
     2 IRQ_PVDDQ_GHJ_VRHOT_LVT3_N @BASEBOARD_FAB2_LIB.BASEBOARD_FAB2(SCH_1):IRQ_PVDDQ_GHJ_VRHOT_LVT3_N    I55 @BASEBOARD_FAB2_LIB.BASEBOARD_FAB2(SCH_1):PAGE223

R1G9 RES_0402-0.0,5%,1/16W,CHIP,G21A
     1 SVID_ALERT_PVDDQ_GHJ @BASEBOARD_FAB2_LIB.BASEBOARD_FAB2(SCH_1):SVID_ALERT_PVDDQ_GHJ    I50 @BASEBOARD_FAB2_LIB.BASEBOARD_FAB2(SCH_1):PAGE223
     2 SVID_ALERT1_CPU1_R_N @BASEBOARD_FAB2_LIB.BASEBOARD_FAB2(SCH_1):SVID_ALERT1_CPU1_R_N    I50 @BASEBOARD_FAB2_LIB.BASEBOARD_FAB2(SCH_1):PAGE223

R1G10 RES_0402-0.0,5%,1/16W,CHIP,G21A
     1 SVID_VDIO_PVDDQ_GHJ @BASEBOARD_FAB2_LIB.BASEBOARD_FAB2(SCH_1):SVID_VDIO_PVDDQ_GHJ    I41 @BASEBOARD_FAB2_LIB.BASEBOARD_FAB2(SCH_1):PAGE223
     2 SVID_DIO1_CPU1_R @BASEBOARD_FAB2_LIB.BASEBOARD_FAB2(SCH_1):SVID_DIO1_CPU1_R    I41 @BASEBOARD_FAB2_LIB.BASEBOARD_FAB2(SCH_1):PAGE223

R1G11 RES_0402-1.00K,1%,1/16W,CHIP,GA
     1 P3V3_STBY @BASEBOARD_FAB2_LIB.BASEBOARD_FAB2(SCH_1):P3V3_STBY    I49 @BASEBOARD_FAB2_LIB.BASEBOARD_FAB2(SCH_1):PAGE223
     2 IRQ_PVDDQ_GHJ_VRHOT_LVT3_R_N @BASEBOARD_FAB2_LIB.BASEBOARD_FAB2(SCH_1):IRQ_PVDDQ_GHJ_VRHOT_LVT3_R_N    I49 @BASEBOARD_FAB2_LIB.BASEBOARD_FAB2(SCH_1):PAGE223

R1G12 RES_0402-22.1,1.0%,1/16W,CHIP,A
     1 PWRGD_PVDDQ_GHJ_R @BASEBOARD_FAB2_LIB.BASEBOARD_FAB2(SCH_1):PWRGD_PVDDQ_GHJ_R    I54 @BASEBOARD_FAB2_LIB.BASEBOARD_FAB2(SCH_1):PAGE223
     2 PWRGD_PVDDQ_GHJ @BASEBOARD_FAB2_LIB.BASEBOARD_FAB2(SCH_1):PWRGD_PVDDQ_GHJ    I54 @BASEBOARD_FAB2_LIB.BASEBOARD_FAB2(SCH_1):PAGE223

R1G14 RES_0402-2,1.0%,1/16W,CHIP,G21A
     1 M_J_CPU_VREF @BASEBOARD_FAB2_LIB.BASEBOARD_FAB2(SCH_1):M_J_CPU_VREF    I41 @BASEBOARD_FAB2_LIB.BASEBOARD_FAB2(SCH_1):PAGE100
     2 M_J_VREF @BASEBOARD_FAB2_LIB.BASEBOARD_FAB2(SCH_1):M_J_VREF    I41 @BASEBOARD_FAB2_LIB.BASEBOARD_FAB2(SCH_1):PAGE100

R1G15 RES_0402-1.00K,1%,1/16W,CHIP,GA
     1 PVDDQ_GHJ @BASEBOARD_FAB2_LIB.BASEBOARD_FAB2(SCH_1):PVDDQ_GHJ    I35 @BASEBOARD_FAB2_LIB.BASEBOARD_FAB2(SCH_1):PAGE100
     2 M_J_VREF @BASEBOARD_FAB2_LIB.BASEBOARD_FAB2(SCH_1):M_J_VREF    I35 @BASEBOARD_FAB2_LIB.BASEBOARD_FAB2(SCH_1):PAGE100

R1G16 RES_0402-1.00K,1%,1/16W,CHIP,GA
     1 P3V3_STBY @BASEBOARD_FAB2_LIB.BASEBOARD_FAB2(SCH_1):P3V3_STBY    I48 @BASEBOARD_FAB2_LIB.BASEBOARD_FAB2(SCH_1):PAGE223
     2 PWRGD_PVDDQ_GHJ_R @BASEBOARD_FAB2_LIB.BASEBOARD_FAB2(SCH_1):PWRGD_PVDDQ_GHJ_R    I48 @BASEBOARD_FAB2_LIB.BASEBOARD_FAB2(SCH_1):PAGE223

R1G17 RES_0402-1.00K,1%,1/16W,CHIP,GA
     1 M_J_VREF @BASEBOARD_FAB2_LIB.BASEBOARD_FAB2(SCH_1):M_J_VREF    I36 @BASEBOARD_FAB2_LIB.BASEBOARD_FAB2(SCH_1):PAGE100
     2    GND @BASEBOARD_FAB2_LIB.BASEBOARD_FAB2(SCH_1):GND    I36 @BASEBOARD_FAB2_LIB.BASEBOARD_FAB2(SCH_1):PAGE100

R1G20 RES_0603-120.0,1%,1/10W,CHIP,GA
     1 PVDDQ_GHJ @BASEBOARD_FAB2_LIB.BASEBOARD_FAB2(SCH_1):PVDDQ_GHJ    I58 @BASEBOARD_FAB2_LIB.BASEBOARD_FAB2(SCH_1):PAGE225
     2    GND @BASEBOARD_FAB2_LIB.BASEBOARD_FAB2(SCH_1):GND    I58 @BASEBOARD_FAB2_LIB.BASEBOARD_FAB2(SCH_1):PAGE225

R1G22 RES_0402-3.16K,1%,1/16W,CHIP,GA
     1 VR_PVDDQ_GHJ_XADDR2 @BASEBOARD_FAB2_LIB.BASEBOARD_FAB2(SCH_1):VR_PVDDQ_GHJ_XADDR2    I74 @BASEBOARD_FAB2_LIB.BASEBOARD_FAB2(SCH_1):PAGE223
     2    GND @BASEBOARD_FAB2_LIB.BASEBOARD_FAB2(SCH_1):GND    I74 @BASEBOARD_FAB2_LIB.BASEBOARD_FAB2(SCH_1):PAGE223

R1G23 RES_0402-5.36K,1.0%,1/16W,CHIPA
     1 VR_PVDDQ_GHJ_XADDR1 @BASEBOARD_FAB2_LIB.BASEBOARD_FAB2(SCH_1):VR_PVDDQ_GHJ_XADDR1    I73 @BASEBOARD_FAB2_LIB.BASEBOARD_FAB2(SCH_1):PAGE223
     2    GND @BASEBOARD_FAB2_LIB.BASEBOARD_FAB2(SCH_1):GND    I73 @BASEBOARD_FAB2_LIB.BASEBOARD_FAB2(SCH_1):PAGE223

R1G25 RES_0402-68.1K,1%,1/16W,EMPTY,A
     1 VR_PVDDQ_GHJ_PH2_OCSET @BASEBOARD_FAB2_LIB.BASEBOARD_FAB2(SCH_1):VR_PVDDQ_GHJ_PH2_OCSET   I114 @BASEBOARD_FAB2_LIB.BASEBOARD_FAB2(SCH_1):PAGE224
     2    GND @BASEBOARD_FAB2_LIB.BASEBOARD_FAB2(SCH_1):GND   I114 @BASEBOARD_FAB2_LIB.BASEBOARD_FAB2(SCH_1):PAGE224

R1G26 RES_0402-68.1K,1%,1/16W,EMPTY,A
     1 VR_PVDDQ_GHJ_PH1_OCSET @BASEBOARD_FAB2_LIB.BASEBOARD_FAB2(SCH_1):VR_PVDDQ_GHJ_PH1_OCSET   I112 @BASEBOARD_FAB2_LIB.BASEBOARD_FAB2(SCH_1):PAGE224
     2    GND @BASEBOARD_FAB2_LIB.BASEBOARD_FAB2(SCH_1):GND   I112 @BASEBOARD_FAB2_LIB.BASEBOARD_FAB2(SCH_1):PAGE224

R1L2 RES_0402-10.0,1%,1/16W,CHIP,G2A
     1 FM_CPLD_DBG_PWR_EN_N @BASEBOARD_FAB2_LIB.BASEBOARD_FAB2(SCH_1):FM_CPLD_DBG_PWR_EN_N   I186 @BASEBOARD_FAB2_LIB.BASEBOARD_FAB2(SCH_1):PAGE155
     2 FM_CPLD_DBG_PWR_EN_R_N @BASEBOARD_FAB2_LIB.BASEBOARD_FAB2(SCH_1):FM_CPLD_DBG_PWR_EN_R_N   I186 @BASEBOARD_FAB2_LIB.BASEBOARD_FAB2(SCH_1):PAGE155

R1L6 RES_0402-0.0,5%,1/16W,CHIP,G21A
     1 FM_UART_SWITCH_N @BASEBOARD_FAB2_LIB.BASEBOARD_FAB2(SCH_1):FM_UART_SWITCH_N     I6 @BASEBOARD_FAB2_LIB.BASEBOARD_FAB2(SCH_1):PAGE168
     2 FM_DB_UART_SEL0_N @BASEBOARD_FAB2_LIB.BASEBOARD_FAB2(SCH_1):FM_DB_UART_SEL0_N     I6 @BASEBOARD_FAB2_LIB.BASEBOARD_FAB2(SCH_1):PAGE168

R1L7 RES_0402-4.75K,1%,1/16W,CHIP,GA
     1 P3V3_STBY @BASEBOARD_FAB2_LIB.BASEBOARD_FAB2(SCH_1):P3V3_STBY   I382 @BASEBOARD_FAB2_LIB.BASEBOARD_FAB2(SCH_1):PAGE157
     2 FM_BMC_CPLD_MP_RST_N @BASEBOARD_FAB2_LIB.BASEBOARD_FAB2(SCH_1):FM_BMC_CPLD_MP_RST_N   I382 @BASEBOARD_FAB2_LIB.BASEBOARD_FAB2(SCH_1):PAGE157

R1L8 RES_0402-470.0,5%,1/16W,CHIP,GA
     1 P5V_STBY @BASEBOARD_FAB2_LIB.BASEBOARD_FAB2(SCH_1):P5V_STBY    I58 @BASEBOARD_FAB2_LIB.BASEBOARD_FAB2(SCH_1):PAGE175
     2 FP_ID_LED_XOR_R @BASEBOARD_FAB2_LIB.BASEBOARD_FAB2(SCH_1):FP_ID_LED_XOR_R    I58 @BASEBOARD_FAB2_LIB.BASEBOARD_FAB2(SCH_1):PAGE175

R1L9 RES_0402-100.0K,1%,1/16W,CHIP,A
     1 P12V_STBY @BASEBOARD_FAB2_LIB.BASEBOARD_FAB2(SCH_1):P12V_STBY   I130 @BASEBOARD_FAB2_LIB.BASEBOARD_FAB2(SCH_1):PAGE155
     2 FM_CPLD_DBG_PWR_EN @BASEBOARD_FAB2_LIB.BASEBOARD_FAB2(SCH_1):FM_CPLD_DBG_PWR_EN   I130 @BASEBOARD_FAB2_LIB.BASEBOARD_FAB2(SCH_1):PAGE155

R1L11 RES_0402-10.0,1%,1/16W,CHIP,G2A
     1 LED_POSTCODE_7 @BASEBOARD_FAB2_LIB.BASEBOARD_FAB2(SCH_1):LED_POSTCODE_7    I76 @BASEBOARD_FAB2_LIB.BASEBOARD_FAB2(SCH_1):PAGE155
     2 LED_POSTCODE_7_R @BASEBOARD_FAB2_LIB.BASEBOARD_FAB2(SCH_1):LED_POSTCODE_7_R    I76 @BASEBOARD_FAB2_LIB.BASEBOARD_FAB2(SCH_1):PAGE155

R1L12 RES_0402-0.0,5%,1/16W,CHIP,G21A
     1 PWRGD_P3V3 @BASEBOARD_FAB2_LIB.BASEBOARD_FAB2(SCH_1):PWRGD_P3V3    I63 @BASEBOARD_FAB2_LIB.BASEBOARD_FAB2(SCH_1):PAGE175
     2 PWRGD_P3V3_R @BASEBOARD_FAB2_LIB.BASEBOARD_FAB2(SCH_1):PWRGD_P3V3_R    I63 @BASEBOARD_FAB2_LIB.BASEBOARD_FAB2(SCH_1):PAGE175

R1L13 RES_0402-1.00K,1%,1/16W,CHIP,GA
     1 XDP_SYSPWROK @BASEBOARD_FAB2_LIB.BASEBOARD_FAB2(SCH_1):XDP_SYSPWROK     I6 @BASEBOARD_FAB2_LIB.BASEBOARD_FAB2(SCH_1):PAGE111
     2 P3V3_STBY @BASEBOARD_FAB2_LIB.BASEBOARD_FAB2(SCH_1):P3V3_STBY     I6 @BASEBOARD_FAB2_LIB.BASEBOARD_FAB2(SCH_1):PAGE111

R1L14 RES_0402-10.0,1%,1/16W,CHIP,G2A
     1 LED_POSTCODE_6 @BASEBOARD_FAB2_LIB.BASEBOARD_FAB2(SCH_1):LED_POSTCODE_6    I75 @BASEBOARD_FAB2_LIB.BASEBOARD_FAB2(SCH_1):PAGE155
     2 LED_POSTCODE_6_R @BASEBOARD_FAB2_LIB.BASEBOARD_FAB2(SCH_1):LED_POSTCODE_6_R    I75 @BASEBOARD_FAB2_LIB.BASEBOARD_FAB2(SCH_1):PAGE155

R1L15 RES_0402-150.0,1%,1/16W,CHIP,GA
     1 PVCCIO_CPU0 @BASEBOARD_FAB2_LIB.BASEBOARD_FAB2(SCH_1):PVCCIO_CPU0    I60 @BASEBOARD_FAB2_LIB.BASEBOARD_FAB2(SCH_1):PAGE112
     2 XDP_CPU_TMS @BASEBOARD_FAB2_LIB.BASEBOARD_FAB2(SCH_1):XDP_CPU_TMS    I60 @BASEBOARD_FAB2_LIB.BASEBOARD_FAB2(SCH_1):PAGE112

R1L16 RES_0402-49.9,1%,1/16W,CHIP,G2A
     1 PWRGD_P3V3_R1 @BASEBOARD_FAB2_LIB.BASEBOARD_FAB2(SCH_1):PWRGD_P3V3_R1    I68 @BASEBOARD_FAB2_LIB.BASEBOARD_FAB2(SCH_1):PAGE196
     2 PWRGD_P3V3 @BASEBOARD_FAB2_LIB.BASEBOARD_FAB2(SCH_1):PWRGD_P3V3    I68 @BASEBOARD_FAB2_LIB.BASEBOARD_FAB2(SCH_1):PAGE196

R1L17 RES_0402-150.0,1%,1/16W,CHIP,GA
     1 XDP_CPU_PWR_DEBUG_N @BASEBOARD_FAB2_LIB.BASEBOARD_FAB2(SCH_1):XDP_CPU_PWR_DEBUG_N    I56 @BASEBOARD_FAB2_LIB.BASEBOARD_FAB2(SCH_1):PAGE111
     2 PVCCIO_CPU0 @BASEBOARD_FAB2_LIB.BASEBOARD_FAB2(SCH_1):PVCCIO_CPU0    I56 @BASEBOARD_FAB2_LIB.BASEBOARD_FAB2(SCH_1):PAGE111

R1L18 RES_0402-10.0,1%,1/16W,CHIP,G2A
     1 LED_POSTCODE_5 @BASEBOARD_FAB2_LIB.BASEBOARD_FAB2(SCH_1):LED_POSTCODE_5    I74 @BASEBOARD_FAB2_LIB.BASEBOARD_FAB2(SCH_1):PAGE155
     2 LED_POSTCODE_5_R @BASEBOARD_FAB2_LIB.BASEBOARD_FAB2(SCH_1):LED_POSTCODE_5_R    I74 @BASEBOARD_FAB2_LIB.BASEBOARD_FAB2(SCH_1):PAGE155

R1L19 RES_0402-4.75K,1%,1/16W,CHIP,GA
     1 P3V3_STBY @BASEBOARD_FAB2_LIB.BASEBOARD_FAB2(SCH_1):P3V3_STBY    I99 @BASEBOARD_FAB2_LIB.BASEBOARD_FAB2(SCH_1):PAGE175
     2 FM_DEBUG_RST_BTN_N @BASEBOARD_FAB2_LIB.BASEBOARD_FAB2(SCH_1):FM_DEBUG_RST_BTN_N    I99 @BASEBOARD_FAB2_LIB.BASEBOARD_FAB2(SCH_1):PAGE175

R1L20 RES_0402-10.0,1%,1/16W,CHIP,G2A
     1 LED_POSTCODE_4 @BASEBOARD_FAB2_LIB.BASEBOARD_FAB2(SCH_1):LED_POSTCODE_4    I73 @BASEBOARD_FAB2_LIB.BASEBOARD_FAB2(SCH_1):PAGE155
     2 LED_POSTCODE_4_R @BASEBOARD_FAB2_LIB.BASEBOARD_FAB2(SCH_1):LED_POSTCODE_4_R    I73 @BASEBOARD_FAB2_LIB.BASEBOARD_FAB2(SCH_1):PAGE155

R1L21 RES_0402-64.9,1.0%,1/16W,CHIP,A
     1   P3V3 @BASEBOARD_FAB2_LIB.BASEBOARD_FAB2(SCH_1):P3V3    I43 @BASEBOARD_FAB2_LIB.BASEBOARD_FAB2(SCH_1):PAGE177
     2 FP_LED_HDD_ACTIVITY_AND_R_N @BASEBOARD_FAB2_LIB.BASEBOARD_FAB2(SCH_1):FP_LED_HDD_ACTIVITY_AND_R_N    I43 @BASEBOARD_FAB2_LIB.BASEBOARD_FAB2(SCH_1):PAGE177

R1L22 RES_0402-200.0,1%,1/16W,CHIP,GA
     1 FM_DEBUG_RST_BTN_N @BASEBOARD_FAB2_LIB.BASEBOARD_FAB2(SCH_1):FM_DEBUG_RST_BTN_N    I22 @BASEBOARD_FAB2_LIB.BASEBOARD_FAB2(SCH_1):PAGE175
     2 FP_RST_BTN_R_N @BASEBOARD_FAB2_LIB.BASEBOARD_FAB2(SCH_1):FP_RST_BTN_R_N    I22 @BASEBOARD_FAB2_LIB.BASEBOARD_FAB2(SCH_1):PAGE175

R1L23 RES_0402-1.00K,1%,1/16W,CHIP,GA
     1 XDP_PWRGD_RST_N @BASEBOARD_FAB2_LIB.BASEBOARD_FAB2(SCH_1):XDP_PWRGD_RST_N    I13 @BASEBOARD_FAB2_LIB.BASEBOARD_FAB2(SCH_1):PAGE111
     2 P3V3_STBY @BASEBOARD_FAB2_LIB.BASEBOARD_FAB2(SCH_1):P3V3_STBY    I13 @BASEBOARD_FAB2_LIB.BASEBOARD_FAB2(SCH_1):PAGE111

R1L24 RES_0402-10.0,1%,1/16W,CHIP,G2A
     1 LED_POSTCODE_3 @BASEBOARD_FAB2_LIB.BASEBOARD_FAB2(SCH_1):LED_POSTCODE_3    I68 @BASEBOARD_FAB2_LIB.BASEBOARD_FAB2(SCH_1):PAGE155
     2 LED_POSTCODE_3_R @BASEBOARD_FAB2_LIB.BASEBOARD_FAB2(SCH_1):LED_POSTCODE_3_R    I68 @BASEBOARD_FAB2_LIB.BASEBOARD_FAB2(SCH_1):PAGE155

R1L25 RES_0402-10.0,1%,1/16W,CHIP,G2A
     1 LED_POSTCODE_2 @BASEBOARD_FAB2_LIB.BASEBOARD_FAB2(SCH_1):LED_POSTCODE_2    I67 @BASEBOARD_FAB2_LIB.BASEBOARD_FAB2(SCH_1):PAGE155
     2 LED_POSTCODE_2_R @BASEBOARD_FAB2_LIB.BASEBOARD_FAB2(SCH_1):LED_POSTCODE_2_R    I67 @BASEBOARD_FAB2_LIB.BASEBOARD_FAB2(SCH_1):PAGE155

R1L26 RES_0402-33.2,1%,1/16W,CHIP,G2A
     1 FM_PWR_BTN_R_N @BASEBOARD_FAB2_LIB.BASEBOARD_FAB2(SCH_1):FM_PWR_BTN_R_N    I13 @BASEBOARD_FAB2_LIB.BASEBOARD_FAB2(SCH_1):PAGE175
     2 FM_PWR_BTN_N @BASEBOARD_FAB2_LIB.BASEBOARD_FAB2(SCH_1):FM_PWR_BTN_N    I13 @BASEBOARD_FAB2_LIB.BASEBOARD_FAB2(SCH_1):PAGE175

R1L27 RES_0402-4.75K,1%,1/16W,CHIP,GA
     1 P3V3_STBY @BASEBOARD_FAB2_LIB.BASEBOARD_FAB2(SCH_1):P3V3_STBY     I5 @BASEBOARD_FAB2_LIB.BASEBOARD_FAB2(SCH_1):PAGE175
     2 FP_PWR_BTN_R_N @BASEBOARD_FAB2_LIB.BASEBOARD_FAB2(SCH_1):FP_PWR_BTN_R_N     I5 @BASEBOARD_FAB2_LIB.BASEBOARD_FAB2(SCH_1):PAGE175

R1L28 RES_0402-4.75K,1%,1/16W,EMPTY,A
     1 P3V3_STBY @BASEBOARD_FAB2_LIB.BASEBOARD_FAB2(SCH_1):P3V3_STBY    I97 @BASEBOARD_FAB2_LIB.BASEBOARD_FAB2(SCH_1):PAGE111
     2 FM_DEBUG_RST_BTN_R1_N @BASEBOARD_FAB2_LIB.BASEBOARD_FAB2(SCH_1):FM_DEBUG_RST_BTN_R1_N    I97 @BASEBOARD_FAB2_LIB.BASEBOARD_FAB2(SCH_1):PAGE111

R1L29 RES_0402-33.2,1%,1/16W,CHIP,G2A
     1 FM_DEBUG_RST_BTN_R1_N @BASEBOARD_FAB2_LIB.BASEBOARD_FAB2(SCH_1):FM_DEBUG_RST_BTN_R1_N    I68 @BASEBOARD_FAB2_LIB.BASEBOARD_FAB2(SCH_1):PAGE111
     2 FM_DEBUG_RST_BTN_N @BASEBOARD_FAB2_LIB.BASEBOARD_FAB2(SCH_1):FM_DEBUG_RST_BTN_N    I68 @BASEBOARD_FAB2_LIB.BASEBOARD_FAB2(SCH_1):PAGE111

R1L30 RES_0402-10.0,1%,1/16W,CHIP,G2A
     1 LED_POSTCODE_1 @BASEBOARD_FAB2_LIB.BASEBOARD_FAB2(SCH_1):LED_POSTCODE_1    I66 @BASEBOARD_FAB2_LIB.BASEBOARD_FAB2(SCH_1):PAGE155
     2 LED_POSTCODE_1_R @BASEBOARD_FAB2_LIB.BASEBOARD_FAB2(SCH_1):LED_POSTCODE_1_R    I66 @BASEBOARD_FAB2_LIB.BASEBOARD_FAB2(SCH_1):PAGE155

R1L31 RES_0402-200.0,1%,1/16W,CHIP,GA
     1 FP_PWR_BTN_R_N @BASEBOARD_FAB2_LIB.BASEBOARD_FAB2(SCH_1):FP_PWR_BTN_R_N     I4 @BASEBOARD_FAB2_LIB.BASEBOARD_FAB2(SCH_1):PAGE175
     2 FP_PWR_BTN_R1_N @BASEBOARD_FAB2_LIB.BASEBOARD_FAB2(SCH_1):FP_PWR_BTN_R1_N     I4 @BASEBOARD_FAB2_LIB.BASEBOARD_FAB2(SCH_1):PAGE175

R1L32 RES_0402-10.0,1%,1/16W,CHIP,G2A
     1 LED_POSTCODE_0 @BASEBOARD_FAB2_LIB.BASEBOARD_FAB2(SCH_1):LED_POSTCODE_0    I65 @BASEBOARD_FAB2_LIB.BASEBOARD_FAB2(SCH_1):PAGE155
     2 LED_POSTCODE_0_R @BASEBOARD_FAB2_LIB.BASEBOARD_FAB2(SCH_1):LED_POSTCODE_0_R    I65 @BASEBOARD_FAB2_LIB.BASEBOARD_FAB2(SCH_1):PAGE155

R1L33 RES_0402-221,1.0%,1/16W,CHIP,GA
     1 FM_BEEP_LED_P @BASEBOARD_FAB2_LIB.BASEBOARD_FAB2(SCH_1):FM_BEEP_LED_P    I45 @BASEBOARD_FAB2_LIB.BASEBOARD_FAB2(SCH_1):PAGE175
     2 P3V3_STBY @BASEBOARD_FAB2_LIB.BASEBOARD_FAB2(SCH_1):P3V3_STBY    I45 @BASEBOARD_FAB2_LIB.BASEBOARD_FAB2(SCH_1):PAGE175

R1L36 RES_0402-1.00K,1%,1/16W,CHIP,GA
     1 P3V3_STBY @BASEBOARD_FAB2_LIB.BASEBOARD_FAB2(SCH_1):P3V3_STBY    I11 @BASEBOARD_FAB2_LIB.BASEBOARD_FAB2(SCH_1):PAGE168
     2 FM_DB_PRESENT @BASEBOARD_FAB2_LIB.BASEBOARD_FAB2(SCH_1):FM_DB_PRESENT    I11 @BASEBOARD_FAB2_LIB.BASEBOARD_FAB2(SCH_1):PAGE168

R1L37 RES_0402-301.0,1%,1/16W,CHIP,GA
     1 P5V_STBY @BASEBOARD_FAB2_LIB.BASEBOARD_FAB2(SCH_1):P5V_STBY    I33 @BASEBOARD_FAB2_LIB.BASEBOARD_FAB2(SCH_1):PAGE177
     2 LED_P5V_STBY @BASEBOARD_FAB2_LIB.BASEBOARD_FAB2(SCH_1):LED_P5V_STBY    I33 @BASEBOARD_FAB2_LIB.BASEBOARD_FAB2(SCH_1):PAGE177

R1L38 RES_0402-1.00K,1%,1/16W,CHIP,GA
     1 P3V3_STBY @BASEBOARD_FAB2_LIB.BASEBOARD_FAB2(SCH_1):P3V3_STBY    I22 @BASEBOARD_FAB2_LIB.BASEBOARD_FAB2(SCH_1):PAGE168
     2 FM_POST_CARD_PRES_BMC_N @BASEBOARD_FAB2_LIB.BASEBOARD_FAB2(SCH_1):FM_POST_CARD_PRES_BMC_N    I22 @BASEBOARD_FAB2_LIB.BASEBOARD_FAB2(SCH_1):PAGE168

R1L39 RES_0402-100.0,1%,1/16W,CHIP,GA
     1 P1V05_PCH_STBY @BASEBOARD_FAB2_LIB.BASEBOARD_FAB2(SCH_1):P1V05_PCH_STBY    I76 @BASEBOARD_FAB2_LIB.BASEBOARD_FAB2(SCH_1):PAGE112
     2 XDP_PRDY_N @BASEBOARD_FAB2_LIB.BASEBOARD_FAB2(SCH_1):XDP_PRDY_N    I76 @BASEBOARD_FAB2_LIB.BASEBOARD_FAB2(SCH_1):PAGE112

R1L41 RES_0402-100.0,1%,1/16W,CHIP,GA
     1 P1V05_PCH_STBY @BASEBOARD_FAB2_LIB.BASEBOARD_FAB2(SCH_1):P1V05_PCH_STBY    I77 @BASEBOARD_FAB2_LIB.BASEBOARD_FAB2(SCH_1):PAGE112
     2 XDP_PREQ_N @BASEBOARD_FAB2_LIB.BASEBOARD_FAB2(SCH_1):XDP_PREQ_N    I77 @BASEBOARD_FAB2_LIB.BASEBOARD_FAB2(SCH_1):PAGE112

R1L43 RES_0402-330,5%,1/16W,CHIP,G21A
     1 FM_UARTSW_LSB_R_N @BASEBOARD_FAB2_LIB.BASEBOARD_FAB2(SCH_1):FM_UARTSW_LSB_R_N   I131 @BASEBOARD_FAB2_LIB.BASEBOARD_FAB2(SCH_1):PAGE158
     2 P3V3_STBY @BASEBOARD_FAB2_LIB.BASEBOARD_FAB2(SCH_1):P3V3_STBY   I131 @BASEBOARD_FAB2_LIB.BASEBOARD_FAB2(SCH_1):PAGE158

R1L44 RES_0402-330,5%,1/16W,CHIP,G21A
     1 FM_UARTSW_MSB_R_N @BASEBOARD_FAB2_LIB.BASEBOARD_FAB2(SCH_1):FM_UARTSW_MSB_R_N   I136 @BASEBOARD_FAB2_LIB.BASEBOARD_FAB2(SCH_1):PAGE158
     2 P3V3_STBY @BASEBOARD_FAB2_LIB.BASEBOARD_FAB2(SCH_1):P3V3_STBY   I136 @BASEBOARD_FAB2_LIB.BASEBOARD_FAB2(SCH_1):PAGE158

R1M3 RES_0402-100.0,1%,1/16W,CHIP,GA
     1 PVCCIO_CPU0 @BASEBOARD_FAB2_LIB.BASEBOARD_FAB2(SCH_1):PVCCIO_CPU0    I51 @BASEBOARD_FAB2_LIB.BASEBOARD_FAB2(SCH_1):PAGE112
     2 XDP_CPU_PRDY_N @BASEBOARD_FAB2_LIB.BASEBOARD_FAB2(SCH_1):XDP_CPU_PRDY_N    I51 @BASEBOARD_FAB2_LIB.BASEBOARD_FAB2(SCH_1):PAGE112

R1M4 RES_0402-100.0,1%,1/16W,CHIP,GA
     1 PVCCIO_CPU0 @BASEBOARD_FAB2_LIB.BASEBOARD_FAB2(SCH_1):PVCCIO_CPU0    I54 @BASEBOARD_FAB2_LIB.BASEBOARD_FAB2(SCH_1):PAGE112
     2 XDP_CPU_PREQ_N @BASEBOARD_FAB2_LIB.BASEBOARD_FAB2(SCH_1):XDP_CPU_PREQ_N    I54 @BASEBOARD_FAB2_LIB.BASEBOARD_FAB2(SCH_1):PAGE112

R1M5 RES_0402-0.0,5%,1/16W,CHIP,G21A
     1 USB2_P01_DP @BASEBOARD_FAB2_LIB.BASEBOARD_FAB2(SCH_1):USB2_P01_DP    I16 @BASEBOARD_FAB2_LIB.BASEBOARD_FAB2(SCH_1):PAGE176
     2 USB2_P01_ESD_DP @BASEBOARD_FAB2_LIB.BASEBOARD_FAB2(SCH_1):USB2_P01_ESD_DP    I16 @BASEBOARD_FAB2_LIB.BASEBOARD_FAB2(SCH_1):PAGE176

R1M6 RES_0402-0.0,5%,1/16W,CHIP,G21A
     1 USB2_P01_DN @BASEBOARD_FAB2_LIB.BASEBOARD_FAB2(SCH_1):USB2_P01_DN    I31 @BASEBOARD_FAB2_LIB.BASEBOARD_FAB2(SCH_1):PAGE176
     2 USB2_P01_ESD_DN @BASEBOARD_FAB2_LIB.BASEBOARD_FAB2(SCH_1):USB2_P01_ESD_DN    I31 @BASEBOARD_FAB2_LIB.BASEBOARD_FAB2(SCH_1):PAGE176

R1M8 RES_0402-20.0,1%,1/16W,CHIP,G2A
     1 SMB_SENSOR_TMP421_1_SCL @BASEBOARD_FAB2_LIB.BASEBOARD_FAB2(SCH_1):SMB_SENSOR_TMP421_1_SCL    I74 @BASEBOARD_FAB2_LIB.BASEBOARD_FAB2(SCH_1):PAGE167
     2 SMB_SENSOR_STBY_LVC3_SCL @BASEBOARD_FAB2_LIB.BASEBOARD_FAB2(SCH_1):SMB_SENSOR_STBY_LVC3_SCL    I74 @BASEBOARD_FAB2_LIB.BASEBOARD_FAB2(SCH_1):PAGE167

R1M9 RES_0402-20.0,1%,1/16W,CHIP,G2A
     1 SMB_SENSOR_TMP421_1_SDA @BASEBOARD_FAB2_LIB.BASEBOARD_FAB2(SCH_1):SMB_SENSOR_TMP421_1_SDA     I8 @BASEBOARD_FAB2_LIB.BASEBOARD_FAB2(SCH_1):PAGE167
     2 SMB_SENSOR_STBY_LVC3_SDA @BASEBOARD_FAB2_LIB.BASEBOARD_FAB2(SCH_1):SMB_SENSOR_STBY_LVC3_SDA     I8 @BASEBOARD_FAB2_LIB.BASEBOARD_FAB2(SCH_1):PAGE167

R1M10 RES_0402-0.0,5%,1/16W,CHIP,G21A
     1 LED_PCH_SATA_HDD_N @BASEBOARD_FAB2_LIB.BASEBOARD_FAB2(SCH_1):LED_PCH_SATA_HDD_N     I6 @BASEBOARD_FAB2_LIB.BASEBOARD_FAB2(SCH_1):PAGE177
     2 LED_SATA_ACT_R_N @BASEBOARD_FAB2_LIB.BASEBOARD_FAB2(SCH_1):LED_SATA_ACT_R_N     I6 @BASEBOARD_FAB2_LIB.BASEBOARD_FAB2(SCH_1):PAGE177

R1M11 RES_0402-10.0K,1%,1/16W,CHIP,GA
     1   P3V3 @BASEBOARD_FAB2_LIB.BASEBOARD_FAB2(SCH_1):P3V3     I9 @BASEBOARD_FAB2_LIB.BASEBOARD_FAB2(SCH_1):PAGE177
     2 LED_SATA_ACT_R_N @BASEBOARD_FAB2_LIB.BASEBOARD_FAB2(SCH_1):LED_SATA_ACT_R_N     I9 @BASEBOARD_FAB2_LIB.BASEBOARD_FAB2(SCH_1):PAGE177

R1M12 RES_0402-10.0K,1%,1/16W,CHIP,GA
     1   P3V3 @BASEBOARD_FAB2_LIB.BASEBOARD_FAB2(SCH_1):P3V3     I8 @BASEBOARD_FAB2_LIB.BASEBOARD_FAB2(SCH_1):PAGE177
     2 LED_SAS_ACT_R_N @BASEBOARD_FAB2_LIB.BASEBOARD_FAB2(SCH_1):LED_SAS_ACT_R_N     I8 @BASEBOARD_FAB2_LIB.BASEBOARD_FAB2(SCH_1):PAGE177

R1M13 RES_0402-0.0,5%,1/16W,CHIP,G21A
     1 LED_PCH_SSATA_HDD_N @BASEBOARD_FAB2_LIB.BASEBOARD_FAB2(SCH_1):LED_PCH_SSATA_HDD_N     I3 @BASEBOARD_FAB2_LIB.BASEBOARD_FAB2(SCH_1):PAGE177
     2 LED_SAS_ACT_R_N @BASEBOARD_FAB2_LIB.BASEBOARD_FAB2(SCH_1):LED_SAS_ACT_R_N     I3 @BASEBOARD_FAB2_LIB.BASEBOARD_FAB2(SCH_1):PAGE177

R1M14 RES_0402-200.0,1%,1/16W,CHIP,GA
     1 RST_PCIE_CPU_DEV0_N @BASEBOARD_FAB2_LIB.BASEBOARD_FAB2(SCH_1):RST_PCIE_CPU_DEV0_N   I220 @BASEBOARD_FAB2_LIB.BASEBOARD_FAB2(SCH_1):PAGE186
     2 RST_PCIE_CPU_DEV0_R_N @BASEBOARD_FAB2_LIB.BASEBOARD_FAB2(SCH_1):RST_PCIE_CPU_DEV0_R_N   I220 @BASEBOARD_FAB2_LIB.BASEBOARD_FAB2(SCH_1):PAGE186

R1M15 RES_0402-0.0,5%,1/16W,CHIP,G21A
     1 RMII_BMC_OCP_CRSDV @BASEBOARD_FAB2_LIB.BASEBOARD_FAB2(SCH_1):RMII_BMC_OCP_CRSDV   I339 @BASEBOARD_FAB2_LIB.BASEBOARD_FAB2(SCH_1):PAGE186
     2 RMII_BMC_OCP_CRSDV_R @BASEBOARD_FAB2_LIB.BASEBOARD_FAB2(SCH_1):RMII_BMC_OCP_CRSDV_R   I339 @BASEBOARD_FAB2_LIB.BASEBOARD_FAB2(SCH_1):PAGE186

R1M16 RES_0402-0.0,5%,1/16W,CHIP,G21A
     1 RMII_BMC_OCP_RXD1 @BASEBOARD_FAB2_LIB.BASEBOARD_FAB2(SCH_1):RMII_BMC_OCP_RXD1   I337 @BASEBOARD_FAB2_LIB.BASEBOARD_FAB2(SCH_1):PAGE186
     2 RMII_BMC_OCP_RXD1_R @BASEBOARD_FAB2_LIB.BASEBOARD_FAB2(SCH_1):RMII_BMC_OCP_RXD1_R   I337 @BASEBOARD_FAB2_LIB.BASEBOARD_FAB2(SCH_1):PAGE186

R1M17 RES_0402-0.0,5%,1/16W,CHIP,G21A
     1 RMII_BMC_OCP_RXD0 @BASEBOARD_FAB2_LIB.BASEBOARD_FAB2(SCH_1):RMII_BMC_OCP_RXD0   I338 @BASEBOARD_FAB2_LIB.BASEBOARD_FAB2(SCH_1):PAGE186
     2 RMII_BMC_OCP_RXD0_R @BASEBOARD_FAB2_LIB.BASEBOARD_FAB2(SCH_1):RMII_BMC_OCP_RXD0_R   I338 @BASEBOARD_FAB2_LIB.BASEBOARD_FAB2(SCH_1):PAGE186

R1M18 RES_0402-0.0,5%,1/16W,CHIP,G21A
     1 RMII_BMC_OCP_RXER_R @BASEBOARD_FAB2_LIB.BASEBOARD_FAB2(SCH_1):RMII_BMC_OCP_RXER_R   I340 @BASEBOARD_FAB2_LIB.BASEBOARD_FAB2(SCH_1):PAGE186
     2 RMII_BMC_OCP_RXER @BASEBOARD_FAB2_LIB.BASEBOARD_FAB2(SCH_1):RMII_BMC_OCP_RXER   I340 @BASEBOARD_FAB2_LIB.BASEBOARD_FAB2(SCH_1):PAGE186

R1M19 RES_0402-1.00K,1%,1/16W,CHIP,GA
     1 P1V8_MCP_CPU0 @BASEBOARD_FAB2_LIB.BASEBOARD_FAB2(SCH_1):P1V8_MCP_CPU0   I202 @BASEBOARD_FAB2_LIB.BASEBOARD_FAB2(SCH_1):PAGE113
     2 JTAG_MCP_TMS @BASEBOARD_FAB2_LIB.BASEBOARD_FAB2(SCH_1):JTAG_MCP_TMS   I202 @BASEBOARD_FAB2_LIB.BASEBOARD_FAB2(SCH_1):PAGE113

R1M20 RES_0402-1.00K,1%,1/16W,CHIP,GA
     1 P1V8_MCP_CPU0 @BASEBOARD_FAB2_LIB.BASEBOARD_FAB2(SCH_1):P1V8_MCP_CPU0   I204 @BASEBOARD_FAB2_LIB.BASEBOARD_FAB2(SCH_1):PAGE113
     2 JTAG_MCP_MUX_TDI @BASEBOARD_FAB2_LIB.BASEBOARD_FAB2(SCH_1):JTAG_MCP_MUX_TDI   I204 @BASEBOARD_FAB2_LIB.BASEBOARD_FAB2(SCH_1):PAGE113

R1M21 RES_0402-1.00K,1%,1/16W,CHIP,GA
     1 P1V8_MCP_CPU0 @BASEBOARD_FAB2_LIB.BASEBOARD_FAB2(SCH_1):P1V8_MCP_CPU0   I205 @BASEBOARD_FAB2_LIB.BASEBOARD_FAB2(SCH_1):PAGE113
     2 JTAG_MCP_TRST_N @BASEBOARD_FAB2_LIB.BASEBOARD_FAB2(SCH_1):JTAG_MCP_TRST_N   I205 @BASEBOARD_FAB2_LIB.BASEBOARD_FAB2(SCH_1):PAGE113

R1M22 RES_0402-49.9,1%,1/16W,CHIP,G2A
     1 JTAG_MCP_TMS_R1 @BASEBOARD_FAB2_LIB.BASEBOARD_FAB2(SCH_1):JTAG_MCP_TMS_R1   I195 @BASEBOARD_FAB2_LIB.BASEBOARD_FAB2(SCH_1):PAGE113
     2 JTAG_MCP_TMS @BASEBOARD_FAB2_LIB.BASEBOARD_FAB2(SCH_1):JTAG_MCP_TMS   I195 @BASEBOARD_FAB2_LIB.BASEBOARD_FAB2(SCH_1):PAGE113

R1M23 RES_0402-1.00K,1%,1/16W,EMPTY,A
     1 JTAG_MCP_TRST_N @BASEBOARD_FAB2_LIB.BASEBOARD_FAB2(SCH_1):JTAG_MCP_TRST_N   I199 @BASEBOARD_FAB2_LIB.BASEBOARD_FAB2(SCH_1):PAGE113
     2    GND @BASEBOARD_FAB2_LIB.BASEBOARD_FAB2(SCH_1):GND   I199 @BASEBOARD_FAB2_LIB.BASEBOARD_FAB2(SCH_1):PAGE113

R1M24 RES_0402-10.0K,1%,1/16W,CHIP,GA
     1 P3V3_STBY @BASEBOARD_FAB2_LIB.BASEBOARD_FAB2(SCH_1):P3V3_STBY   I105 @BASEBOARD_FAB2_LIB.BASEBOARD_FAB2(SCH_1):PAGE176
     2 FM_OC0_USB_N @BASEBOARD_FAB2_LIB.BASEBOARD_FAB2(SCH_1):FM_OC0_USB_N   I105 @BASEBOARD_FAB2_LIB.BASEBOARD_FAB2(SCH_1):PAGE176

R1M25 RES_0402-10.0K,1%,1/16W,CHIP,GA
     1 FM_USB_P0_EN_R_N @BASEBOARD_FAB2_LIB.BASEBOARD_FAB2(SCH_1):FM_USB_P0_EN_R_N   I111 @BASEBOARD_FAB2_LIB.BASEBOARD_FAB2(SCH_1):PAGE176
     2    GND @BASEBOARD_FAB2_LIB.BASEBOARD_FAB2(SCH_1):GND   I111 @BASEBOARD_FAB2_LIB.BASEBOARD_FAB2(SCH_1):PAGE176

R1R1 RES_0402-0.0,5%,1/16W,CHIP,G21A
     1 RST_PLTRST_N @BASEBOARD_FAB2_LIB.BASEBOARD_FAB2(SCH_1):RST_PLTRST_N   I195 @BASEBOARD_FAB2_LIB.BASEBOARD_FAB2(SCH_1):PAGE139
     2 RST_PLTRST_SPRV_R_N @BASEBOARD_FAB2_LIB.BASEBOARD_FAB2(SCH_1):RST_PLTRST_SPRV_R_N   I195 @BASEBOARD_FAB2_LIB.BASEBOARD_FAB2(SCH_1):PAGE139

R1R3 RES_0402-3.32K,1%,1/16W,CHIP,GA
     1 P3V3_STBY @BASEBOARD_FAB2_LIB.BASEBOARD_FAB2(SCH_1):P3V3_STBY    I11 @BASEBOARD_FAB2_LIB.BASEBOARD_FAB2(SCH_1):PAGE140
     2 PU_NV_WP_N @BASEBOARD_FAB2_LIB.BASEBOARD_FAB2(SCH_1):PU_NV_WP_N    I11 @BASEBOARD_FAB2_LIB.BASEBOARD_FAB2(SCH_1):PAGE140

R1R5 RES_0402-4.75K,1%,1/16W,CHIP,GA
     1 P3V3_STBY @BASEBOARD_FAB2_LIB.BASEBOARD_FAB2(SCH_1):P3V3_STBY    I73 @BASEBOARD_FAB2_LIB.BASEBOARD_FAB2(SCH_1):PAGE170
     2 FM_FAST_PROCHOT_THROTTLE_DLY_BU @BASEBOARD_FAB2_LIB.BASEBOARD_FAB2(SCH_1):FM_FAST_PROCHOT_THROTTLE_DLY_BUF_N    I73 @BASEBOARD_FAB2_LIB.BASEBOARD_FAB2(SCH_1):PAGE170

R1R6 RES_0402-3.32K,1%,1/16W,EMPTY,A
     1 SPI_NIC_MOSI @BASEBOARD_FAB2_LIB.BASEBOARD_FAB2(SCH_1):SPI_NIC_MOSI    I14 @BASEBOARD_FAB2_LIB.BASEBOARD_FAB2(SCH_1):PAGE140
     2    GND @BASEBOARD_FAB2_LIB.BASEBOARD_FAB2(SCH_1):GND    I14 @BASEBOARD_FAB2_LIB.BASEBOARD_FAB2(SCH_1):PAGE140

R1R7 RES_0402-20.0K,1%,1/16W,CHIP,GA
     1 P3V3_STBY @BASEBOARD_FAB2_LIB.BASEBOARD_FAB2(SCH_1):P3V3_STBY    I12 @BASEBOARD_FAB2_LIB.BASEBOARD_FAB2(SCH_1):PAGE140
     2 SPI_NIC_MOSI @BASEBOARD_FAB2_LIB.BASEBOARD_FAB2(SCH_1):SPI_NIC_MOSI    I12 @BASEBOARD_FAB2_LIB.BASEBOARD_FAB2(SCH_1):PAGE140

R1R8 RES_0402-0.0,5%,1/16W,CHIP,G21A
     1 FM_THROTTLE_R1_N @BASEBOARD_FAB2_LIB.BASEBOARD_FAB2(SCH_1):FM_THROTTLE_R1_N    I51 @BASEBOARD_FAB2_LIB.BASEBOARD_FAB2(SCH_1):PAGE170
     2 FM_THROTTLE_N @BASEBOARD_FAB2_LIB.BASEBOARD_FAB2(SCH_1):FM_THROTTLE_N    I51 @BASEBOARD_FAB2_LIB.BASEBOARD_FAB2(SCH_1):PAGE170

R1R9 RES_0402-3.32K,1%,1/16W,CHIP,GA
     1 P3V3_STBY @BASEBOARD_FAB2_LIB.BASEBOARD_FAB2(SCH_1):P3V3_STBY    I10 @BASEBOARD_FAB2_LIB.BASEBOARD_FAB2(SCH_1):PAGE140
     2 PU_NV_HOLD_N @BASEBOARD_FAB2_LIB.BASEBOARD_FAB2(SCH_1):PU_NV_HOLD_N    I10 @BASEBOARD_FAB2_LIB.BASEBOARD_FAB2(SCH_1):PAGE140

R1R12 RES_0402-10.0K,1%,1/16W,CHIP,GA
     1 CLK_50M_CKMNG_SPRVLLE @BASEBOARD_FAB2_LIB.BASEBOARD_FAB2(SCH_1):CLK_50M_CKMNG_SPRVLLE   I213 @BASEBOARD_FAB2_LIB.BASEBOARD_FAB2(SCH_1):PAGE139
     2    GND @BASEBOARD_FAB2_LIB.BASEBOARD_FAB2(SCH_1):GND   I213 @BASEBOARD_FAB2_LIB.BASEBOARD_FAB2(SCH_1):PAGE139

R1R15 RES_0603-0,5.0%,1/10W,CHIP,G22A
     1 P0V9_LAN @BASEBOARD_FAB2_LIB.BASEBOARD_FAB2(SCH_1):P0V9_LAN   I237 @BASEBOARD_FAB2_LIB.BASEBOARD_FAB2(SCH_1):PAGE139
     2 P0V9_LAN_I210 @BASEBOARD_FAB2_LIB.BASEBOARD_FAB2(SCH_1):P0V9_LAN_I210   I237 @BASEBOARD_FAB2_LIB.BASEBOARD_FAB2(SCH_1):PAGE139

R1R16 RES_0402-2.21K,1%,1/16W,CHIP,GA
     1 P3V3_STBY @BASEBOARD_FAB2_LIB.BASEBOARD_FAB2(SCH_1):P3V3_STBY    I93 @BASEBOARD_FAB2_LIB.BASEBOARD_FAB2(SCH_1):PAGE188
     2 SMB_PCH_MEZZ_LOM2_SCL @BASEBOARD_FAB2_LIB.BASEBOARD_FAB2(SCH_1):SMB_PCH_MEZZ_LOM2_SCL    I93 @BASEBOARD_FAB2_LIB.BASEBOARD_FAB2(SCH_1):PAGE188

R1R17 RES_0402-2.21K,1%,1/16W,CHIP,GA
     1 P3V3_STBY @BASEBOARD_FAB2_LIB.BASEBOARD_FAB2(SCH_1):P3V3_STBY    I94 @BASEBOARD_FAB2_LIB.BASEBOARD_FAB2(SCH_1):PAGE188
     2 SMB_PCH_MEZZ_LOM2_SDA @BASEBOARD_FAB2_LIB.BASEBOARD_FAB2(SCH_1):SMB_PCH_MEZZ_LOM2_SDA    I94 @BASEBOARD_FAB2_LIB.BASEBOARD_FAB2(SCH_1):PAGE188

R1R18 RES_0402-2.21K,1%,1/16W,CHIP,GA
     1 P3V3_STBY @BASEBOARD_FAB2_LIB.BASEBOARD_FAB2(SCH_1):P3V3_STBY    I88 @BASEBOARD_FAB2_LIB.BASEBOARD_FAB2(SCH_1):PAGE188
     2 SMB_PCH_MEZZ_LOM0_SCL @BASEBOARD_FAB2_LIB.BASEBOARD_FAB2(SCH_1):SMB_PCH_MEZZ_LOM0_SCL    I88 @BASEBOARD_FAB2_LIB.BASEBOARD_FAB2(SCH_1):PAGE188

R1R19 RES_0402-2.21K,1%,1/16W,CHIP,GA
     1 P3V3_STBY @BASEBOARD_FAB2_LIB.BASEBOARD_FAB2(SCH_1):P3V3_STBY    I89 @BASEBOARD_FAB2_LIB.BASEBOARD_FAB2(SCH_1):PAGE188
     2 SMB_PCH_MEZZ_LOM0_SDA @BASEBOARD_FAB2_LIB.BASEBOARD_FAB2(SCH_1):SMB_PCH_MEZZ_LOM0_SDA    I89 @BASEBOARD_FAB2_LIB.BASEBOARD_FAB2(SCH_1):PAGE188

R1R20 RES_0402-2.21K,1%,1/16W,CHIP,GA
     1 P3V3_STBY @BASEBOARD_FAB2_LIB.BASEBOARD_FAB2(SCH_1):P3V3_STBY    I91 @BASEBOARD_FAB2_LIB.BASEBOARD_FAB2(SCH_1):PAGE188
     2 SMB_PCH_MEZZ_LOM1_SCL @BASEBOARD_FAB2_LIB.BASEBOARD_FAB2(SCH_1):SMB_PCH_MEZZ_LOM1_SCL    I91 @BASEBOARD_FAB2_LIB.BASEBOARD_FAB2(SCH_1):PAGE188

R1R21 RES_0402-2.21K,1%,1/16W,CHIP,GA
     1 P3V3_STBY @BASEBOARD_FAB2_LIB.BASEBOARD_FAB2(SCH_1):P3V3_STBY    I90 @BASEBOARD_FAB2_LIB.BASEBOARD_FAB2(SCH_1):PAGE188
     2 SMB_PCH_MEZZ_LOM1_SDA @BASEBOARD_FAB2_LIB.BASEBOARD_FAB2(SCH_1):SMB_PCH_MEZZ_LOM1_SDA    I90 @BASEBOARD_FAB2_LIB.BASEBOARD_FAB2(SCH_1):PAGE188

R1R22 RES_0402-2.21K,1%,1/16W,CHIP,GA
     1 P3V3_STBY @BASEBOARD_FAB2_LIB.BASEBOARD_FAB2(SCH_1):P3V3_STBY    I92 @BASEBOARD_FAB2_LIB.BASEBOARD_FAB2(SCH_1):PAGE188
     2 SMB_PCH_MEZZ_LOM3_SDA @BASEBOARD_FAB2_LIB.BASEBOARD_FAB2(SCH_1):SMB_PCH_MEZZ_LOM3_SDA    I92 @BASEBOARD_FAB2_LIB.BASEBOARD_FAB2(SCH_1):PAGE188

R1R23 RES_0402-2.21K,1%,1/16W,CHIP,GA
     1 P3V3_STBY @BASEBOARD_FAB2_LIB.BASEBOARD_FAB2(SCH_1):P3V3_STBY    I95 @BASEBOARD_FAB2_LIB.BASEBOARD_FAB2(SCH_1):PAGE188
     2 SMB_PCH_MEZZ_LOM3_SCL @BASEBOARD_FAB2_LIB.BASEBOARD_FAB2(SCH_1):SMB_PCH_MEZZ_LOM3_SCL    I95 @BASEBOARD_FAB2_LIB.BASEBOARD_FAB2(SCH_1):PAGE188

R1T1 RES_0402-10.0K,1%,1/16W,CHIP,GA
     1 RMII_BMC_PCH_SPRNGVLLE_CRSDV @BASEBOARD_FAB2_LIB.BASEBOARD_FAB2(SCH_1):RMII_BMC_PCH_SPRNGVLLE_CRSDV   I214 @BASEBOARD_FAB2_LIB.BASEBOARD_FAB2(SCH_1):PAGE139
     2    GND @BASEBOARD_FAB2_LIB.BASEBOARD_FAB2(SCH_1):GND   I214 @BASEBOARD_FAB2_LIB.BASEBOARD_FAB2(SCH_1):PAGE139

R1T2 RES_0402-665,1.0%,1/16W,CHIP,GA
     1 P3V3_STBY @BASEBOARD_FAB2_LIB.BASEBOARD_FAB2(SCH_1):P3V3_STBY    I49 @BASEBOARD_FAB2_LIB.BASEBOARD_FAB2(SCH_1):PAGE160
     2 SMB_SLOTX24_STBY_LVC3_SCL_R @BASEBOARD_FAB2_LIB.BASEBOARD_FAB2(SCH_1):SMB_SLOTX24_STBY_LVC3_SCL_R    I49 @BASEBOARD_FAB2_LIB.BASEBOARD_FAB2(SCH_1):PAGE160

R1T3 RES_0402-665,1.0%,1/16W,CHIP,GA
     1 P3V3_STBY @BASEBOARD_FAB2_LIB.BASEBOARD_FAB2(SCH_1):P3V3_STBY    I46 @BASEBOARD_FAB2_LIB.BASEBOARD_FAB2(SCH_1):PAGE160
     2 SMB_SLOTX24_STBY_LVC3_SDA_R @BASEBOARD_FAB2_LIB.BASEBOARD_FAB2(SCH_1):SMB_SLOTX24_STBY_LVC3_SDA_R    I46 @BASEBOARD_FAB2_LIB.BASEBOARD_FAB2(SCH_1):PAGE160

R1T4 RES_0402-2.7K,1%,1/16W,CHIP,G2A
     1 P3V3_STBY @BASEBOARD_FAB2_LIB.BASEBOARD_FAB2(SCH_1):P3V3_STBY   I100 @BASEBOARD_FAB2_LIB.BASEBOARD_FAB2(SCH_1):PAGE164
     2 FM_BOARD_REV_ID0 @BASEBOARD_FAB2_LIB.BASEBOARD_FAB2(SCH_1):FM_BOARD_REV_ID0   I100 @BASEBOARD_FAB2_LIB.BASEBOARD_FAB2(SCH_1):PAGE164

R1T5 RES_0402-2.7K,1%,1/16W,EMPTY,GA
     1 P3V3_STBY @BASEBOARD_FAB2_LIB.BASEBOARD_FAB2(SCH_1):P3V3_STBY    I11 @BASEBOARD_FAB2_LIB.BASEBOARD_FAB2(SCH_1):PAGE164
     2 FM_BOARD_REV_ID2 @BASEBOARD_FAB2_LIB.BASEBOARD_FAB2(SCH_1):FM_BOARD_REV_ID2    I11 @BASEBOARD_FAB2_LIB.BASEBOARD_FAB2(SCH_1):PAGE164

R1T6 RES_0402-2.7K,1%,1/16W,CHIP,G2A
     1 P3V3_STBY @BASEBOARD_FAB2_LIB.BASEBOARD_FAB2(SCH_1):P3V3_STBY    I51 @BASEBOARD_FAB2_LIB.BASEBOARD_FAB2(SCH_1):PAGE164
     2 FM_BOARD_REV_ID1 @BASEBOARD_FAB2_LIB.BASEBOARD_FAB2(SCH_1):FM_BOARD_REV_ID1    I51 @BASEBOARD_FAB2_LIB.BASEBOARD_FAB2(SCH_1):PAGE164

R1T7 RES_0402-20.0,1%,1/16W,CHIP,G2A
     1 SMB_SLOTX24_STBY_LVC3_SCL_R @BASEBOARD_FAB2_LIB.BASEBOARD_FAB2(SCH_1):SMB_SLOTX24_STBY_LVC3_SCL_R    I50 @BASEBOARD_FAB2_LIB.BASEBOARD_FAB2(SCH_1):PAGE160
     2 SMB_SLOTX24_BMC_STBY_LVC3_SCL @BASEBOARD_FAB2_LIB.BASEBOARD_FAB2(SCH_1):SMB_SLOTX24_BMC_STBY_LVC3_SCL    I50 @BASEBOARD_FAB2_LIB.BASEBOARD_FAB2(SCH_1):PAGE160

R1T8 RES_0402-20.0,1%,1/16W,CHIP,G2A
     1 SMB_SLOTX24_STBY_LVC3_SDA_R @BASEBOARD_FAB2_LIB.BASEBOARD_FAB2(SCH_1):SMB_SLOTX24_STBY_LVC3_SDA_R     I4 @BASEBOARD_FAB2_LIB.BASEBOARD_FAB2(SCH_1):PAGE160
     2 SMB_SLOTX24_BMC_STBY_LVC3_SDA @BASEBOARD_FAB2_LIB.BASEBOARD_FAB2(SCH_1):SMB_SLOTX24_BMC_STBY_LVC3_SDA     I4 @BASEBOARD_FAB2_LIB.BASEBOARD_FAB2(SCH_1):PAGE160

R1T9 RES_0402-22.1,1.0%,1/16W,CHIP,A
     1 PWRGD_P1V2_BMC_STBY_R @BASEBOARD_FAB2_LIB.BASEBOARD_FAB2(SCH_1):PWRGD_P1V2_BMC_STBY_R    I72 @BASEBOARD_FAB2_LIB.BASEBOARD_FAB2(SCH_1):PAGE239
     2 PWRGD_P1V2_BMC_STBY @BASEBOARD_FAB2_LIB.BASEBOARD_FAB2(SCH_1):PWRGD_P1V2_BMC_STBY    I72 @BASEBOARD_FAB2_LIB.BASEBOARD_FAB2(SCH_1):PAGE239

R1T10 RES_0402-1.00K,1%,1/16W,CHIP,GA
     1 FM_BOARD_REV_ID0 @BASEBOARD_FAB2_LIB.BASEBOARD_FAB2(SCH_1):FM_BOARD_REV_ID0   I101 @BASEBOARD_FAB2_LIB.BASEBOARD_FAB2(SCH_1):PAGE164
     2    GND @BASEBOARD_FAB2_LIB.BASEBOARD_FAB2(SCH_1):GND   I101 @BASEBOARD_FAB2_LIB.BASEBOARD_FAB2(SCH_1):PAGE164

R1T11 RES_0402-1.00K,1%,1/16W,CHIP,GA
     1 FM_BOARD_REV_ID2 @BASEBOARD_FAB2_LIB.BASEBOARD_FAB2(SCH_1):FM_BOARD_REV_ID2     I7 @BASEBOARD_FAB2_LIB.BASEBOARD_FAB2(SCH_1):PAGE164
     2    GND @BASEBOARD_FAB2_LIB.BASEBOARD_FAB2(SCH_1):GND     I7 @BASEBOARD_FAB2_LIB.BASEBOARD_FAB2(SCH_1):PAGE164

R1T12 RES_0402-1.00K,1%,1/16W,CHIP,GA
     1 FM_BOARD_REV_ID1 @BASEBOARD_FAB2_LIB.BASEBOARD_FAB2(SCH_1):FM_BOARD_REV_ID1    I53 @BASEBOARD_FAB2_LIB.BASEBOARD_FAB2(SCH_1):PAGE164
     2    GND @BASEBOARD_FAB2_LIB.BASEBOARD_FAB2(SCH_1):GND    I53 @BASEBOARD_FAB2_LIB.BASEBOARD_FAB2(SCH_1):PAGE164

R1T15 RES_0402-0.0,5%,1/16W,EMPTY,G2A
     1 FM_BMC_ONCTL_N @BASEBOARD_FAB2_LIB.BASEBOARD_FAB2(SCH_1):FM_BMC_ONCTL_N   I100 @BASEBOARD_FAB2_LIB.BASEBOARD_FAB2(SCH_1):PAGE145
     2 FM_BMC_ONCTL_R_N @BASEBOARD_FAB2_LIB.BASEBOARD_FAB2(SCH_1):FM_BMC_ONCTL_R_N   I100 @BASEBOARD_FAB2_LIB.BASEBOARD_FAB2(SCH_1):PAGE145

R1T23 RES_0402-0.0,5%,1/16W,EMPTY,G2A
     1 FM_BMC_ONCTL_R_N @BASEBOARD_FAB2_LIB.BASEBOARD_FAB2(SCH_1):FM_BMC_ONCTL_R_N   I101 @BASEBOARD_FAB2_LIB.BASEBOARD_FAB2(SCH_1):PAGE145
     2    GND @BASEBOARD_FAB2_LIB.BASEBOARD_FAB2(SCH_1):GND   I101 @BASEBOARD_FAB2_LIB.BASEBOARD_FAB2(SCH_1):PAGE145

R1T24 RES_0402-0.0,5%,1/16W,EMPTY,G2A
     1 PUMP_TACH0 @BASEBOARD_FAB2_LIB.BASEBOARD_FAB2(SCH_1):PUMP_TACH0   I129 @BASEBOARD_FAB2_LIB.BASEBOARD_FAB2(SCH_1):PAGE147
     2 FM_FLASH_DESC_OVERRIDE @BASEBOARD_FAB2_LIB.BASEBOARD_FAB2(SCH_1):FM_FLASH_DESC_OVERRIDE   I129 @BASEBOARD_FAB2_LIB.BASEBOARD_FAB2(SCH_1):PAGE147

R1T25 RES_0402-8.2K,1%,1/16W,CHIP,G2A
     1 A_USB2BVRES @BASEBOARD_FAB2_LIB.BASEBOARD_FAB2(SCH_1):A_USB2BVRES    I35 @BASEBOARD_FAB2_LIB.BASEBOARD_FAB2(SCH_1):PAGE146
     2    GND @BASEBOARD_FAB2_LIB.BASEBOARD_FAB2(SCH_1):GND    I35 @BASEBOARD_FAB2_LIB.BASEBOARD_FAB2(SCH_1):PAGE146

R1T26 RES_0402-8.2K,1%,1/16W,CHIP,G2A
     1 A_USB2AVRES @BASEBOARD_FAB2_LIB.BASEBOARD_FAB2(SCH_1):A_USB2AVRES    I37 @BASEBOARD_FAB2_LIB.BASEBOARD_FAB2(SCH_1):PAGE146
     2    GND @BASEBOARD_FAB2_LIB.BASEBOARD_FAB2(SCH_1):GND    I37 @BASEBOARD_FAB2_LIB.BASEBOARD_FAB2(SCH_1):PAGE146

R1T27 RES_0402-240,1.0%,1/16W,CHIP,GA
     1    GND @BASEBOARD_FAB2_LIB.BASEBOARD_FAB2(SCH_1):GND    I58 @BASEBOARD_FAB2_LIB.BASEBOARD_FAB2(SCH_1):PAGE143
     2 BMC_MIOZ @BASEBOARD_FAB2_LIB.BASEBOARD_FAB2(SCH_1):BMC_MIOZ    I58 @BASEBOARD_FAB2_LIB.BASEBOARD_FAB2(SCH_1):PAGE143

R1T28 RES_0402-49.9,1%,1/16W,CHIP,G2A
     1 BMC_M_CLK_DN @BASEBOARD_FAB2_LIB.BASEBOARD_FAB2(SCH_1):BMC_M_CLK_DN   I279 @BASEBOARD_FAB2_LIB.BASEBOARD_FAB2(SCH_1):PAGE151
     2 BMC_M_CLK @BASEBOARD_FAB2_LIB.BASEBOARD_FAB2(SCH_1):BMC_M_CLK   I279 @BASEBOARD_FAB2_LIB.BASEBOARD_FAB2(SCH_1):PAGE151

R1T29 RES_0402-1.00K,1%,1/16W,CHIP,GA
     1 BMC_M_VREFCA @BASEBOARD_FAB2_LIB.BASEBOARD_FAB2(SCH_1):BMC_M_VREFCA   I202 @BASEBOARD_FAB2_LIB.BASEBOARD_FAB2(SCH_1):PAGE151
     2    GND @BASEBOARD_FAB2_LIB.BASEBOARD_FAB2(SCH_1):GND   I202 @BASEBOARD_FAB2_LIB.BASEBOARD_FAB2(SCH_1):PAGE151

R1T30 RES_0402-1.00K,1%,1/16W,CHIP,GA
     1 P1V2_AUX_BMC @BASEBOARD_FAB2_LIB.BASEBOARD_FAB2(SCH_1):P1V2_AUX_BMC   I201 @BASEBOARD_FAB2_LIB.BASEBOARD_FAB2(SCH_1):PAGE151
     2 BMC_M_VREFCA @BASEBOARD_FAB2_LIB.BASEBOARD_FAB2(SCH_1):BMC_M_VREFCA   I201 @BASEBOARD_FAB2_LIB.BASEBOARD_FAB2(SCH_1):PAGE151

R1T32 RES_0603-0,5.0%,1/10W,CHIP,G22A
     1 P1V5_LAN @BASEBOARD_FAB2_LIB.BASEBOARD_FAB2(SCH_1):P1V5_LAN   I238 @BASEBOARD_FAB2_LIB.BASEBOARD_FAB2(SCH_1):PAGE139
     2 P1V5_LAN_I210 @BASEBOARD_FAB2_LIB.BASEBOARD_FAB2(SCH_1):P1V5_LAN_I210   I238 @BASEBOARD_FAB2_LIB.BASEBOARD_FAB2(SCH_1):PAGE139

R1T33 RES_0603-0,5.0%,1/10W,EMPTY,G2A
     1 P1V5_LAN @BASEBOARD_FAB2_LIB.BASEBOARD_FAB2(SCH_1):P1V5_LAN   I240 @BASEBOARD_FAB2_LIB.BASEBOARD_FAB2(SCH_1):PAGE139
     2 P3V3_STBY_P1V5_LAN_I210 @BASEBOARD_FAB2_LIB.BASEBOARD_FAB2(SCH_1):P3V3_STBY_P1V5_LAN_I210   I240 @BASEBOARD_FAB2_LIB.BASEBOARD_FAB2(SCH_1):PAGE139

R1T34 RES_0603-0,5.0%,1/10W,CHIP,G22A
     1 P3V3_STBY @BASEBOARD_FAB2_LIB.BASEBOARD_FAB2(SCH_1):P3V3_STBY   I239 @BASEBOARD_FAB2_LIB.BASEBOARD_FAB2(SCH_1):PAGE139
     2 P3V3_STBY_P1V5_LAN_I210 @BASEBOARD_FAB2_LIB.BASEBOARD_FAB2(SCH_1):P3V3_STBY_P1V5_LAN_I210   I239 @BASEBOARD_FAB2_LIB.BASEBOARD_FAB2(SCH_1):PAGE139

R1T35 RES_0402-0.0,5%,1/16W,EMPTY,G2A
     1 FM_CPU0_PROCHOT_LVT3_N @BASEBOARD_FAB2_LIB.BASEBOARD_FAB2(SCH_1):FM_CPU0_PROCHOT_LVT3_N   I135 @BASEBOARD_FAB2_LIB.BASEBOARD_FAB2(SCH_1):PAGE93
     2 FM_CPU0_PROCHOT_PCH_N @BASEBOARD_FAB2_LIB.BASEBOARD_FAB2(SCH_1):FM_CPU0_PROCHOT_PCH_N   I135 @BASEBOARD_FAB2_LIB.BASEBOARD_FAB2(SCH_1):PAGE93

R1T36 RES_0402-0.0,5%,1/16W,CHIP,G21A
     1 FM_CPU0_PROCHOT_LVT3_N @BASEBOARD_FAB2_LIB.BASEBOARD_FAB2(SCH_1):FM_CPU0_PROCHOT_LVT3_N   I122 @BASEBOARD_FAB2_LIB.BASEBOARD_FAB2(SCH_1):PAGE93
     2 FM_CPU0_PROCHOT_LVT3_BMC_N @BASEBOARD_FAB2_LIB.BASEBOARD_FAB2(SCH_1):FM_CPU0_PROCHOT_LVT3_BMC_N   I122 @BASEBOARD_FAB2_LIB.BASEBOARD_FAB2(SCH_1):PAGE93

R1T37 RES_0402-0.0,5%,1/16W,CHIP,G21A
     1 FM_CPU1_PROCHOT_LVT3_N @BASEBOARD_FAB2_LIB.BASEBOARD_FAB2(SCH_1):FM_CPU1_PROCHOT_LVT3_N   I123 @BASEBOARD_FAB2_LIB.BASEBOARD_FAB2(SCH_1):PAGE93
     2 FM_CPU1_PROCHOT_LVT3_BMC_N @BASEBOARD_FAB2_LIB.BASEBOARD_FAB2(SCH_1):FM_CPU1_PROCHOT_LVT3_BMC_N   I123 @BASEBOARD_FAB2_LIB.BASEBOARD_FAB2(SCH_1):PAGE93

R1T38 RES_0402-0.0,5%,1/16W,EMPTY,G2A
     1 FM_CPU1_PROCHOT_LVT3_N @BASEBOARD_FAB2_LIB.BASEBOARD_FAB2(SCH_1):FM_CPU1_PROCHOT_LVT3_N   I137 @BASEBOARD_FAB2_LIB.BASEBOARD_FAB2(SCH_1):PAGE93
     2 FM_CPU1_PROCHOT_PCH_N @BASEBOARD_FAB2_LIB.BASEBOARD_FAB2(SCH_1):FM_CPU1_PROCHOT_PCH_N   I137 @BASEBOARD_FAB2_LIB.BASEBOARD_FAB2(SCH_1):PAGE93

R1T40 RES_0402-49.9,1%,1/16W,CHIP,G2A
     1 BMC_M_CLK_DP @BASEBOARD_FAB2_LIB.BASEBOARD_FAB2(SCH_1):BMC_M_CLK_DP   I278 @BASEBOARD_FAB2_LIB.BASEBOARD_FAB2(SCH_1):PAGE151
     2 BMC_M_CLK @BASEBOARD_FAB2_LIB.BASEBOARD_FAB2(SCH_1):BMC_M_CLK   I278 @BASEBOARD_FAB2_LIB.BASEBOARD_FAB2(SCH_1):PAGE151

R1U1 RES_0402-100.0K,1%,1/16W,CHIP,A
     1 FAN_TACH3 @BASEBOARD_FAB2_LIB.BASEBOARD_FAB2(SCH_1):FAN_TACH3    I61 @BASEBOARD_FAB2_LIB.BASEBOARD_FAB2(SCH_1):PAGE147
     2    GND @BASEBOARD_FAB2_LIB.BASEBOARD_FAB2(SCH_1):GND    I61 @BASEBOARD_FAB2_LIB.BASEBOARD_FAB2(SCH_1):PAGE147

R1U2 RES_0402-100.0K,1%,1/16W,CHIP,A
     1 FAN_TACH2 @BASEBOARD_FAB2_LIB.BASEBOARD_FAB2(SCH_1):FAN_TACH2    I62 @BASEBOARD_FAB2_LIB.BASEBOARD_FAB2(SCH_1):PAGE147
     2    GND @BASEBOARD_FAB2_LIB.BASEBOARD_FAB2(SCH_1):GND    I62 @BASEBOARD_FAB2_LIB.BASEBOARD_FAB2(SCH_1):PAGE147

R1U4 RES_0402-100.0K,1%,1/16W,CHIP,A
     1 FAN_TACH1 @BASEBOARD_FAB2_LIB.BASEBOARD_FAB2(SCH_1):FAN_TACH1    I65 @BASEBOARD_FAB2_LIB.BASEBOARD_FAB2(SCH_1):PAGE147
     2    GND @BASEBOARD_FAB2_LIB.BASEBOARD_FAB2(SCH_1):GND    I65 @BASEBOARD_FAB2_LIB.BASEBOARD_FAB2(SCH_1):PAGE147

R1U5 RES_0402-100.0K,1%,1/16W,CHIP,A
     1 FAN_TACH0 @BASEBOARD_FAB2_LIB.BASEBOARD_FAB2(SCH_1):FAN_TACH0    I66 @BASEBOARD_FAB2_LIB.BASEBOARD_FAB2(SCH_1):PAGE147
     2    GND @BASEBOARD_FAB2_LIB.BASEBOARD_FAB2(SCH_1):GND    I66 @BASEBOARD_FAB2_LIB.BASEBOARD_FAB2(SCH_1):PAGE147

R1U6 RES_0402-10.0K,1%,1/16W,CHIP,GA
     1 FM_BIOS_SPI_BMC_CTRL @BASEBOARD_FAB2_LIB.BASEBOARD_FAB2(SCH_1):FM_BIOS_SPI_BMC_CTRL   I128 @BASEBOARD_FAB2_LIB.BASEBOARD_FAB2(SCH_1):PAGE154
     2    GND @BASEBOARD_FAB2_LIB.BASEBOARD_FAB2(SCH_1):GND   I128 @BASEBOARD_FAB2_LIB.BASEBOARD_FAB2(SCH_1):PAGE154

R1U7 RES_0402-10.0K,1%,1/16W,CHIP,GA
     1    GND @BASEBOARD_FAB2_LIB.BASEBOARD_FAB2(SCH_1):GND    I78 @BASEBOARD_FAB2_LIB.BASEBOARD_FAB2(SCH_1):PAGE146
     2 PD_SP_ENTEST @BASEBOARD_FAB2_LIB.BASEBOARD_FAB2(SCH_1):PD_SP_ENTEST    I78 @BASEBOARD_FAB2_LIB.BASEBOARD_FAB2(SCH_1):PAGE146

R1U8 RES_0402-0.0,5%,1/16W,CHIP,G21A
     1 SMB_VR_STBY_LVC3_SDA_R @BASEBOARD_FAB2_LIB.BASEBOARD_FAB2(SCH_1):SMB_VR_STBY_LVC3_SDA_R   I223 @BASEBOARD_FAB2_LIB.BASEBOARD_FAB2(SCH_1):PAGE159
     2 SMB_VR_STBY_LVC3_SDA @BASEBOARD_FAB2_LIB.BASEBOARD_FAB2(SCH_1):SMB_VR_STBY_LVC3_SDA   I223 @BASEBOARD_FAB2_LIB.BASEBOARD_FAB2(SCH_1):PAGE159

R1U9 RES_0402-20.0,1%,1/16W,CHIP,G2A
     1 SMB_SMLINK0_STBY_LVC3_SCL_R @BASEBOARD_FAB2_LIB.BASEBOARD_FAB2(SCH_1):SMB_SMLINK0_STBY_LVC3_SCL_R   I232 @BASEBOARD_FAB2_LIB.BASEBOARD_FAB2(SCH_1):PAGE159
     2 SMB_SMLINK0_STBY_LVC3_SCL @BASEBOARD_FAB2_LIB.BASEBOARD_FAB2(SCH_1):SMB_SMLINK0_STBY_LVC3_SCL   I232 @BASEBOARD_FAB2_LIB.BASEBOARD_FAB2(SCH_1):PAGE159

R1U10 RES_0402-20.0,1%,1/16W,CHIP,G2A
     1 SMB_SMLINK0_STBY_LVC3_SDA_R @BASEBOARD_FAB2_LIB.BASEBOARD_FAB2(SCH_1):SMB_SMLINK0_STBY_LVC3_SDA_R   I233 @BASEBOARD_FAB2_LIB.BASEBOARD_FAB2(SCH_1):PAGE159
     2 SMB_SMLINK0_STBY_LVC3_SDA @BASEBOARD_FAB2_LIB.BASEBOARD_FAB2(SCH_1):SMB_SMLINK0_STBY_LVC3_SDA   I233 @BASEBOARD_FAB2_LIB.BASEBOARD_FAB2(SCH_1):PAGE159

R1U11 RES_0402-0.0,5%,1/16W,CHIP,G21A
     1 SMB_VR_STBY_LVC3_SCL_R @BASEBOARD_FAB2_LIB.BASEBOARD_FAB2(SCH_1):SMB_VR_STBY_LVC3_SCL_R   I222 @BASEBOARD_FAB2_LIB.BASEBOARD_FAB2(SCH_1):PAGE159
     2 SMB_VR_STBY_LVC3_SCL @BASEBOARD_FAB2_LIB.BASEBOARD_FAB2(SCH_1):SMB_VR_STBY_LVC3_SCL   I222 @BASEBOARD_FAB2_LIB.BASEBOARD_FAB2(SCH_1):PAGE159

R1U12 RES_0402-51,5.0%,1/16W,CHIP,G2A
     1 SGPIO_BMC_LD_R_N @BASEBOARD_FAB2_LIB.BASEBOARD_FAB2(SCH_1):SGPIO_BMC_LD_R_N    I59 @BASEBOARD_FAB2_LIB.BASEBOARD_FAB2(SCH_1):PAGE144
     2 SGPIO_BMC_LD_N @BASEBOARD_FAB2_LIB.BASEBOARD_FAB2(SCH_1):SGPIO_BMC_LD_N    I59 @BASEBOARD_FAB2_LIB.BASEBOARD_FAB2(SCH_1):PAGE144

R1U13 RES_0402-51,5.0%,1/16W,CHIP,G2A
     1 SGPIO_BMC_DOUT_R @BASEBOARD_FAB2_LIB.BASEBOARD_FAB2(SCH_1):SGPIO_BMC_DOUT_R    I58 @BASEBOARD_FAB2_LIB.BASEBOARD_FAB2(SCH_1):PAGE144
     2 SGPIO_BMC_DOUT @BASEBOARD_FAB2_LIB.BASEBOARD_FAB2(SCH_1):SGPIO_BMC_DOUT    I58 @BASEBOARD_FAB2_LIB.BASEBOARD_FAB2(SCH_1):PAGE144

R1U14 RES_0402-51,5.0%,1/16W,CHIP,G2A
     1 SGPIO_BMC_CLK_R @BASEBOARD_FAB2_LIB.BASEBOARD_FAB2(SCH_1):SGPIO_BMC_CLK_R    I57 @BASEBOARD_FAB2_LIB.BASEBOARD_FAB2(SCH_1):PAGE144
     2 SGPIO_BMC_CLK @BASEBOARD_FAB2_LIB.BASEBOARD_FAB2(SCH_1):SGPIO_BMC_CLK    I57 @BASEBOARD_FAB2_LIB.BASEBOARD_FAB2(SCH_1):PAGE144

R1U15 RES_0402-1.00K,1%,1/16W,CHIP,GA
     1 FM_BOARD_SKU_ID3 @BASEBOARD_FAB2_LIB.BASEBOARD_FAB2(SCH_1):FM_BOARD_SKU_ID3    I48 @BASEBOARD_FAB2_LIB.BASEBOARD_FAB2(SCH_1):PAGE164
     2    GND @BASEBOARD_FAB2_LIB.BASEBOARD_FAB2(SCH_1):GND    I48 @BASEBOARD_FAB2_LIB.BASEBOARD_FAB2(SCH_1):PAGE164

R1U16 RES_0402-1.00K,1%,1/16W,CHIP,GA
     1 FM_BOARD_SKU_ID1 @BASEBOARD_FAB2_LIB.BASEBOARD_FAB2(SCH_1):FM_BOARD_SKU_ID1    I37 @BASEBOARD_FAB2_LIB.BASEBOARD_FAB2(SCH_1):PAGE164
     2    GND @BASEBOARD_FAB2_LIB.BASEBOARD_FAB2(SCH_1):GND    I37 @BASEBOARD_FAB2_LIB.BASEBOARD_FAB2(SCH_1):PAGE164

R1U17 RES_0402-1.00K,1%,1/16W,CHIP,GA
     1 FM_BOARD_SKU_ID2 @BASEBOARD_FAB2_LIB.BASEBOARD_FAB2(SCH_1):FM_BOARD_SKU_ID2    I21 @BASEBOARD_FAB2_LIB.BASEBOARD_FAB2(SCH_1):PAGE164
     2    GND @BASEBOARD_FAB2_LIB.BASEBOARD_FAB2(SCH_1):GND    I21 @BASEBOARD_FAB2_LIB.BASEBOARD_FAB2(SCH_1):PAGE164

R1U18 RES_0402-1.00K,1%,1/16W,CHIP,GA
     1 FM_BOARD_SKU_ID0 @BASEBOARD_FAB2_LIB.BASEBOARD_FAB2(SCH_1):FM_BOARD_SKU_ID0    I40 @BASEBOARD_FAB2_LIB.BASEBOARD_FAB2(SCH_1):PAGE164
     2    GND @BASEBOARD_FAB2_LIB.BASEBOARD_FAB2(SCH_1):GND    I40 @BASEBOARD_FAB2_LIB.BASEBOARD_FAB2(SCH_1):PAGE164

R1U19 RES_0402-20.0,1%,1/16W,CHIP,G2A
     1 SMB_SMLINK0_STBY_LVC3_SCL @BASEBOARD_FAB2_LIB.BASEBOARD_FAB2(SCH_1):SMB_SMLINK0_STBY_LVC3_SCL   I226 @BASEBOARD_FAB2_LIB.BASEBOARD_FAB2(SCH_1):PAGE159
     2 SMB_SPRINGVILLE_STBY_LVC3_SCL @BASEBOARD_FAB2_LIB.BASEBOARD_FAB2(SCH_1):SMB_SPRINGVILLE_STBY_LVC3_SCL   I226 @BASEBOARD_FAB2_LIB.BASEBOARD_FAB2(SCH_1):PAGE159

R1U20 RES_0402-20.0,1%,1/16W,CHIP,G2A
     1 SMB_SMLINK0_STBY_LVC3_SDA @BASEBOARD_FAB2_LIB.BASEBOARD_FAB2(SCH_1):SMB_SMLINK0_STBY_LVC3_SDA   I225 @BASEBOARD_FAB2_LIB.BASEBOARD_FAB2(SCH_1):PAGE159
     2 SMB_SPRINGVILLE_STBY_LVC3_SDA @BASEBOARD_FAB2_LIB.BASEBOARD_FAB2(SCH_1):SMB_SPRINGVILLE_STBY_LVC3_SDA   I225 @BASEBOARD_FAB2_LIB.BASEBOARD_FAB2(SCH_1):PAGE159

R1U21 RES_0402-2.7K,1%,1/16W,CHIP,G2A
     1 P3V3_STBY @BASEBOARD_FAB2_LIB.BASEBOARD_FAB2(SCH_1):P3V3_STBY    I41 @BASEBOARD_FAB2_LIB.BASEBOARD_FAB2(SCH_1):PAGE164
     2 FM_BOARD_SKU_ID3 @BASEBOARD_FAB2_LIB.BASEBOARD_FAB2(SCH_1):FM_BOARD_SKU_ID3    I41 @BASEBOARD_FAB2_LIB.BASEBOARD_FAB2(SCH_1):PAGE164

R1U22 RES_0402-2.7K,1%,1/16W,CHIP,G2A
     1 P3V3_STBY @BASEBOARD_FAB2_LIB.BASEBOARD_FAB2(SCH_1):P3V3_STBY    I43 @BASEBOARD_FAB2_LIB.BASEBOARD_FAB2(SCH_1):PAGE164
     2 FM_BOARD_SKU_ID1 @BASEBOARD_FAB2_LIB.BASEBOARD_FAB2(SCH_1):FM_BOARD_SKU_ID1    I43 @BASEBOARD_FAB2_LIB.BASEBOARD_FAB2(SCH_1):PAGE164

R1U23 RES_0402-2.7K,1%,1/16W,CHIP,G2A
     1 P3V3_STBY @BASEBOARD_FAB2_LIB.BASEBOARD_FAB2(SCH_1):P3V3_STBY    I34 @BASEBOARD_FAB2_LIB.BASEBOARD_FAB2(SCH_1):PAGE164
     2 FM_BOARD_SKU_ID0 @BASEBOARD_FAB2_LIB.BASEBOARD_FAB2(SCH_1):FM_BOARD_SKU_ID0    I34 @BASEBOARD_FAB2_LIB.BASEBOARD_FAB2(SCH_1):PAGE164

R1U24 RES_0402-2.7K,1%,1/16W,CHIP,G2A
     1 P3V3_STBY @BASEBOARD_FAB2_LIB.BASEBOARD_FAB2(SCH_1):P3V3_STBY    I47 @BASEBOARD_FAB2_LIB.BASEBOARD_FAB2(SCH_1):PAGE164
     2 FM_BOARD_SKU_ID2 @BASEBOARD_FAB2_LIB.BASEBOARD_FAB2(SCH_1):FM_BOARD_SKU_ID2    I47 @BASEBOARD_FAB2_LIB.BASEBOARD_FAB2(SCH_1):PAGE164

R1U26 RES_0402-5.11K,1%,1/16W,CHIP,GA
     1   P3V3 @BASEBOARD_FAB2_LIB.BASEBOARD_FAB2(SCH_1):P3V3   I148 @BASEBOARD_FAB2_LIB.BASEBOARD_FAB2(SCH_1):PAGE169
     2 A_P3V3_SCALED @BASEBOARD_FAB2_LIB.BASEBOARD_FAB2(SCH_1):A_P3V3_SCALED   I148 @BASEBOARD_FAB2_LIB.BASEBOARD_FAB2(SCH_1):PAGE169

R1U27 RES_0402-3.48K,1.0%,1/16W,CHIPA
     1 A_P3V3_SCALED @BASEBOARD_FAB2_LIB.BASEBOARD_FAB2(SCH_1):A_P3V3_SCALED   I173 @BASEBOARD_FAB2_LIB.BASEBOARD_FAB2(SCH_1):PAGE169
     2    GND @BASEBOARD_FAB2_LIB.BASEBOARD_FAB2(SCH_1):GND   I173 @BASEBOARD_FAB2_LIB.BASEBOARD_FAB2(SCH_1):PAGE169

R1U28 1K82R2F-1-GP_SMD-RG-1K82R2F-1-A
     1 A_P5V_SCALED @BASEBOARD_FAB2_LIB.BASEBOARD_FAB2(SCH_1):A_P5V_SCALED   I169 @BASEBOARD_FAB2_LIB.BASEBOARD_FAB2(SCH_1):PAGE169
     2    GND @BASEBOARD_FAB2_LIB.BASEBOARD_FAB2(SCH_1):GND   I169 @BASEBOARD_FAB2_LIB.BASEBOARD_FAB2(SCH_1):PAGE169

R1U29 RES_0402-5.11K,1%,1/16W,CHIP,GA
     1    P5V @BASEBOARD_FAB2_LIB.BASEBOARD_FAB2(SCH_1):P5V   I141 @BASEBOARD_FAB2_LIB.BASEBOARD_FAB2(SCH_1):PAGE169
     2 A_P5V_SCALED @BASEBOARD_FAB2_LIB.BASEBOARD_FAB2(SCH_1):A_P5V_SCALED   I141 @BASEBOARD_FAB2_LIB.BASEBOARD_FAB2(SCH_1):PAGE169

R1U30 RES_0402-1.00K,1%,1/16W,CHIP,GA
     1 PD_DIR_2 @BASEBOARD_FAB2_LIB.BASEBOARD_FAB2(SCH_1):PD_DIR_2     I2 @BASEBOARD_FAB2_LIB.BASEBOARD_FAB2(SCH_1):PAGE152
     2    GND @BASEBOARD_FAB2_LIB.BASEBOARD_FAB2(SCH_1):GND     I2 @BASEBOARD_FAB2_LIB.BASEBOARD_FAB2(SCH_1):PAGE152

R1U32 RES_0402-5.11K,1%,1/16W,CHIP,GA
     1 P12V_STBY @BASEBOARD_FAB2_LIB.BASEBOARD_FAB2(SCH_1):P12V_STBY    I82 @BASEBOARD_FAB2_LIB.BASEBOARD_FAB2(SCH_1):PAGE169
     2 A_P12V_STBY_SCALED @BASEBOARD_FAB2_LIB.BASEBOARD_FAB2(SCH_1):A_P12V_STBY_SCALED    I82 @BASEBOARD_FAB2_LIB.BASEBOARD_FAB2(SCH_1):PAGE169

R1U33 649R2F-GP_RCL_GP-649R2F-GP,64.A
     1 A_P12V_STBY_SCALED @BASEBOARD_FAB2_LIB.BASEBOARD_FAB2(SCH_1):A_P12V_STBY_SCALED   I171 @BASEBOARD_FAB2_LIB.BASEBOARD_FAB2(SCH_1):PAGE169
     2    GND @BASEBOARD_FAB2_LIB.BASEBOARD_FAB2(SCH_1):GND   I171 @BASEBOARD_FAB2_LIB.BASEBOARD_FAB2(SCH_1):PAGE169

R1U34 RES_0402-33.2,1%,1/16W,CHIP,G2A
     1 H_CPU1_MEMKLM_MEMHOT_LVT3_K_N @BASEBOARD_FAB2_LIB.BASEBOARD_FAB2(SCH_1):H_CPU1_MEMKLM_MEMHOT_LVT3_K_N    I16 @BASEBOARD_FAB2_LIB.BASEBOARD_FAB2(SCH_1):PAGE152
     2 H_CPU1_MEMKLM_MEMHOT_LVT3_N @BASEBOARD_FAB2_LIB.BASEBOARD_FAB2(SCH_1):H_CPU1_MEMKLM_MEMHOT_LVT3_N    I16 @BASEBOARD_FAB2_LIB.BASEBOARD_FAB2(SCH_1):PAGE152

R1U35 RES_0402-150.0,1%,1/16W,CHIP,GA
     1 PVCCIO_CPU1 @BASEBOARD_FAB2_LIB.BASEBOARD_FAB2(SCH_1):PVCCIO_CPU1    I57 @BASEBOARD_FAB2_LIB.BASEBOARD_FAB2(SCH_1):PAGE152
     2 H_CPU1_MEMKLM_MEMHOT_G_N @BASEBOARD_FAB2_LIB.BASEBOARD_FAB2(SCH_1):H_CPU1_MEMKLM_MEMHOT_G_N    I57 @BASEBOARD_FAB2_LIB.BASEBOARD_FAB2(SCH_1):PAGE152

R1U36 RES_0402-33.2,1%,1/16W,CHIP,G2A
     1 H_CPU1_MEMGHJ_MEMHOT_LVT3_K_N @BASEBOARD_FAB2_LIB.BASEBOARD_FAB2(SCH_1):H_CPU1_MEMGHJ_MEMHOT_LVT3_K_N    I15 @BASEBOARD_FAB2_LIB.BASEBOARD_FAB2(SCH_1):PAGE152
     2 H_CPU1_MEMGHJ_MEMHOT_LVT3_N @BASEBOARD_FAB2_LIB.BASEBOARD_FAB2(SCH_1):H_CPU1_MEMGHJ_MEMHOT_LVT3_N    I15 @BASEBOARD_FAB2_LIB.BASEBOARD_FAB2(SCH_1):PAGE152

R1U37 RES_0402-100.0,1%,1/16W,CHIP,GA
     1 P0V7_GTL2014_2 @BASEBOARD_FAB2_LIB.BASEBOARD_FAB2(SCH_1):P0V7_GTL2014_2    I26 @BASEBOARD_FAB2_LIB.BASEBOARD_FAB2(SCH_1):PAGE152
     2    GND @BASEBOARD_FAB2_LIB.BASEBOARD_FAB2(SCH_1):GND    I26 @BASEBOARD_FAB2_LIB.BASEBOARD_FAB2(SCH_1):PAGE152

R1U38 RES_0402-3.48K,1.0%,1/16W,CHIPA
     1 A_P3V3_STBY_SCALED @BASEBOARD_FAB2_LIB.BASEBOARD_FAB2(SCH_1):A_P3V3_STBY_SCALED   I172 @BASEBOARD_FAB2_LIB.BASEBOARD_FAB2(SCH_1):PAGE169
     2    GND @BASEBOARD_FAB2_LIB.BASEBOARD_FAB2(SCH_1):GND   I172 @BASEBOARD_FAB2_LIB.BASEBOARD_FAB2(SCH_1):PAGE169

R1U39 RES_0402-5.11K,1%,1/16W,CHIP,GA
     1 P3V3_STBY @BASEBOARD_FAB2_LIB.BASEBOARD_FAB2(SCH_1):P3V3_STBY    I88 @BASEBOARD_FAB2_LIB.BASEBOARD_FAB2(SCH_1):PAGE169
     2 A_P3V3_STBY_SCALED @BASEBOARD_FAB2_LIB.BASEBOARD_FAB2(SCH_1):A_P3V3_STBY_SCALED    I88 @BASEBOARD_FAB2_LIB.BASEBOARD_FAB2(SCH_1):PAGE169

R1U41 RES_0402-150.0,1%,1/16W,CHIP,GA
     1 PVCCIO_CPU1 @BASEBOARD_FAB2_LIB.BASEBOARD_FAB2(SCH_1):PVCCIO_CPU1    I56 @BASEBOARD_FAB2_LIB.BASEBOARD_FAB2(SCH_1):PAGE152
     2 H_CPU1_MEMGHJ_MEMHOT_G_N @BASEBOARD_FAB2_LIB.BASEBOARD_FAB2(SCH_1):H_CPU1_MEMGHJ_MEMHOT_G_N    I56 @BASEBOARD_FAB2_LIB.BASEBOARD_FAB2(SCH_1):PAGE152

R1U43 374R2F-1-GP_SMD-RG-374R2F-1-GPA
     1   P3V3 @BASEBOARD_FAB2_LIB.BASEBOARD_FAB2(SCH_1):P3V3   I106 @BASEBOARD_FAB2_LIB.BASEBOARD_FAB2(SCH_1):PAGE152
     2 P0V7_GTL2014_2 @BASEBOARD_FAB2_LIB.BASEBOARD_FAB2(SCH_1):P0V7_GTL2014_2   I106 @BASEBOARD_FAB2_LIB.BASEBOARD_FAB2(SCH_1):PAGE152

R1U44 1K82R2F-1-GP_SMD-RG-1K82R2F-1-A
     1 A_P5V_STBY_SCALED @BASEBOARD_FAB2_LIB.BASEBOARD_FAB2(SCH_1):A_P5V_STBY_SCALED   I170 @BASEBOARD_FAB2_LIB.BASEBOARD_FAB2(SCH_1):PAGE169
     2    GND @BASEBOARD_FAB2_LIB.BASEBOARD_FAB2(SCH_1):GND   I170 @BASEBOARD_FAB2_LIB.BASEBOARD_FAB2(SCH_1):PAGE169

R1U46 RES_0402-33.2,1%,1/16W,CHIP,G2A
     1 H_CPU0_MEMABC_MEMHOT_LVT3_K_N @BASEBOARD_FAB2_LIB.BASEBOARD_FAB2(SCH_1):H_CPU0_MEMABC_MEMHOT_LVT3_K_N     I6 @BASEBOARD_FAB2_LIB.BASEBOARD_FAB2(SCH_1):PAGE152
     2 H_CPU0_MEMABC_MEMHOT_LVT3_N @BASEBOARD_FAB2_LIB.BASEBOARD_FAB2(SCH_1):H_CPU0_MEMABC_MEMHOT_LVT3_N     I6 @BASEBOARD_FAB2_LIB.BASEBOARD_FAB2(SCH_1):PAGE152

R1U47 RES_0402-5.11K,1%,1/16W,CHIP,GA
     1 P5V_STBY @BASEBOARD_FAB2_LIB.BASEBOARD_FAB2(SCH_1):P5V_STBY   I115 @BASEBOARD_FAB2_LIB.BASEBOARD_FAB2(SCH_1):PAGE169
     2 A_P5V_STBY_SCALED @BASEBOARD_FAB2_LIB.BASEBOARD_FAB2(SCH_1):A_P5V_STBY_SCALED   I115 @BASEBOARD_FAB2_LIB.BASEBOARD_FAB2(SCH_1):PAGE169

R1U49 RES_0402-2.7K,1%,1/16W,CHIP,G2A
     1 P3V3_STBY @BASEBOARD_FAB2_LIB.BASEBOARD_FAB2(SCH_1):P3V3_STBY   I163 @BASEBOARD_FAB2_LIB.BASEBOARD_FAB2(SCH_1):PAGE169
     2 FM_BATTERY_SENSE_EN @BASEBOARD_FAB2_LIB.BASEBOARD_FAB2(SCH_1):FM_BATTERY_SENSE_EN   I163 @BASEBOARD_FAB2_LIB.BASEBOARD_FAB2(SCH_1):PAGE169

R1U50 RES_0402-200.0K,1%,1/16W,CHIP,A
     1 A_P3V_BAT_R @BASEBOARD_FAB2_LIB.BASEBOARD_FAB2(SCH_1):A_P3V_BAT_R   I126 @BASEBOARD_FAB2_LIB.BASEBOARD_FAB2(SCH_1):PAGE169
     2 P3V_BAT_SOURCE_R @BASEBOARD_FAB2_LIB.BASEBOARD_FAB2(SCH_1):P3V_BAT_SOURCE_R   I126 @BASEBOARD_FAB2_LIB.BASEBOARD_FAB2(SCH_1):PAGE169

R1U53 RES_0402-0.0,5%,1/16W,CHIP,G21A
     1 H_CPU1_MEMGHJ_MEMHOT_G_N @BASEBOARD_FAB2_LIB.BASEBOARD_FAB2(SCH_1):H_CPU1_MEMGHJ_MEMHOT_G_N    I64 @BASEBOARD_FAB2_LIB.BASEBOARD_FAB2(SCH_1):PAGE152
     2 H_CPU1_MEMGHJ_MEMHOT_G_R_N @BASEBOARD_FAB2_LIB.BASEBOARD_FAB2(SCH_1):H_CPU1_MEMGHJ_MEMHOT_G_R_N    I64 @BASEBOARD_FAB2_LIB.BASEBOARD_FAB2(SCH_1):PAGE152

R1U54 RES_0402-0.0,5%,1/16W,CHIP,G21A
     1 H_CPU1_MEMGHJ_MEMHOT_LVT3_N @BASEBOARD_FAB2_LIB.BASEBOARD_FAB2(SCH_1):H_CPU1_MEMGHJ_MEMHOT_LVT3_N    I93 @BASEBOARD_FAB2_LIB.BASEBOARD_FAB2(SCH_1):PAGE152
     2 H_CPU1_MEMGHJ_MEMHOT_LVT3_BMC_N @BASEBOARD_FAB2_LIB.BASEBOARD_FAB2(SCH_1):H_CPU1_MEMGHJ_MEMHOT_LVT3_BMC_N    I93 @BASEBOARD_FAB2_LIB.BASEBOARD_FAB2(SCH_1):PAGE152

R1U55 RES_0402-0.0,5%,1/16W,EMPTY,G2A
     1 H_CPU1_MEMGHJ_MEMHOT_G_N @BASEBOARD_FAB2_LIB.BASEBOARD_FAB2(SCH_1):H_CPU1_MEMGHJ_MEMHOT_G_N    I67 @BASEBOARD_FAB2_LIB.BASEBOARD_FAB2(SCH_1):PAGE152
     2 H_CPU1_MEMGHJ_MEMHOT_G_PCH_N @BASEBOARD_FAB2_LIB.BASEBOARD_FAB2(SCH_1):H_CPU1_MEMGHJ_MEMHOT_G_PCH_N    I67 @BASEBOARD_FAB2_LIB.BASEBOARD_FAB2(SCH_1):PAGE152

R1U56 RES_0402-0.0,5%,1/16W,EMPTY,G2A
     1 H_CPU0_MEMDEF_MEMHOT_G_PCH_N @BASEBOARD_FAB2_LIB.BASEBOARD_FAB2(SCH_1):H_CPU0_MEMDEF_MEMHOT_G_PCH_N    I50 @BASEBOARD_FAB2_LIB.BASEBOARD_FAB2(SCH_1):PAGE152
     2 H_CPU0_MEMDEF_MEMHOT_G_N @BASEBOARD_FAB2_LIB.BASEBOARD_FAB2(SCH_1):H_CPU0_MEMDEF_MEMHOT_G_N    I50 @BASEBOARD_FAB2_LIB.BASEBOARD_FAB2(SCH_1):PAGE152

R1U57 RES_0402-0.0,5%,1/16W,EMPTY,G2A
     1 H_CPU1_MEMGHJ_MEMHOT_LVT3_K_N @BASEBOARD_FAB2_LIB.BASEBOARD_FAB2(SCH_1):H_CPU1_MEMGHJ_MEMHOT_LVT3_K_N    I69 @BASEBOARD_FAB2_LIB.BASEBOARD_FAB2(SCH_1):PAGE152
     2 H_CPU1_MEMGHJ_MEMHOT_G_PCH_N @BASEBOARD_FAB2_LIB.BASEBOARD_FAB2(SCH_1):H_CPU1_MEMGHJ_MEMHOT_G_PCH_N    I69 @BASEBOARD_FAB2_LIB.BASEBOARD_FAB2(SCH_1):PAGE152

R1U58 RES_0402-0.0,5%,1/16W,CHIP,G21A
     1 H_CPU0_MEMDEF_MEMHOT_G_N @BASEBOARD_FAB2_LIB.BASEBOARD_FAB2(SCH_1):H_CPU0_MEMDEF_MEMHOT_G_N    I49 @BASEBOARD_FAB2_LIB.BASEBOARD_FAB2(SCH_1):PAGE152
     2 H_CPU0_MEMDEF_MEMHOT_G_R_N @BASEBOARD_FAB2_LIB.BASEBOARD_FAB2(SCH_1):H_CPU0_MEMDEF_MEMHOT_G_R_N    I49 @BASEBOARD_FAB2_LIB.BASEBOARD_FAB2(SCH_1):PAGE152

R1U59 RES_0402-0.0,5%,1/16W,CHIP,G21A
     1 H_CPU0_ABC_MEMHOT_LVT3_R_N @BASEBOARD_FAB2_LIB.BASEBOARD_FAB2(SCH_1):H_CPU0_ABC_MEMHOT_LVT3_R_N    I74 @BASEBOARD_FAB2_LIB.BASEBOARD_FAB2(SCH_1):PAGE152
     2 H_CPU0_MEMABC_MEMHOT_LVT3_K_N @BASEBOARD_FAB2_LIB.BASEBOARD_FAB2(SCH_1):H_CPU0_MEMABC_MEMHOT_LVT3_K_N    I74 @BASEBOARD_FAB2_LIB.BASEBOARD_FAB2(SCH_1):PAGE152

R1U60 RES_0402-0.0,5%,1/16W,CHIP,G21A
     1 H_CPU1_MEMKLM_MEMHOT_G_N @BASEBOARD_FAB2_LIB.BASEBOARD_FAB2(SCH_1):H_CPU1_MEMKLM_MEMHOT_G_N    I65 @BASEBOARD_FAB2_LIB.BASEBOARD_FAB2(SCH_1):PAGE152
     2 H_CPU1_MEMKLM_MEMHOT_G_R_N @BASEBOARD_FAB2_LIB.BASEBOARD_FAB2(SCH_1):H_CPU1_MEMKLM_MEMHOT_G_R_N    I65 @BASEBOARD_FAB2_LIB.BASEBOARD_FAB2(SCH_1):PAGE152

R1U61 RES_0402-0.0,5%,1/16W,EMPTY,G2A
     1 H_CPU1_MEMKLM_MEMHOT_LVT3_K_N @BASEBOARD_FAB2_LIB.BASEBOARD_FAB2(SCH_1):H_CPU1_MEMKLM_MEMHOT_LVT3_K_N    I70 @BASEBOARD_FAB2_LIB.BASEBOARD_FAB2(SCH_1):PAGE152
     2 H_CPU1_MEMKLM_MEMHOT_G_PCH_N @BASEBOARD_FAB2_LIB.BASEBOARD_FAB2(SCH_1):H_CPU1_MEMKLM_MEMHOT_G_PCH_N    I70 @BASEBOARD_FAB2_LIB.BASEBOARD_FAB2(SCH_1):PAGE152

R1U62 RES_0402-0.0,5%,1/16W,EMPTY,G2A
     1 H_CPU1_MEMKLM_MEMHOT_G_N @BASEBOARD_FAB2_LIB.BASEBOARD_FAB2(SCH_1):H_CPU1_MEMKLM_MEMHOT_G_N    I68 @BASEBOARD_FAB2_LIB.BASEBOARD_FAB2(SCH_1):PAGE152
     2 H_CPU1_MEMKLM_MEMHOT_G_PCH_N @BASEBOARD_FAB2_LIB.BASEBOARD_FAB2(SCH_1):H_CPU1_MEMKLM_MEMHOT_G_PCH_N    I68 @BASEBOARD_FAB2_LIB.BASEBOARD_FAB2(SCH_1):PAGE152

R1U63 RES_0402-1.00K,1%,1/16W,CHIP,GA
     1 PD_RST_RTCRST_N @BASEBOARD_FAB2_LIB.BASEBOARD_FAB2(SCH_1):PD_RST_RTCRST_N    I15 @BASEBOARD_FAB2_LIB.BASEBOARD_FAB2(SCH_1):PAGE137
     2    GND @BASEBOARD_FAB2_LIB.BASEBOARD_FAB2(SCH_1):GND    I15 @BASEBOARD_FAB2_LIB.BASEBOARD_FAB2(SCH_1):PAGE137

R1U64 RES_0402-1.00K,1%,1/16W,CHIP,GA
     1 PD_IE_DEBUG_MODE @BASEBOARD_FAB2_LIB.BASEBOARD_FAB2(SCH_1):PD_IE_DEBUG_MODE    I69 @BASEBOARD_FAB2_LIB.BASEBOARD_FAB2(SCH_1):PAGE137
     2    GND @BASEBOARD_FAB2_LIB.BASEBOARD_FAB2(SCH_1):GND    I69 @BASEBOARD_FAB2_LIB.BASEBOARD_FAB2(SCH_1):PAGE137

R1W1 1MR2F-L-GP_SMD-RG1-1MR2F-L-GP,A
     1 P3V3_STBY @BASEBOARD_FAB2_LIB.BASEBOARD_FAB2(SCH_1):P3V3_STBY    I18 @BASEBOARD_FAB2_LIB.BASEBOARD_FAB2(SCH_1):PAGE250
     2 FM_OCP_MEZZA_PRES_N @BASEBOARD_FAB2_LIB.BASEBOARD_FAB2(SCH_1):FM_OCP_MEZZA_PRES_N    I18 @BASEBOARD_FAB2_LIB.BASEBOARD_FAB2(SCH_1):PAGE250

R1W3 1MR2F-L-GP_SMD-RG1-1MR2F-L-GP,A
     1 P3V3_STBY @BASEBOARD_FAB2_LIB.BASEBOARD_FAB2(SCH_1):P3V3_STBY    I27 @BASEBOARD_FAB2_LIB.BASEBOARD_FAB2(SCH_1):PAGE250
     2 FM_OCP_MEZZB_PRES_N @BASEBOARD_FAB2_LIB.BASEBOARD_FAB2(SCH_1):FM_OCP_MEZZB_PRES_N    I27 @BASEBOARD_FAB2_LIB.BASEBOARD_FAB2(SCH_1):PAGE250

R1W4 RES_0402-10.0K,1%,1/16W,CHIP,GA
     1 FM_OCP_MEZZB_PRES_LVT3_BMC @BASEBOARD_FAB2_LIB.BASEBOARD_FAB2(SCH_1):FM_OCP_MEZZB_PRES_LVT3_BMC    I22 @BASEBOARD_FAB2_LIB.BASEBOARD_FAB2(SCH_1):PAGE250
     2 P3V3_STBY @BASEBOARD_FAB2_LIB.BASEBOARD_FAB2(SCH_1):P3V3_STBY    I22 @BASEBOARD_FAB2_LIB.BASEBOARD_FAB2(SCH_1):PAGE250

R1W6 1MR2F-L-GP_SMD-RG1-1MR2F-L-GP,A
     1 P3V3_STBY @BASEBOARD_FAB2_LIB.BASEBOARD_FAB2(SCH_1):P3V3_STBY     I2 @BASEBOARD_FAB2_LIB.BASEBOARD_FAB2(SCH_1):PAGE250
     2 FM_OCP_MEZZC_PRES_N @BASEBOARD_FAB2_LIB.BASEBOARD_FAB2(SCH_1):FM_OCP_MEZZC_PRES_N     I2 @BASEBOARD_FAB2_LIB.BASEBOARD_FAB2(SCH_1):PAGE250

R1W7 RES_0402-10.0K,1%,1/16W,CHIP,GA
     1 FM_OCP_MEZZC_PRES_LVT3_BMC @BASEBOARD_FAB2_LIB.BASEBOARD_FAB2(SCH_1):FM_OCP_MEZZC_PRES_LVT3_BMC     I6 @BASEBOARD_FAB2_LIB.BASEBOARD_FAB2(SCH_1):PAGE250
     2 P3V3_STBY @BASEBOARD_FAB2_LIB.BASEBOARD_FAB2(SCH_1):P3V3_STBY     I6 @BASEBOARD_FAB2_LIB.BASEBOARD_FAB2(SCH_1):PAGE250

R1W9 RES_0402-22.1,1.0%,1/16W,CHIP,A
     1 PWRGD_P2V5_BMC_STBY_R @BASEBOARD_FAB2_LIB.BASEBOARD_FAB2(SCH_1):PWRGD_P2V5_BMC_STBY_R    I77 @BASEBOARD_FAB2_LIB.BASEBOARD_FAB2(SCH_1):PAGE239
     2 PWRGD_P2V5_BMC_STBY @BASEBOARD_FAB2_LIB.BASEBOARD_FAB2(SCH_1):PWRGD_P2V5_BMC_STBY    I77 @BASEBOARD_FAB2_LIB.BASEBOARD_FAB2(SCH_1):PAGE239

R1W10 RES_0805-0.0,5%,1/8W,CHIP,G221A
     1 P5V_STBY @BASEBOARD_FAB2_LIB.BASEBOARD_FAB2(SCH_1):P5V_STBY   I132 @BASEBOARD_FAB2_LIB.BASEBOARD_FAB2(SCH_1):PAGE176
     2 P5V_TPS2061 @BASEBOARD_FAB2_LIB.BASEBOARD_FAB2(SCH_1):P5V_TPS2061   I132 @BASEBOARD_FAB2_LIB.BASEBOARD_FAB2(SCH_1):PAGE176

R1W11 RES_0805-0.0,5%,1/8W,EMPTY,G22A
     1    P5V @BASEBOARD_FAB2_LIB.BASEBOARD_FAB2(SCH_1):P5V   I133 @BASEBOARD_FAB2_LIB.BASEBOARD_FAB2(SCH_1):PAGE176
     2 P5V_TPS2061 @BASEBOARD_FAB2_LIB.BASEBOARD_FAB2(SCH_1):P5V_TPS2061   I133 @BASEBOARD_FAB2_LIB.BASEBOARD_FAB2(SCH_1):PAGE176

R1W12 RES_0402-0.0,5%,1/16W,CHIP,G21A
     1 FM_CPLD_USB_P0_EN_N @BASEBOARD_FAB2_LIB.BASEBOARD_FAB2(SCH_1):FM_CPLD_USB_P0_EN_N   I137 @BASEBOARD_FAB2_LIB.BASEBOARD_FAB2(SCH_1):PAGE176
     2 FM_USB_P0_EN_R_N @BASEBOARD_FAB2_LIB.BASEBOARD_FAB2(SCH_1):FM_USB_P0_EN_R_N   I137 @BASEBOARD_FAB2_LIB.BASEBOARD_FAB2(SCH_1):PAGE176

R1W13 RES_0402-0.0,5%,1/16W,CHIP,G21A
     1 FM_USB_P0_EN_BOOT_BIOS_STRAP_N @BASEBOARD_FAB2_LIB.BASEBOARD_FAB2(SCH_1):FM_USB_P0_EN_BOOT_BIOS_STRAP_N   I138 @BASEBOARD_FAB2_LIB.BASEBOARD_FAB2(SCH_1):PAGE176
     2 FM_USB_P0_EN_R_N @BASEBOARD_FAB2_LIB.BASEBOARD_FAB2(SCH_1):FM_USB_P0_EN_R_N   I138 @BASEBOARD_FAB2_LIB.BASEBOARD_FAB2(SCH_1):PAGE176

R1W14 RES_0402-0.0,5%,1/16W,CHIP,G21A
     1 USB2_PCH_BMC_P5_DP_R @BASEBOARD_FAB2_LIB.BASEBOARD_FAB2(SCH_1):USB2_PCH_BMC_P5_DP_R   I118 @BASEBOARD_FAB2_LIB.BASEBOARD_FAB2(SCH_1):PAGE115
     2 USB2_PCH_BMC_P5_DP @BASEBOARD_FAB2_LIB.BASEBOARD_FAB2(SCH_1):USB2_PCH_BMC_P5_DP   I118 @BASEBOARD_FAB2_LIB.BASEBOARD_FAB2(SCH_1):PAGE115

R1W15 RES_0402-0.0,5%,1/16W,CHIP,G21A
     1 USB2_PCH_BMC_P5_DN_R @BASEBOARD_FAB2_LIB.BASEBOARD_FAB2(SCH_1):USB2_PCH_BMC_P5_DN_R   I119 @BASEBOARD_FAB2_LIB.BASEBOARD_FAB2(SCH_1):PAGE115
     2 USB2_PCH_BMC_P5_DN @BASEBOARD_FAB2_LIB.BASEBOARD_FAB2(SCH_1):USB2_PCH_BMC_P5_DN   I119 @BASEBOARD_FAB2_LIB.BASEBOARD_FAB2(SCH_1):PAGE115

R1W16 RES_0402-0.0,5%,1/16W,CHIP,G21A
     1 USB_PCH_BMC_P4_DP_R @BASEBOARD_FAB2_LIB.BASEBOARD_FAB2(SCH_1):USB_PCH_BMC_P4_DP_R   I121 @BASEBOARD_FAB2_LIB.BASEBOARD_FAB2(SCH_1):PAGE115
     2 USB_PCH_BMC_P4_DP @BASEBOARD_FAB2_LIB.BASEBOARD_FAB2(SCH_1):USB_PCH_BMC_P4_DP   I121 @BASEBOARD_FAB2_LIB.BASEBOARD_FAB2(SCH_1):PAGE115

R1W17 RES_0402-0.0,5%,1/16W,CHIP,G21A
     1 USB_PCH_BMC_P4_DN_R @BASEBOARD_FAB2_LIB.BASEBOARD_FAB2(SCH_1):USB_PCH_BMC_P4_DN_R   I120 @BASEBOARD_FAB2_LIB.BASEBOARD_FAB2(SCH_1):PAGE115
     2 USB_PCH_BMC_P4_DN @BASEBOARD_FAB2_LIB.BASEBOARD_FAB2(SCH_1):USB_PCH_BMC_P4_DN   I120 @BASEBOARD_FAB2_LIB.BASEBOARD_FAB2(SCH_1):PAGE115

R1W18 RES_0402-0.0,5%,1/16W,CHIP,G21A
     1 USB2_P02_DP_R @BASEBOARD_FAB2_LIB.BASEBOARD_FAB2(SCH_1):USB2_P02_DP_R   I123 @BASEBOARD_FAB2_LIB.BASEBOARD_FAB2(SCH_1):PAGE115
     2 USB2_P02_DP @BASEBOARD_FAB2_LIB.BASEBOARD_FAB2(SCH_1):USB2_P02_DP   I123 @BASEBOARD_FAB2_LIB.BASEBOARD_FAB2(SCH_1):PAGE115

R1W19 RES_0402-0.0,5%,1/16W,CHIP,G21A
     1 USB2_P02_DN_R @BASEBOARD_FAB2_LIB.BASEBOARD_FAB2(SCH_1):USB2_P02_DN_R   I122 @BASEBOARD_FAB2_LIB.BASEBOARD_FAB2(SCH_1):PAGE115
     2 USB2_P02_DN @BASEBOARD_FAB2_LIB.BASEBOARD_FAB2(SCH_1):USB2_P02_DN   I122 @BASEBOARD_FAB2_LIB.BASEBOARD_FAB2(SCH_1):PAGE115

R1W20 RES_0402-0.0,5%,1/16W,CHIP,G21A
     1 A_HSC_TEMP @BASEBOARD_FAB2_LIB.BASEBOARD_FAB2(SCH_1):A_HSC_TEMP   I134 @BASEBOARD_FAB2_LIB.BASEBOARD_FAB2(SCH_1):PAGE199
     2 TEMP_SENSOR_B @BASEBOARD_FAB2_LIB.BASEBOARD_FAB2(SCH_1):TEMP_SENSOR_B   I134 @BASEBOARD_FAB2_LIB.BASEBOARD_FAB2(SCH_1):PAGE199

R1W21 RES_0402-0.0,5%,1/16W,CHIP,G21A
     1    GND @BASEBOARD_FAB2_LIB.BASEBOARD_FAB2(SCH_1):GND   I135 @BASEBOARD_FAB2_LIB.BASEBOARD_FAB2(SCH_1):PAGE199
     2 TEMP_SENSOR_E @BASEBOARD_FAB2_LIB.BASEBOARD_FAB2(SCH_1):TEMP_SENSOR_E   I135 @BASEBOARD_FAB2_LIB.BASEBOARD_FAB2(SCH_1):PAGE199

R1W22 RES_0402-0.0,5%,1/16W,CHIP,G21A
     1 SMB_HOST_STBY_LVC3_SCL @BASEBOARD_FAB2_LIB.BASEBOARD_FAB2(SCH_1):SMB_HOST_STBY_LVC3_SCL   I134 @BASEBOARD_FAB2_LIB.BASEBOARD_FAB2(SCH_1):PAGE101
     2 SMB_HOST_STBY_LVC3_SCL_R4 @BASEBOARD_FAB2_LIB.BASEBOARD_FAB2(SCH_1):SMB_HOST_STBY_LVC3_SCL_R4   I134 @BASEBOARD_FAB2_LIB.BASEBOARD_FAB2(SCH_1):PAGE101

R1W23 RES_0402-0.0,5%,1/16W,CHIP,G21A
     1 SMB_HOST_STBY_LVC3_SDA @BASEBOARD_FAB2_LIB.BASEBOARD_FAB2(SCH_1):SMB_HOST_STBY_LVC3_SDA   I135 @BASEBOARD_FAB2_LIB.BASEBOARD_FAB2(SCH_1):PAGE101
     2 SMB_HOST_STBY_LVC3_SDA_R4 @BASEBOARD_FAB2_LIB.BASEBOARD_FAB2(SCH_1):SMB_HOST_STBY_LVC3_SDA_R4   I135 @BASEBOARD_FAB2_LIB.BASEBOARD_FAB2(SCH_1):PAGE101

R1W24 RES_0402-0.0,5%,1/16W,CHIP,G21A
     1 XTAL_CK_MNG_OUT @BASEBOARD_FAB2_LIB.BASEBOARD_FAB2(SCH_1):XTAL_CK_MNG_OUT   I138 @BASEBOARD_FAB2_LIB.BASEBOARD_FAB2(SCH_1):PAGE101
     2 XTAL_CK_MNG_OUT_R @BASEBOARD_FAB2_LIB.BASEBOARD_FAB2(SCH_1):XTAL_CK_MNG_OUT_R   I138 @BASEBOARD_FAB2_LIB.BASEBOARD_FAB2(SCH_1):PAGE101

R1W25 RES_0402-1.00K,1%,1/16W,CHIP,GA
     1 PU_33P_33M_SMBADR @BASEBOARD_FAB2_LIB.BASEBOARD_FAB2(SCH_1):PU_33P_33M_SMBADR   I140 @BASEBOARD_FAB2_LIB.BASEBOARD_FAB2(SCH_1):PAGE101
     2    GND @BASEBOARD_FAB2_LIB.BASEBOARD_FAB2(SCH_1):GND   I140 @BASEBOARD_FAB2_LIB.BASEBOARD_FAB2(SCH_1):PAGE101

R1W26 RES_0402-10.0K,1%,1/16W,EMPTY,A
     1 RST_RSMRST_R_N @BASEBOARD_FAB2_LIB.BASEBOARD_FAB2(SCH_1):RST_RSMRST_R_N   I349 @BASEBOARD_FAB2_LIB.BASEBOARD_FAB2(SCH_1):PAGE190
     2    GND @BASEBOARD_FAB2_LIB.BASEBOARD_FAB2(SCH_1):GND   I349 @BASEBOARD_FAB2_LIB.BASEBOARD_FAB2(SCH_1):PAGE190

R1W27 RES_0402-0.0,5%,1/16W,CHIP,G21A
     1 FM_PWR_BTN_N @BASEBOARD_FAB2_LIB.BASEBOARD_FAB2(SCH_1):FM_PWR_BTN_N   I351 @BASEBOARD_FAB2_LIB.BASEBOARD_FAB2(SCH_1):PAGE190
     2 FM_PWR_BTN_R2_N @BASEBOARD_FAB2_LIB.BASEBOARD_FAB2(SCH_1):FM_PWR_BTN_R2_N   I351 @BASEBOARD_FAB2_LIB.BASEBOARD_FAB2(SCH_1):PAGE190

R1W28 RES_0402-0.0,5%,1/16W,CHIP,G21A
     1 FM_PCH_PWRBTN_R1_N @BASEBOARD_FAB2_LIB.BASEBOARD_FAB2(SCH_1):FM_PCH_PWRBTN_R1_N   I197 @BASEBOARD_FAB2_LIB.BASEBOARD_FAB2(SCH_1):PAGE191
     2 FM_PCH_PWRBTN_N @BASEBOARD_FAB2_LIB.BASEBOARD_FAB2(SCH_1):FM_PCH_PWRBTN_N   I197 @BASEBOARD_FAB2_LIB.BASEBOARD_FAB2(SCH_1):PAGE191

R1W29 RES_0402-0.0,5%,1/16W,CHIP,G21A
     1 RST_BMC_SYSRST_BTN_OUT_B_N @BASEBOARD_FAB2_LIB.BASEBOARD_FAB2(SCH_1):RST_BMC_SYSRST_BTN_OUT_B_N   I198 @BASEBOARD_FAB2_LIB.BASEBOARD_FAB2(SCH_1):PAGE191
     2 RST_BMC_SYSRST_BTN_OUT_B_R1_N @BASEBOARD_FAB2_LIB.BASEBOARD_FAB2(SCH_1):RST_BMC_SYSRST_BTN_OUT_B_R1_N   I198 @BASEBOARD_FAB2_LIB.BASEBOARD_FAB2(SCH_1):PAGE191

R1W30 RES_0402-0.0,5%,1/16W,EMPTY,G2A
     1 RST_BMC_SYSRST_BTN_OUT_B_N @BASEBOARD_FAB2_LIB.BASEBOARD_FAB2(SCH_1):RST_BMC_SYSRST_BTN_OUT_B_N   I168 @BASEBOARD_FAB2_LIB.BASEBOARD_FAB2(SCH_1):PAGE118
     2 RST_SYSTEM_BTN_BUF_N @BASEBOARD_FAB2_LIB.BASEBOARD_FAB2(SCH_1):RST_SYSTEM_BTN_BUF_N   I168 @BASEBOARD_FAB2_LIB.BASEBOARD_FAB2(SCH_1):PAGE118

R1W31 RES_0402-330,5%,1/16W,CHIP,G21A
     1 FM_ADR_COMPLETE_R @BASEBOARD_FAB2_LIB.BASEBOARD_FAB2(SCH_1):FM_ADR_COMPLETE_R    I56 @BASEBOARD_FAB2_LIB.BASEBOARD_FAB2(SCH_1):PAGE89
     2 FM_ADR_COMPLETE_CPU1_R @BASEBOARD_FAB2_LIB.BASEBOARD_FAB2(SCH_1):FM_ADR_COMPLETE_CPU1_R    I56 @BASEBOARD_FAB2_LIB.BASEBOARD_FAB2(SCH_1):PAGE89

R1W32 RES_0402-330,5%,1/16W,CHIP,G21A
     1 FM_ADR_COMPLETE_R @BASEBOARD_FAB2_LIB.BASEBOARD_FAB2(SCH_1):FM_ADR_COMPLETE_R    I54 @BASEBOARD_FAB2_LIB.BASEBOARD_FAB2(SCH_1):PAGE89
     2 FM_ADR_COMPLETE_CPU0_R @BASEBOARD_FAB2_LIB.BASEBOARD_FAB2(SCH_1):FM_ADR_COMPLETE_CPU0_R    I54 @BASEBOARD_FAB2_LIB.BASEBOARD_FAB2(SCH_1):PAGE89

R1W33 RES_0402-0.0,5%,1/16W,CHIP,G21A
     1 SMB_DEBUG_STBY_LVC3_SCL_R1 @BASEBOARD_FAB2_LIB.BASEBOARD_FAB2(SCH_1):SMB_DEBUG_STBY_LVC3_SCL_R1   I142 @BASEBOARD_FAB2_LIB.BASEBOARD_FAB2(SCH_1):PAGE176
     2 SMB_DEBUG_STBY_LVC3_SCL @BASEBOARD_FAB2_LIB.BASEBOARD_FAB2(SCH_1):SMB_DEBUG_STBY_LVC3_SCL   I142 @BASEBOARD_FAB2_LIB.BASEBOARD_FAB2(SCH_1):PAGE176

R1W34 RES_0402-0.0,5%,1/16W,CHIP,G21A
     1 SMB_DEBUG_STBY_LVC3_SDA_R1 @BASEBOARD_FAB2_LIB.BASEBOARD_FAB2(SCH_1):SMB_DEBUG_STBY_LVC3_SDA_R1   I143 @BASEBOARD_FAB2_LIB.BASEBOARD_FAB2(SCH_1):PAGE176
     2 SMB_DEBUG_STBY_LVC3_SDA @BASEBOARD_FAB2_LIB.BASEBOARD_FAB2(SCH_1):SMB_DEBUG_STBY_LVC3_SDA   I143 @BASEBOARD_FAB2_LIB.BASEBOARD_FAB2(SCH_1):PAGE176

R1W35 RES_0402-49.9,1%,1/16W,EMPTY,GA
     1 PVCCIO_CPU0 @BASEBOARD_FAB2_LIB.BASEBOARD_FAB2(SCH_1):PVCCIO_CPU0   I105 @BASEBOARD_FAB2_LIB.BASEBOARD_FAB2(SCH_1):PAGE152
     2 P0V7_GTL2014_2 @BASEBOARD_FAB2_LIB.BASEBOARD_FAB2(SCH_1):P0V7_GTL2014_2   I105 @BASEBOARD_FAB2_LIB.BASEBOARD_FAB2(SCH_1):PAGE152

R1W36 RES_0402-4.75K,1%,1/16W,CHIP,GA
     1 P3V3_STBY @BASEBOARD_FAB2_LIB.BASEBOARD_FAB2(SCH_1):P3V3_STBY   I172 @BASEBOARD_FAB2_LIB.BASEBOARD_FAB2(SCH_1):PAGE176
     2 SMB_DEBUG_STBY_LVC3_SCL_CONN @BASEBOARD_FAB2_LIB.BASEBOARD_FAB2(SCH_1):SMB_DEBUG_STBY_LVC3_SCL_CONN   I172 @BASEBOARD_FAB2_LIB.BASEBOARD_FAB2(SCH_1):PAGE176

R1W37 RES_0402-4.75K,1%,1/16W,CHIP,GA
     1 P3V3_STBY @BASEBOARD_FAB2_LIB.BASEBOARD_FAB2(SCH_1):P3V3_STBY   I173 @BASEBOARD_FAB2_LIB.BASEBOARD_FAB2(SCH_1):PAGE176
     2 SMB_DEBUG_STBY_LVC3_SDA_CONN @BASEBOARD_FAB2_LIB.BASEBOARD_FAB2(SCH_1):SMB_DEBUG_STBY_LVC3_SDA_CONN   I173 @BASEBOARD_FAB2_LIB.BASEBOARD_FAB2(SCH_1):PAGE176

R1W38 RES_0402-0.0,5%,1/16W,CHIP,G21A
     1 SMB_DEBUG_STBY_LVC3_SCL_CONN @BASEBOARD_FAB2_LIB.BASEBOARD_FAB2(SCH_1):SMB_DEBUG_STBY_LVC3_SCL_CONN   I176 @BASEBOARD_FAB2_LIB.BASEBOARD_FAB2(SCH_1):PAGE176
     2 SMB_DEBUG_STBY_LVC3_SCL_R1 @BASEBOARD_FAB2_LIB.BASEBOARD_FAB2(SCH_1):SMB_DEBUG_STBY_LVC3_SCL_R1   I176 @BASEBOARD_FAB2_LIB.BASEBOARD_FAB2(SCH_1):PAGE176

R1W39 RES_0402-0.0,5%,1/16W,CHIP,G21A
     1 SMB_DEBUG_STBY_LVC3_SDA_CONN @BASEBOARD_FAB2_LIB.BASEBOARD_FAB2(SCH_1):SMB_DEBUG_STBY_LVC3_SDA_CONN   I175 @BASEBOARD_FAB2_LIB.BASEBOARD_FAB2(SCH_1):PAGE176
     2 SMB_DEBUG_STBY_LVC3_SDA_R1 @BASEBOARD_FAB2_LIB.BASEBOARD_FAB2(SCH_1):SMB_DEBUG_STBY_LVC3_SDA_R1   I175 @BASEBOARD_FAB2_LIB.BASEBOARD_FAB2(SCH_1):PAGE176

R1W40 RES_0402-4.75K,1%,1/16W,CHIP,GA
     1 P3V3_STBY @BASEBOARD_FAB2_LIB.BASEBOARD_FAB2(SCH_1):P3V3_STBY   I128 @BASEBOARD_FAB2_LIB.BASEBOARD_FAB2(SCH_1):PAGE188
     2 EXT_MDIO_I2C_SEL @BASEBOARD_FAB2_LIB.BASEBOARD_FAB2(SCH_1):EXT_MDIO_I2C_SEL   I128 @BASEBOARD_FAB2_LIB.BASEBOARD_FAB2(SCH_1):PAGE188

R1W41 RES_0402-4.75K,1%,1/16W,CHIP,GA
     1    GND @BASEBOARD_FAB2_LIB.BASEBOARD_FAB2(SCH_1):GND   I129 @BASEBOARD_FAB2_LIB.BASEBOARD_FAB2(SCH_1):PAGE188
     2 EXT_MDIO_I2C_SEL @BASEBOARD_FAB2_LIB.BASEBOARD_FAB2(SCH_1):EXT_MDIO_I2C_SEL   I129 @BASEBOARD_FAB2_LIB.BASEBOARD_FAB2(SCH_1):PAGE188

R1W42 RES_0402-4.75K,1%,1/16W,CHIP,GA
     1 P3V3_STBY @BASEBOARD_FAB2_LIB.BASEBOARD_FAB2(SCH_1):P3V3_STBY   I131 @BASEBOARD_FAB2_LIB.BASEBOARD_FAB2(SCH_1):PAGE188
     2 FM_GBE0_LVC3_MOD_ABS @BASEBOARD_FAB2_LIB.BASEBOARD_FAB2(SCH_1):FM_GBE0_LVC3_MOD_ABS   I131 @BASEBOARD_FAB2_LIB.BASEBOARD_FAB2(SCH_1):PAGE188

R1W43 RES_0402-4.75K,1%,1/16W,CHIP,GA
     1 P3V3_STBY @BASEBOARD_FAB2_LIB.BASEBOARD_FAB2(SCH_1):P3V3_STBY   I132 @BASEBOARD_FAB2_LIB.BASEBOARD_FAB2(SCH_1):PAGE188
     2 FM_GBE1_LVC3_MOD_ABS @BASEBOARD_FAB2_LIB.BASEBOARD_FAB2(SCH_1):FM_GBE1_LVC3_MOD_ABS   I132 @BASEBOARD_FAB2_LIB.BASEBOARD_FAB2(SCH_1):PAGE188

R1W44 RES_0402-4.75K,1%,1/16W,CHIP,GA
     1 P3V3_STBY @BASEBOARD_FAB2_LIB.BASEBOARD_FAB2(SCH_1):P3V3_STBY   I133 @BASEBOARD_FAB2_LIB.BASEBOARD_FAB2(SCH_1):PAGE188
     2 FM_GBE2_LVC3_MOD_ABS @BASEBOARD_FAB2_LIB.BASEBOARD_FAB2(SCH_1):FM_GBE2_LVC3_MOD_ABS   I133 @BASEBOARD_FAB2_LIB.BASEBOARD_FAB2(SCH_1):PAGE188

R1W45 RES_0402-4.75K,1%,1/16W,CHIP,GA
     1 P3V3_STBY @BASEBOARD_FAB2_LIB.BASEBOARD_FAB2(SCH_1):P3V3_STBY   I134 @BASEBOARD_FAB2_LIB.BASEBOARD_FAB2(SCH_1):PAGE188
     2 FM_GBE3_LVC3_MOD_ABS @BASEBOARD_FAB2_LIB.BASEBOARD_FAB2(SCH_1):FM_GBE3_LVC3_MOD_ABS   I134 @BASEBOARD_FAB2_LIB.BASEBOARD_FAB2(SCH_1):PAGE188

R2L4 RES_0402-2.0K,1%,1/16W,CHIP,G2A
     1 P3V3_STBY @BASEBOARD_FAB2_LIB.BASEBOARD_FAB2(SCH_1):P3V3_STBY    I18 @BASEBOARD_FAB2_LIB.BASEBOARD_FAB2(SCH_1):PAGE178
     2 SGPIO_PCH_SSATA_DOUT0_R @BASEBOARD_FAB2_LIB.BASEBOARD_FAB2(SCH_1):SGPIO_PCH_SSATA_DOUT0_R    I18 @BASEBOARD_FAB2_LIB.BASEBOARD_FAB2(SCH_1):PAGE178

R2L5 RES_0402-2.0K,1%,1/16W,CHIP,G2A
     1 P3V3_STBY @BASEBOARD_FAB2_LIB.BASEBOARD_FAB2(SCH_1):P3V3_STBY    I20 @BASEBOARD_FAB2_LIB.BASEBOARD_FAB2(SCH_1):PAGE178
     2 SGPIO_PCH_SSATA_LOAD_R @BASEBOARD_FAB2_LIB.BASEBOARD_FAB2(SCH_1):SGPIO_PCH_SSATA_LOAD_R    I20 @BASEBOARD_FAB2_LIB.BASEBOARD_FAB2(SCH_1):PAGE178

R2L6 RES_0402-2.0K,1%,1/16W,CHIP,G2A
     1 P3V3_STBY @BASEBOARD_FAB2_LIB.BASEBOARD_FAB2(SCH_1):P3V3_STBY    I17 @BASEBOARD_FAB2_LIB.BASEBOARD_FAB2(SCH_1):PAGE178
     2 SGPIO_PCH_SSATA_CLOCK_R @BASEBOARD_FAB2_LIB.BASEBOARD_FAB2(SCH_1):SGPIO_PCH_SSATA_CLOCK_R    I17 @BASEBOARD_FAB2_LIB.BASEBOARD_FAB2(SCH_1):PAGE178

R2L8 RES_0603-10.0,1%,1/10W,CHIP,G2A
     1 VSENSE_P1V05_PCH_STBY_AVSP @BASEBOARD_FAB2_LIB.BASEBOARD_FAB2(SCH_1):VSENSE_P1V05_PCH_STBY_AVSP   I154 @BASEBOARD_FAB2_LIB.BASEBOARD_FAB2(SCH_1):PAGE235
     2 VR_P1V05_PCH_STBY_AVSP @BASEBOARD_FAB2_LIB.BASEBOARD_FAB2(SCH_1):VR_P1V05_PCH_STBY_AVSP   I154 @BASEBOARD_FAB2_LIB.BASEBOARD_FAB2(SCH_1):PAGE235

R2L9 RES_0402-4.02K,1%,1/16W,CHIP,GA
     1 VR_PVNN_PCH_XADDR1 @BASEBOARD_FAB2_LIB.BASEBOARD_FAB2(SCH_1):VR_PVNN_PCH_XADDR1   I254 @BASEBOARD_FAB2_LIB.BASEBOARD_FAB2(SCH_1):PAGE235
     2    GND @BASEBOARD_FAB2_LIB.BASEBOARD_FAB2(SCH_1):GND   I254 @BASEBOARD_FAB2_LIB.BASEBOARD_FAB2(SCH_1):PAGE235

R2L10 RES_0402-1.5K,1%,1/16W,CHIP,G2A
     1 VR_PVNN_PCH_VINSEN @BASEBOARD_FAB2_LIB.BASEBOARD_FAB2(SCH_1):VR_PVNN_PCH_VINSEN   I166 @BASEBOARD_FAB2_LIB.BASEBOARD_FAB2(SCH_1):PAGE235
     2    GND @BASEBOARD_FAB2_LIB.BASEBOARD_FAB2(SCH_1):GND   I166 @BASEBOARD_FAB2_LIB.BASEBOARD_FAB2(SCH_1):PAGE235

R2L11 RES_0402-2.0K,1%,1/16W,CHIP,G2A
     1 P3V3_STBY @BASEBOARD_FAB2_LIB.BASEBOARD_FAB2(SCH_1):P3V3_STBY    I13 @BASEBOARD_FAB2_LIB.BASEBOARD_FAB2(SCH_1):PAGE178
     2 SGPIO_PCH_SATA_CLOCK_R @BASEBOARD_FAB2_LIB.BASEBOARD_FAB2(SCH_1):SGPIO_PCH_SATA_CLOCK_R    I13 @BASEBOARD_FAB2_LIB.BASEBOARD_FAB2(SCH_1):PAGE178

R2L12 RES_0402-2.0K,1%,1/16W,CHIP,G2A
     1 P3V3_STBY @BASEBOARD_FAB2_LIB.BASEBOARD_FAB2(SCH_1):P3V3_STBY     I2 @BASEBOARD_FAB2_LIB.BASEBOARD_FAB2(SCH_1):PAGE178
     2 SGPIO_PCH_SATA_LOAD_R @BASEBOARD_FAB2_LIB.BASEBOARD_FAB2(SCH_1):SGPIO_PCH_SATA_LOAD_R     I2 @BASEBOARD_FAB2_LIB.BASEBOARD_FAB2(SCH_1):PAGE178

R2L14 RES_0402-0.0,5%,1/16W,CHIP,G21A
     1 P3V3_STBY @BASEBOARD_FAB2_LIB.BASEBOARD_FAB2(SCH_1):P3V3_STBY   I159 @BASEBOARD_FAB2_LIB.BASEBOARD_FAB2(SCH_1):PAGE235
     2 VR_PVNN_PCH_VDD @BASEBOARD_FAB2_LIB.BASEBOARD_FAB2(SCH_1):VR_PVNN_PCH_VDD   I159 @BASEBOARD_FAB2_LIB.BASEBOARD_FAB2(SCH_1):PAGE235

R2L15 RES_0402-2.0K,1%,1/16W,CHIP,G2A
     1 P3V3_STBY @BASEBOARD_FAB2_LIB.BASEBOARD_FAB2(SCH_1):P3V3_STBY    I12 @BASEBOARD_FAB2_LIB.BASEBOARD_FAB2(SCH_1):PAGE178
     2 SGPIO_PCH_SATA_DOUT0_R @BASEBOARD_FAB2_LIB.BASEBOARD_FAB2(SCH_1):SGPIO_PCH_SATA_DOUT0_R    I12 @BASEBOARD_FAB2_LIB.BASEBOARD_FAB2(SCH_1):PAGE178

R2L16 RES_0402-22.1,1.0%,1/16W,CHIP,A
     1 PWRGD_PVNN_PCH_R @BASEBOARD_FAB2_LIB.BASEBOARD_FAB2(SCH_1):PWRGD_PVNN_PCH_R   I147 @BASEBOARD_FAB2_LIB.BASEBOARD_FAB2(SCH_1):PAGE235
     2 PWRGD_PVNN_P1V05_PCH @BASEBOARD_FAB2_LIB.BASEBOARD_FAB2(SCH_1):PWRGD_PVNN_P1V05_PCH   I147 @BASEBOARD_FAB2_LIB.BASEBOARD_FAB2(SCH_1):PAGE235

R2L17 RES_0402-0.0,5%,1/16W,CHIP,G21A
     1 PWRGD_P1V8_PCH_STBY @BASEBOARD_FAB2_LIB.BASEBOARD_FAB2(SCH_1):PWRGD_P1V8_PCH_STBY   I221 @BASEBOARD_FAB2_LIB.BASEBOARD_FAB2(SCH_1):PAGE235
     2 VR_PVNN_PCH_VREN @BASEBOARD_FAB2_LIB.BASEBOARD_FAB2(SCH_1):VR_PVNN_PCH_VREN   I221 @BASEBOARD_FAB2_LIB.BASEBOARD_FAB2(SCH_1):PAGE235

R2L18 RES_0402-1.00K,1%,1/16W,CHIP,GA
     1 PD_SATA0_CONTROLLER_TYPE_R @BASEBOARD_FAB2_LIB.BASEBOARD_FAB2(SCH_1):PD_SATA0_CONTROLLER_TYPE_R   I266 @BASEBOARD_FAB2_LIB.BASEBOARD_FAB2(SCH_1):PAGE173
     2    GND @BASEBOARD_FAB2_LIB.BASEBOARD_FAB2(SCH_1):GND   I266 @BASEBOARD_FAB2_LIB.BASEBOARD_FAB2(SCH_1):PAGE173

R2L19 RES_0402-49.9K,1%,1/16W,CHIP,GA
     1 VR_P1V8_PCH_STBY_FB @BASEBOARD_FAB2_LIB.BASEBOARD_FAB2(SCH_1):VR_P1V8_PCH_STBY_FB    I80 @BASEBOARD_FAB2_LIB.BASEBOARD_FAB2(SCH_1):PAGE237
     2    GND @BASEBOARD_FAB2_LIB.BASEBOARD_FAB2(SCH_1):GND    I80 @BASEBOARD_FAB2_LIB.BASEBOARD_FAB2(SCH_1):PAGE237

R2L20 RES_0402-63.4K,1.0%,1/16W,CHIPA
     1 P1V8_PCH_STBY @BASEBOARD_FAB2_LIB.BASEBOARD_FAB2(SCH_1):P1V8_PCH_STBY    I81 @BASEBOARD_FAB2_LIB.BASEBOARD_FAB2(SCH_1):PAGE237
     2 VR_P1V8_PCH_STBY_FB @BASEBOARD_FAB2_LIB.BASEBOARD_FAB2(SCH_1):VR_P1V8_PCH_STBY_FB    I81 @BASEBOARD_FAB2_LIB.BASEBOARD_FAB2(SCH_1):PAGE237

R2L21 RES_0402-2.0K,1%,1/16W,CHIP,G2A
     1   P3V3 @BASEBOARD_FAB2_LIB.BASEBOARD_FAB2(SCH_1):P3V3   I263 @BASEBOARD_FAB2_LIB.BASEBOARD_FAB2(SCH_1):PAGE173
     2 PU_DATAIN1_SATA_0_R @BASEBOARD_FAB2_LIB.BASEBOARD_FAB2(SCH_1):PU_DATAIN1_SATA_0_R   I263 @BASEBOARD_FAB2_LIB.BASEBOARD_FAB2(SCH_1):PAGE173

R2L22 RES_0402-1.00K,1%,1/16W,CHIP,GA
     1 PD_SATA1_CONTROLLER_TYPE_R @BASEBOARD_FAB2_LIB.BASEBOARD_FAB2(SCH_1):PD_SATA1_CONTROLLER_TYPE_R   I264 @BASEBOARD_FAB2_LIB.BASEBOARD_FAB2(SCH_1):PAGE173
     2    GND @BASEBOARD_FAB2_LIB.BASEBOARD_FAB2(SCH_1):GND   I264 @BASEBOARD_FAB2_LIB.BASEBOARD_FAB2(SCH_1):PAGE173

R2L23 RES_0402-2.0K,1%,1/16W,CHIP,G2A
     1   P3V3 @BASEBOARD_FAB2_LIB.BASEBOARD_FAB2(SCH_1):P3V3   I261 @BASEBOARD_FAB2_LIB.BASEBOARD_FAB2(SCH_1):PAGE173
     2 PU_DATAIN1_SATA_1_R @BASEBOARD_FAB2_LIB.BASEBOARD_FAB2(SCH_1):PU_DATAIN1_SATA_1_R   I261 @BASEBOARD_FAB2_LIB.BASEBOARD_FAB2(SCH_1):PAGE173

R2L24 RES_0402-2.26K,1.0%,1/16W,EMPTA
     1 P3V3_STBY @BASEBOARD_FAB2_LIB.BASEBOARD_FAB2(SCH_1):P3V3_STBY   I148 @BASEBOARD_FAB2_LIB.BASEBOARD_FAB2(SCH_1):PAGE235
     2 PU_VR_PVNN_PCH_FAULT1 @BASEBOARD_FAB2_LIB.BASEBOARD_FAB2(SCH_1):PU_VR_PVNN_PCH_FAULT1   I148 @BASEBOARD_FAB2_LIB.BASEBOARD_FAB2(SCH_1):PAGE235

R2L25 RES_0402-100.0K,1%,1/16W,CHIP,A
     1 P3V3_STBY @BASEBOARD_FAB2_LIB.BASEBOARD_FAB2(SCH_1):P3V3_STBY   I252 @BASEBOARD_FAB2_LIB.BASEBOARD_FAB2(SCH_1):PAGE235
     2 VID_PCH_CORE_PVNN_AUX_VID_1 @BASEBOARD_FAB2_LIB.BASEBOARD_FAB2(SCH_1):VID_PCH_CORE_PVNN_AUX_VID_1   I252 @BASEBOARD_FAB2_LIB.BASEBOARD_FAB2(SCH_1):PAGE235

R2L26 RES_0402-100.0K,1%,1/16W,CHIP,A
     1 P3V3_STBY @BASEBOARD_FAB2_LIB.BASEBOARD_FAB2(SCH_1):P3V3_STBY   I253 @BASEBOARD_FAB2_LIB.BASEBOARD_FAB2(SCH_1):PAGE235
     2 VID_PCH_CORE_PVNN_AUX_VID_0 @BASEBOARD_FAB2_LIB.BASEBOARD_FAB2(SCH_1):VID_PCH_CORE_PVNN_AUX_VID_0   I253 @BASEBOARD_FAB2_LIB.BASEBOARD_FAB2(SCH_1):PAGE235

R2M1 RES_0402-33.2,1%,1/16W,CHIP,G2A
     1 FM_CPLD_ADR_TRIGGER_N @BASEBOARD_FAB2_LIB.BASEBOARD_FAB2(SCH_1):FM_CPLD_ADR_TRIGGER_N   I218 @BASEBOARD_FAB2_LIB.BASEBOARD_FAB2(SCH_1):PAGE120
     2 FM_CPLD_ADR_TRIGGER_R_N @BASEBOARD_FAB2_LIB.BASEBOARD_FAB2(SCH_1):FM_CPLD_ADR_TRIGGER_R_N   I218 @BASEBOARD_FAB2_LIB.BASEBOARD_FAB2(SCH_1):PAGE120

R2M2 RES_0402-4.75K,1%,1/16W,CHIP,GA
     1 P3V3_STBY @BASEBOARD_FAB2_LIB.BASEBOARD_FAB2(SCH_1):P3V3_STBY   I346 @BASEBOARD_FAB2_LIB.BASEBOARD_FAB2(SCH_1):PAGE157
     2 FM_ADR_SMI_GPIO_N @BASEBOARD_FAB2_LIB.BASEBOARD_FAB2(SCH_1):FM_ADR_SMI_GPIO_N   I346 @BASEBOARD_FAB2_LIB.BASEBOARD_FAB2(SCH_1):PAGE157

R2M3 RES_0402-33.2,1%,1/16W,CHIP,G2A
     1 FM_PCH_PLD_DATA_R @BASEBOARD_FAB2_LIB.BASEBOARD_FAB2(SCH_1):FM_PCH_PLD_DATA_R   I172 @BASEBOARD_FAB2_LIB.BASEBOARD_FAB2(SCH_1):PAGE119
     2 FM_PCH_PLD_DATA @BASEBOARD_FAB2_LIB.BASEBOARD_FAB2(SCH_1):FM_PCH_PLD_DATA   I172 @BASEBOARD_FAB2_LIB.BASEBOARD_FAB2(SCH_1):PAGE119

R2M4 RES_0402-1.00K,1%,1/16W,CHIP,GA
     1 P3V3_STBY @BASEBOARD_FAB2_LIB.BASEBOARD_FAB2(SCH_1):P3V3_STBY   I284 @BASEBOARD_FAB2_LIB.BASEBOARD_FAB2(SCH_1):PAGE133
     2 IRQ_HSC_FAULT_N @BASEBOARD_FAB2_LIB.BASEBOARD_FAB2(SCH_1):IRQ_HSC_FAULT_N   I284 @BASEBOARD_FAB2_LIB.BASEBOARD_FAB2(SCH_1):PAGE133

R2M5 RES_0402-4.75K,1%,1/16W,CHIP,GA
     1 P3V3_STBY @BASEBOARD_FAB2_LIB.BASEBOARD_FAB2(SCH_1):P3V3_STBY   I348 @BASEBOARD_FAB2_LIB.BASEBOARD_FAB2(SCH_1):PAGE157
     2 FM_BMC_CPLD_GPO @BASEBOARD_FAB2_LIB.BASEBOARD_FAB2(SCH_1):FM_BMC_CPLD_GPO   I348 @BASEBOARD_FAB2_LIB.BASEBOARD_FAB2(SCH_1):PAGE157

R2M6 RES_0402-1.0K,0.1%,1/16W,CHIP,A
     1 A_KR1_RBIAS @BASEBOARD_FAB2_LIB.BASEBOARD_FAB2(SCH_1):A_KR1_RBIAS    I99 @BASEBOARD_FAB2_LIB.BASEBOARD_FAB2(SCH_1):PAGE118
     2 P1V05_PCH_STBY_KR_PLL @BASEBOARD_FAB2_LIB.BASEBOARD_FAB2(SCH_1):P1V05_PCH_STBY_KR_PLL    I99 @BASEBOARD_FAB2_LIB.BASEBOARD_FAB2(SCH_1):PAGE118

R2M7 RES_0402-33.2,1%,1/16W,CHIP,G2A
     1 FM_ADR_MODE_SEL_R @BASEBOARD_FAB2_LIB.BASEBOARD_FAB2(SCH_1):FM_ADR_MODE_SEL_R   I174 @BASEBOARD_FAB2_LIB.BASEBOARD_FAB2(SCH_1):PAGE119
     2 FM_ADR_MODE_SEL @BASEBOARD_FAB2_LIB.BASEBOARD_FAB2(SCH_1):FM_ADR_MODE_SEL   I174 @BASEBOARD_FAB2_LIB.BASEBOARD_FAB2(SCH_1):PAGE119

R2M8 RES_0402-1.5K,1%,1/16W,CHIP,G2A
     1 P3V3_STBY @BASEBOARD_FAB2_LIB.BASEBOARD_FAB2(SCH_1):P3V3_STBY   I349 @BASEBOARD_FAB2_LIB.BASEBOARD_FAB2(SCH_1):PAGE133
     2 FM_CPU0_RC_ERROR_N @BASEBOARD_FAB2_LIB.BASEBOARD_FAB2(SCH_1):FM_CPU0_RC_ERROR_N   I349 @BASEBOARD_FAB2_LIB.BASEBOARD_FAB2(SCH_1):PAGE133

R2N1 RES_0402-33.2,1%,1/16W,CHIP,G2A
     1 FM_CPU_CATERR_DLY_LVT3_R_N @BASEBOARD_FAB2_LIB.BASEBOARD_FAB2(SCH_1):FM_CPU_CATERR_DLY_LVT3_R_N   I173 @BASEBOARD_FAB2_LIB.BASEBOARD_FAB2(SCH_1):PAGE119
     2 FM_CPU_CATERR_DLY_LVT3_N @BASEBOARD_FAB2_LIB.BASEBOARD_FAB2(SCH_1):FM_CPU_CATERR_DLY_LVT3_N   I173 @BASEBOARD_FAB2_LIB.BASEBOARD_FAB2(SCH_1):PAGE119

R2N4 RES_0402-1.0K,0.1%,1/16W,CHIP,A
     1 P1V05_PCH_STBY_KR_PLL @BASEBOARD_FAB2_LIB.BASEBOARD_FAB2(SCH_1):P1V05_PCH_STBY_KR_PLL    I96 @BASEBOARD_FAB2_LIB.BASEBOARD_FAB2(SCH_1):PAGE118
     2 A_KR0_RBIAS @BASEBOARD_FAB2_LIB.BASEBOARD_FAB2(SCH_1):A_KR0_RBIAS    I96 @BASEBOARD_FAB2_LIB.BASEBOARD_FAB2(SCH_1):PAGE118

R2N5 RES_0402-665,1.0%,1/16W,CHIP,GA
     1 P3V3_STBY @BASEBOARD_FAB2_LIB.BASEBOARD_FAB2(SCH_1):P3V3_STBY    I90 @BASEBOARD_FAB2_LIB.BASEBOARD_FAB2(SCH_1):PAGE138
     2 SMB_SMLINK0_STBY_LVC3_SCL @BASEBOARD_FAB2_LIB.BASEBOARD_FAB2(SCH_1):SMB_SMLINK0_STBY_LVC3_SCL    I90 @BASEBOARD_FAB2_LIB.BASEBOARD_FAB2(SCH_1):PAGE138

R2N6 RES_0402-10.0K,1%,1/16W,CHIP,GA
     1 P3V3_STBY @BASEBOARD_FAB2_LIB.BASEBOARD_FAB2(SCH_1):P3V3_STBY   I128 @BASEBOARD_FAB2_LIB.BASEBOARD_FAB2(SCH_1):PAGE118
     2 FM_GBE_LOM_DISABLE_N @BASEBOARD_FAB2_LIB.BASEBOARD_FAB2(SCH_1):FM_GBE_LOM_DISABLE_N   I128 @BASEBOARD_FAB2_LIB.BASEBOARD_FAB2(SCH_1):PAGE118

R2N7 RES_0402-4.75K,1%,1/16W,CHIP,GA
     1 P3V3_STBY @BASEBOARD_FAB2_LIB.BASEBOARD_FAB2(SCH_1):P3V3_STBY   I309 @BASEBOARD_FAB2_LIB.BASEBOARD_FAB2(SCH_1):PAGE133
     2 IRQ_BOARD_BMC_ALERT_N @BASEBOARD_FAB2_LIB.BASEBOARD_FAB2(SCH_1):IRQ_BOARD_BMC_ALERT_N   I309 @BASEBOARD_FAB2_LIB.BASEBOARD_FAB2(SCH_1):PAGE133

R2N8 RES_0402-665,1.0%,1/16W,CHIP,GA
     1 P3V3_STBY @BASEBOARD_FAB2_LIB.BASEBOARD_FAB2(SCH_1):P3V3_STBY    I89 @BASEBOARD_FAB2_LIB.BASEBOARD_FAB2(SCH_1):PAGE138
     2 SMB_SMLINK0_STBY_LVC3_SDA @BASEBOARD_FAB2_LIB.BASEBOARD_FAB2(SCH_1):SMB_SMLINK0_STBY_LVC3_SDA    I89 @BASEBOARD_FAB2_LIB.BASEBOARD_FAB2(SCH_1):PAGE138

R2N9 RES_0402-10.0K,1%,1/16W,CHIP,GA
     1 P3V3_STBY @BASEBOARD_FAB2_LIB.BASEBOARD_FAB2(SCH_1):P3V3_STBY   I267 @BASEBOARD_FAB2_LIB.BASEBOARD_FAB2(SCH_1):PAGE133
     2 PU_10GBE_LOM_PCI_DISABLE_N @BASEBOARD_FAB2_LIB.BASEBOARD_FAB2(SCH_1):PU_10GBE_LOM_PCI_DISABLE_N   I267 @BASEBOARD_FAB2_LIB.BASEBOARD_FAB2(SCH_1):PAGE133

R2N10 RES_0402-4.75K,1%,1/16W,EMPTY,A
     1 P3V3_STBY @BASEBOARD_FAB2_LIB.BASEBOARD_FAB2(SCH_1):P3V3_STBY    I27 @BASEBOARD_FAB2_LIB.BASEBOARD_FAB2(SCH_1):PAGE126
     2 FM_PCH_BMC_THERMTRIP_EXI_STRAP_ @BASEBOARD_FAB2_LIB.BASEBOARD_FAB2(SCH_1):FM_PCH_BMC_THERMTRIP_EXI_STRAP_N    I27 @BASEBOARD_FAB2_LIB.BASEBOARD_FAB2(SCH_1):PAGE126

R2N12 RES_0402-10.0K,1%,1/16W,EMPTY,A
     1    GND @BASEBOARD_FAB2_LIB.BASEBOARD_FAB2(SCH_1):GND   I122 @BASEBOARD_FAB2_LIB.BASEBOARD_FAB2(SCH_1):PAGE133
     2 PWRGD_SYS_PWROK @BASEBOARD_FAB2_LIB.BASEBOARD_FAB2(SCH_1):PWRGD_SYS_PWROK   I122 @BASEBOARD_FAB2_LIB.BASEBOARD_FAB2(SCH_1):PAGE133

R2N13 RES_0402-10.0K,1%,1/16W,CHIP,GA
     1 FM_BIOS_PREFRB2_GOOD @BASEBOARD_FAB2_LIB.BASEBOARD_FAB2(SCH_1):FM_BIOS_PREFRB2_GOOD    I75 @BASEBOARD_FAB2_LIB.BASEBOARD_FAB2(SCH_1):PAGE147
     2    GND @BASEBOARD_FAB2_LIB.BASEBOARD_FAB2(SCH_1):GND    I75 @BASEBOARD_FAB2_LIB.BASEBOARD_FAB2(SCH_1):PAGE147

R2N14 RES_0402-1.00K,1%,1/16W,EMPTY,A
     1 P3V3_STBY @BASEBOARD_FAB2_LIB.BASEBOARD_FAB2(SCH_1):P3V3_STBY    I83 @BASEBOARD_FAB2_LIB.BASEBOARD_FAB2(SCH_1):PAGE125
     2 FM_USB_P0_EN_BOOT_BIOS_STRAP_N @BASEBOARD_FAB2_LIB.BASEBOARD_FAB2(SCH_1):FM_USB_P0_EN_BOOT_BIOS_STRAP_N    I83 @BASEBOARD_FAB2_LIB.BASEBOARD_FAB2(SCH_1):PAGE125

R2N16 RES_0402-10.0K,1%,1/16W,CHIP,GA
     1 P3V3_STBY @BASEBOARD_FAB2_LIB.BASEBOARD_FAB2(SCH_1):P3V3_STBY   I247 @BASEBOARD_FAB2_LIB.BASEBOARD_FAB2(SCH_1):PAGE133
     2 PU_IRQ_VRALERT_N @BASEBOARD_FAB2_LIB.BASEBOARD_FAB2(SCH_1):PU_IRQ_VRALERT_N   I247 @BASEBOARD_FAB2_LIB.BASEBOARD_FAB2(SCH_1):PAGE133

R2N17 RES_0402-2.7K,1%,1/16W,CHIP,G2A
     1 P3V3_STBY @BASEBOARD_FAB2_LIB.BASEBOARD_FAB2(SCH_1):P3V3_STBY    I46 @BASEBOARD_FAB2_LIB.BASEBOARD_FAB2(SCH_1):PAGE164
     2 FM_BOARD_SKU_ID4 @BASEBOARD_FAB2_LIB.BASEBOARD_FAB2(SCH_1):FM_BOARD_SKU_ID4    I46 @BASEBOARD_FAB2_LIB.BASEBOARD_FAB2(SCH_1):PAGE164

R2N18 RES_0402-1.00K,1%,1/16W,CHIP,GA
     1 FM_BOARD_SKU_ID4 @BASEBOARD_FAB2_LIB.BASEBOARD_FAB2(SCH_1):FM_BOARD_SKU_ID4    I32 @BASEBOARD_FAB2_LIB.BASEBOARD_FAB2(SCH_1):PAGE164
     2    GND @BASEBOARD_FAB2_LIB.BASEBOARD_FAB2(SCH_1):GND    I32 @BASEBOARD_FAB2_LIB.BASEBOARD_FAB2(SCH_1):PAGE164

R2N19 RES_0402-49.9,1%,1/16W,CHIP,G2A
     1 SGPIO_PCH_SSATA_LOAD @BASEBOARD_FAB2_LIB.BASEBOARD_FAB2(SCH_1):SGPIO_PCH_SSATA_LOAD    I22 @BASEBOARD_FAB2_LIB.BASEBOARD_FAB2(SCH_1):PAGE178
     2 SGPIO_PCH_SSATA_LOAD_R @BASEBOARD_FAB2_LIB.BASEBOARD_FAB2(SCH_1):SGPIO_PCH_SSATA_LOAD_R    I22 @BASEBOARD_FAB2_LIB.BASEBOARD_FAB2(SCH_1):PAGE178

R2N20 RES_0402-0.0,5%,1/16W,CHIP,G21A
     1 SMB_LAN_STBY_LVC3_SDA_R2 @BASEBOARD_FAB2_LIB.BASEBOARD_FAB2(SCH_1):SMB_LAN_STBY_LVC3_SDA_R2   I171 @BASEBOARD_FAB2_LIB.BASEBOARD_FAB2(SCH_1):PAGE138
     2 SMB_LAN_STBY_LVC3_SDA @BASEBOARD_FAB2_LIB.BASEBOARD_FAB2(SCH_1):SMB_LAN_STBY_LVC3_SDA   I171 @BASEBOARD_FAB2_LIB.BASEBOARD_FAB2(SCH_1):PAGE138

R2N21 RES_0402-0.0,5%,1/16W,CHIP,G21A
     1 SMB_LAN_STBY_LVC3_SCL_R2 @BASEBOARD_FAB2_LIB.BASEBOARD_FAB2(SCH_1):SMB_LAN_STBY_LVC3_SCL_R2   I175 @BASEBOARD_FAB2_LIB.BASEBOARD_FAB2(SCH_1):PAGE138
     2 SMB_LAN_STBY_LVC3_SCL @BASEBOARD_FAB2_LIB.BASEBOARD_FAB2(SCH_1):SMB_LAN_STBY_LVC3_SCL   I175 @BASEBOARD_FAB2_LIB.BASEBOARD_FAB2(SCH_1):PAGE138

R2N22 RES_0402-49.9,1%,1/16W,CHIP,G2A
     1 SGPIO_PCH_SSATA_CLOCK @BASEBOARD_FAB2_LIB.BASEBOARD_FAB2(SCH_1):SGPIO_PCH_SSATA_CLOCK    I23 @BASEBOARD_FAB2_LIB.BASEBOARD_FAB2(SCH_1):PAGE178
     2 SGPIO_PCH_SSATA_CLOCK_R @BASEBOARD_FAB2_LIB.BASEBOARD_FAB2(SCH_1):SGPIO_PCH_SSATA_CLOCK_R    I23 @BASEBOARD_FAB2_LIB.BASEBOARD_FAB2(SCH_1):PAGE178

R2N23 RES_0402-10.0K,1%,1/16W,CHIP,GA
     1 P3V3_STBY @BASEBOARD_FAB2_LIB.BASEBOARD_FAB2(SCH_1):P3V3_STBY   I112 @BASEBOARD_FAB2_LIB.BASEBOARD_FAB2(SCH_1):PAGE135
     2 FM_QAT_EN_N @BASEBOARD_FAB2_LIB.BASEBOARD_FAB2(SCH_1):FM_QAT_EN_N   I112 @BASEBOARD_FAB2_LIB.BASEBOARD_FAB2(SCH_1):PAGE135

R2N24 RES_0402-1.00K,1%,1/16W,EMPTY,A
     1 FM_QAT_EN_N @BASEBOARD_FAB2_LIB.BASEBOARD_FAB2(SCH_1):FM_QAT_EN_N   I113 @BASEBOARD_FAB2_LIB.BASEBOARD_FAB2(SCH_1):PAGE135
     2    GND @BASEBOARD_FAB2_LIB.BASEBOARD_FAB2(SCH_1):GND   I113 @BASEBOARD_FAB2_LIB.BASEBOARD_FAB2(SCH_1):PAGE135

R2N25 RES_0402-51.1,1.0%,1/16W,CHIP,A
     1 FM_NMI_EVENT_N @BASEBOARD_FAB2_LIB.BASEBOARD_FAB2(SCH_1):FM_NMI_EVENT_N   I302 @BASEBOARD_FAB2_LIB.BASEBOARD_FAB2(SCH_1):PAGE157
     2 FM_BMC_NMI_N @BASEBOARD_FAB2_LIB.BASEBOARD_FAB2(SCH_1):FM_BMC_NMI_N   I302 @BASEBOARD_FAB2_LIB.BASEBOARD_FAB2(SCH_1):PAGE157

R2N26 RES_0402-33.2,1%,1/16W,CHIP,G2A
     1 FM_ADR_COMPLETE @BASEBOARD_FAB2_LIB.BASEBOARD_FAB2(SCH_1):FM_ADR_COMPLETE   I219 @BASEBOARD_FAB2_LIB.BASEBOARD_FAB2(SCH_1):PAGE120
     2 FM_ADR_COMPLETE_R1 @BASEBOARD_FAB2_LIB.BASEBOARD_FAB2(SCH_1):FM_ADR_COMPLETE_R1   I219 @BASEBOARD_FAB2_LIB.BASEBOARD_FAB2(SCH_1):PAGE120

R2N27 RES_0402-4.75K,1%,1/16W,CHIP,GA
     1   P3V3 @BASEBOARD_FAB2_LIB.BASEBOARD_FAB2(SCH_1):P3V3    I97 @BASEBOARD_FAB2_LIB.BASEBOARD_FAB2(SCH_1):PAGE157
     2 FM_BMC_NMI_N @BASEBOARD_FAB2_LIB.BASEBOARD_FAB2(SCH_1):FM_BMC_NMI_N    I97 @BASEBOARD_FAB2_LIB.BASEBOARD_FAB2(SCH_1):PAGE157

R2N28 RES_0402-10.0K,1%,1/16W,CHIP,GA
     1 P3V3_STBY @BASEBOARD_FAB2_LIB.BASEBOARD_FAB2(SCH_1):P3V3_STBY   I147 @BASEBOARD_FAB2_LIB.BASEBOARD_FAB2(SCH_1):PAGE136
     2 FM_PASSWORD_CLEAR_N @BASEBOARD_FAB2_LIB.BASEBOARD_FAB2(SCH_1):FM_PASSWORD_CLEAR_N   I147 @BASEBOARD_FAB2_LIB.BASEBOARD_FAB2(SCH_1):PAGE136

R2N29 RES_0402-1.5K,1%,1/16W,CHIP,G2A
     1 P3V3_STBY @BASEBOARD_FAB2_LIB.BASEBOARD_FAB2(SCH_1):P3V3_STBY   I352 @BASEBOARD_FAB2_LIB.BASEBOARD_FAB2(SCH_1):PAGE133
     2 FM_CPU1_RC_ERROR_N @BASEBOARD_FAB2_LIB.BASEBOARD_FAB2(SCH_1):FM_CPU1_RC_ERROR_N   I352 @BASEBOARD_FAB2_LIB.BASEBOARD_FAB2(SCH_1):PAGE133

R2N31 RES_0402-49.9,1%,1/16W,CHIP,G2A
     1 SGPIO_PCH_SATA_CLOCK @BASEBOARD_FAB2_LIB.BASEBOARD_FAB2(SCH_1):SGPIO_PCH_SATA_CLOCK    I11 @BASEBOARD_FAB2_LIB.BASEBOARD_FAB2(SCH_1):PAGE178
     2 SGPIO_PCH_SATA_CLOCK_R @BASEBOARD_FAB2_LIB.BASEBOARD_FAB2(SCH_1):SGPIO_PCH_SATA_CLOCK_R    I11 @BASEBOARD_FAB2_LIB.BASEBOARD_FAB2(SCH_1):PAGE178

R2N32 RES_0402-4.75K,1%,1/16W,CHIP,GA
     1 P3V3_STBY @BASEBOARD_FAB2_LIB.BASEBOARD_FAB2(SCH_1):P3V3_STBY   I341 @BASEBOARD_FAB2_LIB.BASEBOARD_FAB2(SCH_1):PAGE133
     2 FM_BIOS_SMI_ACTIVE_N @BASEBOARD_FAB2_LIB.BASEBOARD_FAB2(SCH_1):FM_BIOS_SMI_ACTIVE_N   I341 @BASEBOARD_FAB2_LIB.BASEBOARD_FAB2(SCH_1):PAGE133

R2P1 RES_0402-0.0,5%,1/16W,CHIP,G21A
     1 RMII_SPRNGVLLE_BMC_PCH_RXD1 @BASEBOARD_FAB2_LIB.BASEBOARD_FAB2(SCH_1):RMII_SPRNGVLLE_BMC_PCH_RXD1    I91 @BASEBOARD_FAB2_LIB.BASEBOARD_FAB2(SCH_1):PAGE121
     2 RMII_SPRNGVLLE_BMC_PCH_RXD1_R1 @BASEBOARD_FAB2_LIB.BASEBOARD_FAB2(SCH_1):RMII_SPRNGVLLE_BMC_PCH_RXD1_R1    I91 @BASEBOARD_FAB2_LIB.BASEBOARD_FAB2(SCH_1):PAGE121

R2P2 RES_0402-1.00K,1%,1/16W,CHIP,GA
     1 SPI_PCH_IO2 @BASEBOARD_FAB2_LIB.BASEBOARD_FAB2(SCH_1):SPI_PCH_IO2    I37 @BASEBOARD_FAB2_LIB.BASEBOARD_FAB2(SCH_1):PAGE111
     2 XDP_DEBUG_CONSENT_N @BASEBOARD_FAB2_LIB.BASEBOARD_FAB2(SCH_1):XDP_DEBUG_CONSENT_N    I37 @BASEBOARD_FAB2_LIB.BASEBOARD_FAB2(SCH_1):PAGE111

R2P3 RES_0402-4.75K,1%,1/16W,CHIP,GA
     1 P3V3_STBY @BASEBOARD_FAB2_LIB.BASEBOARD_FAB2(SCH_1):P3V3_STBY     I2 @BASEBOARD_FAB2_LIB.BASEBOARD_FAB2(SCH_1):PAGE170
     2 IRQ_FORCE_NM_THROTTLE_R_N @BASEBOARD_FAB2_LIB.BASEBOARD_FAB2(SCH_1):IRQ_FORCE_NM_THROTTLE_R_N     I2 @BASEBOARD_FAB2_LIB.BASEBOARD_FAB2(SCH_1):PAGE170

R2P4 RES_0402-33.2,1%,1/16W,CHIP,G2A
     1 IRQ_FORCE_NM_THROTTLE_R_N @BASEBOARD_FAB2_LIB.BASEBOARD_FAB2(SCH_1):IRQ_FORCE_NM_THROTTLE_R_N    I74 @BASEBOARD_FAB2_LIB.BASEBOARD_FAB2(SCH_1):PAGE170
     2 IRQ_FORCE_NM_THROTTLE_N @BASEBOARD_FAB2_LIB.BASEBOARD_FAB2(SCH_1):IRQ_FORCE_NM_THROTTLE_N    I74 @BASEBOARD_FAB2_LIB.BASEBOARD_FAB2(SCH_1):PAGE170

R2P5 RES_0402-4.75K,1%,1/16W,CHIP,GA
     1 P3V3_STBY @BASEBOARD_FAB2_LIB.BASEBOARD_FAB2(SCH_1):P3V3_STBY    I56 @BASEBOARD_FAB2_LIB.BASEBOARD_FAB2(SCH_1):PAGE170
     2 FM_PMBUS_ALERT_BUF_EN @BASEBOARD_FAB2_LIB.BASEBOARD_FAB2(SCH_1):FM_PMBUS_ALERT_BUF_EN    I56 @BASEBOARD_FAB2_LIB.BASEBOARD_FAB2(SCH_1):PAGE170

R2P8 RES_0402-4.75K,1%,1/16W,CHIP,GA
     1 P3V3_STBY @BASEBOARD_FAB2_LIB.BASEBOARD_FAB2(SCH_1):P3V3_STBY    I75 @BASEBOARD_FAB2_LIB.BASEBOARD_FAB2(SCH_1):PAGE170
     2 IRQ_SML1_PMBUS_ALERT_N @BASEBOARD_FAB2_LIB.BASEBOARD_FAB2(SCH_1):IRQ_SML1_PMBUS_ALERT_N    I75 @BASEBOARD_FAB2_LIB.BASEBOARD_FAB2(SCH_1):PAGE170

R2P11 RES_0402-1.00K,1%,1/16W,EMPTY,A
     1 FM_PMBUS_ALERT_BUF_EN_N @BASEBOARD_FAB2_LIB.BASEBOARD_FAB2(SCH_1):FM_PMBUS_ALERT_BUF_EN_N    I63 @BASEBOARD_FAB2_LIB.BASEBOARD_FAB2(SCH_1):PAGE170
     2    GND @BASEBOARD_FAB2_LIB.BASEBOARD_FAB2(SCH_1):GND    I63 @BASEBOARD_FAB2_LIB.BASEBOARD_FAB2(SCH_1):PAGE170

R2P12 RES_0402-0.0,5%,1/16W,EMPTY,G2A
     1 IRQ_DIMM_SAVE_LVT3_N @BASEBOARD_FAB2_LIB.BASEBOARD_FAB2(SCH_1):IRQ_DIMM_SAVE_LVT3_N    I23 @BASEBOARD_FAB2_LIB.BASEBOARD_FAB2(SCH_1):PAGE89
     2 FM_ADR_SMI_GPIO_N @BASEBOARD_FAB2_LIB.BASEBOARD_FAB2(SCH_1):FM_ADR_SMI_GPIO_N    I23 @BASEBOARD_FAB2_LIB.BASEBOARD_FAB2(SCH_1):PAGE89

R2P13 RES_0402-4.75K,1%,1/16W,CHIP,GA
     1 P3V3_STBY @BASEBOARD_FAB2_LIB.BASEBOARD_FAB2(SCH_1):P3V3_STBY    I61 @BASEBOARD_FAB2_LIB.BASEBOARD_FAB2(SCH_1):PAGE170
     2 FM_PMBUS_ALERT_BUF_EN_N @BASEBOARD_FAB2_LIB.BASEBOARD_FAB2(SCH_1):FM_PMBUS_ALERT_BUF_EN_N    I61 @BASEBOARD_FAB2_LIB.BASEBOARD_FAB2(SCH_1):PAGE170

R2P14 RES_0402-0.0,5%,1/16W,CHIP,G21A
     1 FM_M2_DET_LVC3 @BASEBOARD_FAB2_LIB.BASEBOARD_FAB2(SCH_1):FM_M2_DET_LVC3   I115 @BASEBOARD_FAB2_LIB.BASEBOARD_FAB2(SCH_1):PAGE185
     2 FM_SSATA_PCIE_M2_SEL @BASEBOARD_FAB2_LIB.BASEBOARD_FAB2(SCH_1):FM_SSATA_PCIE_M2_SEL   I115 @BASEBOARD_FAB2_LIB.BASEBOARD_FAB2(SCH_1):PAGE185

R2P15 RES_0402-10.0K,1%,1/16W,CHIP,GA
     1   P3V3 @BASEBOARD_FAB2_LIB.BASEBOARD_FAB2(SCH_1):P3V3   I111 @BASEBOARD_FAB2_LIB.BASEBOARD_FAB2(SCH_1):PAGE185
     2 FM_M2_SSD_PEDET @BASEBOARD_FAB2_LIB.BASEBOARD_FAB2(SCH_1):FM_M2_SSD_PEDET   I111 @BASEBOARD_FAB2_LIB.BASEBOARD_FAB2(SCH_1):PAGE185

R2P16 RES_0402-10.0K,1%,1/16W,CHIP,GA
     1 P3V3_STBY @BASEBOARD_FAB2_LIB.BASEBOARD_FAB2(SCH_1):P3V3_STBY   I113 @BASEBOARD_FAB2_LIB.BASEBOARD_FAB2(SCH_1):PAGE185
     2 FM_M2_DET_LVC3 @BASEBOARD_FAB2_LIB.BASEBOARD_FAB2(SCH_1):FM_M2_DET_LVC3   I113 @BASEBOARD_FAB2_LIB.BASEBOARD_FAB2(SCH_1):PAGE185

R2P17 RES_0402-4.75K,1%,1/16W,CHIP,GA
     1 P3V3_STBY @BASEBOARD_FAB2_LIB.BASEBOARD_FAB2(SCH_1):P3V3_STBY     I3 @BASEBOARD_FAB2_LIB.BASEBOARD_FAB2(SCH_1):PAGE134
     2 FM_PCH_BMC_THERMTRIP_N @BASEBOARD_FAB2_LIB.BASEBOARD_FAB2(SCH_1):FM_PCH_BMC_THERMTRIP_N     I3 @BASEBOARD_FAB2_LIB.BASEBOARD_FAB2(SCH_1):PAGE134

R2P18 RES_0402-10.0K,1%,1/16W,CHIP,GA
     1 P3V3_STBY @BASEBOARD_FAB2_LIB.BASEBOARD_FAB2(SCH_1):P3V3_STBY   I121 @BASEBOARD_FAB2_LIB.BASEBOARD_FAB2(SCH_1):PAGE196
     2 PWRGD_P5V_N @BASEBOARD_FAB2_LIB.BASEBOARD_FAB2(SCH_1):PWRGD_P5V_N   I121 @BASEBOARD_FAB2_LIB.BASEBOARD_FAB2(SCH_1):PAGE196

R2P19 RES_0402-10.0K,1%,1/16W,CHIP,GA
     1 P3V3_STBY @BASEBOARD_FAB2_LIB.BASEBOARD_FAB2(SCH_1):P3V3_STBY   I107 @BASEBOARD_FAB2_LIB.BASEBOARD_FAB2(SCH_1):PAGE135
     2 FM_DIS_ADR_DLY @BASEBOARD_FAB2_LIB.BASEBOARD_FAB2(SCH_1):FM_DIS_ADR_DLY   I107 @BASEBOARD_FAB2_LIB.BASEBOARD_FAB2(SCH_1):PAGE135

R2P20 RES_0402-100.0,1%,1/16W,CHIP,GA
     1 PWRGD_P5V_R @BASEBOARD_FAB2_LIB.BASEBOARD_FAB2(SCH_1):PWRGD_P5V_R    I65 @BASEBOARD_FAB2_LIB.BASEBOARD_FAB2(SCH_1):PAGE196
     2 PWRGD_P5V @BASEBOARD_FAB2_LIB.BASEBOARD_FAB2(SCH_1):PWRGD_P5V    I65 @BASEBOARD_FAB2_LIB.BASEBOARD_FAB2(SCH_1):PAGE196

R2P21 RES_0402-10.0K,1%,1/16W,CHIP,GA
     1 P3V3_STBY @BASEBOARD_FAB2_LIB.BASEBOARD_FAB2(SCH_1):P3V3_STBY   I122 @BASEBOARD_FAB2_LIB.BASEBOARD_FAB2(SCH_1):PAGE196
     2 PWRGD_P5V_R @BASEBOARD_FAB2_LIB.BASEBOARD_FAB2(SCH_1):PWRGD_P5V_R   I122 @BASEBOARD_FAB2_LIB.BASEBOARD_FAB2(SCH_1):PAGE196

R2P22 RES_0402-10.0K,1%,1/16W,CHIP,GA
     1 P3V3_STBY @BASEBOARD_FAB2_LIB.BASEBOARD_FAB2(SCH_1):P3V3_STBY   I360 @BASEBOARD_FAB2_LIB.BASEBOARD_FAB2(SCH_1):PAGE133
     2 FM_CPU1_RC_EN @BASEBOARD_FAB2_LIB.BASEBOARD_FAB2(SCH_1):FM_CPU1_RC_EN   I360 @BASEBOARD_FAB2_LIB.BASEBOARD_FAB2(SCH_1):PAGE133

R2R1 RES_0402-10.0K,1%,1/16W,CHIP,GA
     1 P3V3_STBY @BASEBOARD_FAB2_LIB.BASEBOARD_FAB2(SCH_1):P3V3_STBY    I34 @BASEBOARD_FAB2_LIB.BASEBOARD_FAB2(SCH_1):PAGE192
     2 PU_RST_PERST_BIT0 @BASEBOARD_FAB2_LIB.BASEBOARD_FAB2(SCH_1):PU_RST_PERST_BIT0    I34 @BASEBOARD_FAB2_LIB.BASEBOARD_FAB2(SCH_1):PAGE192

R2R2 RES_0402-33.2,1%,1/16W,CHIP,G2A
     1 RST_RSMRST_R_N @BASEBOARD_FAB2_LIB.BASEBOARD_FAB2(SCH_1):RST_RSMRST_R_N   I338 @BASEBOARD_FAB2_LIB.BASEBOARD_FAB2(SCH_1):PAGE190
     2 RST_RSMRST_N @BASEBOARD_FAB2_LIB.BASEBOARD_FAB2(SCH_1):RST_RSMRST_N   I338 @BASEBOARD_FAB2_LIB.BASEBOARD_FAB2(SCH_1):PAGE190

R2R3 RES_0402-10.0K,1%,1/16W,CHIP,GA
     1 P3V3_STBY @BASEBOARD_FAB2_LIB.BASEBOARD_FAB2(SCH_1):P3V3_STBY    I41 @BASEBOARD_FAB2_LIB.BASEBOARD_FAB2(SCH_1):PAGE192
     2 FM_PLD_DEBUG_MODE_N @BASEBOARD_FAB2_LIB.BASEBOARD_FAB2(SCH_1):FM_PLD_DEBUG_MODE_N    I41 @BASEBOARD_FAB2_LIB.BASEBOARD_FAB2(SCH_1):PAGE192

R2R4 RES_0402-0.0,5%,1/16W,CHIP,G21A
     1 FM_ADR_SMI_GPIO_R_N @BASEBOARD_FAB2_LIB.BASEBOARD_FAB2(SCH_1):FM_ADR_SMI_GPIO_R_N   I184 @BASEBOARD_FAB2_LIB.BASEBOARD_FAB2(SCH_1):PAGE191
     2 FM_ADR_SMI_GPIO_N @BASEBOARD_FAB2_LIB.BASEBOARD_FAB2(SCH_1):FM_ADR_SMI_GPIO_N   I184 @BASEBOARD_FAB2_LIB.BASEBOARD_FAB2(SCH_1):PAGE191

R2R5 RES_0402-1.00K,1%,1/16W,CHIP,GA
     1 P3V3_STBY @BASEBOARD_FAB2_LIB.BASEBOARD_FAB2(SCH_1):P3V3_STBY   I258 @BASEBOARD_FAB2_LIB.BASEBOARD_FAB2(SCH_1):PAGE133
     2 FM_PCH_PLD_DATA @BASEBOARD_FAB2_LIB.BASEBOARD_FAB2(SCH_1):FM_PCH_PLD_DATA   I258 @BASEBOARD_FAB2_LIB.BASEBOARD_FAB2(SCH_1):PAGE133

R2R6 RES_0402-51,5.0%,1/16W,CHIP,G2A
     1 SGPIO_BMC_DIN_R @BASEBOARD_FAB2_LIB.BASEBOARD_FAB2(SCH_1):SGPIO_BMC_DIN_R   I166 @BASEBOARD_FAB2_LIB.BASEBOARD_FAB2(SCH_1):PAGE191
     2 SGPIO_BMC_DIN @BASEBOARD_FAB2_LIB.BASEBOARD_FAB2(SCH_1):SGPIO_BMC_DIN   I166 @BASEBOARD_FAB2_LIB.BASEBOARD_FAB2(SCH_1):PAGE191

R2R7 RES_0402-4.75K,1%,1/16W,CHIP,GA
     1 P3V3_STBY @BASEBOARD_FAB2_LIB.BASEBOARD_FAB2(SCH_1):P3V3_STBY   I172 @BASEBOARD_FAB2_LIB.BASEBOARD_FAB2(SCH_1):PAGE191
     2 FM_FORCE_ADR_N @BASEBOARD_FAB2_LIB.BASEBOARD_FAB2(SCH_1):FM_FORCE_ADR_N   I172 @BASEBOARD_FAB2_LIB.BASEBOARD_FAB2(SCH_1):PAGE191

R2R8 887R2F-L-GP_SMD-RG-887R2F-L-GPA
     1 FM_MEZZB_PRSNT1_N @BASEBOARD_FAB2_LIB.BASEBOARD_FAB2(SCH_1):FM_MEZZB_PRSNT1_N   I175 @BASEBOARD_FAB2_LIB.BASEBOARD_FAB2(SCH_1):PAGE187
     2    GND @BASEBOARD_FAB2_LIB.BASEBOARD_FAB2(SCH_1):GND   I175 @BASEBOARD_FAB2_LIB.BASEBOARD_FAB2(SCH_1):PAGE187

R2R9 RES_0402-200.0,1%,1/16W,CHIP,GA
     1 FP_NMI_BTN_OUT_R_N @BASEBOARD_FAB2_LIB.BASEBOARD_FAB2(SCH_1):FP_NMI_BTN_OUT_R_N   I352 @BASEBOARD_FAB2_LIB.BASEBOARD_FAB2(SCH_1):PAGE157
     2 FP_NMI_BTN_OUT_N @BASEBOARD_FAB2_LIB.BASEBOARD_FAB2(SCH_1):FP_NMI_BTN_OUT_N   I352 @BASEBOARD_FAB2_LIB.BASEBOARD_FAB2(SCH_1):PAGE157

R2R10 RES_0402-33.2,1%,1/16W,CHIP,G2A
     1 FP_NMI_BTN_R_N @BASEBOARD_FAB2_LIB.BASEBOARD_FAB2(SCH_1):FP_NMI_BTN_R_N   I391 @BASEBOARD_FAB2_LIB.BASEBOARD_FAB2(SCH_1):PAGE157
     2 FP_NMI_BTN_N @BASEBOARD_FAB2_LIB.BASEBOARD_FAB2(SCH_1):FP_NMI_BTN_N   I391 @BASEBOARD_FAB2_LIB.BASEBOARD_FAB2(SCH_1):PAGE157

R2R11 RES_0402-1.00K,1%,1/16W,EMPTY,A
     1 SPI_PCH_IO2 @BASEBOARD_FAB2_LIB.BASEBOARD_FAB2(SCH_1):SPI_PCH_IO2    I11 @BASEBOARD_FAB2_LIB.BASEBOARD_FAB2(SCH_1):PAGE125
     2    GND @BASEBOARD_FAB2_LIB.BASEBOARD_FAB2(SCH_1):GND    I11 @BASEBOARD_FAB2_LIB.BASEBOARD_FAB2(SCH_1):PAGE125

R2R12 RES_0402-0.0,5%,1/16W,CHIP,G21A
     1 SPI_PCH_IO2 @BASEBOARD_FAB2_LIB.BASEBOARD_FAB2(SCH_1):SPI_PCH_IO2    I93 @BASEBOARD_FAB2_LIB.BASEBOARD_FAB2(SCH_1):PAGE154
     2 SPI_PCH_IO2_R1 @BASEBOARD_FAB2_LIB.BASEBOARD_FAB2(SCH_1):SPI_PCH_IO2_R1    I93 @BASEBOARD_FAB2_LIB.BASEBOARD_FAB2(SCH_1):PAGE154

R2T1 RES_0402-1.00K,1%,1/16W,EMPTY,A
     1 SPI_PCH_IO3 @BASEBOARD_FAB2_LIB.BASEBOARD_FAB2(SCH_1):SPI_PCH_IO3    I89 @BASEBOARD_FAB2_LIB.BASEBOARD_FAB2(SCH_1):PAGE125
     2    GND @BASEBOARD_FAB2_LIB.BASEBOARD_FAB2(SCH_1):GND    I89 @BASEBOARD_FAB2_LIB.BASEBOARD_FAB2(SCH_1):PAGE125

R2T2 RES_0402-0.0,5%,1/16W,CHIP,G21A
     1 SPI_PCH_IO3 @BASEBOARD_FAB2_LIB.BASEBOARD_FAB2(SCH_1):SPI_PCH_IO3    I92 @BASEBOARD_FAB2_LIB.BASEBOARD_FAB2(SCH_1):PAGE154
     2 SPI_PCH_IO3_R1 @BASEBOARD_FAB2_LIB.BASEBOARD_FAB2(SCH_1):SPI_PCH_IO3_R1    I92 @BASEBOARD_FAB2_LIB.BASEBOARD_FAB2(SCH_1):PAGE154

R2T3 RES_0402-4.75K,1%,1/16W,CHIP,GA
     1 P3V3_STBY @BASEBOARD_FAB2_LIB.BASEBOARD_FAB2(SCH_1):P3V3_STBY    I54 @BASEBOARD_FAB2_LIB.BASEBOARD_FAB2(SCH_1):PAGE170
     2 FM_FAST_PROCHOT_EN_N @BASEBOARD_FAB2_LIB.BASEBOARD_FAB2(SCH_1):FM_FAST_PROCHOT_EN_N    I54 @BASEBOARD_FAB2_LIB.BASEBOARD_FAB2(SCH_1):PAGE170

R2T4 RES_0402-1.0K,0.1%,1/16W,CHIP,A
     1 P3V3_STBY @BASEBOARD_FAB2_LIB.BASEBOARD_FAB2(SCH_1):P3V3_STBY   I152 @BASEBOARD_FAB2_LIB.BASEBOARD_FAB2(SCH_1):PAGE240
     2    GND @BASEBOARD_FAB2_LIB.BASEBOARD_FAB2(SCH_1):GND   I152 @BASEBOARD_FAB2_LIB.BASEBOARD_FAB2(SCH_1):PAGE240

R2T5 RES_0402-1.00K,1%,1/16W,CHIP,GA
     1 P3V3_STBY @BASEBOARD_FAB2_LIB.BASEBOARD_FAB2(SCH_1):P3V3_STBY   I326 @BASEBOARD_FAB2_LIB.BASEBOARD_FAB2(SCH_1):PAGE157
     2 H_CPU0_FAST_WAKE @BASEBOARD_FAB2_LIB.BASEBOARD_FAB2(SCH_1):H_CPU0_FAST_WAKE   I326 @BASEBOARD_FAB2_LIB.BASEBOARD_FAB2(SCH_1):PAGE157

R2T6 RES_0402-4.75K,1%,1/16W,CHIP,GA
     1 P3V3_STBY @BASEBOARD_FAB2_LIB.BASEBOARD_FAB2(SCH_1):P3V3_STBY   I127 @BASEBOARD_FAB2_LIB.BASEBOARD_FAB2(SCH_1):PAGE154
     2 FM_BACKUP_BIOS_SEL_N @BASEBOARD_FAB2_LIB.BASEBOARD_FAB2(SCH_1):FM_BACKUP_BIOS_SEL_N   I127 @BASEBOARD_FAB2_LIB.BASEBOARD_FAB2(SCH_1):PAGE154

R2T7 RES_0402-1.00K,1%,1/16W,CHIP,GA
     1 P3V3_STBY @BASEBOARD_FAB2_LIB.BASEBOARD_FAB2(SCH_1):P3V3_STBY   I327 @BASEBOARD_FAB2_LIB.BASEBOARD_FAB2(SCH_1):PAGE157
     2 H_CPU0_FAST_WAKE_LVT3_N @BASEBOARD_FAB2_LIB.BASEBOARD_FAB2(SCH_1):H_CPU0_FAST_WAKE_LVT3_N   I327 @BASEBOARD_FAB2_LIB.BASEBOARD_FAB2(SCH_1):PAGE157

R2T8 RES_0402-10.0K,1%,1/16W,CHIP,GA
     1 P3V3_STBY @BASEBOARD_FAB2_LIB.BASEBOARD_FAB2(SCH_1):P3V3_STBY   I106 @BASEBOARD_FAB2_LIB.BASEBOARD_FAB2(SCH_1):PAGE154
     2 SPI_SWITCH_CS0_N @BASEBOARD_FAB2_LIB.BASEBOARD_FAB2(SCH_1):SPI_SWITCH_CS0_N   I106 @BASEBOARD_FAB2_LIB.BASEBOARD_FAB2(SCH_1):PAGE154

R2T9 RES_0402-75,1.0%,1/16W,CHIP,G2A
     1 SPI_CS0_SECONDARY_N @BASEBOARD_FAB2_LIB.BASEBOARD_FAB2(SCH_1):SPI_CS0_SECONDARY_N    I62 @BASEBOARD_FAB2_LIB.BASEBOARD_FAB2(SCH_1):PAGE154
     2 SPI_CS0_SECONDARY_R_N @BASEBOARD_FAB2_LIB.BASEBOARD_FAB2(SCH_1):SPI_CS0_SECONDARY_R_N    I62 @BASEBOARD_FAB2_LIB.BASEBOARD_FAB2(SCH_1):PAGE154

R2T11 RES_0402-4.75K,1%,1/16W,CHIP,GA
     1 P3V3_STBY @BASEBOARD_FAB2_LIB.BASEBOARD_FAB2(SCH_1):P3V3_STBY   I105 @BASEBOARD_FAB2_LIB.BASEBOARD_FAB2(SCH_1):PAGE154
     2 FM_DUAL_BIOS_SEL_N @BASEBOARD_FAB2_LIB.BASEBOARD_FAB2(SCH_1):FM_DUAL_BIOS_SEL_N   I105 @BASEBOARD_FAB2_LIB.BASEBOARD_FAB2(SCH_1):PAGE154

R2T13 RES_0402-200.0,1%,1/16W,CHIP,GA
     1 SPI_CS0_PRIMARY_N @BASEBOARD_FAB2_LIB.BASEBOARD_FAB2(SCH_1):SPI_CS0_PRIMARY_N   I101 @BASEBOARD_FAB2_LIB.BASEBOARD_FAB2(SCH_1):PAGE154
     2 SPI_CS0_PRIMARY_R_N @BASEBOARD_FAB2_LIB.BASEBOARD_FAB2(SCH_1):SPI_CS0_PRIMARY_R_N   I101 @BASEBOARD_FAB2_LIB.BASEBOARD_FAB2(SCH_1):PAGE154

R2T16 RES_0402-75,1.0%,1/16W,CHIP,G2A
     1 H_CPU_ERR0_GTL_R_N @BASEBOARD_FAB2_LIB.BASEBOARD_FAB2(SCH_1):H_CPU_ERR0_GTL_R_N    I67 @BASEBOARD_FAB2_LIB.BASEBOARD_FAB2(SCH_1):PAGE93
     2 H_CPU_ERR0_GTL_N @BASEBOARD_FAB2_LIB.BASEBOARD_FAB2(SCH_1):H_CPU_ERR0_GTL_N    I67 @BASEBOARD_FAB2_LIB.BASEBOARD_FAB2(SCH_1):PAGE93

R2T17 RES_0402-0.0,5%,1/16W,CHIP,G21A
     1 H_CPU0_ERR0_G_N @BASEBOARD_FAB2_LIB.BASEBOARD_FAB2(SCH_1):H_CPU0_ERR0_G_N    I23 @BASEBOARD_FAB2_LIB.BASEBOARD_FAB2(SCH_1):PAGE93
     2 H_CPU_ERR0_GTL_R_N @BASEBOARD_FAB2_LIB.BASEBOARD_FAB2(SCH_1):H_CPU_ERR0_GTL_R_N    I23 @BASEBOARD_FAB2_LIB.BASEBOARD_FAB2(SCH_1):PAGE93

R2T18 RES_0402-49.9,1%,1/16W,CHIP,G2A
     1 RST_BMC_SYSRST_BTN_OUT_B_R_N @BASEBOARD_FAB2_LIB.BASEBOARD_FAB2(SCH_1):RST_BMC_SYSRST_BTN_OUT_B_R_N   I288 @BASEBOARD_FAB2_LIB.BASEBOARD_FAB2(SCH_1):PAGE156
     2 RST_BMC_SYSRST_BTN_OUT_B_N @BASEBOARD_FAB2_LIB.BASEBOARD_FAB2(SCH_1):RST_BMC_SYSRST_BTN_OUT_B_N   I288 @BASEBOARD_FAB2_LIB.BASEBOARD_FAB2(SCH_1):PAGE156

R2T19 RES_0402-200.0,1%,1/16W,CHIP,GA
     1 PVCCIO_CPU0 @BASEBOARD_FAB2_LIB.BASEBOARD_FAB2(SCH_1):PVCCIO_CPU0    I63 @BASEBOARD_FAB2_LIB.BASEBOARD_FAB2(SCH_1):PAGE93
     2 H_CPU_ERR0_GTL_R_N @BASEBOARD_FAB2_LIB.BASEBOARD_FAB2(SCH_1):H_CPU_ERR0_GTL_R_N    I63 @BASEBOARD_FAB2_LIB.BASEBOARD_FAB2(SCH_1):PAGE93

R2T20 RES_0402-0.0,5%,1/16W,CHIP,G21A
     1 H_CPU1_ERR0_G_N @BASEBOARD_FAB2_LIB.BASEBOARD_FAB2(SCH_1):H_CPU1_ERR0_G_N    I16 @BASEBOARD_FAB2_LIB.BASEBOARD_FAB2(SCH_1):PAGE93
     2 H_CPU_ERR0_GTL_R_N @BASEBOARD_FAB2_LIB.BASEBOARD_FAB2(SCH_1):H_CPU_ERR0_GTL_R_N    I16 @BASEBOARD_FAB2_LIB.BASEBOARD_FAB2(SCH_1):PAGE93

R2T21 RES_0603-2.2,1.0%,1/10W,CHIP,GA
     1 P3V3_STBY_MNG @BASEBOARD_FAB2_LIB.BASEBOARD_FAB2(SCH_1):P3V3_STBY_MNG   I105 @BASEBOARD_FAB2_LIB.BASEBOARD_FAB2(SCH_1):PAGE101
     2 P3V3_STBY_MNG_CPU @BASEBOARD_FAB2_LIB.BASEBOARD_FAB2(SCH_1):P3V3_STBY_MNG_CPU   I105 @BASEBOARD_FAB2_LIB.BASEBOARD_FAB2(SCH_1):PAGE101

R2T22 RES_0402-10.0K,1%,1/16W,CHIP,GA
     1 P3V3_STBY @BASEBOARD_FAB2_LIB.BASEBOARD_FAB2(SCH_1):P3V3_STBY   I210 @BASEBOARD_FAB2_LIB.BASEBOARD_FAB2(SCH_1):PAGE156
     2 RST_BMC_SYSRST_BTN_OUT_B_R_N @BASEBOARD_FAB2_LIB.BASEBOARD_FAB2(SCH_1):RST_BMC_SYSRST_BTN_OUT_B_R_N   I210 @BASEBOARD_FAB2_LIB.BASEBOARD_FAB2(SCH_1):PAGE156

R2T23 RES_0603-2.2,1.0%,1/10W,CHIP,GA
     1 P3V3_STBY_MNG @BASEBOARD_FAB2_LIB.BASEBOARD_FAB2(SCH_1):P3V3_STBY_MNG    I94 @BASEBOARD_FAB2_LIB.BASEBOARD_FAB2(SCH_1):PAGE101
     2 P3V3_STBY_MNG_RGMII @BASEBOARD_FAB2_LIB.BASEBOARD_FAB2(SCH_1):P3V3_STBY_MNG_RGMII    I94 @BASEBOARD_FAB2_LIB.BASEBOARD_FAB2(SCH_1):PAGE101

R2T25 RES_0402-1.00K,1%,1/16W,CHIP,GA
     1 PD_CKMNG_OE @BASEBOARD_FAB2_LIB.BASEBOARD_FAB2(SCH_1):PD_CKMNG_OE    I48 @BASEBOARD_FAB2_LIB.BASEBOARD_FAB2(SCH_1):PAGE101
     2    GND @BASEBOARD_FAB2_LIB.BASEBOARD_FAB2(SCH_1):GND    I48 @BASEBOARD_FAB2_LIB.BASEBOARD_FAB2(SCH_1):PAGE101

R2T26 RES_0402-200.0,1%,1/16W,CHIP,GA
     1 PVCCIO_CPU0 @BASEBOARD_FAB2_LIB.BASEBOARD_FAB2(SCH_1):PVCCIO_CPU0    I87 @BASEBOARD_FAB2_LIB.BASEBOARD_FAB2(SCH_1):PAGE93
     2 H_CPU_ERR1_GTL_R_N @BASEBOARD_FAB2_LIB.BASEBOARD_FAB2(SCH_1):H_CPU_ERR1_GTL_R_N    I87 @BASEBOARD_FAB2_LIB.BASEBOARD_FAB2(SCH_1):PAGE93

R2T27 RES_0402-0.0,5%,1/16W,CHIP,G21A
     1 H_CPU1_ERR1_G_N @BASEBOARD_FAB2_LIB.BASEBOARD_FAB2(SCH_1):H_CPU1_ERR1_G_N    I13 @BASEBOARD_FAB2_LIB.BASEBOARD_FAB2(SCH_1):PAGE93
     2 H_CPU_ERR1_GTL_R_N @BASEBOARD_FAB2_LIB.BASEBOARD_FAB2(SCH_1):H_CPU_ERR1_GTL_R_N    I13 @BASEBOARD_FAB2_LIB.BASEBOARD_FAB2(SCH_1):PAGE93

R2T28 RES_0402-33.2,1%,1/16W,CHIP,G2A
     1 FM_PCH_PWRBTN_R_N @BASEBOARD_FAB2_LIB.BASEBOARD_FAB2(SCH_1):FM_PCH_PWRBTN_R_N   I289 @BASEBOARD_FAB2_LIB.BASEBOARD_FAB2(SCH_1):PAGE156
     2 FM_PCH_PWRBTN_N @BASEBOARD_FAB2_LIB.BASEBOARD_FAB2(SCH_1):FM_PCH_PWRBTN_N   I289 @BASEBOARD_FAB2_LIB.BASEBOARD_FAB2(SCH_1):PAGE156

R2T29 RES_0402-2.21K,1%,1/16W,CHIP,GA
     1 P3V3_STBY @BASEBOARD_FAB2_LIB.BASEBOARD_FAB2(SCH_1):P3V3_STBY   I298 @BASEBOARD_FAB2_LIB.BASEBOARD_FAB2(SCH_1):PAGE157
     2 IRQ_OOB_MGMT_RISER_ALERT_N @BASEBOARD_FAB2_LIB.BASEBOARD_FAB2(SCH_1):IRQ_OOB_MGMT_RISER_ALERT_N   I298 @BASEBOARD_FAB2_LIB.BASEBOARD_FAB2(SCH_1):PAGE157

R2T30 RES_0402-33.2,1%,1/16W,CHIP,G2A
     1 FM_CPU_ERR0_LVT3_K_N @BASEBOARD_FAB2_LIB.BASEBOARD_FAB2(SCH_1):FM_CPU_ERR0_LVT3_K_N    I42 @BASEBOARD_FAB2_LIB.BASEBOARD_FAB2(SCH_1):PAGE93
     2 FM_CPU_ERR0_LVT3_N @BASEBOARD_FAB2_LIB.BASEBOARD_FAB2(SCH_1):FM_CPU_ERR0_LVT3_N    I42 @BASEBOARD_FAB2_LIB.BASEBOARD_FAB2(SCH_1):PAGE93

R2T31 RES_0402-75,1.0%,1/16W,CHIP,G2A
     1 H_CPU_ERR1_GTL_R_N @BASEBOARD_FAB2_LIB.BASEBOARD_FAB2(SCH_1):H_CPU_ERR1_GTL_R_N    I68 @BASEBOARD_FAB2_LIB.BASEBOARD_FAB2(SCH_1):PAGE93
     2 H_CPU_ERR1_GTL_N @BASEBOARD_FAB2_LIB.BASEBOARD_FAB2(SCH_1):H_CPU_ERR1_GTL_N    I68 @BASEBOARD_FAB2_LIB.BASEBOARD_FAB2(SCH_1):PAGE93

R2T32 RES_0402-0.0,5%,1/16W,CHIP,G21A
     1 H_CPU0_ERR1_G_N @BASEBOARD_FAB2_LIB.BASEBOARD_FAB2(SCH_1):H_CPU0_ERR1_G_N    I15 @BASEBOARD_FAB2_LIB.BASEBOARD_FAB2(SCH_1):PAGE93
     2 H_CPU_ERR1_GTL_R_N @BASEBOARD_FAB2_LIB.BASEBOARD_FAB2(SCH_1):H_CPU_ERR1_GTL_R_N    I15 @BASEBOARD_FAB2_LIB.BASEBOARD_FAB2(SCH_1):PAGE93

R2T33 RES_0402-33.2,1%,1/16W,CHIP,G2A
     1 FM_CPU_ERR1_LVT3_K_N @BASEBOARD_FAB2_LIB.BASEBOARD_FAB2(SCH_1):FM_CPU_ERR1_LVT3_K_N    I40 @BASEBOARD_FAB2_LIB.BASEBOARD_FAB2(SCH_1):PAGE93
     2 FM_CPU_ERR1_LVT3_N @BASEBOARD_FAB2_LIB.BASEBOARD_FAB2(SCH_1):FM_CPU_ERR1_LVT3_N    I40 @BASEBOARD_FAB2_LIB.BASEBOARD_FAB2(SCH_1):PAGE93

R2T34 RES_0402-4.75K,1%,1/16W,CHIP,GA
     1 P3V3_STBY @BASEBOARD_FAB2_LIB.BASEBOARD_FAB2(SCH_1):P3V3_STBY   I206 @BASEBOARD_FAB2_LIB.BASEBOARD_FAB2(SCH_1):PAGE156
     2 FM_BMC_PWRBTN_OUT_N @BASEBOARD_FAB2_LIB.BASEBOARD_FAB2(SCH_1):FM_BMC_PWRBTN_OUT_N   I206 @BASEBOARD_FAB2_LIB.BASEBOARD_FAB2(SCH_1):PAGE156

R2T35 RES_0402-4.75K,1%,1/16W,CHIP,GA
     1 P3V3_STBY @BASEBOARD_FAB2_LIB.BASEBOARD_FAB2(SCH_1):P3V3_STBY   I207 @BASEBOARD_FAB2_LIB.BASEBOARD_FAB2(SCH_1):PAGE156
     2 RST_BMC_SYSRST_BTN_OUT_N @BASEBOARD_FAB2_LIB.BASEBOARD_FAB2(SCH_1):RST_BMC_SYSRST_BTN_OUT_N   I207 @BASEBOARD_FAB2_LIB.BASEBOARD_FAB2(SCH_1):PAGE156

R2T36 374R2F-1-GP_SMD-RG-374R2F-1-GPA
     1   P3V3 @BASEBOARD_FAB2_LIB.BASEBOARD_FAB2(SCH_1):P3V3   I148 @BASEBOARD_FAB2_LIB.BASEBOARD_FAB2(SCH_1):PAGE93
     2 P0V7_GTL2104_5_VREF @BASEBOARD_FAB2_LIB.BASEBOARD_FAB2(SCH_1):P0V7_GTL2104_5_VREF   I148 @BASEBOARD_FAB2_LIB.BASEBOARD_FAB2(SCH_1):PAGE93

R2T37 RES_0402-200.0,1%,1/16W,CHIP,GA
     1 PVCCIO_CPU0 @BASEBOARD_FAB2_LIB.BASEBOARD_FAB2(SCH_1):PVCCIO_CPU0    I94 @BASEBOARD_FAB2_LIB.BASEBOARD_FAB2(SCH_1):PAGE92
     2 H_CPU_ERR2_G_R_N @BASEBOARD_FAB2_LIB.BASEBOARD_FAB2(SCH_1):H_CPU_ERR2_G_R_N    I94 @BASEBOARD_FAB2_LIB.BASEBOARD_FAB2(SCH_1):PAGE92

R2T38 RES_0402-33.2,1%,1/16W,CHIP,G2A
     1 FM_CPU0_PROCHOT_LVT3_K_N @BASEBOARD_FAB2_LIB.BASEBOARD_FAB2(SCH_1):FM_CPU0_PROCHOT_LVT3_K_N    I39 @BASEBOARD_FAB2_LIB.BASEBOARD_FAB2(SCH_1):PAGE93
     2 FM_CPU0_PROCHOT_LVT3_N @BASEBOARD_FAB2_LIB.BASEBOARD_FAB2(SCH_1):FM_CPU0_PROCHOT_LVT3_N    I39 @BASEBOARD_FAB2_LIB.BASEBOARD_FAB2(SCH_1):PAGE93

R2T39 RES_0402-100.0,1%,1/16W,CHIP,GA
     1 P0V7_GTL2104_5_VREF @BASEBOARD_FAB2_LIB.BASEBOARD_FAB2(SCH_1):P0V7_GTL2104_5_VREF    I98 @BASEBOARD_FAB2_LIB.BASEBOARD_FAB2(SCH_1):PAGE93
     2    GND @BASEBOARD_FAB2_LIB.BASEBOARD_FAB2(SCH_1):GND    I98 @BASEBOARD_FAB2_LIB.BASEBOARD_FAB2(SCH_1):PAGE93

R2T40 RES_0402-0.0,5%,1/16W,CHIP,G21A
     1 H_CPU0_ERR2_G_N @BASEBOARD_FAB2_LIB.BASEBOARD_FAB2(SCH_1):H_CPU0_ERR2_G_N    I93 @BASEBOARD_FAB2_LIB.BASEBOARD_FAB2(SCH_1):PAGE92
     2 H_CPU_ERR2_G_R_N @BASEBOARD_FAB2_LIB.BASEBOARD_FAB2(SCH_1):H_CPU_ERR2_G_R_N    I93 @BASEBOARD_FAB2_LIB.BASEBOARD_FAB2(SCH_1):PAGE92

R2T41 RES_0402-22.1,1.0%,1/16W,CHIP,A
     1 IRQ_FORCE_NM_THROTTLE_N @BASEBOARD_FAB2_LIB.BASEBOARD_FAB2(SCH_1):IRQ_FORCE_NM_THROTTLE_N   I136 @BASEBOARD_FAB2_LIB.BASEBOARD_FAB2(SCH_1):PAGE145
     2 FM_BMC_SYS_THROTTLE_R_N @BASEBOARD_FAB2_LIB.BASEBOARD_FAB2(SCH_1):FM_BMC_SYS_THROTTLE_R_N   I136 @BASEBOARD_FAB2_LIB.BASEBOARD_FAB2(SCH_1):PAGE145

R2T42 RES_0402-22.1,1.0%,1/16W,CHIP,A
     1 CLK_50M_CKMNG_OCP_R @BASEBOARD_FAB2_LIB.BASEBOARD_FAB2(SCH_1):CLK_50M_CKMNG_OCP_R   I124 @BASEBOARD_FAB2_LIB.BASEBOARD_FAB2(SCH_1):PAGE101
     2 CLK_50M_CKMNG_OCP @BASEBOARD_FAB2_LIB.BASEBOARD_FAB2(SCH_1):CLK_50M_CKMNG_OCP   I124 @BASEBOARD_FAB2_LIB.BASEBOARD_FAB2(SCH_1):PAGE101

R2T43 RES_0402-75,1.0%,1/16W,CHIP,G2A
     1 H_CPU_ERR2_G_R_N @BASEBOARD_FAB2_LIB.BASEBOARD_FAB2(SCH_1):H_CPU_ERR2_G_R_N    I96 @BASEBOARD_FAB2_LIB.BASEBOARD_FAB2(SCH_1):PAGE92
     2 H_CPU_ERR2_GTL_N @BASEBOARD_FAB2_LIB.BASEBOARD_FAB2(SCH_1):H_CPU_ERR2_GTL_N    I96 @BASEBOARD_FAB2_LIB.BASEBOARD_FAB2(SCH_1):PAGE92

R2T44 RES_0402-0.0,5%,1/16W,CHIP,G21A
     1 H_CPU1_ERR2_G_N @BASEBOARD_FAB2_LIB.BASEBOARD_FAB2(SCH_1):H_CPU1_ERR2_G_N    I92 @BASEBOARD_FAB2_LIB.BASEBOARD_FAB2(SCH_1):PAGE92
     2 H_CPU_ERR2_G_R_N @BASEBOARD_FAB2_LIB.BASEBOARD_FAB2(SCH_1):H_CPU_ERR2_G_R_N    I92 @BASEBOARD_FAB2_LIB.BASEBOARD_FAB2(SCH_1):PAGE92

R2T46 RES_0402-22.1,1.0%,1/16W,CHIP,A
     1 CLK_50M_CKMNG_BMC_1_R @BASEBOARD_FAB2_LIB.BASEBOARD_FAB2(SCH_1):CLK_50M_CKMNG_BMC_1_R   I125 @BASEBOARD_FAB2_LIB.BASEBOARD_FAB2(SCH_1):PAGE101
     2 CLK_50M_CKMNG_BMC_1 @BASEBOARD_FAB2_LIB.BASEBOARD_FAB2(SCH_1):CLK_50M_CKMNG_BMC_1   I125 @BASEBOARD_FAB2_LIB.BASEBOARD_FAB2(SCH_1):PAGE101

R2T47 RES_0402-33.2,1%,1/16W,CHIP,G2A
     1 CLK_25M_CPLD_R @BASEBOARD_FAB2_LIB.BASEBOARD_FAB2(SCH_1):CLK_25M_CPLD_R   I130 @BASEBOARD_FAB2_LIB.BASEBOARD_FAB2(SCH_1):PAGE101
     2 CLK_25M_CPLD @BASEBOARD_FAB2_LIB.BASEBOARD_FAB2(SCH_1):CLK_25M_CPLD   I130 @BASEBOARD_FAB2_LIB.BASEBOARD_FAB2(SCH_1):PAGE101

R2T49 RES_0402-20.0,1%,1/16W,CHIP,G2A
     1 SMB_BMC_PMBUS_STBY_LVC3_SDA_R @BASEBOARD_FAB2_LIB.BASEBOARD_FAB2(SCH_1):SMB_BMC_PMBUS_STBY_LVC3_SDA_R   I219 @BASEBOARD_FAB2_LIB.BASEBOARD_FAB2(SCH_1):PAGE159
     2 SMB_BMC_PMBUS_STBY_LVC3_SDA @BASEBOARD_FAB2_LIB.BASEBOARD_FAB2(SCH_1):SMB_BMC_PMBUS_STBY_LVC3_SDA   I219 @BASEBOARD_FAB2_LIB.BASEBOARD_FAB2(SCH_1):PAGE159

R2T50 RES_0402-1.00K,1%,1/16W,CHIP,GA
     1 PD_GTL2104_4_DIR @BASEBOARD_FAB2_LIB.BASEBOARD_FAB2(SCH_1):PD_GTL2104_4_DIR   I127 @BASEBOARD_FAB2_LIB.BASEBOARD_FAB2(SCH_1):PAGE93
     2    GND @BASEBOARD_FAB2_LIB.BASEBOARD_FAB2(SCH_1):GND   I127 @BASEBOARD_FAB2_LIB.BASEBOARD_FAB2(SCH_1):PAGE93

R2T52 RES_0603-2.2,1.0%,1/10W,CHIP,GA
     1 P3V3_STBY_MNG @BASEBOARD_FAB2_LIB.BASEBOARD_FAB2(SCH_1):P3V3_STBY_MNG    I95 @BASEBOARD_FAB2_LIB.BASEBOARD_FAB2(SCH_1):PAGE101
     2 P3V3_STBY_MNG_RMII @BASEBOARD_FAB2_LIB.BASEBOARD_FAB2(SCH_1):P3V3_STBY_MNG_RMII    I95 @BASEBOARD_FAB2_LIB.BASEBOARD_FAB2(SCH_1):PAGE101

R2T53 RES_0402-665,1.0%,1/16W,CHIP,GA
     1 P3V3_STBY @BASEBOARD_FAB2_LIB.BASEBOARD_FAB2(SCH_1):P3V3_STBY    I83 @BASEBOARD_FAB2_LIB.BASEBOARD_FAB2(SCH_1):PAGE138
     2 SMB_BMC_PMBUS_STBY_LVC3_SDA @BASEBOARD_FAB2_LIB.BASEBOARD_FAB2(SCH_1):SMB_BMC_PMBUS_STBY_LVC3_SDA    I83 @BASEBOARD_FAB2_LIB.BASEBOARD_FAB2(SCH_1):PAGE138

R2T54 RES_0402-665,1.0%,1/16W,CHIP,GA
     1 P3V3_STBY @BASEBOARD_FAB2_LIB.BASEBOARD_FAB2(SCH_1):P3V3_STBY    I84 @BASEBOARD_FAB2_LIB.BASEBOARD_FAB2(SCH_1):PAGE138
     2 SMB_BMC_PMBUS_STBY_LVC3_SCL @BASEBOARD_FAB2_LIB.BASEBOARD_FAB2(SCH_1):SMB_BMC_PMBUS_STBY_LVC3_SCL    I84 @BASEBOARD_FAB2_LIB.BASEBOARD_FAB2(SCH_1):PAGE138

R2T57 RES_0402-0.0,5%,1/16W,EMPTY,G2A
     1 H_CPU_ERR0_PCH_N @BASEBOARD_FAB2_LIB.BASEBOARD_FAB2(SCH_1):H_CPU_ERR0_PCH_N    I88 @BASEBOARD_FAB2_LIB.BASEBOARD_FAB2(SCH_1):PAGE93
     2 H_CPU_ERR0_GTL_R_N @BASEBOARD_FAB2_LIB.BASEBOARD_FAB2(SCH_1):H_CPU_ERR0_GTL_R_N    I88 @BASEBOARD_FAB2_LIB.BASEBOARD_FAB2(SCH_1):PAGE93

R2T58 RES_0402-0.0,5%,1/16W,EMPTY,G2A
     1 H_CPU_ERR0_PCH_N @BASEBOARD_FAB2_LIB.BASEBOARD_FAB2(SCH_1):H_CPU_ERR0_PCH_N    I94 @BASEBOARD_FAB2_LIB.BASEBOARD_FAB2(SCH_1):PAGE93
     2 FM_CPU_ERR0_LVT3_K_N @BASEBOARD_FAB2_LIB.BASEBOARD_FAB2(SCH_1):FM_CPU_ERR0_LVT3_K_N    I94 @BASEBOARD_FAB2_LIB.BASEBOARD_FAB2(SCH_1):PAGE93

R2T59 RES_0402-0.0,5%,1/16W,EMPTY,G2A
     1 H_CPU0_PROCHOT_G_N @BASEBOARD_FAB2_LIB.BASEBOARD_FAB2(SCH_1):H_CPU0_PROCHOT_G_N   I107 @BASEBOARD_FAB2_LIB.BASEBOARD_FAB2(SCH_1):PAGE93
     2 H_CPU0_PROCHOT_G_PCH_N @BASEBOARD_FAB2_LIB.BASEBOARD_FAB2(SCH_1):H_CPU0_PROCHOT_G_PCH_N   I107 @BASEBOARD_FAB2_LIB.BASEBOARD_FAB2(SCH_1):PAGE93

R2T60 RES_0402-0.0,5%,1/16W,CHIP,G21A
     1 H_CPU0_PROCHOT_G_N @BASEBOARD_FAB2_LIB.BASEBOARD_FAB2(SCH_1):H_CPU0_PROCHOT_G_N   I103 @BASEBOARD_FAB2_LIB.BASEBOARD_FAB2(SCH_1):PAGE93
     2 H_CPU0_PROCHOT_G_R_N @BASEBOARD_FAB2_LIB.BASEBOARD_FAB2(SCH_1):H_CPU0_PROCHOT_G_R_N   I103 @BASEBOARD_FAB2_LIB.BASEBOARD_FAB2(SCH_1):PAGE93

R2T61 RES_0402-0.0,5%,1/16W,EMPTY,G2A
     1 H_CPU_ERR1_PCH_N @BASEBOARD_FAB2_LIB.BASEBOARD_FAB2(SCH_1):H_CPU_ERR1_PCH_N    I89 @BASEBOARD_FAB2_LIB.BASEBOARD_FAB2(SCH_1):PAGE93
     2 H_CPU_ERR1_GTL_R_N @BASEBOARD_FAB2_LIB.BASEBOARD_FAB2(SCH_1):H_CPU_ERR1_GTL_R_N    I89 @BASEBOARD_FAB2_LIB.BASEBOARD_FAB2(SCH_1):PAGE93

R2T62 RES_0402-0.0,5%,1/16W,EMPTY,G2A
     1 H_CPU_ERR1_PCH_N @BASEBOARD_FAB2_LIB.BASEBOARD_FAB2(SCH_1):H_CPU_ERR1_PCH_N    I93 @BASEBOARD_FAB2_LIB.BASEBOARD_FAB2(SCH_1):PAGE93
     2 FM_CPU_ERR1_LVT3_K_N @BASEBOARD_FAB2_LIB.BASEBOARD_FAB2(SCH_1):FM_CPU_ERR1_LVT3_K_N    I93 @BASEBOARD_FAB2_LIB.BASEBOARD_FAB2(SCH_1):PAGE93

R2T63 RES_0402-0.0,5%,1/16W,EMPTY,G2A
     1 FM_CPU_ERR1_LVT3_N @BASEBOARD_FAB2_LIB.BASEBOARD_FAB2(SCH_1):FM_CPU_ERR1_LVT3_N   I133 @BASEBOARD_FAB2_LIB.BASEBOARD_FAB2(SCH_1):PAGE93
     2 FM_CPU_ERR1_PCH_N @BASEBOARD_FAB2_LIB.BASEBOARD_FAB2(SCH_1):FM_CPU_ERR1_PCH_N   I133 @BASEBOARD_FAB2_LIB.BASEBOARD_FAB2(SCH_1):PAGE93

R2T64 RES_0402-0.0,5%,1/16W,CHIP,G21A
     1 FM_CPU_ERR1_LVT3_N @BASEBOARD_FAB2_LIB.BASEBOARD_FAB2(SCH_1):FM_CPU_ERR1_LVT3_N   I121 @BASEBOARD_FAB2_LIB.BASEBOARD_FAB2(SCH_1):PAGE93
     2 FM_CPU_ERR1_LVT3_BMC_N @BASEBOARD_FAB2_LIB.BASEBOARD_FAB2(SCH_1):FM_CPU_ERR1_LVT3_BMC_N   I121 @BASEBOARD_FAB2_LIB.BASEBOARD_FAB2(SCH_1):PAGE93

R2T65 RES_0402-0.0,5%,1/16W,CHIP,G21A
     1 FM_CPU_ERR0_LVT3_R_N @BASEBOARD_FAB2_LIB.BASEBOARD_FAB2(SCH_1):FM_CPU_ERR0_LVT3_R_N   I111 @BASEBOARD_FAB2_LIB.BASEBOARD_FAB2(SCH_1):PAGE93
     2 FM_CPU_ERR0_LVT3_K_N @BASEBOARD_FAB2_LIB.BASEBOARD_FAB2(SCH_1):FM_CPU_ERR0_LVT3_K_N   I111 @BASEBOARD_FAB2_LIB.BASEBOARD_FAB2(SCH_1):PAGE93

R2T66 RES_0402-0.0,5%,1/16W,CHIP,G21A
     1 FM_CPU_ERR1_LVT3_R_N @BASEBOARD_FAB2_LIB.BASEBOARD_FAB2(SCH_1):FM_CPU_ERR1_LVT3_R_N   I112 @BASEBOARD_FAB2_LIB.BASEBOARD_FAB2(SCH_1):PAGE93
     2 FM_CPU_ERR1_LVT3_K_N @BASEBOARD_FAB2_LIB.BASEBOARD_FAB2(SCH_1):FM_CPU_ERR1_LVT3_K_N   I112 @BASEBOARD_FAB2_LIB.BASEBOARD_FAB2(SCH_1):PAGE93

R2T67 RES_0402-0.0,5%,1/16W,CHIP,G21A
     1 FM_CPU0_PROCHOT_LVT3_R_N @BASEBOARD_FAB2_LIB.BASEBOARD_FAB2(SCH_1):FM_CPU0_PROCHOT_LVT3_R_N   I113 @BASEBOARD_FAB2_LIB.BASEBOARD_FAB2(SCH_1):PAGE93
     2 FM_CPU0_PROCHOT_LVT3_K_N @BASEBOARD_FAB2_LIB.BASEBOARD_FAB2(SCH_1):FM_CPU0_PROCHOT_LVT3_K_N   I113 @BASEBOARD_FAB2_LIB.BASEBOARD_FAB2(SCH_1):PAGE93

R2T68 RES_0402-0.0,5%,1/16W,CHIP,G21A
     1 H_CPU1_PROCHOT_G_N @BASEBOARD_FAB2_LIB.BASEBOARD_FAB2(SCH_1):H_CPU1_PROCHOT_G_N   I102 @BASEBOARD_FAB2_LIB.BASEBOARD_FAB2(SCH_1):PAGE93
     2 H_CPU1_PROCHOT_G_R_N @BASEBOARD_FAB2_LIB.BASEBOARD_FAB2(SCH_1):H_CPU1_PROCHOT_G_R_N   I102 @BASEBOARD_FAB2_LIB.BASEBOARD_FAB2(SCH_1):PAGE93

R2T69 RES_0402-0.0,5%,1/16W,EMPTY,G2A
     1 H_CPU1_PROCHOT_G_N @BASEBOARD_FAB2_LIB.BASEBOARD_FAB2(SCH_1):H_CPU1_PROCHOT_G_N   I108 @BASEBOARD_FAB2_LIB.BASEBOARD_FAB2(SCH_1):PAGE93
     2 H_CPU1_PROCHOT_G_PCH_N @BASEBOARD_FAB2_LIB.BASEBOARD_FAB2(SCH_1):H_CPU1_PROCHOT_G_PCH_N   I108 @BASEBOARD_FAB2_LIB.BASEBOARD_FAB2(SCH_1):PAGE93

R2T71 RES_0402-0.0,5%,1/16W,EMPTY,G2A
     1 FM_CPU0_PROCHOT_LVT3_K_N @BASEBOARD_FAB2_LIB.BASEBOARD_FAB2(SCH_1):FM_CPU0_PROCHOT_LVT3_K_N   I109 @BASEBOARD_FAB2_LIB.BASEBOARD_FAB2(SCH_1):PAGE93
     2 H_CPU0_PROCHOT_G_PCH_N @BASEBOARD_FAB2_LIB.BASEBOARD_FAB2(SCH_1):H_CPU0_PROCHOT_G_PCH_N   I109 @BASEBOARD_FAB2_LIB.BASEBOARD_FAB2(SCH_1):PAGE93

R2T72 RES_0402-150.0,1%,1/16W,CHIP,GA
     1 PVCCIO_CPU0 @BASEBOARD_FAB2_LIB.BASEBOARD_FAB2(SCH_1):PVCCIO_CPU0   I143 @BASEBOARD_FAB2_LIB.BASEBOARD_FAB2(SCH_1):PAGE93
     2 H_CPU0_PROCHOT_G_N @BASEBOARD_FAB2_LIB.BASEBOARD_FAB2(SCH_1):H_CPU0_PROCHOT_G_N   I143 @BASEBOARD_FAB2_LIB.BASEBOARD_FAB2(SCH_1):PAGE93

R2T73 RES_0402-150.0,1%,1/16W,CHIP,GA
     1 PVCCIO_CPU1 @BASEBOARD_FAB2_LIB.BASEBOARD_FAB2(SCH_1):PVCCIO_CPU1   I144 @BASEBOARD_FAB2_LIB.BASEBOARD_FAB2(SCH_1):PAGE93
     2 H_CPU1_PROCHOT_G_N @BASEBOARD_FAB2_LIB.BASEBOARD_FAB2(SCH_1):H_CPU1_PROCHOT_G_N   I144 @BASEBOARD_FAB2_LIB.BASEBOARD_FAB2(SCH_1):PAGE93

R2U1 RES_0402-20.0,1%,1/16W,CHIP,G2A
     1 SMB_BMC_PMBUS_STBY_LVC3_SCL_R @BASEBOARD_FAB2_LIB.BASEBOARD_FAB2(SCH_1):SMB_BMC_PMBUS_STBY_LVC3_SCL_R   I218 @BASEBOARD_FAB2_LIB.BASEBOARD_FAB2(SCH_1):PAGE159
     2 SMB_BMC_PMBUS_STBY_LVC3_SCL @BASEBOARD_FAB2_LIB.BASEBOARD_FAB2(SCH_1):SMB_BMC_PMBUS_STBY_LVC3_SCL   I218 @BASEBOARD_FAB2_LIB.BASEBOARD_FAB2(SCH_1):PAGE159

R2U2 RES_0402-4.75K,1%,1/16W,CHIP,GA
     1 P3V3_STBY @BASEBOARD_FAB2_LIB.BASEBOARD_FAB2(SCH_1):P3V3_STBY   I265 @BASEBOARD_FAB2_LIB.BASEBOARD_FAB2(SCH_1):PAGE156
     2 RST_PCH_SYSRST_BTN_OUT_N @BASEBOARD_FAB2_LIB.BASEBOARD_FAB2(SCH_1):RST_PCH_SYSRST_BTN_OUT_N   I265 @BASEBOARD_FAB2_LIB.BASEBOARD_FAB2(SCH_1):PAGE156

R2U3 RES_0402-665,1.0%,1/16W,CHIP,GA
     1 P3V3_STBY @BASEBOARD_FAB2_LIB.BASEBOARD_FAB2(SCH_1):P3V3_STBY    I98 @BASEBOARD_FAB2_LIB.BASEBOARD_FAB2(SCH_1):PAGE138
     2 SMB_LAN_STBY_LVC3_SCL @BASEBOARD_FAB2_LIB.BASEBOARD_FAB2(SCH_1):SMB_LAN_STBY_LVC3_SCL    I98 @BASEBOARD_FAB2_LIB.BASEBOARD_FAB2(SCH_1):PAGE138

R2U4 RES_0402-4.75K,1%,1/16W,CHIP,GA
     1 P3V3_STBY @BASEBOARD_FAB2_LIB.BASEBOARD_FAB2(SCH_1):P3V3_STBY   I367 @BASEBOARD_FAB2_LIB.BASEBOARD_FAB2(SCH_1):PAGE157
     2 FM_CPLD_BMC_PWRDN_N @BASEBOARD_FAB2_LIB.BASEBOARD_FAB2(SCH_1):FM_CPLD_BMC_PWRDN_N   I367 @BASEBOARD_FAB2_LIB.BASEBOARD_FAB2(SCH_1):PAGE157

R2U5 RES_0402-2.26K,1.0%,1/16W,CHIPA
     1 P3V3_STBY @BASEBOARD_FAB2_LIB.BASEBOARD_FAB2(SCH_1):P3V3_STBY   I214 @BASEBOARD_FAB2_LIB.BASEBOARD_FAB2(SCH_1):PAGE159
     2 SMB_OCP_FRU_STBY_LVC3_SCL_R @BASEBOARD_FAB2_LIB.BASEBOARD_FAB2(SCH_1):SMB_OCP_FRU_STBY_LVC3_SCL_R   I214 @BASEBOARD_FAB2_LIB.BASEBOARD_FAB2(SCH_1):PAGE159

R2U6 RES_0402-20.0,1%,1/16W,CHIP,G2A
     1 SMB_LAN_STBY_LVC3_SCL_R1 @BASEBOARD_FAB2_LIB.BASEBOARD_FAB2(SCH_1):SMB_LAN_STBY_LVC3_SCL_R1   I166 @BASEBOARD_FAB2_LIB.BASEBOARD_FAB2(SCH_1):PAGE138
     2 SMB_LAN_STBY_LVC3_SCL @BASEBOARD_FAB2_LIB.BASEBOARD_FAB2(SCH_1):SMB_LAN_STBY_LVC3_SCL   I166 @BASEBOARD_FAB2_LIB.BASEBOARD_FAB2(SCH_1):PAGE138

R2U7 RES_0402-20.0,1%,1/16W,CHIP,G2A
     1 SMB_OCP_FRU_STBY_LVC3_SCL_R @BASEBOARD_FAB2_LIB.BASEBOARD_FAB2(SCH_1):SMB_OCP_FRU_STBY_LVC3_SCL_R   I220 @BASEBOARD_FAB2_LIB.BASEBOARD_FAB2(SCH_1):PAGE159
     2 SMB_OCP_FRU_STBY_LVC3_SCL @BASEBOARD_FAB2_LIB.BASEBOARD_FAB2(SCH_1):SMB_OCP_FRU_STBY_LVC3_SCL   I220 @BASEBOARD_FAB2_LIB.BASEBOARD_FAB2(SCH_1):PAGE159

R2U8 RES_0402-20.0,1%,1/16W,EMPTY,GA
     1 SMB_LAN_STBY_LVC3_SCL @BASEBOARD_FAB2_LIB.BASEBOARD_FAB2(SCH_1):SMB_LAN_STBY_LVC3_SCL   I158 @BASEBOARD_FAB2_LIB.BASEBOARD_FAB2(SCH_1):PAGE138
     2 SMB_OCP_FRU_STBY_LVC3_SCL @BASEBOARD_FAB2_LIB.BASEBOARD_FAB2(SCH_1):SMB_OCP_FRU_STBY_LVC3_SCL   I158 @BASEBOARD_FAB2_LIB.BASEBOARD_FAB2(SCH_1):PAGE138

R2U9 RES_0402-20.0,1%,1/16W,CHIP,G2A
     1 SMB_LAN_STBY_LVC3_SDA_R1 @BASEBOARD_FAB2_LIB.BASEBOARD_FAB2(SCH_1):SMB_LAN_STBY_LVC3_SDA_R1   I165 @BASEBOARD_FAB2_LIB.BASEBOARD_FAB2(SCH_1):PAGE138
     2 SMB_LAN_STBY_LVC3_SDA @BASEBOARD_FAB2_LIB.BASEBOARD_FAB2(SCH_1):SMB_LAN_STBY_LVC3_SDA   I165 @BASEBOARD_FAB2_LIB.BASEBOARD_FAB2(SCH_1):PAGE138

R2U10 RES_0402-20.0,1%,1/16W,CHIP,G2A
     1 SMB_OCP_FRU_STBY_LVC3_SDA_R @BASEBOARD_FAB2_LIB.BASEBOARD_FAB2(SCH_1):SMB_OCP_FRU_STBY_LVC3_SDA_R   I221 @BASEBOARD_FAB2_LIB.BASEBOARD_FAB2(SCH_1):PAGE159
     2 SMB_OCP_FRU_STBY_LVC3_SDA @BASEBOARD_FAB2_LIB.BASEBOARD_FAB2(SCH_1):SMB_OCP_FRU_STBY_LVC3_SDA   I221 @BASEBOARD_FAB2_LIB.BASEBOARD_FAB2(SCH_1):PAGE159

R2U11 RES_0402-665,1.0%,1/16W,CHIP,GA
     1 P3V3_STBY @BASEBOARD_FAB2_LIB.BASEBOARD_FAB2(SCH_1):P3V3_STBY    I97 @BASEBOARD_FAB2_LIB.BASEBOARD_FAB2(SCH_1):PAGE138
     2 SMB_LAN_STBY_LVC3_SDA @BASEBOARD_FAB2_LIB.BASEBOARD_FAB2(SCH_1):SMB_LAN_STBY_LVC3_SDA    I97 @BASEBOARD_FAB2_LIB.BASEBOARD_FAB2(SCH_1):PAGE138

R2U12 RES_0402-20.0,1%,1/16W,EMPTY,GA
     1 SMB_LAN_STBY_LVC3_SDA @BASEBOARD_FAB2_LIB.BASEBOARD_FAB2(SCH_1):SMB_LAN_STBY_LVC3_SDA   I159 @BASEBOARD_FAB2_LIB.BASEBOARD_FAB2(SCH_1):PAGE138
     2 SMB_OCP_FRU_STBY_LVC3_SDA @BASEBOARD_FAB2_LIB.BASEBOARD_FAB2(SCH_1):SMB_OCP_FRU_STBY_LVC3_SDA   I159 @BASEBOARD_FAB2_LIB.BASEBOARD_FAB2(SCH_1):PAGE138

R2U13 RES_0402-2.26K,1.0%,1/16W,CHIPA
     1 P3V3_STBY @BASEBOARD_FAB2_LIB.BASEBOARD_FAB2(SCH_1):P3V3_STBY   I216 @BASEBOARD_FAB2_LIB.BASEBOARD_FAB2(SCH_1):PAGE159
     2 SMB_OCP_FRU_STBY_LVC3_SDA_R @BASEBOARD_FAB2_LIB.BASEBOARD_FAB2(SCH_1):SMB_OCP_FRU_STBY_LVC3_SDA_R   I216 @BASEBOARD_FAB2_LIB.BASEBOARD_FAB2(SCH_1):PAGE159

R2U14 RES_0402-0.0,5%,1/16W,CHIP,G21A
     1 P3E_CPU0_PE1_SS_RXP<0> @BASEBOARD_FAB2_LIB.BASEBOARD_FAB2(SCH_1):P3E_CPU0_PE1_SS_RXP(0)   I499 @BASEBOARD_FAB2_LIB.BASEBOARD_FAB2(SCH_1):PAGE107
     2 P3E_CPU0_PE1_SS_R_RXP<0> @BASEBOARD_FAB2_LIB.BASEBOARD_FAB2(SCH_1):P3E_CPU0_PE1_SS_R_RXP(0)   I499 @BASEBOARD_FAB2_LIB.BASEBOARD_FAB2(SCH_1):PAGE107

R2U15 RES_0402-0.0,5%,1/16W,CHIP,G21A
     1 P3E_CPU0_PE1_SS_RXN<0> @BASEBOARD_FAB2_LIB.BASEBOARD_FAB2(SCH_1):P3E_CPU0_PE1_SS_RXN(0)   I490 @BASEBOARD_FAB2_LIB.BASEBOARD_FAB2(SCH_1):PAGE107
     2 P3E_CPU0_PE1_SS_R_RXN<0> @BASEBOARD_FAB2_LIB.BASEBOARD_FAB2(SCH_1):P3E_CPU0_PE1_SS_R_RXN(0)   I490 @BASEBOARD_FAB2_LIB.BASEBOARD_FAB2(SCH_1):PAGE107

R2U16 RES_0402-0.0,5%,1/16W,CHIP,G21A
     1 P3E_CPU0_PE1_SS_RXP<1> @BASEBOARD_FAB2_LIB.BASEBOARD_FAB2(SCH_1):P3E_CPU0_PE1_SS_RXP(1)   I501 @BASEBOARD_FAB2_LIB.BASEBOARD_FAB2(SCH_1):PAGE107
     2 P3E_CPU0_PE1_SS_R_RXP<1> @BASEBOARD_FAB2_LIB.BASEBOARD_FAB2(SCH_1):P3E_CPU0_PE1_SS_R_RXP(1)   I501 @BASEBOARD_FAB2_LIB.BASEBOARD_FAB2(SCH_1):PAGE107

R2U17 RES_0402-0.0,5%,1/16W,CHIP,G21A
     1 P3E_CPU0_PE1_SS_RXN<1> @BASEBOARD_FAB2_LIB.BASEBOARD_FAB2(SCH_1):P3E_CPU0_PE1_SS_RXN(1)   I492 @BASEBOARD_FAB2_LIB.BASEBOARD_FAB2(SCH_1):PAGE107
     2 P3E_CPU0_PE1_SS_R_RXN<1> @BASEBOARD_FAB2_LIB.BASEBOARD_FAB2(SCH_1):P3E_CPU0_PE1_SS_R_RXN(1)   I492 @BASEBOARD_FAB2_LIB.BASEBOARD_FAB2(SCH_1):PAGE107

R2U18 RES_0402-0.0,5%,1/16W,CHIP,G21A
     1 P3E_CPU0_PE1_SS_RXP<2> @BASEBOARD_FAB2_LIB.BASEBOARD_FAB2(SCH_1):P3E_CPU0_PE1_SS_RXP(2)   I502 @BASEBOARD_FAB2_LIB.BASEBOARD_FAB2(SCH_1):PAGE107
     2 P3E_CPU0_PE1_SS_R_RXP<2> @BASEBOARD_FAB2_LIB.BASEBOARD_FAB2(SCH_1):P3E_CPU0_PE1_SS_R_RXP(2)   I502 @BASEBOARD_FAB2_LIB.BASEBOARD_FAB2(SCH_1):PAGE107

R2U19 RES_0402-0.0,5%,1/16W,CHIP,G21A
     1 P3E_CPU0_PE1_SS_RXN<2> @BASEBOARD_FAB2_LIB.BASEBOARD_FAB2(SCH_1):P3E_CPU0_PE1_SS_RXN(2)   I493 @BASEBOARD_FAB2_LIB.BASEBOARD_FAB2(SCH_1):PAGE107
     2 P3E_CPU0_PE1_SS_R_RXN<2> @BASEBOARD_FAB2_LIB.BASEBOARD_FAB2(SCH_1):P3E_CPU0_PE1_SS_R_RXN(2)   I493 @BASEBOARD_FAB2_LIB.BASEBOARD_FAB2(SCH_1):PAGE107

R2U20 RES_0402-0.0,5%,1/16W,CHIP,G21A
     1 P3E_CPU0_PE1_SS_RXP<3> @BASEBOARD_FAB2_LIB.BASEBOARD_FAB2(SCH_1):P3E_CPU0_PE1_SS_RXP(3)   I503 @BASEBOARD_FAB2_LIB.BASEBOARD_FAB2(SCH_1):PAGE107
     2 P3E_CPU0_PE1_SS_R_RXP<3> @BASEBOARD_FAB2_LIB.BASEBOARD_FAB2(SCH_1):P3E_CPU0_PE1_SS_R_RXP(3)   I503 @BASEBOARD_FAB2_LIB.BASEBOARD_FAB2(SCH_1):PAGE107

R2U21 RES_0402-0.0,5%,1/16W,CHIP,G21A
     1 P3E_CPU0_PE1_SS_RXN<3> @BASEBOARD_FAB2_LIB.BASEBOARD_FAB2(SCH_1):P3E_CPU0_PE1_SS_RXN(3)   I491 @BASEBOARD_FAB2_LIB.BASEBOARD_FAB2(SCH_1):PAGE107
     2 P3E_CPU0_PE1_SS_R_RXN<3> @BASEBOARD_FAB2_LIB.BASEBOARD_FAB2(SCH_1):P3E_CPU0_PE1_SS_R_RXN(3)   I491 @BASEBOARD_FAB2_LIB.BASEBOARD_FAB2(SCH_1):PAGE107

R2U22 RES_0402-0.0,5%,1/16W,CHIP,G21A
     1 P3E_CPU0_PE1_SS_RXP<4> @BASEBOARD_FAB2_LIB.BASEBOARD_FAB2(SCH_1):P3E_CPU0_PE1_SS_RXP(4)   I504 @BASEBOARD_FAB2_LIB.BASEBOARD_FAB2(SCH_1):PAGE107
     2 P3E_CPU0_PE1_SS_R_RXP<4> @BASEBOARD_FAB2_LIB.BASEBOARD_FAB2(SCH_1):P3E_CPU0_PE1_SS_R_RXP(4)   I504 @BASEBOARD_FAB2_LIB.BASEBOARD_FAB2(SCH_1):PAGE107

R2U23 RES_0402-0.0,5%,1/16W,CHIP,G21A
     1 P3E_CPU0_PE1_SS_RXN<4> @BASEBOARD_FAB2_LIB.BASEBOARD_FAB2(SCH_1):P3E_CPU0_PE1_SS_RXN(4)   I495 @BASEBOARD_FAB2_LIB.BASEBOARD_FAB2(SCH_1):PAGE107
     2 P3E_CPU0_PE1_SS_R_RXN<4> @BASEBOARD_FAB2_LIB.BASEBOARD_FAB2(SCH_1):P3E_CPU0_PE1_SS_R_RXN(4)   I495 @BASEBOARD_FAB2_LIB.BASEBOARD_FAB2(SCH_1):PAGE107

R2U24 RES_0402-0.0,5%,1/16W,CHIP,G21A
     1 P3E_CPU0_PE1_SS_RXP<5> @BASEBOARD_FAB2_LIB.BASEBOARD_FAB2(SCH_1):P3E_CPU0_PE1_SS_RXP(5)   I505 @BASEBOARD_FAB2_LIB.BASEBOARD_FAB2(SCH_1):PAGE107
     2 P3E_CPU0_PE1_SS_R_RXP<5> @BASEBOARD_FAB2_LIB.BASEBOARD_FAB2(SCH_1):P3E_CPU0_PE1_SS_R_RXP(5)   I505 @BASEBOARD_FAB2_LIB.BASEBOARD_FAB2(SCH_1):PAGE107

R2U25 RES_0402-0.0,5%,1/16W,CHIP,G21A
     1 P3E_CPU0_PE1_SS_RXN<5> @BASEBOARD_FAB2_LIB.BASEBOARD_FAB2(SCH_1):P3E_CPU0_PE1_SS_RXN(5)   I496 @BASEBOARD_FAB2_LIB.BASEBOARD_FAB2(SCH_1):PAGE107
     2 P3E_CPU0_PE1_SS_R_RXN<5> @BASEBOARD_FAB2_LIB.BASEBOARD_FAB2(SCH_1):P3E_CPU0_PE1_SS_R_RXN(5)   I496 @BASEBOARD_FAB2_LIB.BASEBOARD_FAB2(SCH_1):PAGE107

R2U26 RES_0402-0.0,5%,1/16W,CHIP,G21A
     1 P3E_CPU0_PE1_SS_RXP<6> @BASEBOARD_FAB2_LIB.BASEBOARD_FAB2(SCH_1):P3E_CPU0_PE1_SS_RXP(6)   I498 @BASEBOARD_FAB2_LIB.BASEBOARD_FAB2(SCH_1):PAGE107
     2 P3E_CPU0_PE1_SS_R_RXP<6> @BASEBOARD_FAB2_LIB.BASEBOARD_FAB2(SCH_1):P3E_CPU0_PE1_SS_R_RXP(6)   I498 @BASEBOARD_FAB2_LIB.BASEBOARD_FAB2(SCH_1):PAGE107

R2U27 RES_0402-0.0,5%,1/16W,CHIP,G21A
     1 P3E_CPU0_PE1_SS_RXN<6> @BASEBOARD_FAB2_LIB.BASEBOARD_FAB2(SCH_1):P3E_CPU0_PE1_SS_RXN(6)   I497 @BASEBOARD_FAB2_LIB.BASEBOARD_FAB2(SCH_1):PAGE107
     2 P3E_CPU0_PE1_SS_R_RXN<6> @BASEBOARD_FAB2_LIB.BASEBOARD_FAB2(SCH_1):P3E_CPU0_PE1_SS_R_RXN(6)   I497 @BASEBOARD_FAB2_LIB.BASEBOARD_FAB2(SCH_1):PAGE107

R2U28 RES_0402-0.0,5%,1/16W,CHIP,G21A
     1 P3E_CPU0_PE1_SS_RXP<7> @BASEBOARD_FAB2_LIB.BASEBOARD_FAB2(SCH_1):P3E_CPU0_PE1_SS_RXP(7)   I500 @BASEBOARD_FAB2_LIB.BASEBOARD_FAB2(SCH_1):PAGE107
     2 P3E_CPU0_PE1_SS_R_RXP<7> @BASEBOARD_FAB2_LIB.BASEBOARD_FAB2(SCH_1):P3E_CPU0_PE1_SS_R_RXP(7)   I500 @BASEBOARD_FAB2_LIB.BASEBOARD_FAB2(SCH_1):PAGE107

R2U29 RES_0402-0.0,5%,1/16W,CHIP,G21A
     1 P3E_CPU0_PE1_SS_RXN<7> @BASEBOARD_FAB2_LIB.BASEBOARD_FAB2(SCH_1):P3E_CPU0_PE1_SS_RXN(7)   I494 @BASEBOARD_FAB2_LIB.BASEBOARD_FAB2(SCH_1):PAGE107
     2 P3E_CPU0_PE1_SS_R_RXN<7> @BASEBOARD_FAB2_LIB.BASEBOARD_FAB2(SCH_1):P3E_CPU0_PE1_SS_R_RXN(7)   I494 @BASEBOARD_FAB2_LIB.BASEBOARD_FAB2(SCH_1):PAGE107

R2U30 RES_0402-4.75K,1%,1/16W,EMPTY,A
     1 P3V3_STBY @BASEBOARD_FAB2_LIB.BASEBOARD_FAB2(SCH_1):P3V3_STBY    I88 @BASEBOARD_FAB2_LIB.BASEBOARD_FAB2(SCH_1):PAGE125
     2 FM_UV_ADR_TRIGGER_EN @BASEBOARD_FAB2_LIB.BASEBOARD_FAB2(SCH_1):FM_UV_ADR_TRIGGER_EN    I88 @BASEBOARD_FAB2_LIB.BASEBOARD_FAB2(SCH_1):PAGE125

R2U31 RES_0402-20.0,1%,1/16W,CHIP,G2A
     1 SMB_SLOTX24_BMC_STBY_LVC3_SDA @BASEBOARD_FAB2_LIB.BASEBOARD_FAB2(SCH_1):SMB_SLOTX24_BMC_STBY_LVC3_SDA   I330 @BASEBOARD_FAB2_LIB.BASEBOARD_FAB2(SCH_1):PAGE108
     2 SMB_SLOTX24_STBY_LVC3_SDA_R2 @BASEBOARD_FAB2_LIB.BASEBOARD_FAB2(SCH_1):SMB_SLOTX24_STBY_LVC3_SDA_R2   I330 @BASEBOARD_FAB2_LIB.BASEBOARD_FAB2(SCH_1):PAGE108

R2U32 RES_0402-20.0,1%,1/16W,CHIP,G2A
     1 SMB_SLOTX24_BMC_STBY_LVC3_SCL @BASEBOARD_FAB2_LIB.BASEBOARD_FAB2(SCH_1):SMB_SLOTX24_BMC_STBY_LVC3_SCL   I339 @BASEBOARD_FAB2_LIB.BASEBOARD_FAB2(SCH_1):PAGE108
     2 SMB_SLOTX24_STBY_LVC3_SCL_R2 @BASEBOARD_FAB2_LIB.BASEBOARD_FAB2(SCH_1):SMB_SLOTX24_STBY_LVC3_SCL_R2   I339 @BASEBOARD_FAB2_LIB.BASEBOARD_FAB2(SCH_1):PAGE108

R2U33 RES_0402-20.0,1%,1/16W,CHIP,G2A
     1 SMB_HOST_STBY_LVC3_SDA_R @BASEBOARD_FAB2_LIB.BASEBOARD_FAB2(SCH_1):SMB_HOST_STBY_LVC3_SDA_R   I231 @BASEBOARD_FAB2_LIB.BASEBOARD_FAB2(SCH_1):PAGE159
     2 SMB_HOST_STBY_LVC3_SDA @BASEBOARD_FAB2_LIB.BASEBOARD_FAB2(SCH_1):SMB_HOST_STBY_LVC3_SDA   I231 @BASEBOARD_FAB2_LIB.BASEBOARD_FAB2(SCH_1):PAGE159

R2U34 RES_0402-20.0,1%,1/16W,CHIP,G2A
     1 SMB_HOST_STBY_LVC3_SCL_R @BASEBOARD_FAB2_LIB.BASEBOARD_FAB2(SCH_1):SMB_HOST_STBY_LVC3_SCL_R   I230 @BASEBOARD_FAB2_LIB.BASEBOARD_FAB2(SCH_1):PAGE159
     2 SMB_HOST_STBY_LVC3_SCL @BASEBOARD_FAB2_LIB.BASEBOARD_FAB2(SCH_1):SMB_HOST_STBY_LVC3_SCL   I230 @BASEBOARD_FAB2_LIB.BASEBOARD_FAB2(SCH_1):PAGE159

R2U35 RES_0402-20.0,1%,1/16W,EMPTY,GA
     1 SMB_SLOTX24_PCH_STBY_LVC3_SDA @BASEBOARD_FAB2_LIB.BASEBOARD_FAB2(SCH_1):SMB_SLOTX24_PCH_STBY_LVC3_SDA   I350 @BASEBOARD_FAB2_LIB.BASEBOARD_FAB2(SCH_1):PAGE108
     2 SMB_SLOTX24_STBY_LVC3_SDA_R2 @BASEBOARD_FAB2_LIB.BASEBOARD_FAB2(SCH_1):SMB_SLOTX24_STBY_LVC3_SDA_R2   I350 @BASEBOARD_FAB2_LIB.BASEBOARD_FAB2(SCH_1):PAGE108

R2U36 RES_0402-20.0,1%,1/16W,EMPTY,GA
     1 SMB_SLOTX24_PCH_STBY_LVC3_SCL @BASEBOARD_FAB2_LIB.BASEBOARD_FAB2(SCH_1):SMB_SLOTX24_PCH_STBY_LVC3_SCL   I351 @BASEBOARD_FAB2_LIB.BASEBOARD_FAB2(SCH_1):PAGE108
     2 SMB_SLOTX24_STBY_LVC3_SCL_R2 @BASEBOARD_FAB2_LIB.BASEBOARD_FAB2(SCH_1):SMB_SLOTX24_STBY_LVC3_SCL_R2   I351 @BASEBOARD_FAB2_LIB.BASEBOARD_FAB2(SCH_1):PAGE108

R2U37 RES_0402-0.0,5%,1/16W,CHIP,G21A
     1 RST_PCIE_RISER1_PERST_N @BASEBOARD_FAB2_LIB.BASEBOARD_FAB2(SCH_1):RST_PCIE_RISER1_PERST_N   I173 @BASEBOARD_FAB2_LIB.BASEBOARD_FAB2(SCH_1):PAGE108
     2 RST_PCIE_RISER1_PERST_R_N @BASEBOARD_FAB2_LIB.BASEBOARD_FAB2(SCH_1):RST_PCIE_RISER1_PERST_R_N   I173 @BASEBOARD_FAB2_LIB.BASEBOARD_FAB2(SCH_1):PAGE108

R2U38 RES_0402-665,1.0%,1/16W,CHIP,GA
     1 P3V3_STBY @BASEBOARD_FAB2_LIB.BASEBOARD_FAB2(SCH_1):P3V3_STBY    I80 @BASEBOARD_FAB2_LIB.BASEBOARD_FAB2(SCH_1):PAGE167
     2 SMB_SENSOR_STBY_LVC3_SCL @BASEBOARD_FAB2_LIB.BASEBOARD_FAB2(SCH_1):SMB_SENSOR_STBY_LVC3_SCL    I80 @BASEBOARD_FAB2_LIB.BASEBOARD_FAB2(SCH_1):PAGE167

R2U39 RES_0402-665,1.0%,1/16W,CHIP,GA
     1 P3V3_STBY @BASEBOARD_FAB2_LIB.BASEBOARD_FAB2(SCH_1):P3V3_STBY    I83 @BASEBOARD_FAB2_LIB.BASEBOARD_FAB2(SCH_1):PAGE167
     2 SMB_SENSOR_STBY_LVC3_SDA @BASEBOARD_FAB2_LIB.BASEBOARD_FAB2(SCH_1):SMB_SENSOR_STBY_LVC3_SDA    I83 @BASEBOARD_FAB2_LIB.BASEBOARD_FAB2(SCH_1):PAGE167

R2U40 RES_0402-150.0,1%,1/16W,CHIP,GA
     1 PVCCIO_CPU0 @BASEBOARD_FAB2_LIB.BASEBOARD_FAB2(SCH_1):PVCCIO_CPU0    I53 @BASEBOARD_FAB2_LIB.BASEBOARD_FAB2(SCH_1):PAGE152
     2 H_CPU0_MEMABC_MEMHOT_G_N @BASEBOARD_FAB2_LIB.BASEBOARD_FAB2(SCH_1):H_CPU0_MEMABC_MEMHOT_G_N    I53 @BASEBOARD_FAB2_LIB.BASEBOARD_FAB2(SCH_1):PAGE152

R2U41 RES_0402-150.0,1%,1/16W,CHIP,GA
     1 PVCCIO_CPU0 @BASEBOARD_FAB2_LIB.BASEBOARD_FAB2(SCH_1):PVCCIO_CPU0    I54 @BASEBOARD_FAB2_LIB.BASEBOARD_FAB2(SCH_1):PAGE152
     2 H_CPU0_MEMDEF_MEMHOT_G_N @BASEBOARD_FAB2_LIB.BASEBOARD_FAB2(SCH_1):H_CPU0_MEMDEF_MEMHOT_G_N    I54 @BASEBOARD_FAB2_LIB.BASEBOARD_FAB2(SCH_1):PAGE152

R2U42 RES_0402-221,1.0%,1/16W,CHIP,GA
     1 FAN_PWM_OUT_SYS0_BUF @BASEBOARD_FAB2_LIB.BASEBOARD_FAB2(SCH_1):FAN_PWM_OUT_SYS0_BUF    I99 @BASEBOARD_FAB2_LIB.BASEBOARD_FAB2(SCH_1):PAGE161
     2 FAN_PWM_OUT_SYS0_R @BASEBOARD_FAB2_LIB.BASEBOARD_FAB2(SCH_1):FAN_PWM_OUT_SYS0_R    I99 @BASEBOARD_FAB2_LIB.BASEBOARD_FAB2(SCH_1):PAGE161

R2U43 RES_0402-1.00K,1%,1/16W,CHIP,GA
     1 P3V_BAT_SOURCE @BASEBOARD_FAB2_LIB.BASEBOARD_FAB2(SCH_1):P3V_BAT_SOURCE    I46 @BASEBOARD_FAB2_LIB.BASEBOARD_FAB2(SCH_1):PAGE196
     2 A_P3V_BAT_R @BASEBOARD_FAB2_LIB.BASEBOARD_FAB2(SCH_1):A_P3V_BAT_R    I46 @BASEBOARD_FAB2_LIB.BASEBOARD_FAB2(SCH_1):PAGE196

R2U44 RES_0402-221,1.0%,1/16W,CHIP,GA
     1 FAN_PWM_OUT_SYS1_BUF @BASEBOARD_FAB2_LIB.BASEBOARD_FAB2(SCH_1):FAN_PWM_OUT_SYS1_BUF   I102 @BASEBOARD_FAB2_LIB.BASEBOARD_FAB2(SCH_1):PAGE161
     2 FAN_PWM_OUT_SYS1_R @BASEBOARD_FAB2_LIB.BASEBOARD_FAB2(SCH_1):FAN_PWM_OUT_SYS1_R   I102 @BASEBOARD_FAB2_LIB.BASEBOARD_FAB2(SCH_1):PAGE161

R2U45 RES_0402-0.0,5%,1/16W,EMPTY,G2A
     1 H_CPU1_MEMKLM_MEMHOT_LVT3_N @BASEBOARD_FAB2_LIB.BASEBOARD_FAB2(SCH_1):H_CPU1_MEMKLM_MEMHOT_LVT3_N   I102 @BASEBOARD_FAB2_LIB.BASEBOARD_FAB2(SCH_1):PAGE152
     2 H_CPU1_MEMKLM_MEMHOT_PCH_N @BASEBOARD_FAB2_LIB.BASEBOARD_FAB2(SCH_1):H_CPU1_MEMKLM_MEMHOT_PCH_N   I102 @BASEBOARD_FAB2_LIB.BASEBOARD_FAB2(SCH_1):PAGE152

R2U46 RES_0402-0.0,5%,1/16W,CHIP,G21A
     1 H_CPU1_MEMKLM_MEMHOT_LVT3_N @BASEBOARD_FAB2_LIB.BASEBOARD_FAB2(SCH_1):H_CPU1_MEMKLM_MEMHOT_LVT3_N    I94 @BASEBOARD_FAB2_LIB.BASEBOARD_FAB2(SCH_1):PAGE152
     2 H_CPU1_MEMKLM_MEMHOT_LVT3_BMC_N @BASEBOARD_FAB2_LIB.BASEBOARD_FAB2(SCH_1):H_CPU1_MEMKLM_MEMHOT_LVT3_BMC_N    I94 @BASEBOARD_FAB2_LIB.BASEBOARD_FAB2(SCH_1):PAGE152

R2U47 RES_0402-0.0,5%,1/16W,CHIP,G21A
     1 H_CPU0_MEMABC_MEMHOT_LVT3_N @BASEBOARD_FAB2_LIB.BASEBOARD_FAB2(SCH_1):H_CPU0_MEMABC_MEMHOT_LVT3_N    I79 @BASEBOARD_FAB2_LIB.BASEBOARD_FAB2(SCH_1):PAGE152
     2 H_CPU0_MEMABC_MEMHOT_LVT3_BMC_N @BASEBOARD_FAB2_LIB.BASEBOARD_FAB2(SCH_1):H_CPU0_MEMABC_MEMHOT_LVT3_BMC_N    I79 @BASEBOARD_FAB2_LIB.BASEBOARD_FAB2(SCH_1):PAGE152

R2U48 RES_0402-4.75K,1%,1/16W,CHIP,GA
     1 P3V3_STBY @BASEBOARD_FAB2_LIB.BASEBOARD_FAB2(SCH_1):P3V3_STBY   I213 @BASEBOARD_FAB2_LIB.BASEBOARD_FAB2(SCH_1):PAGE119
     2 FM_SLT_CFG2_R @BASEBOARD_FAB2_LIB.BASEBOARD_FAB2(SCH_1):FM_SLT_CFG2_R   I213 @BASEBOARD_FAB2_LIB.BASEBOARD_FAB2(SCH_1):PAGE119

R2U49 RES_0402-0.0,5%,1/16W,EMPTY,G2A
     1 H_CPU0_MEMABC_MEMHOT_G_PCH_N @BASEBOARD_FAB2_LIB.BASEBOARD_FAB2(SCH_1):H_CPU0_MEMABC_MEMHOT_G_PCH_N    I66 @BASEBOARD_FAB2_LIB.BASEBOARD_FAB2(SCH_1):PAGE152
     2 H_CPU0_MEMABC_MEMHOT_LVT3_K_N @BASEBOARD_FAB2_LIB.BASEBOARD_FAB2(SCH_1):H_CPU0_MEMABC_MEMHOT_LVT3_K_N    I66 @BASEBOARD_FAB2_LIB.BASEBOARD_FAB2(SCH_1):PAGE152

R2U50 RES_0402-0.0,5%,1/16W,CHIP,G21A
     1 FM_SLT_CFG2_R @BASEBOARD_FAB2_LIB.BASEBOARD_FAB2(SCH_1):FM_SLT_CFG2_R   I228 @BASEBOARD_FAB2_LIB.BASEBOARD_FAB2(SCH_1):PAGE119
     2 FM_PWRBRK_SLOT_N @BASEBOARD_FAB2_LIB.BASEBOARD_FAB2(SCH_1):FM_PWRBRK_SLOT_N   I228 @BASEBOARD_FAB2_LIB.BASEBOARD_FAB2(SCH_1):PAGE119

R2U51 RES_0402-0.0,5%,1/16W,EMPTY,G2A
     1 H_CPU0_MEMABC_MEMHOT_G_PCH_N @BASEBOARD_FAB2_LIB.BASEBOARD_FAB2(SCH_1):H_CPU0_MEMABC_MEMHOT_G_PCH_N    I51 @BASEBOARD_FAB2_LIB.BASEBOARD_FAB2(SCH_1):PAGE152
     2 H_CPU0_MEMABC_MEMHOT_G_N @BASEBOARD_FAB2_LIB.BASEBOARD_FAB2(SCH_1):H_CPU0_MEMABC_MEMHOT_G_N    I51 @BASEBOARD_FAB2_LIB.BASEBOARD_FAB2(SCH_1):PAGE152

R2W1 RES_0402-10.0K,1%,1/16W,CHIP,GA
     1 P3V3_STBY @BASEBOARD_FAB2_LIB.BASEBOARD_FAB2(SCH_1):P3V3_STBY   I174 @BASEBOARD_FAB2_LIB.BASEBOARD_FAB2(SCH_1):PAGE187
     2 FM_MEZZB_PRSNT1_N @BASEBOARD_FAB2_LIB.BASEBOARD_FAB2(SCH_1):FM_MEZZB_PRSNT1_N   I174 @BASEBOARD_FAB2_LIB.BASEBOARD_FAB2(SCH_1):PAGE187

R2W2 RES_0402-49.9,1%,1/16W,EMPTY,GA
     1 PVCCIO_CPU0 @BASEBOARD_FAB2_LIB.BASEBOARD_FAB2(SCH_1):PVCCIO_CPU0   I147 @BASEBOARD_FAB2_LIB.BASEBOARD_FAB2(SCH_1):PAGE93
     2 P0V7_GTL2104_5_VREF @BASEBOARD_FAB2_LIB.BASEBOARD_FAB2(SCH_1):P0V7_GTL2104_5_VREF   I147 @BASEBOARD_FAB2_LIB.BASEBOARD_FAB2(SCH_1):PAGE93

R2W3 RES_0402-0.0,5%,1/16W,CHIP,G21A
     1 FM_PMBUS_ALERT_BUF_EN_R_N @BASEBOARD_FAB2_LIB.BASEBOARD_FAB2(SCH_1):FM_PMBUS_ALERT_BUF_EN_R_N   I223 @BASEBOARD_FAB2_LIB.BASEBOARD_FAB2(SCH_1):PAGE119
     2 FM_PMBUS_ALERT_BUF_EN_N @BASEBOARD_FAB2_LIB.BASEBOARD_FAB2(SCH_1):FM_PMBUS_ALERT_BUF_EN_N   I223 @BASEBOARD_FAB2_LIB.BASEBOARD_FAB2(SCH_1):PAGE119

R2W4 RES_0402-0.0,5%,1/16W,CHIP,G21A
     1 FM_PMBUS_ALERT_BUF_EN_N @BASEBOARD_FAB2_LIB.BASEBOARD_FAB2(SCH_1):FM_PMBUS_ALERT_BUF_EN_N   I224 @BASEBOARD_FAB2_LIB.BASEBOARD_FAB2(SCH_1):PAGE119
     2 FM_PMBUS_ALERT_BUF_EN_R2_N @BASEBOARD_FAB2_LIB.BASEBOARD_FAB2(SCH_1):FM_PMBUS_ALERT_BUF_EN_R2_N   I224 @BASEBOARD_FAB2_LIB.BASEBOARD_FAB2(SCH_1):PAGE119

R2W5 RES_0402-0.0,5%,1/16W,CHIP,G21A
     1 FM_PMBUS_ALERT_BUF_EN_R3_N @BASEBOARD_FAB2_LIB.BASEBOARD_FAB2(SCH_1):FM_PMBUS_ALERT_BUF_EN_R3_N   I176 @BASEBOARD_FAB2_LIB.BASEBOARD_FAB2(SCH_1):PAGE145
     2 FM_PMBUS_ALERT_BUF_EN_N @BASEBOARD_FAB2_LIB.BASEBOARD_FAB2(SCH_1):FM_PMBUS_ALERT_BUF_EN_N   I176 @BASEBOARD_FAB2_LIB.BASEBOARD_FAB2(SCH_1):PAGE145

R3B1 RES_0402-221,1.0%,1/16W,CHIP,GA
     1 SVID_ALERT0_CPU1_N @BASEBOARD_FAB2_LIB.BASEBOARD_FAB2(SCH_1):SVID_ALERT0_CPU1_N    I27 @BASEBOARD_FAB2_LIB.BASEBOARD_FAB2(SCH_1):PAGE55
     2 SVID_ALERT0_CPU1_R_N @BASEBOARD_FAB2_LIB.BASEBOARD_FAB2(SCH_1):SVID_ALERT0_CPU1_R_N    I27 @BASEBOARD_FAB2_LIB.BASEBOARD_FAB2(SCH_1):PAGE55

R3B2 RES_0402-49.9,1%,1/16W,CHIP,G2A
     1 SVID_ALERT0_CPU1_R_N @BASEBOARD_FAB2_LIB.BASEBOARD_FAB2(SCH_1):SVID_ALERT0_CPU1_R_N    I19 @BASEBOARD_FAB2_LIB.BASEBOARD_FAB2(SCH_1):PAGE55
     2 PVCCIO_CPU1 @BASEBOARD_FAB2_LIB.BASEBOARD_FAB2(SCH_1):PVCCIO_CPU1    I19 @BASEBOARD_FAB2_LIB.BASEBOARD_FAB2(SCH_1):PAGE55

R3B3 RES_0402-0.0,5%,1/16W,CHIP,G21A
     1 SVID_DIO0_CPU1 @BASEBOARD_FAB2_LIB.BASEBOARD_FAB2(SCH_1):SVID_DIO0_CPU1    I29 @BASEBOARD_FAB2_LIB.BASEBOARD_FAB2(SCH_1):PAGE55
     2 SVID_DIO0_CPU1_R @BASEBOARD_FAB2_LIB.BASEBOARD_FAB2(SCH_1):SVID_DIO0_CPU1_R    I29 @BASEBOARD_FAB2_LIB.BASEBOARD_FAB2(SCH_1):PAGE55

R3B4 RES_0402-100.0,1%,1/16W,CHIP,GA
     1 SVID_DIO0_CPU1_R @BASEBOARD_FAB2_LIB.BASEBOARD_FAB2(SCH_1):SVID_DIO0_CPU1_R    I21 @BASEBOARD_FAB2_LIB.BASEBOARD_FAB2(SCH_1):PAGE55
     2 PVCCIO_CPU1 @BASEBOARD_FAB2_LIB.BASEBOARD_FAB2(SCH_1):PVCCIO_CPU1    I21 @BASEBOARD_FAB2_LIB.BASEBOARD_FAB2(SCH_1):PAGE55

R3B5 RES_0402-0.0,5%,1/16W,CHIP,G21A
     1 SVID_CLK0_CPU1 @BASEBOARD_FAB2_LIB.BASEBOARD_FAB2(SCH_1):SVID_CLK0_CPU1    I28 @BASEBOARD_FAB2_LIB.BASEBOARD_FAB2(SCH_1):PAGE55
     2 SVID_CLK0_CPU1_R @BASEBOARD_FAB2_LIB.BASEBOARD_FAB2(SCH_1):SVID_CLK0_CPU1_R    I28 @BASEBOARD_FAB2_LIB.BASEBOARD_FAB2(SCH_1):PAGE55

R3D1 RES_0402-90.9,1%,1/16W,CHIP,G2A
     1 A_CPU1_KLM_RCOMP0 @BASEBOARD_FAB2_LIB.BASEBOARD_FAB2(SCH_1):A_CPU1_KLM_RCOMP0   I116 @BASEBOARD_FAB2_LIB.BASEBOARD_FAB2(SCH_1):PAGE55
     2    GND @BASEBOARD_FAB2_LIB.BASEBOARD_FAB2(SCH_1):GND   I116 @BASEBOARD_FAB2_LIB.BASEBOARD_FAB2(SCH_1):PAGE55

R3D2 RES_0402-90.9,1%,1/16W,CHIP,G2A
     1 A_CPU1_KLM_RCOMP1 @BASEBOARD_FAB2_LIB.BASEBOARD_FAB2(SCH_1):A_CPU1_KLM_RCOMP1   I117 @BASEBOARD_FAB2_LIB.BASEBOARD_FAB2(SCH_1):PAGE55
     2    GND @BASEBOARD_FAB2_LIB.BASEBOARD_FAB2(SCH_1):GND   I117 @BASEBOARD_FAB2_LIB.BASEBOARD_FAB2(SCH_1):PAGE55

R3D3 RES_0402-100.0,1%,1/16W,CHIP,GA
     1 A_CPU1_KLM_RCOMP2 @BASEBOARD_FAB2_LIB.BASEBOARD_FAB2(SCH_1):A_CPU1_KLM_RCOMP2   I118 @BASEBOARD_FAB2_LIB.BASEBOARD_FAB2(SCH_1):PAGE55
     2    GND @BASEBOARD_FAB2_LIB.BASEBOARD_FAB2(SCH_1):GND   I118 @BASEBOARD_FAB2_LIB.BASEBOARD_FAB2(SCH_1):PAGE55

R3D4 RES_0402-49.9,1%,1/16W,CHIP,G2A
     1 A_CPU1_MCP01_RBIAS @BASEBOARD_FAB2_LIB.BASEBOARD_FAB2(SCH_1):A_CPU1_MCP01_RBIAS   I155 @BASEBOARD_FAB2_LIB.BASEBOARD_FAB2(SCH_1):PAGE55
     2    GND @BASEBOARD_FAB2_LIB.BASEBOARD_FAB2(SCH_1):GND   I155 @BASEBOARD_FAB2_LIB.BASEBOARD_FAB2(SCH_1):PAGE55

R3D9 RES_0402-49.9,1%,1/16W,CHIP,G2A
     1 PD_CPU1_TEST12 @BASEBOARD_FAB2_LIB.BASEBOARD_FAB2(SCH_1):PD_CPU1_TEST12    I88 @BASEBOARD_FAB2_LIB.BASEBOARD_FAB2(SCH_1):PAGE90
     2    GND @BASEBOARD_FAB2_LIB.BASEBOARD_FAB2(SCH_1):GND    I88 @BASEBOARD_FAB2_LIB.BASEBOARD_FAB2(SCH_1):PAGE90

R3D12 RES_0402-240,1.0%,1/16W,EMPTY,A
     1    GND @BASEBOARD_FAB2_LIB.BASEBOARD_FAB2(SCH_1):GND   I102 @BASEBOARD_FAB2_LIB.BASEBOARD_FAB2(SCH_1):PAGE90
     2 PD_CPU1_TXT_PLTEN @BASEBOARD_FAB2_LIB.BASEBOARD_FAB2(SCH_1):PD_CPU1_TXT_PLTEN   I102 @BASEBOARD_FAB2_LIB.BASEBOARD_FAB2(SCH_1):PAGE90

R3D13 RES_0402-240,1.0%,1/16W,EMPTY,A
     1    GND @BASEBOARD_FAB2_LIB.BASEBOARD_FAB2(SCH_1):GND    I99 @BASEBOARD_FAB2_LIB.BASEBOARD_FAB2(SCH_1):PAGE90
     2 PD_CPU1_BIST_ENABLE @BASEBOARD_FAB2_LIB.BASEBOARD_FAB2(SCH_1):PD_CPU1_BIST_ENABLE    I99 @BASEBOARD_FAB2_LIB.BASEBOARD_FAB2(SCH_1):PAGE90

R3D14 RES_0603-2.2,1.0%,1/10W,CHIP,GA
     1 P3V3_DB1200 @BASEBOARD_FAB2_LIB.BASEBOARD_FAB2(SCH_1):P3V3_DB1200    I21 @BASEBOARD_FAB2_LIB.BASEBOARD_FAB2(SCH_1):PAGE102
     2 P3V3_DB1200_A @BASEBOARD_FAB2_LIB.BASEBOARD_FAB2(SCH_1):P3V3_DB1200_A    I21 @BASEBOARD_FAB2_LIB.BASEBOARD_FAB2(SCH_1):PAGE102

R3D15 RES_0402-49.9,1%,1/16W,CHIP,G2A
     1 PVCCIO_CPU1 @BASEBOARD_FAB2_LIB.BASEBOARD_FAB2(SCH_1):PVCCIO_CPU1    I26 @BASEBOARD_FAB2_LIB.BASEBOARD_FAB2(SCH_1):PAGE96
     2 PWRGD_CPU1_G @BASEBOARD_FAB2_LIB.BASEBOARD_FAB2(SCH_1):PWRGD_CPU1_G    I26 @BASEBOARD_FAB2_LIB.BASEBOARD_FAB2(SCH_1):PAGE96

R3D16 RES_0402-240,1.0%,1/16W,EMPTY,A
     1 PVCCIO_CPU1 @BASEBOARD_FAB2_LIB.BASEBOARD_FAB2(SCH_1):PVCCIO_CPU1    I24 @BASEBOARD_FAB2_LIB.BASEBOARD_FAB2(SCH_1):PAGE90
     2 H_CPU1_BMCINIT @BASEBOARD_FAB2_LIB.BASEBOARD_FAB2(SCH_1):H_CPU1_BMCINIT    I24 @BASEBOARD_FAB2_LIB.BASEBOARD_FAB2(SCH_1):PAGE90

R3D17 RES_0402-240,1.0%,1/16W,EMPTY,A
     1 PVCCIO_CPU1 @BASEBOARD_FAB2_LIB.BASEBOARD_FAB2(SCH_1):PVCCIO_CPU1    I60 @BASEBOARD_FAB2_LIB.BASEBOARD_FAB2(SCH_1):PAGE90
     2 PU_CPU1_SOCKET_ID_1 @BASEBOARD_FAB2_LIB.BASEBOARD_FAB2(SCH_1):PU_CPU1_SOCKET_ID_1    I60 @BASEBOARD_FAB2_LIB.BASEBOARD_FAB2(SCH_1):PAGE90

R3D18 RES_0402-0.0,5%,1/16W,CHIP,G21A
     1 H_CPU0_FAST_WAKE_N @BASEBOARD_FAB2_LIB.BASEBOARD_FAB2(SCH_1):H_CPU0_FAST_WAKE_N    I33 @BASEBOARD_FAB2_LIB.BASEBOARD_FAB2(SCH_1):PAGE97
     2 H_CPU1_FAST_WAKE_N @BASEBOARD_FAB2_LIB.BASEBOARD_FAB2(SCH_1):H_CPU1_FAST_WAKE_N    I33 @BASEBOARD_FAB2_LIB.BASEBOARD_FAB2(SCH_1):PAGE97

R3D19 RES_0402-49.9,1%,1/16W,CHIP,G2A
     1 A_CPU1_UPI01_RBIAS @BASEBOARD_FAB2_LIB.BASEBOARD_FAB2(SCH_1):A_CPU1_UPI01_RBIAS   I125 @BASEBOARD_FAB2_LIB.BASEBOARD_FAB2(SCH_1):PAGE55
     2    GND @BASEBOARD_FAB2_LIB.BASEBOARD_FAB2(SCH_1):GND   I125 @BASEBOARD_FAB2_LIB.BASEBOARD_FAB2(SCH_1):PAGE55

R3D20 RES_0402-49.9,1%,1/16W,CHIP,G2A
     1 PVCCIO_CPU1 @BASEBOARD_FAB2_LIB.BASEBOARD_FAB2(SCH_1):PVCCIO_CPU1    I25 @BASEBOARD_FAB2_LIB.BASEBOARD_FAB2(SCH_1):PAGE96
     2 RST_CPU1_G_N @BASEBOARD_FAB2_LIB.BASEBOARD_FAB2(SCH_1):RST_CPU1_G_N    I25 @BASEBOARD_FAB2_LIB.BASEBOARD_FAB2(SCH_1):PAGE96

R3D21 RES_0402-64.9,1.0%,1/16W,CHIP,A
     1 PVDDQ_GHJ @BASEBOARD_FAB2_LIB.BASEBOARD_FAB2(SCH_1):PVDDQ_GHJ    I30 @BASEBOARD_FAB2_LIB.BASEBOARD_FAB2(SCH_1):PAGE96
     2 PWRGD_CPU1_DRAMPWROK_GHJ_G @BASEBOARD_FAB2_LIB.BASEBOARD_FAB2(SCH_1):PWRGD_CPU1_DRAMPWROK_GHJ_G    I30 @BASEBOARD_FAB2_LIB.BASEBOARD_FAB2(SCH_1):PAGE96

R3D22 RES_0402-240,1.0%,1/16W,EMPTY,A
     1 PVCCIO_CPU1 @BASEBOARD_FAB2_LIB.BASEBOARD_FAB2(SCH_1):PVCCIO_CPU1    I17 @BASEBOARD_FAB2_LIB.BASEBOARD_FAB2(SCH_1):PAGE90
     2 PU_CPU1_FRMAGENT @BASEBOARD_FAB2_LIB.BASEBOARD_FAB2(SCH_1):PU_CPU1_FRMAGENT    I17 @BASEBOARD_FAB2_LIB.BASEBOARD_FAB2(SCH_1):PAGE90

R3D23 RES_0402-240,1.0%,1/16W,EMPTY,A
     1 PVCCIO_CPU1 @BASEBOARD_FAB2_LIB.BASEBOARD_FAB2(SCH_1):PVCCIO_CPU1    I25 @BASEBOARD_FAB2_LIB.BASEBOARD_FAB2(SCH_1):PAGE90
     2 PU_CPU1_TXT_AGENT @BASEBOARD_FAB2_LIB.BASEBOARD_FAB2(SCH_1):PU_CPU1_TXT_AGENT    I25 @BASEBOARD_FAB2_LIB.BASEBOARD_FAB2(SCH_1):PAGE90

R3D24 RES_0402-240,1.0%,1/16W,CHIP,GA
     1 PVCCIO_CPU1 @BASEBOARD_FAB2_LIB.BASEBOARD_FAB2(SCH_1):PVCCIO_CPU1    I59 @BASEBOARD_FAB2_LIB.BASEBOARD_FAB2(SCH_1):PAGE90
     2 PU_CPU1_SOCKET_ID_0 @BASEBOARD_FAB2_LIB.BASEBOARD_FAB2(SCH_1):PU_CPU1_SOCKET_ID_0    I59 @BASEBOARD_FAB2_LIB.BASEBOARD_FAB2(SCH_1):PAGE90

R3D25 RES_0402-240,1.0%,1/16W,EMPTY,A
     1    GND @BASEBOARD_FAB2_LIB.BASEBOARD_FAB2(SCH_1):GND    I66 @BASEBOARD_FAB2_LIB.BASEBOARD_FAB2(SCH_1):PAGE90
     2 PD_CPU1_EAR_N @BASEBOARD_FAB2_LIB.BASEBOARD_FAB2(SCH_1):PD_CPU1_EAR_N    I66 @BASEBOARD_FAB2_LIB.BASEBOARD_FAB2(SCH_1):PAGE90

R3D26 RES_0402-240,1.0%,1/16W,EMPTY,A
     1 PVCCIO_CPU1 @BASEBOARD_FAB2_LIB.BASEBOARD_FAB2(SCH_1):PVCCIO_CPU1    I28 @BASEBOARD_FAB2_LIB.BASEBOARD_FAB2(SCH_1):PAGE90
     2 PU_CPU1_SAFE_MODE_BOOT @BASEBOARD_FAB2_LIB.BASEBOARD_FAB2(SCH_1):PU_CPU1_SAFE_MODE_BOOT    I28 @BASEBOARD_FAB2_LIB.BASEBOARD_FAB2(SCH_1):PAGE90

R3D27 RES_0402-249,0.1%,1/16W,CHIP,GA
     1 VSENSE_PMAX_CPU1 @BASEBOARD_FAB2_LIB.BASEBOARD_FAB2(SCH_1):VSENSE_PMAX_CPU1    I43 @BASEBOARD_FAB2_LIB.BASEBOARD_FAB2(SCH_1):PAGE71
     2    GND @BASEBOARD_FAB2_LIB.BASEBOARD_FAB2(SCH_1):GND    I43 @BASEBOARD_FAB2_LIB.BASEBOARD_FAB2(SCH_1):PAGE71

R3D28 RES_0402-100.0,1%,1/16W,CHIP,GA
     1 VSENSE_PVCCIO_CPU1_AVSN @BASEBOARD_FAB2_LIB.BASEBOARD_FAB2(SCH_1):VSENSE_PVCCIO_CPU1_AVSN   I101 @BASEBOARD_FAB2_LIB.BASEBOARD_FAB2(SCH_1):PAGE214
     2    GND @BASEBOARD_FAB2_LIB.BASEBOARD_FAB2(SCH_1):GND   I101 @BASEBOARD_FAB2_LIB.BASEBOARD_FAB2(SCH_1):PAGE214

R3D31 RES_0402-0.0,5%,1/16W,EMPTY,G2A
     1 FM_CPU_BMC_INIT @BASEBOARD_FAB2_LIB.BASEBOARD_FAB2(SCH_1):FM_CPU_BMC_INIT   I300 @BASEBOARD_FAB2_LIB.BASEBOARD_FAB2(SCH_1):PAGE156
     2 H_CPU1_BMCINIT @BASEBOARD_FAB2_LIB.BASEBOARD_FAB2(SCH_1):H_CPU1_BMCINIT   I300 @BASEBOARD_FAB2_LIB.BASEBOARD_FAB2(SCH_1):PAGE156

R3D32 RES_0402-10.0,1%,1/16W,EMPTY,GA
     1 PVCCIO_CPU1 @BASEBOARD_FAB2_LIB.BASEBOARD_FAB2(SCH_1):PVCCIO_CPU1    I53 @BASEBOARD_FAB2_LIB.BASEBOARD_FAB2(SCH_1):PAGE71
     2 VSENSE_PMAX_CPU1 @BASEBOARD_FAB2_LIB.BASEBOARD_FAB2(SCH_1):VSENSE_PMAX_CPU1    I53 @BASEBOARD_FAB2_LIB.BASEBOARD_FAB2(SCH_1):PAGE71

R3E1 RES_0402-100.0,1%,1/16W,CHIP,GA
     1 VSENSE_PVCCIO_CPU1_AVSP @BASEBOARD_FAB2_LIB.BASEBOARD_FAB2(SCH_1):VSENSE_PVCCIO_CPU1_AVSP   I105 @BASEBOARD_FAB2_LIB.BASEBOARD_FAB2(SCH_1):PAGE214
     2 PVCCIO_CPU1 @BASEBOARD_FAB2_LIB.BASEBOARD_FAB2(SCH_1):PVCCIO_CPU1   I105 @BASEBOARD_FAB2_LIB.BASEBOARD_FAB2(SCH_1):PAGE214

R3F1 RES_0402-0.0,5%,1/16W,EMPTY,G2A
     1 CLK_322M_156M_CPU1_OSC_VRM_DN @BASEBOARD_FAB2_LIB.BASEBOARD_FAB2(SCH_1):CLK_322M_156M_CPU1_OSC_VRM_DN    I51 @BASEBOARD_FAB2_LIB.BASEBOARD_FAB2(SCH_1):PAGE104
     2 CLK_156M_OSC_CPU1_HFI_DN @BASEBOARD_FAB2_LIB.BASEBOARD_FAB2(SCH_1):CLK_156M_OSC_CPU1_HFI_DN    I51 @BASEBOARD_FAB2_LIB.BASEBOARD_FAB2(SCH_1):PAGE104

R3F2 RES_0402-0.0,5%,1/16W,CHIP,G21A
     1 CLK_156M_OSC_BRD_CPU1_DN @BASEBOARD_FAB2_LIB.BASEBOARD_FAB2(SCH_1):CLK_156M_OSC_BRD_CPU1_DN    I69 @BASEBOARD_FAB2_LIB.BASEBOARD_FAB2(SCH_1):PAGE104
     2 CLK_156M_OSC_CPU1_HFI_DN @BASEBOARD_FAB2_LIB.BASEBOARD_FAB2(SCH_1):CLK_156M_OSC_CPU1_HFI_DN    I69 @BASEBOARD_FAB2_LIB.BASEBOARD_FAB2(SCH_1):PAGE104

R3F3 RES_0402-0.0,5%,1/16W,EMPTY,G2A
     1 CLK_322M_156M_CPU1_OSC_VRM_DP @BASEBOARD_FAB2_LIB.BASEBOARD_FAB2(SCH_1):CLK_322M_156M_CPU1_OSC_VRM_DP    I53 @BASEBOARD_FAB2_LIB.BASEBOARD_FAB2(SCH_1):PAGE104
     2 CLK_156M_OSC_CPU1_HFI_DP @BASEBOARD_FAB2_LIB.BASEBOARD_FAB2(SCH_1):CLK_156M_OSC_CPU1_HFI_DP    I53 @BASEBOARD_FAB2_LIB.BASEBOARD_FAB2(SCH_1):PAGE104

R3F4 RES_0402-0.0,5%,1/16W,CHIP,G21A
     1 CLK_156M_OSC_BRD_CPU1_DP @BASEBOARD_FAB2_LIB.BASEBOARD_FAB2(SCH_1):CLK_156M_OSC_BRD_CPU1_DP    I70 @BASEBOARD_FAB2_LIB.BASEBOARD_FAB2(SCH_1):PAGE104
     2 CLK_156M_OSC_CPU1_HFI_DP @BASEBOARD_FAB2_LIB.BASEBOARD_FAB2(SCH_1):CLK_156M_OSC_CPU1_HFI_DP    I70 @BASEBOARD_FAB2_LIB.BASEBOARD_FAB2(SCH_1):PAGE104

R3F5 RES_0402-0.0,5%,1/16W,EMPTY,G2A
     1 CLK_322M_156M_CPU1_OSC_VRM_DN @BASEBOARD_FAB2_LIB.BASEBOARD_FAB2(SCH_1):CLK_322M_156M_CPU1_OSC_VRM_DN    I84 @BASEBOARD_FAB2_LIB.BASEBOARD_FAB2(SCH_1):PAGE104
     2 CLK_322M_OSC_CPU1_RC_DN @BASEBOARD_FAB2_LIB.BASEBOARD_FAB2(SCH_1):CLK_322M_OSC_CPU1_RC_DN    I84 @BASEBOARD_FAB2_LIB.BASEBOARD_FAB2(SCH_1):PAGE104

R3F6 RES_0402-0.0,5%,1/16W,EMPTY,G2A
     1 CLK_322M_156M_CPU1_OSC_VRM_DP @BASEBOARD_FAB2_LIB.BASEBOARD_FAB2(SCH_1):CLK_322M_156M_CPU1_OSC_VRM_DP    I88 @BASEBOARD_FAB2_LIB.BASEBOARD_FAB2(SCH_1):PAGE104
     2 CLK_322M_OSC_CPU1_RC_DP @BASEBOARD_FAB2_LIB.BASEBOARD_FAB2(SCH_1):CLK_322M_OSC_CPU1_RC_DP    I88 @BASEBOARD_FAB2_LIB.BASEBOARD_FAB2(SCH_1):PAGE104

R3L1 RES_0402-0.0,5%,1/16W,CHIP,G21A
     1 VR_PVNN_PCH_PH1_VCIN @BASEBOARD_FAB2_LIB.BASEBOARD_FAB2(SCH_1):VR_PVNN_PCH_PH1_VCIN   I175 @BASEBOARD_FAB2_LIB.BASEBOARD_FAB2(SCH_1):PAGE236
     2 P5V_STBY @BASEBOARD_FAB2_LIB.BASEBOARD_FAB2(SCH_1):P5V_STBY   I175 @BASEBOARD_FAB2_LIB.BASEBOARD_FAB2(SCH_1):PAGE236

R3L4 RES_0402-0.0,5%,1/16W,CHIP,G21A
     1 VR_P1V05_PCH_STBY_PH1_VCIN @BASEBOARD_FAB2_LIB.BASEBOARD_FAB2(SCH_1):VR_P1V05_PCH_STBY_PH1_VCIN   I177 @BASEBOARD_FAB2_LIB.BASEBOARD_FAB2(SCH_1):PAGE236
     2 P5V_STBY @BASEBOARD_FAB2_LIB.BASEBOARD_FAB2(SCH_1):P5V_STBY   I177 @BASEBOARD_FAB2_LIB.BASEBOARD_FAB2(SCH_1):PAGE236

R3L6 RES_0402-0.0,5%,1/16W,CHIP,G21A
     1 VR_PVDDQ_DEF_PH1_VCIN @BASEBOARD_FAB2_LIB.BASEBOARD_FAB2(SCH_1):VR_PVDDQ_DEF_PH1_VCIN   I147 @BASEBOARD_FAB2_LIB.BASEBOARD_FAB2(SCH_1):PAGE219
     2 P5V_STBY @BASEBOARD_FAB2_LIB.BASEBOARD_FAB2(SCH_1):P5V_STBY   I147 @BASEBOARD_FAB2_LIB.BASEBOARD_FAB2(SCH_1):PAGE219

R3L8 RES_0402-0.0,5%,1/16W,CHIP,G21A
     1 VR_PVDDQ_DEF_PH2_VCIN @BASEBOARD_FAB2_LIB.BASEBOARD_FAB2(SCH_1):VR_PVDDQ_DEF_PH2_VCIN   I148 @BASEBOARD_FAB2_LIB.BASEBOARD_FAB2(SCH_1):PAGE219
     2 P5V_STBY @BASEBOARD_FAB2_LIB.BASEBOARD_FAB2(SCH_1):P5V_STBY   I148 @BASEBOARD_FAB2_LIB.BASEBOARD_FAB2(SCH_1):PAGE219

R3L11 RES_0402-100.0,1%,1/16W,EMPTY,A
     1 PVCCIO_CPU0 @BASEBOARD_FAB2_LIB.BASEBOARD_FAB2(SCH_1):PVCCIO_CPU0    I67 @BASEBOARD_FAB2_LIB.BASEBOARD_FAB2(SCH_1):PAGE218
     2 SVID_DIO1_CPU0_R @BASEBOARD_FAB2_LIB.BASEBOARD_FAB2(SCH_1):SVID_DIO1_CPU0_R    I67 @BASEBOARD_FAB2_LIB.BASEBOARD_FAB2(SCH_1):PAGE218

R3L13 RES_0402-49.9,1%,1/16W,EMPTY,GA
     1 PVCCIO_CPU0 @BASEBOARD_FAB2_LIB.BASEBOARD_FAB2(SCH_1):PVCCIO_CPU0    I70 @BASEBOARD_FAB2_LIB.BASEBOARD_FAB2(SCH_1):PAGE218
     2 SVID_CLK1_CPU0_R @BASEBOARD_FAB2_LIB.BASEBOARD_FAB2(SCH_1):SVID_CLK1_CPU0_R    I70 @BASEBOARD_FAB2_LIB.BASEBOARD_FAB2(SCH_1):PAGE218

R3L14 RES_0402-68.1K,1%,1/16W,EMPTY,A
     1 VR_P1V05_PCH_STBY_OCSET @BASEBOARD_FAB2_LIB.BASEBOARD_FAB2(SCH_1):VR_P1V05_PCH_STBY_OCSET   I120 @BASEBOARD_FAB2_LIB.BASEBOARD_FAB2(SCH_1):PAGE236
     2    GND @BASEBOARD_FAB2_LIB.BASEBOARD_FAB2(SCH_1):GND   I120 @BASEBOARD_FAB2_LIB.BASEBOARD_FAB2(SCH_1):PAGE236

R3L15 RES_0402-68.1K,1%,1/16W,EMPTY,A
     1 VR_PVNN_PCH_STBY_OCSET @BASEBOARD_FAB2_LIB.BASEBOARD_FAB2(SCH_1):VR_PVNN_PCH_STBY_OCSET   I118 @BASEBOARD_FAB2_LIB.BASEBOARD_FAB2(SCH_1):PAGE236
     2    GND @BASEBOARD_FAB2_LIB.BASEBOARD_FAB2(SCH_1):GND   I118 @BASEBOARD_FAB2_LIB.BASEBOARD_FAB2(SCH_1):PAGE236

R3M1 RES_0402-0.0,5%,1/16W,CHIP,G21A
     1 P3V3_STBY @BASEBOARD_FAB2_LIB.BASEBOARD_FAB2(SCH_1):P3V3_STBY    I35 @BASEBOARD_FAB2_LIB.BASEBOARD_FAB2(SCH_1):PAGE218
     2 VR_PVDDQ_DEF_VDD @BASEBOARD_FAB2_LIB.BASEBOARD_FAB2(SCH_1):VR_PVDDQ_DEF_VDD    I35 @BASEBOARD_FAB2_LIB.BASEBOARD_FAB2(SCH_1):PAGE218

R3M3 RES_0402-22.1,1.0%,1/16W,CHIP,A
     1 PWRGD_PVDDQ_DEF_R @BASEBOARD_FAB2_LIB.BASEBOARD_FAB2(SCH_1):PWRGD_PVDDQ_DEF_R    I60 @BASEBOARD_FAB2_LIB.BASEBOARD_FAB2(SCH_1):PAGE218
     2 PWRGD_PVDDQ_DEF @BASEBOARD_FAB2_LIB.BASEBOARD_FAB2(SCH_1):PWRGD_PVDDQ_DEF    I60 @BASEBOARD_FAB2_LIB.BASEBOARD_FAB2(SCH_1):PAGE218

R3M5 RES_0402-100.0K,1%,1/16W,EMPTYA
     1 P3V3_STBY @BASEBOARD_FAB2_LIB.BASEBOARD_FAB2(SCH_1):P3V3_STBY    I34 @BASEBOARD_FAB2_LIB.BASEBOARD_FAB2(SCH_1):PAGE218
     2 VR_PVDDQ_DEF_VREN @BASEBOARD_FAB2_LIB.BASEBOARD_FAB2(SCH_1):VR_PVDDQ_DEF_VREN    I34 @BASEBOARD_FAB2_LIB.BASEBOARD_FAB2(SCH_1):PAGE218

R3M6 RES_0402-0.0,5%,1/16W,CHIP,G21A
     1 FM_PVDDQ_DEF_EN @BASEBOARD_FAB2_LIB.BASEBOARD_FAB2(SCH_1):FM_PVDDQ_DEF_EN    I15 @BASEBOARD_FAB2_LIB.BASEBOARD_FAB2(SCH_1):PAGE218
     2 VR_PVDDQ_DEF_VREN @BASEBOARD_FAB2_LIB.BASEBOARD_FAB2(SCH_1):VR_PVDDQ_DEF_VREN    I15 @BASEBOARD_FAB2_LIB.BASEBOARD_FAB2(SCH_1):PAGE218

R3M8 RES_0402-100.0K,1%,1/16W,CHIP,A
     1 P2E_SSB_BMC_RX_C_DP @BASEBOARD_FAB2_LIB.BASEBOARD_FAB2(SCH_1):P2E_SSB_BMC_RX_C_DP   I235 @BASEBOARD_FAB2_LIB.BASEBOARD_FAB2(SCH_1):PAGE116
     2    GND @BASEBOARD_FAB2_LIB.BASEBOARD_FAB2(SCH_1):GND   I235 @BASEBOARD_FAB2_LIB.BASEBOARD_FAB2(SCH_1):PAGE116

R3M9 RES_0402-100.0K,1%,1/16W,CHIP,A
     1 P2E_SSB_BMC_RX_C_DN @BASEBOARD_FAB2_LIB.BASEBOARD_FAB2(SCH_1):P2E_SSB_BMC_RX_C_DN   I234 @BASEBOARD_FAB2_LIB.BASEBOARD_FAB2(SCH_1):PAGE116
     2    GND @BASEBOARD_FAB2_LIB.BASEBOARD_FAB2(SCH_1):GND   I234 @BASEBOARD_FAB2_LIB.BASEBOARD_FAB2(SCH_1):PAGE116

R3M10 RES_0402-1.00K,1%,1/16W,CHIP,GA
     1 XDP_PCH_CPU_TCK0 @BASEBOARD_FAB2_LIB.BASEBOARD_FAB2(SCH_1):XDP_PCH_CPU_TCK0    I85 @BASEBOARD_FAB2_LIB.BASEBOARD_FAB2(SCH_1):PAGE112
     2    GND @BASEBOARD_FAB2_LIB.BASEBOARD_FAB2(SCH_1):GND    I85 @BASEBOARD_FAB2_LIB.BASEBOARD_FAB2(SCH_1):PAGE112

R3M11 RES_0402-100.0,1%,1/16W,CHIP,GA
     1 A_PCIE_RCOMP_P @BASEBOARD_FAB2_LIB.BASEBOARD_FAB2(SCH_1):A_PCIE_RCOMP_P   I108 @BASEBOARD_FAB2_LIB.BASEBOARD_FAB2(SCH_1):PAGE116
     2 A_PCIE_RCOMP_N @BASEBOARD_FAB2_LIB.BASEBOARD_FAB2(SCH_1):A_PCIE_RCOMP_N   I108 @BASEBOARD_FAB2_LIB.BASEBOARD_FAB2(SCH_1):PAGE116

R3M12 RES_0402-100.0,1%,1/16W,CHIP,GA
     1 A_PCIEUP_RCOMP_P @BASEBOARD_FAB2_LIB.BASEBOARD_FAB2(SCH_1):A_PCIEUP_RCOMP_P   I181 @BASEBOARD_FAB2_LIB.BASEBOARD_FAB2(SCH_1):PAGE116
     2 A_PCIEUP_RCOMP_N @BASEBOARD_FAB2_LIB.BASEBOARD_FAB2(SCH_1):A_PCIEUP_RCOMP_N   I181 @BASEBOARD_FAB2_LIB.BASEBOARD_FAB2(SCH_1):PAGE116

R3N1 RES_0402-169,1.0%,1/16W,CHIP,GA
     1 A_PCH_XCLK_BIASREF @BASEBOARD_FAB2_LIB.BASEBOARD_FAB2(SCH_1):A_PCH_XCLK_BIASREF   I149 @BASEBOARD_FAB2_LIB.BASEBOARD_FAB2(SCH_1):PAGE114
     2    GND @BASEBOARD_FAB2_LIB.BASEBOARD_FAB2(SCH_1):GND   I149 @BASEBOARD_FAB2_LIB.BASEBOARD_FAB2(SCH_1):PAGE114

R3N2 RES_0402-4.75K,1%,1/16W,EMPTY,A
     1 P3V3_STBY @BASEBOARD_FAB2_LIB.BASEBOARD_FAB2(SCH_1):P3V3_STBY    I72 @BASEBOARD_FAB2_LIB.BASEBOARD_FAB2(SCH_1):PAGE125
     2 FM_FLASH_DESC_OVERRIDE @BASEBOARD_FAB2_LIB.BASEBOARD_FAB2(SCH_1):FM_FLASH_DESC_OVERRIDE    I72 @BASEBOARD_FAB2_LIB.BASEBOARD_FAB2(SCH_1):PAGE125

R3N3 RES_0402-2.0K,1%,1/16W,CHIP,G2A
     1    GND @BASEBOARD_FAB2_LIB.BASEBOARD_FAB2(SCH_1):GND   I120 @BASEBOARD_FAB2_LIB.BASEBOARD_FAB2(SCH_1):PAGE133
     2 PWRGD_PCH_PWROK @BASEBOARD_FAB2_LIB.BASEBOARD_FAB2(SCH_1):PWRGD_PCH_PWROK   I120 @BASEBOARD_FAB2_LIB.BASEBOARD_FAB2(SCH_1):PAGE133

R3N4 RES_0402-20.0K,1%,1/16W,CHIP,GA
     1 P3V3_RTC_STBY @BASEBOARD_FAB2_LIB.BASEBOARD_FAB2(SCH_1):P3V3_RTC_STBY    I19 @BASEBOARD_FAB2_LIB.BASEBOARD_FAB2(SCH_1):PAGE137
     2 RST_SRTCRST_N @BASEBOARD_FAB2_LIB.BASEBOARD_FAB2(SCH_1):RST_SRTCRST_N    I19 @BASEBOARD_FAB2_LIB.BASEBOARD_FAB2(SCH_1):PAGE137

R3N7 RES_0402-0.0,5%,1/16W,CHIP,G21A
     1 VR_PVCCIO_CPU0_PH1_VCIN @BASEBOARD_FAB2_LIB.BASEBOARD_FAB2(SCH_1):VR_PVCCIO_CPU0_PH1_VCIN   I140 @BASEBOARD_FAB2_LIB.BASEBOARD_FAB2(SCH_1):PAGE212
     2 P5V_STBY @BASEBOARD_FAB2_LIB.BASEBOARD_FAB2(SCH_1):P5V_STBY   I140 @BASEBOARD_FAB2_LIB.BASEBOARD_FAB2(SCH_1):PAGE212

R3N9 RES_0402-10.0,1%,1/16W,CHIP,G2A
     1 H_PM_SYNC1_GTL_R @BASEBOARD_FAB2_LIB.BASEBOARD_FAB2(SCH_1):H_PM_SYNC1_GTL_R    I66 @BASEBOARD_FAB2_LIB.BASEBOARD_FAB2(SCH_1):PAGE118
     2 H_PM_SYNC_GTL @BASEBOARD_FAB2_LIB.BASEBOARD_FAB2(SCH_1):H_PM_SYNC_GTL    I66 @BASEBOARD_FAB2_LIB.BASEBOARD_FAB2(SCH_1):PAGE118

R3N10 RES_0402-10.0K,1%,1/16W,CHIP,GA
     1 P3V3_STBY @BASEBOARD_FAB2_LIB.BASEBOARD_FAB2(SCH_1):P3V3_STBY    I37 @BASEBOARD_FAB2_LIB.BASEBOARD_FAB2(SCH_1):PAGE121
     2 FM_INTRUDER_HDR_PCH_N @BASEBOARD_FAB2_LIB.BASEBOARD_FAB2(SCH_1):FM_INTRUDER_HDR_PCH_N    I37 @BASEBOARD_FAB2_LIB.BASEBOARD_FAB2(SCH_1):PAGE121

R3N11 RES_0402-4.75K,1%,1/16W,CHIP,GA
     1 P3V3_STBY @BASEBOARD_FAB2_LIB.BASEBOARD_FAB2(SCH_1):P3V3_STBY   I344 @BASEBOARD_FAB2_LIB.BASEBOARD_FAB2(SCH_1):PAGE157
     2 FM_MP_PS_REDUNDANT_LOST_N @BASEBOARD_FAB2_LIB.BASEBOARD_FAB2(SCH_1):FM_MP_PS_REDUNDANT_LOST_N   I344 @BASEBOARD_FAB2_LIB.BASEBOARD_FAB2(SCH_1):PAGE157

R3N12 RES_0402-4.75K,1%,1/16W,CHIP,GA
     1 P3V3_STBY @BASEBOARD_FAB2_LIB.BASEBOARD_FAB2(SCH_1):P3V3_STBY   I342 @BASEBOARD_FAB2_LIB.BASEBOARD_FAB2(SCH_1):PAGE157
     2 FM_MP_PS_FAIL_N @BASEBOARD_FAB2_LIB.BASEBOARD_FAB2(SCH_1):FM_MP_PS_FAIL_N   I342 @BASEBOARD_FAB2_LIB.BASEBOARD_FAB2(SCH_1):PAGE157

R3N13 RES_0402-4.75K,1%,1/16W,CHIP,GA
     1 P3V3_STBY @BASEBOARD_FAB2_LIB.BASEBOARD_FAB2(SCH_1):P3V3_STBY    I71 @BASEBOARD_FAB2_LIB.BASEBOARD_FAB2(SCH_1):PAGE118
     2 IRQ_LVC3_WAKE_N @BASEBOARD_FAB2_LIB.BASEBOARD_FAB2(SCH_1):IRQ_LVC3_WAKE_N    I71 @BASEBOARD_FAB2_LIB.BASEBOARD_FAB2(SCH_1):PAGE118

R3N14 RES_0402-49.9,1%,1/16W,EMPTY,GA
     1 H_PM_SYNC_GTL @BASEBOARD_FAB2_LIB.BASEBOARD_FAB2(SCH_1):H_PM_SYNC_GTL    I67 @BASEBOARD_FAB2_LIB.BASEBOARD_FAB2(SCH_1):PAGE118
     2    GND @BASEBOARD_FAB2_LIB.BASEBOARD_FAB2(SCH_1):GND    I67 @BASEBOARD_FAB2_LIB.BASEBOARD_FAB2(SCH_1):PAGE118

R3N15 RES_0402-1.00K,1%,1/16W,EMPTY,A
     1 P1V05_PCH_STBY @BASEBOARD_FAB2_LIB.BASEBOARD_FAB2(SCH_1):P1V05_PCH_STBY   I368 @BASEBOARD_FAB2_LIB.BASEBOARD_FAB2(SCH_1):PAGE133
     2 FM_PRSNT_2_4_N @BASEBOARD_FAB2_LIB.BASEBOARD_FAB2(SCH_1):FM_PRSNT_2_4_N   I368 @BASEBOARD_FAB2_LIB.BASEBOARD_FAB2(SCH_1):PAGE133

R3N16 RES_0402-1.00K,1%,1/16W,EMPTY,A
     1 P1V05_PCH_STBY @BASEBOARD_FAB2_LIB.BASEBOARD_FAB2(SCH_1):P1V05_PCH_STBY   I369 @BASEBOARD_FAB2_LIB.BASEBOARD_FAB2(SCH_1):PAGE133
     2 FM_PRSNT_2_5_N @BASEBOARD_FAB2_LIB.BASEBOARD_FAB2(SCH_1):FM_PRSNT_2_5_N   I369 @BASEBOARD_FAB2_LIB.BASEBOARD_FAB2(SCH_1):PAGE133

R3N17 RES_0402-1.00K,1%,1/16W,EMPTY,A
     1 P3V3_STBY @BASEBOARD_FAB2_LIB.BASEBOARD_FAB2(SCH_1):P3V3_STBY    I78 @BASEBOARD_FAB2_LIB.BASEBOARD_FAB2(SCH_1):PAGE125
     2 SPI_PCH_IO3 @BASEBOARD_FAB2_LIB.BASEBOARD_FAB2(SCH_1):SPI_PCH_IO3    I78 @BASEBOARD_FAB2_LIB.BASEBOARD_FAB2(SCH_1):PAGE125

R3N19 RES_0402-10.0,1%,1/16W,CHIP,G2A
     1 VSENSE_PVCCIO_CPU0_AVSP @BASEBOARD_FAB2_LIB.BASEBOARD_FAB2(SCH_1):VSENSE_PVCCIO_CPU0_AVSP    I81 @BASEBOARD_FAB2_LIB.BASEBOARD_FAB2(SCH_1):PAGE211
     2 VR_PVCCIO_CPU0_AVSP @BASEBOARD_FAB2_LIB.BASEBOARD_FAB2(SCH_1):VR_PVCCIO_CPU0_AVSP    I81 @BASEBOARD_FAB2_LIB.BASEBOARD_FAB2(SCH_1):PAGE211

R3N20 RES_0402-100.0,1%,1/16W,CHIP,GA
     1 VSENSE_PVCCIO_CPU0_AVSN @BASEBOARD_FAB2_LIB.BASEBOARD_FAB2(SCH_1):VSENSE_PVCCIO_CPU0_AVSN    I68 @BASEBOARD_FAB2_LIB.BASEBOARD_FAB2(SCH_1):PAGE212
     2    GND @BASEBOARD_FAB2_LIB.BASEBOARD_FAB2(SCH_1):GND    I68 @BASEBOARD_FAB2_LIB.BASEBOARD_FAB2(SCH_1):PAGE212

R3N21 RES_0402-100.0,1%,1/16W,CHIP,GA
     1 VSENSE_PVCCIO_CPU0_AVSP @BASEBOARD_FAB2_LIB.BASEBOARD_FAB2(SCH_1):VSENSE_PVCCIO_CPU0_AVSP    I74 @BASEBOARD_FAB2_LIB.BASEBOARD_FAB2(SCH_1):PAGE212
     2 PVCCIO_CPU0 @BASEBOARD_FAB2_LIB.BASEBOARD_FAB2(SCH_1):PVCCIO_CPU0    I74 @BASEBOARD_FAB2_LIB.BASEBOARD_FAB2(SCH_1):PAGE212

R3N22 RES_0402-4.02K,1%,1/16W,CHIP,GA
     1 VR_PVCCIO_CPU0_XADDR2 @BASEBOARD_FAB2_LIB.BASEBOARD_FAB2(SCH_1):VR_PVCCIO_CPU0_XADDR2   I102 @BASEBOARD_FAB2_LIB.BASEBOARD_FAB2(SCH_1):PAGE211
     2    GND @BASEBOARD_FAB2_LIB.BASEBOARD_FAB2(SCH_1):GND   I102 @BASEBOARD_FAB2_LIB.BASEBOARD_FAB2(SCH_1):PAGE211

R3N23 RES_0402-2.26K,1.0%,1/16W,EMPTA
     1 P3V3_STBY @BASEBOARD_FAB2_LIB.BASEBOARD_FAB2(SCH_1):P3V3_STBY    I60 @BASEBOARD_FAB2_LIB.BASEBOARD_FAB2(SCH_1):PAGE211
     2 PU_VR_PVCCIO_CPU0_FAULT1 @BASEBOARD_FAB2_LIB.BASEBOARD_FAB2(SCH_1):PU_VR_PVCCIO_CPU0_FAULT1    I60 @BASEBOARD_FAB2_LIB.BASEBOARD_FAB2(SCH_1):PAGE211

R3N24 RES_0402-33.2,1%,1/16W,CHIP,G2A
     1 LPC_LAD2_IO2 @BASEBOARD_FAB2_LIB.BASEBOARD_FAB2(SCH_1):LPC_LAD2_IO2    I74 @BASEBOARD_FAB2_LIB.BASEBOARD_FAB2(SCH_1):PAGE146
     2 LPC_LAD2_IO2_R @BASEBOARD_FAB2_LIB.BASEBOARD_FAB2(SCH_1):LPC_LAD2_IO2_R    I74 @BASEBOARD_FAB2_LIB.BASEBOARD_FAB2(SCH_1):PAGE146

R3N26 RES_0402-33.2,1%,1/16W,CHIP,G2A
     1 LPC_LAD0_IO0 @BASEBOARD_FAB2_LIB.BASEBOARD_FAB2(SCH_1):LPC_LAD0_IO0    I75 @BASEBOARD_FAB2_LIB.BASEBOARD_FAB2(SCH_1):PAGE146
     2 LPC_LAD0_IO0_R @BASEBOARD_FAB2_LIB.BASEBOARD_FAB2(SCH_1):LPC_LAD0_IO0_R    I75 @BASEBOARD_FAB2_LIB.BASEBOARD_FAB2(SCH_1):PAGE146

R3N29 RES_0402-16K,1.0%,1/16W,CHIP,GA
     1 VR_PVCCIOMCP_CPU0_XADDR1 @BASEBOARD_FAB2_LIB.BASEBOARD_FAB2(SCH_1):VR_PVCCIOMCP_CPU0_XADDR1   I156 @BASEBOARD_FAB2_LIB.BASEBOARD_FAB2(SCH_1):PAGE194
     2    GND @BASEBOARD_FAB2_LIB.BASEBOARD_FAB2(SCH_1):GND   I156 @BASEBOARD_FAB2_LIB.BASEBOARD_FAB2(SCH_1):PAGE194

R3N30 RES_0402-0.0,5%,1/16W,EMPTY,G2A
     1 H_CPU0_MEMABC_MEMHOT_LVT3_N @BASEBOARD_FAB2_LIB.BASEBOARD_FAB2(SCH_1):H_CPU0_MEMABC_MEMHOT_LVT3_N    I95 @BASEBOARD_FAB2_LIB.BASEBOARD_FAB2(SCH_1):PAGE152
     2 H_CPU0_MEMABC_MEMHOT_PCH_N @BASEBOARD_FAB2_LIB.BASEBOARD_FAB2(SCH_1):H_CPU0_MEMABC_MEMHOT_PCH_N    I95 @BASEBOARD_FAB2_LIB.BASEBOARD_FAB2(SCH_1):PAGE152

R3N31 RES_0402-3.16K,1%,1/16W,CHIP,GA
     1 VR_PVCCIO_CPU0_XADDR1 @BASEBOARD_FAB2_LIB.BASEBOARD_FAB2(SCH_1):VR_PVCCIO_CPU0_XADDR1    I52 @BASEBOARD_FAB2_LIB.BASEBOARD_FAB2(SCH_1):PAGE211
     2    GND @BASEBOARD_FAB2_LIB.BASEBOARD_FAB2(SCH_1):GND    I52 @BASEBOARD_FAB2_LIB.BASEBOARD_FAB2(SCH_1):PAGE211

R3P1 RES_0402-0.0,5%,1/16W,CHIP,G21A
     1 SVID_ALERT_PVCCIO_CPU0 @BASEBOARD_FAB2_LIB.BASEBOARD_FAB2(SCH_1):SVID_ALERT_PVCCIO_CPU0    I61 @BASEBOARD_FAB2_LIB.BASEBOARD_FAB2(SCH_1):PAGE211
     2 SVID_ALERT0_CPU0_R_N @BASEBOARD_FAB2_LIB.BASEBOARD_FAB2(SCH_1):SVID_ALERT0_CPU0_R_N    I61 @BASEBOARD_FAB2_LIB.BASEBOARD_FAB2(SCH_1):PAGE211

R3P2 RES_0402-0.0,5%,1/16W,CHIP,G21A
     1 RMII_BMC_PCH_SPRNGVLLE_CRSDV @BASEBOARD_FAB2_LIB.BASEBOARD_FAB2(SCH_1):RMII_BMC_PCH_SPRNGVLLE_CRSDV    I90 @BASEBOARD_FAB2_LIB.BASEBOARD_FAB2(SCH_1):PAGE121
     2 RMII_BMC_PCH_SPRNGVLLE_CRSDV_R1 @BASEBOARD_FAB2_LIB.BASEBOARD_FAB2(SCH_1):RMII_BMC_PCH_SPRNGVLLE_CRSDV_R1    I90 @BASEBOARD_FAB2_LIB.BASEBOARD_FAB2(SCH_1):PAGE121

R3P3 RES_0402-0.0,5%,1/16W,CHIP,G21A
     1 RMII_SPRNGVLLE_BMC_PCH_RXD0 @BASEBOARD_FAB2_LIB.BASEBOARD_FAB2(SCH_1):RMII_SPRNGVLLE_BMC_PCH_RXD0    I89 @BASEBOARD_FAB2_LIB.BASEBOARD_FAB2(SCH_1):PAGE121
     2 RMII_SPRNGVLLE_BMC_PCH_RXD0_R1 @BASEBOARD_FAB2_LIB.BASEBOARD_FAB2(SCH_1):RMII_SPRNGVLLE_BMC_PCH_RXD0_R1    I89 @BASEBOARD_FAB2_LIB.BASEBOARD_FAB2(SCH_1):PAGE121

R3P5 RES_0402-1.00K,1%,1/16W,EMPTY,A
     1 P1V05_PCH_STBY @BASEBOARD_FAB2_LIB.BASEBOARD_FAB2(SCH_1):P1V05_PCH_STBY   I366 @BASEBOARD_FAB2_LIB.BASEBOARD_FAB2(SCH_1):PAGE133
     2 FM_PRSNT_2_2_N @BASEBOARD_FAB2_LIB.BASEBOARD_FAB2(SCH_1):FM_PRSNT_2_2_N   I366 @BASEBOARD_FAB2_LIB.BASEBOARD_FAB2(SCH_1):PAGE133

R3P6 RES_0402-1.00K,1%,1/16W,EMPTY,A
     1 P1V05_PCH_STBY @BASEBOARD_FAB2_LIB.BASEBOARD_FAB2(SCH_1):P1V05_PCH_STBY   I367 @BASEBOARD_FAB2_LIB.BASEBOARD_FAB2(SCH_1):PAGE133
     2 FM_PRSNT_2_3_N @BASEBOARD_FAB2_LIB.BASEBOARD_FAB2(SCH_1):FM_PRSNT_2_3_N   I367 @BASEBOARD_FAB2_LIB.BASEBOARD_FAB2(SCH_1):PAGE133

R3P7 RES_0402-1.00K,1%,1/16W,EMPTY,A
     1 P1V05_PCH_STBY @BASEBOARD_FAB2_LIB.BASEBOARD_FAB2(SCH_1):P1V05_PCH_STBY   I370 @BASEBOARD_FAB2_LIB.BASEBOARD_FAB2(SCH_1):PAGE133
     2 FM_PRSNT_2_1_N @BASEBOARD_FAB2_LIB.BASEBOARD_FAB2(SCH_1):FM_PRSNT_2_1_N   I370 @BASEBOARD_FAB2_LIB.BASEBOARD_FAB2(SCH_1):PAGE133

R3P8 RES_0402-1.00K,1%,1/16W,CHIP,GA
     1 P1V05_PCH_STBY @BASEBOARD_FAB2_LIB.BASEBOARD_FAB2(SCH_1):P1V05_PCH_STBY   I322 @BASEBOARD_FAB2_LIB.BASEBOARD_FAB2(SCH_1):PAGE133
     2 FM_PRSNT_2_6_N @BASEBOARD_FAB2_LIB.BASEBOARD_FAB2(SCH_1):FM_PRSNT_2_6_N   I322 @BASEBOARD_FAB2_LIB.BASEBOARD_FAB2(SCH_1):PAGE133

R3P11 RES_0402-0.0,5%,1/16W,CHIP,G21A
     1 SVID_DIO0_CPU0_R @BASEBOARD_FAB2_LIB.BASEBOARD_FAB2(SCH_1):SVID_DIO0_CPU0_R    I16 @BASEBOARD_FAB2_LIB.BASEBOARD_FAB2(SCH_1):PAGE211
     2 SVID_VDIO_PVCCIO_CPU0 @BASEBOARD_FAB2_LIB.BASEBOARD_FAB2(SCH_1):SVID_VDIO_PVCCIO_CPU0    I16 @BASEBOARD_FAB2_LIB.BASEBOARD_FAB2(SCH_1):PAGE211

R3P12 RES_0402-100.0K,1%,1/16W,CHIP,B
     1 VR_FET_SW_P12V_STBY_PVCCIO_CPU0 @BASEBOARD_FAB2_LIB.BASEBOARD_FAB2(SCH_1):VR_FET_SW_P12V_STBY_PVCCIO_CPU0    I31 @BASEBOARD_FAB2_LIB.BASEBOARD_FAB2(SCH_1):PAGE211
     2 VR_PVCCIO_CPU0_VINSEN @BASEBOARD_FAB2_LIB.BASEBOARD_FAB2(SCH_1):VR_PVCCIO_CPU0_VINSEN    I31 @BASEBOARD_FAB2_LIB.BASEBOARD_FAB2(SCH_1):PAGE211

R3P13 RES_0402-100.0,1%,1/16W,CHIP,GA
     1 PVCCIO_CPU0 @BASEBOARD_FAB2_LIB.BASEBOARD_FAB2(SCH_1):PVCCIO_CPU0   I100 @BASEBOARD_FAB2_LIB.BASEBOARD_FAB2(SCH_1):PAGE211
     2 SVID_DIO0_CPU0_R @BASEBOARD_FAB2_LIB.BASEBOARD_FAB2(SCH_1):SVID_DIO0_CPU0_R   I100 @BASEBOARD_FAB2_LIB.BASEBOARD_FAB2(SCH_1):PAGE211

R3P15 RES_0402-150.0,1%,1/16W,CHIP,GA
     1 SVID_CLK0_CPU0_R @BASEBOARD_FAB2_LIB.BASEBOARD_FAB2(SCH_1):SVID_CLK0_CPU0_R    I29 @BASEBOARD_FAB2_LIB.BASEBOARD_FAB2(SCH_1):PAGE211
     2 SVID_CLK_PVCCIO_CPU0 @BASEBOARD_FAB2_LIB.BASEBOARD_FAB2(SCH_1):SVID_CLK_PVCCIO_CPU0    I29 @BASEBOARD_FAB2_LIB.BASEBOARD_FAB2(SCH_1):PAGE211

R3P16 RES_0402-1.5K,1%,1/16W,CHIP,G2A
     1 VR_PVCCIO_CPU0_VINSEN @BASEBOARD_FAB2_LIB.BASEBOARD_FAB2(SCH_1):VR_PVCCIO_CPU0_VINSEN    I32 @BASEBOARD_FAB2_LIB.BASEBOARD_FAB2(SCH_1):PAGE211
     2    GND @BASEBOARD_FAB2_LIB.BASEBOARD_FAB2(SCH_1):GND    I32 @BASEBOARD_FAB2_LIB.BASEBOARD_FAB2(SCH_1):PAGE211

R3P17 RES_0402-49.9,1%,1/16W,CHIP,G2A
     1 PVCCIO_CPU0 @BASEBOARD_FAB2_LIB.BASEBOARD_FAB2(SCH_1):PVCCIO_CPU0    I99 @BASEBOARD_FAB2_LIB.BASEBOARD_FAB2(SCH_1):PAGE211
     2 SVID_CLK0_CPU0_R @BASEBOARD_FAB2_LIB.BASEBOARD_FAB2(SCH_1):SVID_CLK0_CPU0_R    I99 @BASEBOARD_FAB2_LIB.BASEBOARD_FAB2(SCH_1):PAGE211

R3P18 RES_0402-1.00K,1%,1/16W,CHIP,GA
     1 P3V3_STBY @BASEBOARD_FAB2_LIB.BASEBOARD_FAB2(SCH_1):P3V3_STBY    I64 @BASEBOARD_FAB2_LIB.BASEBOARD_FAB2(SCH_1):PAGE211
     2 IRQ_PVCCIO_CPU0_VRHOT_N @BASEBOARD_FAB2_LIB.BASEBOARD_FAB2(SCH_1):IRQ_PVCCIO_CPU0_VRHOT_N    I64 @BASEBOARD_FAB2_LIB.BASEBOARD_FAB2(SCH_1):PAGE211

R3P20 RES_0402-22.1,1.0%,1/16W,CHIP,A
     1 PWRGD_PVCCIO_CPU0_R @BASEBOARD_FAB2_LIB.BASEBOARD_FAB2(SCH_1):PWRGD_PVCCIO_CPU0_R    I58 @BASEBOARD_FAB2_LIB.BASEBOARD_FAB2(SCH_1):PAGE211
     2 PWRGD_PVCCIO_CPU0 @BASEBOARD_FAB2_LIB.BASEBOARD_FAB2(SCH_1):PWRGD_PVCCIO_CPU0    I58 @BASEBOARD_FAB2_LIB.BASEBOARD_FAB2(SCH_1):PAGE211

R3P21 RES_0402-100.0K,1%,1/16W,EMPTYA
     1 P3V3_STBY @BASEBOARD_FAB2_LIB.BASEBOARD_FAB2(SCH_1):P3V3_STBY    I88 @BASEBOARD_FAB2_LIB.BASEBOARD_FAB2(SCH_1):PAGE211
     2 VR_PVCCIO_CPU0_EN @BASEBOARD_FAB2_LIB.BASEBOARD_FAB2(SCH_1):VR_PVCCIO_CPU0_EN    I88 @BASEBOARD_FAB2_LIB.BASEBOARD_FAB2(SCH_1):PAGE211

R3P22 RES_0402-0.0,5%,1/16W,CHIP,G21A
     1 P3V3_STBY @BASEBOARD_FAB2_LIB.BASEBOARD_FAB2(SCH_1):P3V3_STBY    I24 @BASEBOARD_FAB2_LIB.BASEBOARD_FAB2(SCH_1):PAGE211
     2 VR_PVCCIO_CPU0_VDD @BASEBOARD_FAB2_LIB.BASEBOARD_FAB2(SCH_1):VR_PVCCIO_CPU0_VDD    I24 @BASEBOARD_FAB2_LIB.BASEBOARD_FAB2(SCH_1):PAGE211

R3P25 RES_0402-1.00K,1%,1/16W,CHIP,GA
     1 P3V3_STBY @BASEBOARD_FAB2_LIB.BASEBOARD_FAB2(SCH_1):P3V3_STBY    I56 @BASEBOARD_FAB2_LIB.BASEBOARD_FAB2(SCH_1):PAGE211
     2 PWRGD_PVCCIO_CPU0_R @BASEBOARD_FAB2_LIB.BASEBOARD_FAB2(SCH_1):PWRGD_PVCCIO_CPU0_R    I56 @BASEBOARD_FAB2_LIB.BASEBOARD_FAB2(SCH_1):PAGE211

R3P26 RES_0402-0.0,5%,1/16W,CHIP,G21A
     1 FM_PVCCIO_CPU0_EN @BASEBOARD_FAB2_LIB.BASEBOARD_FAB2(SCH_1):FM_PVCCIO_CPU0_EN    I87 @BASEBOARD_FAB2_LIB.BASEBOARD_FAB2(SCH_1):PAGE211
     2 VR_PVCCIO_CPU0_EN @BASEBOARD_FAB2_LIB.BASEBOARD_FAB2(SCH_1):VR_PVCCIO_CPU0_EN    I87 @BASEBOARD_FAB2_LIB.BASEBOARD_FAB2(SCH_1):PAGE211

R3P29 RES_0402-64.9,1.0%,1/16W,CHIP,A
     1 PVDDQ_DEF @BASEBOARD_FAB2_LIB.BASEBOARD_FAB2(SCH_1):PVDDQ_DEF     I5 @BASEBOARD_FAB2_LIB.BASEBOARD_FAB2(SCH_1):PAGE96
     2 PWRGD_CPU0_DRAMPWROK_DEF_G @BASEBOARD_FAB2_LIB.BASEBOARD_FAB2(SCH_1):PWRGD_CPU0_DRAMPWROK_DEF_G     I5 @BASEBOARD_FAB2_LIB.BASEBOARD_FAB2(SCH_1):PAGE96

R3P32 RES_0402-1.00K,1%,1/16W,CHIP,GA
     1    GND @BASEBOARD_FAB2_LIB.BASEBOARD_FAB2(SCH_1):GND    I71 @BASEBOARD_FAB2_LIB.BASEBOARD_FAB2(SCH_1):PAGE96
     2 PD_GTL2014_1_VREF @BASEBOARD_FAB2_LIB.BASEBOARD_FAB2(SCH_1):PD_GTL2014_1_VREF    I71 @BASEBOARD_FAB2_LIB.BASEBOARD_FAB2(SCH_1):PAGE96

R3P34 RES_0402-0.0,5%,1/16W,CHIP,G21A
     1 RST_CPU0_LVC3_R1_N @BASEBOARD_FAB2_LIB.BASEBOARD_FAB2(SCH_1):RST_CPU0_LVC3_R1_N   I116 @BASEBOARD_FAB2_LIB.BASEBOARD_FAB2(SCH_1):PAGE190
     2 RST_CPU0_LVC3_N @BASEBOARD_FAB2_LIB.BASEBOARD_FAB2(SCH_1):RST_CPU0_LVC3_N   I116 @BASEBOARD_FAB2_LIB.BASEBOARD_FAB2(SCH_1):PAGE190

R3P35 RES_0402-0.0,5%,1/16W,CHIP,G21A
     1 RST_CPU1_LVC3_R1_N @BASEBOARD_FAB2_LIB.BASEBOARD_FAB2(SCH_1):RST_CPU1_LVC3_R1_N   I117 @BASEBOARD_FAB2_LIB.BASEBOARD_FAB2(SCH_1):PAGE190
     2 RST_CPU1_LVC3_N @BASEBOARD_FAB2_LIB.BASEBOARD_FAB2(SCH_1):RST_CPU1_LVC3_N   I117 @BASEBOARD_FAB2_LIB.BASEBOARD_FAB2(SCH_1):PAGE190

R3P36 RES_0402-1.00K,1%,1/16W,CHIP,GA
     1 P3V3_STBY @BASEBOARD_FAB2_LIB.BASEBOARD_FAB2(SCH_1):P3V3_STBY    I36 @BASEBOARD_FAB2_LIB.BASEBOARD_FAB2(SCH_1):PAGE96
     2 PU_GTL2014_1_DIR @BASEBOARD_FAB2_LIB.BASEBOARD_FAB2(SCH_1):PU_GTL2014_1_DIR    I36 @BASEBOARD_FAB2_LIB.BASEBOARD_FAB2(SCH_1):PAGE96

R3P38 RES_0402-64.9,1.0%,1/16W,CHIP,A
     1 PVDDQ_ABC @BASEBOARD_FAB2_LIB.BASEBOARD_FAB2(SCH_1):PVDDQ_ABC     I7 @BASEBOARD_FAB2_LIB.BASEBOARD_FAB2(SCH_1):PAGE96
     2 PWRGD_CPU0_DRAMPWROK_ABC_G @BASEBOARD_FAB2_LIB.BASEBOARD_FAB2(SCH_1):PWRGD_CPU0_DRAMPWROK_ABC_G     I7 @BASEBOARD_FAB2_LIB.BASEBOARD_FAB2(SCH_1):PAGE96

R3P41 RES_0402-75,1.0%,1/16W,CHIP,G2A
     1 PVCCIO_CPU1 @BASEBOARD_FAB2_LIB.BASEBOARD_FAB2(SCH_1):PVCCIO_CPU1     I9 @BASEBOARD_FAB2_LIB.BASEBOARD_FAB2(SCH_1):PAGE92
     2 H_CPU1_THERMTRIP_G_N @BASEBOARD_FAB2_LIB.BASEBOARD_FAB2(SCH_1):H_CPU1_THERMTRIP_G_N     I9 @BASEBOARD_FAB2_LIB.BASEBOARD_FAB2(SCH_1):PAGE92

R3P42 RES_0402-33.2,1%,1/16W,CHIP,G2A
     1 FM_CPU1_THERMTRIP_LVT3_R_N @BASEBOARD_FAB2_LIB.BASEBOARD_FAB2(SCH_1):FM_CPU1_THERMTRIP_LVT3_R_N    I14 @BASEBOARD_FAB2_LIB.BASEBOARD_FAB2(SCH_1):PAGE92
     2 FM_CPU1_THERMTRIP_LVT3_N @BASEBOARD_FAB2_LIB.BASEBOARD_FAB2(SCH_1):FM_CPU1_THERMTRIP_LVT3_N    I14 @BASEBOARD_FAB2_LIB.BASEBOARD_FAB2(SCH_1):PAGE92

R3P43 RES_0402-33.2,1%,1/16W,CHIP,G2A
     1 FM_CPU_CATERR_LVT3_R2_N @BASEBOARD_FAB2_LIB.BASEBOARD_FAB2(SCH_1):FM_CPU_CATERR_LVT3_R2_N    I13 @BASEBOARD_FAB2_LIB.BASEBOARD_FAB2(SCH_1):PAGE92
     2 FM_CPU_CATERR_LVT3_N @BASEBOARD_FAB2_LIB.BASEBOARD_FAB2(SCH_1):FM_CPU_CATERR_LVT3_N    I13 @BASEBOARD_FAB2_LIB.BASEBOARD_FAB2(SCH_1):PAGE92

R3P44 RES_0402-4.75K,1%,1/16W,CHIP,GA
     1 P3V3_STBY @BASEBOARD_FAB2_LIB.BASEBOARD_FAB2(SCH_1):P3V3_STBY    I59 @BASEBOARD_FAB2_LIB.BASEBOARD_FAB2(SCH_1):PAGE196
     2 PWRGD_DSW_PWROK @BASEBOARD_FAB2_LIB.BASEBOARD_FAB2(SCH_1):PWRGD_DSW_PWROK    I59 @BASEBOARD_FAB2_LIB.BASEBOARD_FAB2(SCH_1):PAGE196

R3P45 374R2F-1-GP_SMD-RG-374R2F-1-GPA
     1   P3V3 @BASEBOARD_FAB2_LIB.BASEBOARD_FAB2(SCH_1):P3V3   I110 @BASEBOARD_FAB2_LIB.BASEBOARD_FAB2(SCH_1):PAGE92
     2 P0V7_GTL2104_VREF_1 @BASEBOARD_FAB2_LIB.BASEBOARD_FAB2(SCH_1):P0V7_GTL2104_VREF_1   I110 @BASEBOARD_FAB2_LIB.BASEBOARD_FAB2(SCH_1):PAGE92

R3P46 RES_0402-33.2,1%,1/16W,CHIP,G2A
     1 FM_CPU1_FIVR_FAULT_R_LVT3 @BASEBOARD_FAB2_LIB.BASEBOARD_FAB2(SCH_1):FM_CPU1_FIVR_FAULT_R_LVT3    I12 @BASEBOARD_FAB2_LIB.BASEBOARD_FAB2(SCH_1):PAGE92
     2 FM_CPU1_FIVR_FAULT_LVT3 @BASEBOARD_FAB2_LIB.BASEBOARD_FAB2(SCH_1):FM_CPU1_FIVR_FAULT_LVT3    I12 @BASEBOARD_FAB2_LIB.BASEBOARD_FAB2(SCH_1):PAGE92

R3P48 RES_0402-90.9K,1%,1/16W,CHIP,GA
     1 P12V_STBY @BASEBOARD_FAB2_LIB.BASEBOARD_FAB2(SCH_1):P12V_STBY    I74 @BASEBOARD_FAB2_LIB.BASEBOARD_FAB2(SCH_1):PAGE196
     2 VSENSE_P12V_ADM1085 @BASEBOARD_FAB2_LIB.BASEBOARD_FAB2(SCH_1):VSENSE_P12V_ADM1085    I74 @BASEBOARD_FAB2_LIB.BASEBOARD_FAB2(SCH_1):PAGE196

R3P49 RES_0402-100.0,1%,1/16W,CHIP,GA
     1 P0V7_GTL2104_VREF_1 @BASEBOARD_FAB2_LIB.BASEBOARD_FAB2(SCH_1):P0V7_GTL2104_VREF_1    I38 @BASEBOARD_FAB2_LIB.BASEBOARD_FAB2(SCH_1):PAGE92
     2    GND @BASEBOARD_FAB2_LIB.BASEBOARD_FAB2(SCH_1):GND    I38 @BASEBOARD_FAB2_LIB.BASEBOARD_FAB2(SCH_1):PAGE92

R3P50 RES_0402-10.0K,1%,1/16W,EMPTY,A
     1 P3V3_STBY @BASEBOARD_FAB2_LIB.BASEBOARD_FAB2(SCH_1):P3V3_STBY    I71 @BASEBOARD_FAB2_LIB.BASEBOARD_FAB2(SCH_1):PAGE196
     2 PWRGD_P3V3_STBY @BASEBOARD_FAB2_LIB.BASEBOARD_FAB2(SCH_1):PWRGD_P3V3_STBY    I71 @BASEBOARD_FAB2_LIB.BASEBOARD_FAB2(SCH_1):PAGE196

R3P51 RES_0402-6.34K,1%,1/16W,CHIP,GA
     1 VSENSE_P12V_ADM1085 @BASEBOARD_FAB2_LIB.BASEBOARD_FAB2(SCH_1):VSENSE_P12V_ADM1085    I75 @BASEBOARD_FAB2_LIB.BASEBOARD_FAB2(SCH_1):PAGE196
     2    GND @BASEBOARD_FAB2_LIB.BASEBOARD_FAB2(SCH_1):GND    I75 @BASEBOARD_FAB2_LIB.BASEBOARD_FAB2(SCH_1):PAGE196

R3P53 RES_0402-4.75K,1%,1/16W,CHIP,GA
     1 P1V05_PCH_STBY @BASEBOARD_FAB2_LIB.BASEBOARD_FAB2(SCH_1):P1V05_PCH_STBY   I365 @BASEBOARD_FAB2_LIB.BASEBOARD_FAB2(SCH_1):PAGE133
     2 FM_OCP_MEZZC_PRES_1V05_PCH_N @BASEBOARD_FAB2_LIB.BASEBOARD_FAB2(SCH_1):FM_OCP_MEZZC_PRES_1V05_PCH_N   I365 @BASEBOARD_FAB2_LIB.BASEBOARD_FAB2(SCH_1):PAGE133

R3P54 RES_0402-3.32K,1%,1/16W,EMPTY,A
     1 P3V3_STBY @BASEBOARD_FAB2_LIB.BASEBOARD_FAB2(SCH_1):P3V3_STBY   I331 @BASEBOARD_FAB2_LIB.BASEBOARD_FAB2(SCH_1):PAGE156
     2 FM_CPU0_SM_WP @BASEBOARD_FAB2_LIB.BASEBOARD_FAB2(SCH_1):FM_CPU0_SM_WP   I331 @BASEBOARD_FAB2_LIB.BASEBOARD_FAB2(SCH_1):PAGE156

R3P56 RES_0402-1.00K,1%,1/16W,CHIP,GA
     1 FM_CPU0_SM_WP @BASEBOARD_FAB2_LIB.BASEBOARD_FAB2(SCH_1):FM_CPU0_SM_WP   I333 @BASEBOARD_FAB2_LIB.BASEBOARD_FAB2(SCH_1):PAGE156
     2    GND @BASEBOARD_FAB2_LIB.BASEBOARD_FAB2(SCH_1):GND   I333 @BASEBOARD_FAB2_LIB.BASEBOARD_FAB2(SCH_1):PAGE156

R3P58 RES_0402-0.0,5%,1/16W,CHIP,G21A
     1 H_CPU1_CATERR_G_N @BASEBOARD_FAB2_LIB.BASEBOARD_FAB2(SCH_1):H_CPU1_CATERR_G_N    I98 @BASEBOARD_FAB2_LIB.BASEBOARD_FAB2(SCH_1):PAGE92
     2 H_CPU_CATERR_G_N @BASEBOARD_FAB2_LIB.BASEBOARD_FAB2(SCH_1):H_CPU_CATERR_G_N    I98 @BASEBOARD_FAB2_LIB.BASEBOARD_FAB2(SCH_1):PAGE92

R3P59 RES_0402-0.0,5%,1/16W,CHIP,G21A
     1 H_CPU0_CATERR_G_N @BASEBOARD_FAB2_LIB.BASEBOARD_FAB2(SCH_1):H_CPU0_CATERR_G_N    I97 @BASEBOARD_FAB2_LIB.BASEBOARD_FAB2(SCH_1):PAGE92
     2 H_CPU_CATERR_G_N @BASEBOARD_FAB2_LIB.BASEBOARD_FAB2(SCH_1):H_CPU_CATERR_G_N    I97 @BASEBOARD_FAB2_LIB.BASEBOARD_FAB2(SCH_1):PAGE92

R3P60 RES_0402-240,1.0%,1/16W,CHIP,GA
     1 PVCCIO_CPU0 @BASEBOARD_FAB2_LIB.BASEBOARD_FAB2(SCH_1):PVCCIO_CPU0    I67 @BASEBOARD_FAB2_LIB.BASEBOARD_FAB2(SCH_1):PAGE99
     2 SMB_DDR_DEF_SCL_G @BASEBOARD_FAB2_LIB.BASEBOARD_FAB2(SCH_1):SMB_DDR_DEF_SCL_G    I67 @BASEBOARD_FAB2_LIB.BASEBOARD_FAB2(SCH_1):PAGE99

R3P61 RES_0402-2.26K,1.0%,1/16W,CHIPA
     1 P3V3_STBY @BASEBOARD_FAB2_LIB.BASEBOARD_FAB2(SCH_1):P3V3_STBY    I81 @BASEBOARD_FAB2_LIB.BASEBOARD_FAB2(SCH_1):PAGE181
     2 FM_MB_SLOT_ID2 @BASEBOARD_FAB2_LIB.BASEBOARD_FAB2(SCH_1):FM_MB_SLOT_ID2    I81 @BASEBOARD_FAB2_LIB.BASEBOARD_FAB2(SCH_1):PAGE181

R3P62 RES_0402-4.75K,1%,1/16W,EMPTY,A
     1 P3V3_STBY @BASEBOARD_FAB2_LIB.BASEBOARD_FAB2(SCH_1):P3V3_STBY    I22 @BASEBOARD_FAB2_LIB.BASEBOARD_FAB2(SCH_1):PAGE126
     2 FM_FLASH_ATTACH_CFG_STRAP @BASEBOARD_FAB2_LIB.BASEBOARD_FAB2(SCH_1):FM_FLASH_ATTACH_CFG_STRAP    I22 @BASEBOARD_FAB2_LIB.BASEBOARD_FAB2(SCH_1):PAGE126

R3P63 RES_0402-0.0,5%,1/16W,EMPTY,G2A
     1 H_CPU1_MEMGHJ_MEMHOT_LVT3_N @BASEBOARD_FAB2_LIB.BASEBOARD_FAB2(SCH_1):H_CPU1_MEMGHJ_MEMHOT_LVT3_N   I100 @BASEBOARD_FAB2_LIB.BASEBOARD_FAB2(SCH_1):PAGE152
     2 H_CPU1_MEMGHJ_MEMHOT_PCH_N @BASEBOARD_FAB2_LIB.BASEBOARD_FAB2(SCH_1):H_CPU1_MEMGHJ_MEMHOT_PCH_N   I100 @BASEBOARD_FAB2_LIB.BASEBOARD_FAB2(SCH_1):PAGE152

R3P64 RES_0402-1.00K,1%,1/16W,EMPTY,A
     1 FM_FLASH_ATTACH_CFG_STRAP @BASEBOARD_FAB2_LIB.BASEBOARD_FAB2(SCH_1):FM_FLASH_ATTACH_CFG_STRAP    I23 @BASEBOARD_FAB2_LIB.BASEBOARD_FAB2(SCH_1):PAGE126
     2    GND @BASEBOARD_FAB2_LIB.BASEBOARD_FAB2(SCH_1):GND    I23 @BASEBOARD_FAB2_LIB.BASEBOARD_FAB2(SCH_1):PAGE126

R3R1 RES_0402-1.00K,1%,1/16W,CHIP,GA
     1 PD_GTL2104_DIR_1 @BASEBOARD_FAB2_LIB.BASEBOARD_FAB2(SCH_1):PD_GTL2104_DIR_1    I46 @BASEBOARD_FAB2_LIB.BASEBOARD_FAB2(SCH_1):PAGE92
     2    GND @BASEBOARD_FAB2_LIB.BASEBOARD_FAB2(SCH_1):GND    I46 @BASEBOARD_FAB2_LIB.BASEBOARD_FAB2(SCH_1):PAGE92

R3R2 RES_0402-1.00K,1%,1/16W,CHIP,GA
     1 H_CPU1_FIVR_FAULT_G @BASEBOARD_FAB2_LIB.BASEBOARD_FAB2(SCH_1):H_CPU1_FIVR_FAULT_G    I75 @BASEBOARD_FAB2_LIB.BASEBOARD_FAB2(SCH_1):PAGE92
     2    GND @BASEBOARD_FAB2_LIB.BASEBOARD_FAB2(SCH_1):GND    I75 @BASEBOARD_FAB2_LIB.BASEBOARD_FAB2(SCH_1):PAGE92

R3R3 RES_0402-33.2,1%,1/16W,CHIP,G2A
     1 PWRGD_CPUPWRGD_R1 @BASEBOARD_FAB2_LIB.BASEBOARD_FAB2(SCH_1):PWRGD_CPUPWRGD_R1    I61 @BASEBOARD_FAB2_LIB.BASEBOARD_FAB2(SCH_1):PAGE92
     2 PWRGD_CPUPWRGD @BASEBOARD_FAB2_LIB.BASEBOARD_FAB2(SCH_1):PWRGD_CPUPWRGD    I61 @BASEBOARD_FAB2_LIB.BASEBOARD_FAB2(SCH_1):PAGE92

R3R4 RES_0402-4.75K,1%,1/16W,CHIP,GA
     1   P3V3 @BASEBOARD_FAB2_LIB.BASEBOARD_FAB2(SCH_1):P3V3    I66 @BASEBOARD_FAB2_LIB.BASEBOARD_FAB2(SCH_1):PAGE94
     2 H_CPU0_MEMDEF_MEMHOT @BASEBOARD_FAB2_LIB.BASEBOARD_FAB2(SCH_1):H_CPU0_MEMDEF_MEMHOT    I66 @BASEBOARD_FAB2_LIB.BASEBOARD_FAB2(SCH_1):PAGE94

R3R5 RES_0402-665,1.0%,1/16W,CHIP,GA
     1 PVPP_DEF @BASEBOARD_FAB2_LIB.BASEBOARD_FAB2(SCH_1):PVPP_DEF   I103 @BASEBOARD_FAB2_LIB.BASEBOARD_FAB2(SCH_1):PAGE99
     2 SMB_DDR_DEF_VPP_SCL_R @BASEBOARD_FAB2_LIB.BASEBOARD_FAB2(SCH_1):SMB_DDR_DEF_VPP_SCL_R   I103 @BASEBOARD_FAB2_LIB.BASEBOARD_FAB2(SCH_1):PAGE99

R3R7 RES_0402-10.0,1%,1/16W,CHIP,G2A
     1 SMB_DDR_DEF_SCL_G_R @BASEBOARD_FAB2_LIB.BASEBOARD_FAB2(SCH_1):SMB_DDR_DEF_SCL_G_R    I88 @BASEBOARD_FAB2_LIB.BASEBOARD_FAB2(SCH_1):PAGE99
     2 SMB_DDR_DEF_SCL_G @BASEBOARD_FAB2_LIB.BASEBOARD_FAB2(SCH_1):SMB_DDR_DEF_SCL_G    I88 @BASEBOARD_FAB2_LIB.BASEBOARD_FAB2(SCH_1):PAGE99

R3R8 RES_0402-20.0,1%,1/16W,CHIP,G2A
     1 SMB_DDR_DEF_VPP_SCL_R @BASEBOARD_FAB2_LIB.BASEBOARD_FAB2(SCH_1):SMB_DDR_DEF_VPP_SCL_R    I35 @BASEBOARD_FAB2_LIB.BASEBOARD_FAB2(SCH_1):PAGE99
     2 SMB_DDR_DEF_VPP_SCL @BASEBOARD_FAB2_LIB.BASEBOARD_FAB2(SCH_1):SMB_DDR_DEF_VPP_SCL    I35 @BASEBOARD_FAB2_LIB.BASEBOARD_FAB2(SCH_1):PAGE99

R3R9 RES_0402-20.0,1%,1/16W,CHIP,G2A
     1 SMB_DDR_DEF_VPP_SDA_R @BASEBOARD_FAB2_LIB.BASEBOARD_FAB2(SCH_1):SMB_DDR_DEF_VPP_SDA_R    I34 @BASEBOARD_FAB2_LIB.BASEBOARD_FAB2(SCH_1):PAGE99
     2 SMB_DDR_DEF_VPP_SDA @BASEBOARD_FAB2_LIB.BASEBOARD_FAB2(SCH_1):SMB_DDR_DEF_VPP_SDA    I34 @BASEBOARD_FAB2_LIB.BASEBOARD_FAB2(SCH_1):PAGE99

R3R10 RES_0402-4.75K,1%,1/16W,CHIP,GA
     1   P3V3 @BASEBOARD_FAB2_LIB.BASEBOARD_FAB2(SCH_1):P3V3    I79 @BASEBOARD_FAB2_LIB.BASEBOARD_FAB2(SCH_1):PAGE94
     2 H_CPU1_MEMGHJ_MEMHOT @BASEBOARD_FAB2_LIB.BASEBOARD_FAB2(SCH_1):H_CPU1_MEMGHJ_MEMHOT    I79 @BASEBOARD_FAB2_LIB.BASEBOARD_FAB2(SCH_1):PAGE94

R3R11 RES_0402-10.0K,1%,1/16W,EMPTY,A
     1 FM_JTAG_PLD_EN_DEBUG @BASEBOARD_FAB2_LIB.BASEBOARD_FAB2(SCH_1):FM_JTAG_PLD_EN_DEBUG    I45 @BASEBOARD_FAB2_LIB.BASEBOARD_FAB2(SCH_1):PAGE189
     2    GND @BASEBOARD_FAB2_LIB.BASEBOARD_FAB2(SCH_1):GND    I45 @BASEBOARD_FAB2_LIB.BASEBOARD_FAB2(SCH_1):PAGE189

R3R12 RES_0402-665,1.0%,1/16W,CHIP,GA
     1 PVPP_DEF @BASEBOARD_FAB2_LIB.BASEBOARD_FAB2(SCH_1):PVPP_DEF   I101 @BASEBOARD_FAB2_LIB.BASEBOARD_FAB2(SCH_1):PAGE99
     2 SMB_DDR_DEF_VPP_SDA_R @BASEBOARD_FAB2_LIB.BASEBOARD_FAB2(SCH_1):SMB_DDR_DEF_VPP_SDA_R   I101 @BASEBOARD_FAB2_LIB.BASEBOARD_FAB2(SCH_1):PAGE99

R3R13 RES_0402-240,1.0%,1/16W,CHIP,GA
     1 PVCCIO_CPU0 @BASEBOARD_FAB2_LIB.BASEBOARD_FAB2(SCH_1):PVCCIO_CPU0    I65 @BASEBOARD_FAB2_LIB.BASEBOARD_FAB2(SCH_1):PAGE99
     2 SMB_DDR_DEF_SDA_G @BASEBOARD_FAB2_LIB.BASEBOARD_FAB2(SCH_1):SMB_DDR_DEF_SDA_G    I65 @BASEBOARD_FAB2_LIB.BASEBOARD_FAB2(SCH_1):PAGE99

R3R14 RES_0402-10.0,1%,1/16W,CHIP,G2A
     1 SMB_DDR_DEF_SDA_G_R @BASEBOARD_FAB2_LIB.BASEBOARD_FAB2(SCH_1):SMB_DDR_DEF_SDA_G_R   I110 @BASEBOARD_FAB2_LIB.BASEBOARD_FAB2(SCH_1):PAGE99
     2 SMB_DDR_DEF_SDA_G @BASEBOARD_FAB2_LIB.BASEBOARD_FAB2(SCH_1):SMB_DDR_DEF_SDA_G   I110 @BASEBOARD_FAB2_LIB.BASEBOARD_FAB2(SCH_1):PAGE99

R3R15 RES_0402-1.00K,1%,1/16W,CHIP,GA
     1 P3V3_STBY @BASEBOARD_FAB2_LIB.BASEBOARD_FAB2(SCH_1):P3V3_STBY    I44 @BASEBOARD_FAB2_LIB.BASEBOARD_FAB2(SCH_1):PAGE189
     2 FM_JTAG_PLD_EN_DEBUG @BASEBOARD_FAB2_LIB.BASEBOARD_FAB2(SCH_1):FM_JTAG_PLD_EN_DEBUG    I44 @BASEBOARD_FAB2_LIB.BASEBOARD_FAB2(SCH_1):PAGE189

R3R16 RES_0402-4.75K,1%,1/16W,CHIP,GA
     1 PVPP_ABC @BASEBOARD_FAB2_LIB.BASEBOARD_FAB2(SCH_1):PVPP_ABC    I48 @BASEBOARD_FAB2_LIB.BASEBOARD_FAB2(SCH_1):PAGE192
     2 RST_CD_CPU0_POR_N @BASEBOARD_FAB2_LIB.BASEBOARD_FAB2(SCH_1):RST_CD_CPU0_POR_N    I48 @BASEBOARD_FAB2_LIB.BASEBOARD_FAB2(SCH_1):PAGE192

R3T1 RES_0402-33.2,1%,1/16W,CHIP,G2A
     1 SPI_BIOS_SOCKET_IO3 @BASEBOARD_FAB2_LIB.BASEBOARD_FAB2(SCH_1):SPI_BIOS_SOCKET_IO3   I157 @BASEBOARD_FAB2_LIB.BASEBOARD_FAB2(SCH_1):PAGE153
     2 PU_BIOS_SPI_HOLD1_N @BASEBOARD_FAB2_LIB.BASEBOARD_FAB2(SCH_1):PU_BIOS_SPI_HOLD1_N   I157 @BASEBOARD_FAB2_LIB.BASEBOARD_FAB2(SCH_1):PAGE153

R3T2 RES_0402-33.2,1%,1/16W,CHIP,G2A
     1 SPI_SWITCH_MISO @BASEBOARD_FAB2_LIB.BASEBOARD_FAB2(SCH_1):SPI_SWITCH_MISO   I155 @BASEBOARD_FAB2_LIB.BASEBOARD_FAB2(SCH_1):PAGE153
     2 SPI_MISO_R1 @BASEBOARD_FAB2_LIB.BASEBOARD_FAB2(SCH_1):SPI_MISO_R1   I155 @BASEBOARD_FAB2_LIB.BASEBOARD_FAB2(SCH_1):PAGE153

R3T3 RES_0402-4.75K,1%,1/16W,EMPTY,A
     1 P3V3_STBY @BASEBOARD_FAB2_LIB.BASEBOARD_FAB2(SCH_1):P3V3_STBY   I150 @BASEBOARD_FAB2_LIB.BASEBOARD_FAB2(SCH_1):PAGE153
     2 PU_SPI1_RST @BASEBOARD_FAB2_LIB.BASEBOARD_FAB2(SCH_1):PU_SPI1_RST   I150 @BASEBOARD_FAB2_LIB.BASEBOARD_FAB2(SCH_1):PAGE153

R3T4 RES_0402-10.0K,1%,1/16W,CHIP,GA
     1 P3V3_STBY @BASEBOARD_FAB2_LIB.BASEBOARD_FAB2(SCH_1):P3V3_STBY   I174 @BASEBOARD_FAB2_LIB.BASEBOARD_FAB2(SCH_1):PAGE153
     2 PU_BIOS_SPI_HOLD1_N @BASEBOARD_FAB2_LIB.BASEBOARD_FAB2(SCH_1):PU_BIOS_SPI_HOLD1_N   I174 @BASEBOARD_FAB2_LIB.BASEBOARD_FAB2(SCH_1):PAGE153

R3T5 RES_0402-4.75K,1%,1/16W,CHIP,GA
     1 P3V3_STBY @BASEBOARD_FAB2_LIB.BASEBOARD_FAB2(SCH_1):P3V3_STBY   I152 @BASEBOARD_FAB2_LIB.BASEBOARD_FAB2(SCH_1):PAGE153
     2 SPI_CS0_SECONDARY_R_N @BASEBOARD_FAB2_LIB.BASEBOARD_FAB2(SCH_1):SPI_CS0_SECONDARY_R_N   I152 @BASEBOARD_FAB2_LIB.BASEBOARD_FAB2(SCH_1):PAGE153

R3T9 RES_0402-10.0K,1%,1/16W,EMPTY,A
     1 PU_BIOS_SPI_WP1_N @BASEBOARD_FAB2_LIB.BASEBOARD_FAB2(SCH_1):PU_BIOS_SPI_WP1_N   I179 @BASEBOARD_FAB2_LIB.BASEBOARD_FAB2(SCH_1):PAGE153
     2    GND @BASEBOARD_FAB2_LIB.BASEBOARD_FAB2(SCH_1):GND   I179 @BASEBOARD_FAB2_LIB.BASEBOARD_FAB2(SCH_1):PAGE153

R3T10 RES_0402-33.2,1%,1/16W,CHIP,G2A
     1 SPI_SWITCH_MOSI @BASEBOARD_FAB2_LIB.BASEBOARD_FAB2(SCH_1):SPI_SWITCH_MOSI   I184 @BASEBOARD_FAB2_LIB.BASEBOARD_FAB2(SCH_1):PAGE153
     2 SPI_SWITCH_MOSI_R1 @BASEBOARD_FAB2_LIB.BASEBOARD_FAB2(SCH_1):SPI_SWITCH_MOSI_R1   I184 @BASEBOARD_FAB2_LIB.BASEBOARD_FAB2(SCH_1):PAGE153

R3T11 RES_0402-49.9,1%,1/16W,CHIP,G2A
     1 PVCCIO_CPU0 @BASEBOARD_FAB2_LIB.BASEBOARD_FAB2(SCH_1):PVCCIO_CPU0    I70 @BASEBOARD_FAB2_LIB.BASEBOARD_FAB2(SCH_1):PAGE215
     2 SVID_CLK1_CPU0_R @BASEBOARD_FAB2_LIB.BASEBOARD_FAB2(SCH_1):SVID_CLK1_CPU0_R    I70 @BASEBOARD_FAB2_LIB.BASEBOARD_FAB2(SCH_1):PAGE215

R3T12 RES_0402-10.0K,1%,1/16W,CHIP,GA
     1 P3V3_STBY @BASEBOARD_FAB2_LIB.BASEBOARD_FAB2(SCH_1):P3V3_STBY   I178 @BASEBOARD_FAB2_LIB.BASEBOARD_FAB2(SCH_1):PAGE153
     2 PU_BIOS_SPI_WP1_N @BASEBOARD_FAB2_LIB.BASEBOARD_FAB2(SCH_1):PU_BIOS_SPI_WP1_N   I178 @BASEBOARD_FAB2_LIB.BASEBOARD_FAB2(SCH_1):PAGE153

R3T13 RES_0402-0.0,5%,1/16W,CHIP,G21A
     1 P3V3_STBY @BASEBOARD_FAB2_LIB.BASEBOARD_FAB2(SCH_1):P3V3_STBY    I33 @BASEBOARD_FAB2_LIB.BASEBOARD_FAB2(SCH_1):PAGE215
     2 VR_PVDDQ_ABC_VDD @BASEBOARD_FAB2_LIB.BASEBOARD_FAB2(SCH_1):VR_PVDDQ_ABC_VDD    I33 @BASEBOARD_FAB2_LIB.BASEBOARD_FAB2(SCH_1):PAGE215

R3T14 RES_0402-10.0K,1%,1/16W,CHIP,GA
     1 FM_BIOS_USB_RECOVERY @BASEBOARD_FAB2_LIB.BASEBOARD_FAB2(SCH_1):FM_BIOS_USB_RECOVERY   I156 @BASEBOARD_FAB2_LIB.BASEBOARD_FAB2(SCH_1):PAGE136
     2    GND @BASEBOARD_FAB2_LIB.BASEBOARD_FAB2(SCH_1):GND   I156 @BASEBOARD_FAB2_LIB.BASEBOARD_FAB2(SCH_1):PAGE136

R3U1 RES_0402-33.2,1%,1/16W,CHIP,G2A
     1 SPI_BIOS_SOCKET_IO2 @BASEBOARD_FAB2_LIB.BASEBOARD_FAB2(SCH_1):SPI_BIOS_SOCKET_IO2   I156 @BASEBOARD_FAB2_LIB.BASEBOARD_FAB2(SCH_1):PAGE153
     2 PU_BIOS_SPI_WP1_N @BASEBOARD_FAB2_LIB.BASEBOARD_FAB2(SCH_1):PU_BIOS_SPI_WP1_N   I156 @BASEBOARD_FAB2_LIB.BASEBOARD_FAB2(SCH_1):PAGE153

R3U2 RES_0402-100.0,1%,1/16W,CHIP,GA
     1 PVCCIO_CPU0 @BASEBOARD_FAB2_LIB.BASEBOARD_FAB2(SCH_1):PVCCIO_CPU0    I58 @BASEBOARD_FAB2_LIB.BASEBOARD_FAB2(SCH_1):PAGE215
     2 SVID_DIO1_CPU0_R @BASEBOARD_FAB2_LIB.BASEBOARD_FAB2(SCH_1):SVID_DIO1_CPU0_R    I58 @BASEBOARD_FAB2_LIB.BASEBOARD_FAB2(SCH_1):PAGE215

R3U4 RES_0603-120.0,1%,1/10W,CHIP,GA
     1 PVDDQ_ABC @BASEBOARD_FAB2_LIB.BASEBOARD_FAB2(SCH_1):PVDDQ_ABC    I58 @BASEBOARD_FAB2_LIB.BASEBOARD_FAB2(SCH_1):PAGE217
     2    GND @BASEBOARD_FAB2_LIB.BASEBOARD_FAB2(SCH_1):GND    I58 @BASEBOARD_FAB2_LIB.BASEBOARD_FAB2(SCH_1):PAGE217

R3U6 RES_0402-0.0,5%,1/16W,CHIP,G21A
     1 VR_PVDDQ_ABC_PH1_VCIN @BASEBOARD_FAB2_LIB.BASEBOARD_FAB2(SCH_1):VR_PVDDQ_ABC_PH1_VCIN   I145 @BASEBOARD_FAB2_LIB.BASEBOARD_FAB2(SCH_1):PAGE216
     2 P5V_STBY @BASEBOARD_FAB2_LIB.BASEBOARD_FAB2(SCH_1):P5V_STBY   I145 @BASEBOARD_FAB2_LIB.BASEBOARD_FAB2(SCH_1):PAGE216

R3U9 RES_0402-0.0,5%,1/16W,CHIP,G21A
     1 VR_PVDDQ_ABC_PH2_VCIN @BASEBOARD_FAB2_LIB.BASEBOARD_FAB2(SCH_1):VR_PVDDQ_ABC_PH2_VCIN   I146 @BASEBOARD_FAB2_LIB.BASEBOARD_FAB2(SCH_1):PAGE216
     2 P5V_STBY @BASEBOARD_FAB2_LIB.BASEBOARD_FAB2(SCH_1):P5V_STBY   I146 @BASEBOARD_FAB2_LIB.BASEBOARD_FAB2(SCH_1):PAGE216

R3W1 RES_0402-1.00K,1%,1/16W,CHIP,GA
     1 BMC_SELF_HW_D_RST @BASEBOARD_FAB2_LIB.BASEBOARD_FAB2(SCH_1):BMC_SELF_HW_D_RST     I2 @BASEBOARD_FAB2_LIB.BASEBOARD_FAB2(SCH_1):PAGE249
     2    GND @BASEBOARD_FAB2_LIB.BASEBOARD_FAB2(SCH_1):GND     I2 @BASEBOARD_FAB2_LIB.BASEBOARD_FAB2(SCH_1):PAGE249

R3W2 RES_0402-100.0K,1%,1/16W,CHIP,A
     1 BMC_TPM_HW_C_RST @BASEBOARD_FAB2_LIB.BASEBOARD_FAB2(SCH_1):BMC_TPM_HW_C_RST    I56 @BASEBOARD_FAB2_LIB.BASEBOARD_FAB2(SCH_1):PAGE249
     2    GND @BASEBOARD_FAB2_LIB.BASEBOARD_FAB2(SCH_1):GND    I56 @BASEBOARD_FAB2_LIB.BASEBOARD_FAB2(SCH_1):PAGE249

R3W3 RES_0402-10.0K,1%,1/16W,EMPTY,A
     1 P3V3_STBY @BASEBOARD_FAB2_LIB.BASEBOARD_FAB2(SCH_1):P3V3_STBY    I36 @BASEBOARD_FAB2_LIB.BASEBOARD_FAB2(SCH_1):PAGE249
     2 FM_TPM_PRES_RST_N @BASEBOARD_FAB2_LIB.BASEBOARD_FAB2(SCH_1):FM_TPM_PRES_RST_N    I36 @BASEBOARD_FAB2_LIB.BASEBOARD_FAB2(SCH_1):PAGE249

R3W4 47KR2F-GP_RCL_GP-47KR2F-GP,64.A
     1 FM_TPM_PRES_RST_N @BASEBOARD_FAB2_LIB.BASEBOARD_FAB2(SCH_1):FM_TPM_PRES_RST_N    I31 @BASEBOARD_FAB2_LIB.BASEBOARD_FAB2(SCH_1):PAGE249
     2 FM_TPM_PRES_RST_N_R @BASEBOARD_FAB2_LIB.BASEBOARD_FAB2(SCH_1):FM_TPM_PRES_RST_N_R    I31 @BASEBOARD_FAB2_LIB.BASEBOARD_FAB2(SCH_1):PAGE249

R3W5 RES_0402-10.0K,1%,1/16W,CHIP,GA
     1 P3V3_STBY @BASEBOARD_FAB2_LIB.BASEBOARD_FAB2(SCH_1):P3V3_STBY    I58 @BASEBOARD_FAB2_LIB.BASEBOARD_FAB2(SCH_1):PAGE249
     2 FM_TPM_PRES_RST @BASEBOARD_FAB2_LIB.BASEBOARD_FAB2(SCH_1):FM_TPM_PRES_RST    I58 @BASEBOARD_FAB2_LIB.BASEBOARD_FAB2(SCH_1):PAGE249

R3W6 RES_0402-4.75K,1%,1/16W,CHIP,GA
     1 P3V3_STBY @BASEBOARD_FAB2_LIB.BASEBOARD_FAB2(SCH_1):P3V3_STBY    I48 @BASEBOARD_FAB2_LIB.BASEBOARD_FAB2(SCH_1):PAGE249
     2 RST_BMC_EXTRST_N @BASEBOARD_FAB2_LIB.BASEBOARD_FAB2(SCH_1):RST_BMC_EXTRST_N    I48 @BASEBOARD_FAB2_LIB.BASEBOARD_FAB2(SCH_1):PAGE249

R3W7 RES_0402-4.75K,1%,1/16W,CHIP,GA
     1 P3V3_STBY @BASEBOARD_FAB2_LIB.BASEBOARD_FAB2(SCH_1):P3V3_STBY     I8 @BASEBOARD_FAB2_LIB.BASEBOARD_FAB2(SCH_1):PAGE249
     2 VREF_2V2 @BASEBOARD_FAB2_LIB.BASEBOARD_FAB2(SCH_1):VREF_2V2     I8 @BASEBOARD_FAB2_LIB.BASEBOARD_FAB2(SCH_1):PAGE249

R3W9 RES_0402-10.0K,1%,1/16W,CHIP,GA
     1 VREF_2V2 @BASEBOARD_FAB2_LIB.BASEBOARD_FAB2(SCH_1):VREF_2V2     I7 @BASEBOARD_FAB2_LIB.BASEBOARD_FAB2(SCH_1):PAGE249
     2    GND @BASEBOARD_FAB2_LIB.BASEBOARD_FAB2(SCH_1):GND     I7 @BASEBOARD_FAB2_LIB.BASEBOARD_FAB2(SCH_1):PAGE249

R3W10 RES_0402-49.9,1%,1/16W,EMPTY,GA
     1 PVCCIO_CPU0 @BASEBOARD_FAB2_LIB.BASEBOARD_FAB2(SCH_1):PVCCIO_CPU0   I108 @BASEBOARD_FAB2_LIB.BASEBOARD_FAB2(SCH_1):PAGE92
     2 P0V7_GTL2104_VREF_1 @BASEBOARD_FAB2_LIB.BASEBOARD_FAB2(SCH_1):P0V7_GTL2104_VREF_1   I108 @BASEBOARD_FAB2_LIB.BASEBOARD_FAB2(SCH_1):PAGE92

R4A2 RES_0402-0.0,5%,1/16W,CHIP,G21A
     1 PWRGD_PVDDQ_DEF_R @BASEBOARD_FAB2_LIB.BASEBOARD_FAB2(SCH_1):PWRGD_PVDDQ_DEF_R     I4 @BASEBOARD_FAB2_LIB.BASEBOARD_FAB2(SCH_1):PAGE222
     2 FM_PVTT_DEF_EN_R @BASEBOARD_FAB2_LIB.BASEBOARD_FAB2(SCH_1):FM_PVTT_DEF_EN_R     I4 @BASEBOARD_FAB2_LIB.BASEBOARD_FAB2(SCH_1):PAGE222

R4A3 RES_0402-0.0,5%,1/16W,CHIP,G21A
     1 PWRGD_PVDDQ_KLM_R @BASEBOARD_FAB2_LIB.BASEBOARD_FAB2(SCH_1):PWRGD_PVDDQ_KLM_R     I4 @BASEBOARD_FAB2_LIB.BASEBOARD_FAB2(SCH_1):PAGE230
     2 FM_PVTT_KLM_EN_R @BASEBOARD_FAB2_LIB.BASEBOARD_FAB2(SCH_1):FM_PVTT_KLM_EN_R     I4 @BASEBOARD_FAB2_LIB.BASEBOARD_FAB2(SCH_1):PAGE230

R4A4 RES_0402-33.2,1%,1/16W,CHIP,G2A
     1 PWRGD_PVTT_KLM_CPU1_R @BASEBOARD_FAB2_LIB.BASEBOARD_FAB2(SCH_1):PWRGD_PVTT_KLM_CPU1_R    I32 @BASEBOARD_FAB2_LIB.BASEBOARD_FAB2(SCH_1):PAGE230
     2 PWRGD_PVTT_CPU1 @BASEBOARD_FAB2_LIB.BASEBOARD_FAB2(SCH_1):PWRGD_PVTT_CPU1    I32 @BASEBOARD_FAB2_LIB.BASEBOARD_FAB2(SCH_1):PAGE230

R4A5 RES_0402-10.0K,1%,1/16W,CHIP,GA
     1   P3V3 @BASEBOARD_FAB2_LIB.BASEBOARD_FAB2(SCH_1):P3V3    I21 @BASEBOARD_FAB2_LIB.BASEBOARD_FAB2(SCH_1):PAGE230
     2 PWRGD_PVTT_KLM_CPU1_R @BASEBOARD_FAB2_LIB.BASEBOARD_FAB2(SCH_1):PWRGD_PVTT_KLM_CPU1_R    I21 @BASEBOARD_FAB2_LIB.BASEBOARD_FAB2(SCH_1):PAGE230

R4A6 RES_0402-33.2,1%,1/16W,CHIP,G2A
     1 PWRGD_PVTT_DEF_CPU0_R @BASEBOARD_FAB2_LIB.BASEBOARD_FAB2(SCH_1):PWRGD_PVTT_DEF_CPU0_R    I31 @BASEBOARD_FAB2_LIB.BASEBOARD_FAB2(SCH_1):PAGE222
     2 PWRGD_PVTT_CPU0 @BASEBOARD_FAB2_LIB.BASEBOARD_FAB2(SCH_1):PWRGD_PVTT_CPU0    I31 @BASEBOARD_FAB2_LIB.BASEBOARD_FAB2(SCH_1):PAGE222

R4A7 RES_0402-2.2,5%,1/16W,EMPTY,G2A
     1 VR_PVPP_KLM_SNUB @BASEBOARD_FAB2_LIB.BASEBOARD_FAB2(SCH_1):VR_PVPP_KLM_SNUB   I162 @BASEBOARD_FAB2_LIB.BASEBOARD_FAB2(SCH_1):PAGE234
     2    GND @BASEBOARD_FAB2_LIB.BASEBOARD_FAB2(SCH_1):GND   I162 @BASEBOARD_FAB2_LIB.BASEBOARD_FAB2(SCH_1):PAGE234

R4A8 RES_0402-0.0,5%,1/16W,CHIP,G21A
     1 SMB_LAN_STBY_LVC3_SDA @BASEBOARD_FAB2_LIB.BASEBOARD_FAB2(SCH_1):SMB_LAN_STBY_LVC3_SDA   I322 @BASEBOARD_FAB2_LIB.BASEBOARD_FAB2(SCH_1):PAGE156
     2 SMB_PIROM_CPU0_SDA @BASEBOARD_FAB2_LIB.BASEBOARD_FAB2(SCH_1):SMB_PIROM_CPU0_SDA   I322 @BASEBOARD_FAB2_LIB.BASEBOARD_FAB2(SCH_1):PAGE156

R4A9 RES_0402-0.0,5%,1/16W,CHIP,G21A
     1 SMB_LAN_STBY_LVC3_SCL @BASEBOARD_FAB2_LIB.BASEBOARD_FAB2(SCH_1):SMB_LAN_STBY_LVC3_SCL   I324 @BASEBOARD_FAB2_LIB.BASEBOARD_FAB2(SCH_1):PAGE156
     2 SMB_PIROM_CPU0_SCL @BASEBOARD_FAB2_LIB.BASEBOARD_FAB2(SCH_1):SMB_PIROM_CPU0_SCL   I324 @BASEBOARD_FAB2_LIB.BASEBOARD_FAB2(SCH_1):PAGE156

R4B1 RES_0402-0.0,5%,1/16W,CHIP,G21A
     1 FM_PVPP_CPU1_EN @BASEBOARD_FAB2_LIB.BASEBOARD_FAB2(SCH_1):FM_PVPP_CPU1_EN   I220 @BASEBOARD_FAB2_LIB.BASEBOARD_FAB2(SCH_1):PAGE234
     2 FM_PVPP_PVDDQ_CPU1_EN_KLM @BASEBOARD_FAB2_LIB.BASEBOARD_FAB2(SCH_1):FM_PVPP_PVDDQ_CPU1_EN_KLM   I220 @BASEBOARD_FAB2_LIB.BASEBOARD_FAB2(SCH_1):PAGE234

R4B2 RES_0603-120.0,1%,1/10W,CHIP,GA
     1 PVPP_KLM @BASEBOARD_FAB2_LIB.BASEBOARD_FAB2(SCH_1):PVPP_KLM   I183 @BASEBOARD_FAB2_LIB.BASEBOARD_FAB2(SCH_1):PAGE234
     2    GND @BASEBOARD_FAB2_LIB.BASEBOARD_FAB2(SCH_1):GND   I183 @BASEBOARD_FAB2_LIB.BASEBOARD_FAB2(SCH_1):PAGE234

R4B3 RES_0402-0.0,5%,1/16W,CHIP,G21A
     1 PVPP_KLM @BASEBOARD_FAB2_LIB.BASEBOARD_FAB2(SCH_1):PVPP_KLM   I214 @BASEBOARD_FAB2_LIB.BASEBOARD_FAB2(SCH_1):PAGE234
     2 VSENSE_PVPP_KLM @BASEBOARD_FAB2_LIB.BASEBOARD_FAB2(SCH_1):VSENSE_PVPP_KLM   I214 @BASEBOARD_FAB2_LIB.BASEBOARD_FAB2(SCH_1):PAGE234

R4B4 RES_0402-6.19K,1%,1/16W,CHIP,GA
     1 VR_FB_PVPP_KLM @BASEBOARD_FAB2_LIB.BASEBOARD_FAB2(SCH_1):VR_FB_PVPP_KLM   I227 @BASEBOARD_FAB2_LIB.BASEBOARD_FAB2(SCH_1):PAGE234
     2 AGND_PVPP_KLM @BASEBOARD_FAB2_LIB.BASEBOARD_FAB2(SCH_1):AGND_PVPP_KLM   I227 @BASEBOARD_FAB2_LIB.BASEBOARD_FAB2(SCH_1):PAGE234

R4B5 RES_0402-20.0K,1%,1/16W,CHIP,GA
     1 VSENSE_PVPP_KLM @BASEBOARD_FAB2_LIB.BASEBOARD_FAB2(SCH_1):VSENSE_PVPP_KLM   I215 @BASEBOARD_FAB2_LIB.BASEBOARD_FAB2(SCH_1):PAGE234
     2 VR_FB_PVPP_KLM @BASEBOARD_FAB2_LIB.BASEBOARD_FAB2(SCH_1):VR_FB_PVPP_KLM   I215 @BASEBOARD_FAB2_LIB.BASEBOARD_FAB2(SCH_1):PAGE234

R4B6 RES_0402-7.87K,1.0%,1/16W,CHIPA
     1 VR_PVPP_KLM_ISET @BASEBOARD_FAB2_LIB.BASEBOARD_FAB2(SCH_1):VR_PVPP_KLM_ISET   I228 @BASEBOARD_FAB2_LIB.BASEBOARD_FAB2(SCH_1):PAGE234
     2 AGND_PVPP_KLM @BASEBOARD_FAB2_LIB.BASEBOARD_FAB2(SCH_1):AGND_PVPP_KLM   I228 @BASEBOARD_FAB2_LIB.BASEBOARD_FAB2(SCH_1):PAGE234

R4B7 RES_0402-22.1,1.0%,1/16W,CHIP,A
     1 PWRGD_PVPP_KLM_R @BASEBOARD_FAB2_LIB.BASEBOARD_FAB2(SCH_1):PWRGD_PVPP_KLM_R   I201 @BASEBOARD_FAB2_LIB.BASEBOARD_FAB2(SCH_1):PAGE234
     2 PWRGD_PVPP_KLM @BASEBOARD_FAB2_LIB.BASEBOARD_FAB2(SCH_1):PWRGD_PVPP_KLM   I201 @BASEBOARD_FAB2_LIB.BASEBOARD_FAB2(SCH_1):PAGE234

R4B8 RES_0402-7.87K,1.0%,1/16W,CHIPA
     1 VR_COMP_RC_PVPP_KLM @BASEBOARD_FAB2_LIB.BASEBOARD_FAB2(SCH_1):VR_COMP_RC_PVPP_KLM   I213 @BASEBOARD_FAB2_LIB.BASEBOARD_FAB2(SCH_1):PAGE234
     2 VR_FB_PVPP_KLM @BASEBOARD_FAB2_LIB.BASEBOARD_FAB2(SCH_1):VR_FB_PVPP_KLM   I213 @BASEBOARD_FAB2_LIB.BASEBOARD_FAB2(SCH_1):PAGE234

R4B9 RES_0402-1.0K,0.1%,1/16W,CHIP,A
     1 VSENSE_PVPP_KLM @BASEBOARD_FAB2_LIB.BASEBOARD_FAB2(SCH_1):VSENSE_PVPP_KLM   I219 @BASEBOARD_FAB2_LIB.BASEBOARD_FAB2(SCH_1):PAGE234
     2 VR_COMP_PVPP_KLM @BASEBOARD_FAB2_LIB.BASEBOARD_FAB2(SCH_1):VR_COMP_PVPP_KLM   I219 @BASEBOARD_FAB2_LIB.BASEBOARD_FAB2(SCH_1):PAGE234

R4B10 RES_0402-1.00K,1%,1/16W,CHIP,GA
     1 P3V3_STBY @BASEBOARD_FAB2_LIB.BASEBOARD_FAB2(SCH_1):P3V3_STBY   I143 @BASEBOARD_FAB2_LIB.BASEBOARD_FAB2(SCH_1):PAGE234
     2 PWRGD_PVPP_KLM_R @BASEBOARD_FAB2_LIB.BASEBOARD_FAB2(SCH_1):PWRGD_PVPP_KLM_R   I143 @BASEBOARD_FAB2_LIB.BASEBOARD_FAB2(SCH_1):PAGE234

R4B12 RES_1206-0.002,1%,1W,CHIP,G521A
     1 P12V_STBY @BASEBOARD_FAB2_LIB.BASEBOARD_FAB2(SCH_1):P12V_STBY     I6 @BASEBOARD_FAB2_LIB.BASEBOARD_FAB2(SCH_1):PAGE197
     2 P12V_NVDIMM_DEF @BASEBOARD_FAB2_LIB.BASEBOARD_FAB2(SCH_1):P12V_NVDIMM_DEF     I6 @BASEBOARD_FAB2_LIB.BASEBOARD_FAB2(SCH_1):PAGE197

R4B13 RES_0603-0,5.0%,1/10W,CHIP,G22A
     1 VR_PVPP_KLM_BOOT @BASEBOARD_FAB2_LIB.BASEBOARD_FAB2(SCH_1):VR_PVPP_KLM_BOOT   I226 @BASEBOARD_FAB2_LIB.BASEBOARD_FAB2(SCH_1):PAGE234
     2 VR_PVPP_KLM_BOOT_R @BASEBOARD_FAB2_LIB.BASEBOARD_FAB2(SCH_1):VR_PVPP_KLM_BOOT_R   I226 @BASEBOARD_FAB2_LIB.BASEBOARD_FAB2(SCH_1):PAGE234

R4B14 RES_0402-0.0,5%,1/16W,CHIP,G21A
     1    GND @BASEBOARD_FAB2_LIB.BASEBOARD_FAB2(SCH_1):GND    I29 @BASEBOARD_FAB2_LIB.BASEBOARD_FAB2(SCH_1):PAGE234
     2 AGND_PVPP_KLM @BASEBOARD_FAB2_LIB.BASEBOARD_FAB2(SCH_1):AGND_PVPP_KLM    I29 @BASEBOARD_FAB2_LIB.BASEBOARD_FAB2(SCH_1):PAGE234

R4C1 RES_0402-100.0,1%,1/16W,CHIP,GA
     1 VSENSE_PVSA_CPU0_N @BASEBOARD_FAB2_LIB.BASEBOARD_FAB2(SCH_1):VSENSE_PVSA_CPU0_N    I29 @BASEBOARD_FAB2_LIB.BASEBOARD_FAB2(SCH_1):PAGE205
     2    GND @BASEBOARD_FAB2_LIB.BASEBOARD_FAB2(SCH_1):GND    I29 @BASEBOARD_FAB2_LIB.BASEBOARD_FAB2(SCH_1):PAGE205

R4C2 RES_0402-0.0,5%,1/16W,CHIP,G21A
     1 VSENSE_PVSA_CPU0_N @BASEBOARD_FAB2_LIB.BASEBOARD_FAB2(SCH_1):VSENSE_PVSA_CPU0_N    I30 @BASEBOARD_FAB2_LIB.BASEBOARD_FAB2(SCH_1):PAGE205
     2 VSENSE_PVSA_CPU0_SKT_VRTN @BASEBOARD_FAB2_LIB.BASEBOARD_FAB2(SCH_1):VSENSE_PVSA_CPU0_SKT_VRTN    I30 @BASEBOARD_FAB2_LIB.BASEBOARD_FAB2(SCH_1):PAGE205

R4C3 RES_0402-1.00K,1%,1/16W,EMPTY,A
     1 VSENSE_PVSA_CPU0_P @BASEBOARD_FAB2_LIB.BASEBOARD_FAB2(SCH_1):VSENSE_PVSA_CPU0_P    I37 @BASEBOARD_FAB2_LIB.BASEBOARD_FAB2(SCH_1):PAGE205
     2 VSENSE_PVSA_CPU0_N @BASEBOARD_FAB2_LIB.BASEBOARD_FAB2(SCH_1):VSENSE_PVSA_CPU0_N    I37 @BASEBOARD_FAB2_LIB.BASEBOARD_FAB2(SCH_1):PAGE205

R4C4 RES_0402-0.0,5%,1/16W,CHIP,G21A
     1 VSENSE_PVSA_CPU0_P @BASEBOARD_FAB2_LIB.BASEBOARD_FAB2(SCH_1):VSENSE_PVSA_CPU0_P    I26 @BASEBOARD_FAB2_LIB.BASEBOARD_FAB2(SCH_1):PAGE205
     2 VSENSE_PVSA_CPU0_SKT_VSEN @BASEBOARD_FAB2_LIB.BASEBOARD_FAB2(SCH_1):VSENSE_PVSA_CPU0_SKT_VSEN    I26 @BASEBOARD_FAB2_LIB.BASEBOARD_FAB2(SCH_1):PAGE205

R4C5 RES_0402-100.0,1%,1/16W,CHIP,GA
     1 VSENSE_PVSA_CPU0_P @BASEBOARD_FAB2_LIB.BASEBOARD_FAB2(SCH_1):VSENSE_PVSA_CPU0_P    I24 @BASEBOARD_FAB2_LIB.BASEBOARD_FAB2(SCH_1):PAGE205
     2 PVSA_CPU0 @BASEBOARD_FAB2_LIB.BASEBOARD_FAB2(SCH_1):PVSA_CPU0    I24 @BASEBOARD_FAB2_LIB.BASEBOARD_FAB2(SCH_1):PAGE205

R4C8 RES_0402-1.00K,1%,1/16W,CHIP,GA
     1 P3V3_STBY @BASEBOARD_FAB2_LIB.BASEBOARD_FAB2(SCH_1):P3V3_STBY    I55 @BASEBOARD_FAB2_LIB.BASEBOARD_FAB2(SCH_1):PAGE96
     2 PU_GTL2014_2_DIR @BASEBOARD_FAB2_LIB.BASEBOARD_FAB2(SCH_1):PU_GTL2014_2_DIR    I55 @BASEBOARD_FAB2_LIB.BASEBOARD_FAB2(SCH_1):PAGE96

R4C9 RES_0402-1.00K,1%,1/16W,CHIP,GA
     1    GND @BASEBOARD_FAB2_LIB.BASEBOARD_FAB2(SCH_1):GND    I69 @BASEBOARD_FAB2_LIB.BASEBOARD_FAB2(SCH_1):PAGE96
     2 PD_GTL2014_2_VREF @BASEBOARD_FAB2_LIB.BASEBOARD_FAB2(SCH_1):PD_GTL2014_2_VREF    I69 @BASEBOARD_FAB2_LIB.BASEBOARD_FAB2(SCH_1):PAGE96

R4C10 RES_0402-240,1.0%,1/16W,CHIP,GA
     1 PVCCIO_CPU1 @BASEBOARD_FAB2_LIB.BASEBOARD_FAB2(SCH_1):PVCCIO_CPU1    I76 @BASEBOARD_FAB2_LIB.BASEBOARD_FAB2(SCH_1):PAGE97
     2 PU_CPU1_TSC_SYNC @BASEBOARD_FAB2_LIB.BASEBOARD_FAB2(SCH_1):PU_CPU1_TSC_SYNC    I76 @BASEBOARD_FAB2_LIB.BASEBOARD_FAB2(SCH_1):PAGE97

R4C11 RES_0402-3.16K,1%,1/16W,CHIP,GA
     1 VR_PVCCMCP_CPU1_XADDR2 @BASEBOARD_FAB2_LIB.BASEBOARD_FAB2(SCH_1):VR_PVCCMCP_CPU1_XADDR2   I170 @BASEBOARD_FAB2_LIB.BASEBOARD_FAB2(SCH_1):PAGE193
     2    GND @BASEBOARD_FAB2_LIB.BASEBOARD_FAB2(SCH_1):GND   I170 @BASEBOARD_FAB2_LIB.BASEBOARD_FAB2(SCH_1):PAGE193

R4C12 RES_0402-8.06K,1%,1/16W,CHIP,GA
     1 VR_PVCCIOMCP_CPU1_XADDR1 @BASEBOARD_FAB2_LIB.BASEBOARD_FAB2(SCH_1):VR_PVCCIOMCP_CPU1_XADDR1   I169 @BASEBOARD_FAB2_LIB.BASEBOARD_FAB2(SCH_1):PAGE193
     2    GND @BASEBOARD_FAB2_LIB.BASEBOARD_FAB2(SCH_1):GND   I169 @BASEBOARD_FAB2_LIB.BASEBOARD_FAB2(SCH_1):PAGE193

R4C13 RES_0402-68.1K,1%,1/16W,EMPTY,A
     1 VR_PVSA_CPU0_OCSET @BASEBOARD_FAB2_LIB.BASEBOARD_FAB2(SCH_1):VR_PVSA_CPU0_OCSET    I62 @BASEBOARD_FAB2_LIB.BASEBOARD_FAB2(SCH_1):PAGE205
     2    GND @BASEBOARD_FAB2_LIB.BASEBOARD_FAB2(SCH_1):GND    I62 @BASEBOARD_FAB2_LIB.BASEBOARD_FAB2(SCH_1):PAGE205

R4D1 RES_0402-27.4,1%,1/16W,CHIP,G2A
     1 CLK_100M_CPU1_BCLK1_R_DN @BASEBOARD_FAB2_LIB.BASEBOARD_FAB2(SCH_1):CLK_100M_CPU1_BCLK1_R_DN    I54 @BASEBOARD_FAB2_LIB.BASEBOARD_FAB2(SCH_1):PAGE103
     2 CLK_100M_CPU1_BCLK1_DN @BASEBOARD_FAB2_LIB.BASEBOARD_FAB2(SCH_1):CLK_100M_CPU1_BCLK1_DN    I54 @BASEBOARD_FAB2_LIB.BASEBOARD_FAB2(SCH_1):PAGE103

R4D2 RES_0402-27.4,1%,1/16W,CHIP,G2A
     1 CLK_100M_CPU1_BCLK1_R_DP @BASEBOARD_FAB2_LIB.BASEBOARD_FAB2(SCH_1):CLK_100M_CPU1_BCLK1_R_DP    I49 @BASEBOARD_FAB2_LIB.BASEBOARD_FAB2(SCH_1):PAGE103
     2 CLK_100M_CPU1_BCLK1_DP @BASEBOARD_FAB2_LIB.BASEBOARD_FAB2(SCH_1):CLK_100M_CPU1_BCLK1_DP    I49 @BASEBOARD_FAB2_LIB.BASEBOARD_FAB2(SCH_1):PAGE103

R4D3 RES_0402-27.4,1%,1/16W,CHIP,G2A
     1 CLK_100M_CPU1_BCLK0_R_DN @BASEBOARD_FAB2_LIB.BASEBOARD_FAB2(SCH_1):CLK_100M_CPU1_BCLK0_R_DN    I64 @BASEBOARD_FAB2_LIB.BASEBOARD_FAB2(SCH_1):PAGE103
     2 CLK_100M_CPU1_BCLK0_DN @BASEBOARD_FAB2_LIB.BASEBOARD_FAB2(SCH_1):CLK_100M_CPU1_BCLK0_DN    I64 @BASEBOARD_FAB2_LIB.BASEBOARD_FAB2(SCH_1):PAGE103

R4D4 RES_0402-27.4,1%,1/16W,CHIP,G2A
     1 CLK_100M_CPU1_BCLK0_R_DP @BASEBOARD_FAB2_LIB.BASEBOARD_FAB2(SCH_1):CLK_100M_CPU1_BCLK0_R_DP    I59 @BASEBOARD_FAB2_LIB.BASEBOARD_FAB2(SCH_1):PAGE103
     2 CLK_100M_CPU1_BCLK0_DP @BASEBOARD_FAB2_LIB.BASEBOARD_FAB2(SCH_1):CLK_100M_CPU1_BCLK0_DP    I59 @BASEBOARD_FAB2_LIB.BASEBOARD_FAB2(SCH_1):PAGE103

R4D5 RES_0402-27.4,1%,1/16W,CHIP,G2A
     1 CLK_100M_CPU0_RC_REFCLK1_R_DN @BASEBOARD_FAB2_LIB.BASEBOARD_FAB2(SCH_1):CLK_100M_CPU0_RC_REFCLK1_R_DN    I79 @BASEBOARD_FAB2_LIB.BASEBOARD_FAB2(SCH_1):PAGE103
     2 CLK_100M_CPU0_RC_REFCLK1_DN @BASEBOARD_FAB2_LIB.BASEBOARD_FAB2(SCH_1):CLK_100M_CPU0_RC_REFCLK1_DN    I79 @BASEBOARD_FAB2_LIB.BASEBOARD_FAB2(SCH_1):PAGE103

R4D6 RES_0402-27.4,1%,1/16W,CHIP,G2A
     1 CLK_100M_CPU0_RC_REFCLK1_R_DP @BASEBOARD_FAB2_LIB.BASEBOARD_FAB2(SCH_1):CLK_100M_CPU0_RC_REFCLK1_R_DP    I74 @BASEBOARD_FAB2_LIB.BASEBOARD_FAB2(SCH_1):PAGE103
     2 CLK_100M_CPU0_RC_REFCLK1_DP @BASEBOARD_FAB2_LIB.BASEBOARD_FAB2(SCH_1):CLK_100M_CPU0_RC_REFCLK1_DP    I74 @BASEBOARD_FAB2_LIB.BASEBOARD_FAB2(SCH_1):PAGE103

R4D7 RES_0402-27.4,1%,1/16W,CHIP,G2A
     1 CLK_100M_CPU0_RC_REFCLK0_R_DN @BASEBOARD_FAB2_LIB.BASEBOARD_FAB2(SCH_1):CLK_100M_CPU0_RC_REFCLK0_R_DN    I89 @BASEBOARD_FAB2_LIB.BASEBOARD_FAB2(SCH_1):PAGE103
     2 CLK_100M_CPU0_RC_REFCLK0_DN @BASEBOARD_FAB2_LIB.BASEBOARD_FAB2(SCH_1):CLK_100M_CPU0_RC_REFCLK0_DN    I89 @BASEBOARD_FAB2_LIB.BASEBOARD_FAB2(SCH_1):PAGE103

R4D8 RES_0402-27.4,1%,1/16W,CHIP,G2A
     1 CLK_100M_CPU0_RC_REFCLK0_R_DP @BASEBOARD_FAB2_LIB.BASEBOARD_FAB2(SCH_1):CLK_100M_CPU0_RC_REFCLK0_R_DP    I84 @BASEBOARD_FAB2_LIB.BASEBOARD_FAB2(SCH_1):PAGE103
     2 CLK_100M_CPU0_RC_REFCLK0_DP @BASEBOARD_FAB2_LIB.BASEBOARD_FAB2(SCH_1):CLK_100M_CPU0_RC_REFCLK0_DP    I84 @BASEBOARD_FAB2_LIB.BASEBOARD_FAB2(SCH_1):PAGE103

R4D9 RES_0402-27.4,1%,1/16W,CHIP,G2A
     1 CLK_100M_CPU1_BCLK2_R_DP @BASEBOARD_FAB2_LIB.BASEBOARD_FAB2(SCH_1):CLK_100M_CPU1_BCLK2_R_DP    I39 @BASEBOARD_FAB2_LIB.BASEBOARD_FAB2(SCH_1):PAGE103
     2 CLK_100M_CPU1_BCLK2_DP @BASEBOARD_FAB2_LIB.BASEBOARD_FAB2(SCH_1):CLK_100M_CPU1_BCLK2_DP    I39 @BASEBOARD_FAB2_LIB.BASEBOARD_FAB2(SCH_1):PAGE103

R4D10 RES_0402-27.4,1%,1/16W,CHIP,G2A
     1 CLK_100M_CPU0_PE_REFCLK_R_DN @BASEBOARD_FAB2_LIB.BASEBOARD_FAB2(SCH_1):CLK_100M_CPU0_PE_REFCLK_R_DN    I99 @BASEBOARD_FAB2_LIB.BASEBOARD_FAB2(SCH_1):PAGE103
     2 CLK_100M_CPU0_PE_REFCLK_DN @BASEBOARD_FAB2_LIB.BASEBOARD_FAB2(SCH_1):CLK_100M_CPU0_PE_REFCLK_DN    I99 @BASEBOARD_FAB2_LIB.BASEBOARD_FAB2(SCH_1):PAGE103

R4D11 RES_0402-27.4,1%,1/16W,CHIP,G2A
     1 CLK_100M_CPU1_BCLK2_R_DN @BASEBOARD_FAB2_LIB.BASEBOARD_FAB2(SCH_1):CLK_100M_CPU1_BCLK2_R_DN    I44 @BASEBOARD_FAB2_LIB.BASEBOARD_FAB2(SCH_1):PAGE103
     2 CLK_100M_CPU1_BCLK2_DN @BASEBOARD_FAB2_LIB.BASEBOARD_FAB2(SCH_1):CLK_100M_CPU1_BCLK2_DN    I44 @BASEBOARD_FAB2_LIB.BASEBOARD_FAB2(SCH_1):PAGE103

R4D12 RES_0402-27.4,1%,1/16W,CHIP,G2A
     1 CLK_100M_CPU0_PE_REFCLK_R_DP @BASEBOARD_FAB2_LIB.BASEBOARD_FAB2(SCH_1):CLK_100M_CPU0_PE_REFCLK_R_DP    I94 @BASEBOARD_FAB2_LIB.BASEBOARD_FAB2(SCH_1):PAGE103
     2 CLK_100M_CPU0_PE_REFCLK_DP @BASEBOARD_FAB2_LIB.BASEBOARD_FAB2(SCH_1):CLK_100M_CPU0_PE_REFCLK_DP    I94 @BASEBOARD_FAB2_LIB.BASEBOARD_FAB2(SCH_1):PAGE103

R4D13 RES_0402-27.4,1%,1/16W,CHIP,G2A
     1 CLK_100M_CPU1_PE_REFCLK_R_DP @BASEBOARD_FAB2_LIB.BASEBOARD_FAB2(SCH_1):CLK_100M_CPU1_PE_REFCLK_R_DP    I29 @BASEBOARD_FAB2_LIB.BASEBOARD_FAB2(SCH_1):PAGE103
     2 CLK_100M_CPU1_PE_REFCLK_DP @BASEBOARD_FAB2_LIB.BASEBOARD_FAB2(SCH_1):CLK_100M_CPU1_PE_REFCLK_DP    I29 @BASEBOARD_FAB2_LIB.BASEBOARD_FAB2(SCH_1):PAGE103

R4D14 RES_0402-27.4,1%,1/16W,CHIP,G2A
     1 CLK_100M_CPU0_BCLK2_R_DN @BASEBOARD_FAB2_LIB.BASEBOARD_FAB2(SCH_1):CLK_100M_CPU0_BCLK2_R_DN   I109 @BASEBOARD_FAB2_LIB.BASEBOARD_FAB2(SCH_1):PAGE103
     2 CLK_100M_CPU0_BCLK2_DN @BASEBOARD_FAB2_LIB.BASEBOARD_FAB2(SCH_1):CLK_100M_CPU0_BCLK2_DN   I109 @BASEBOARD_FAB2_LIB.BASEBOARD_FAB2(SCH_1):PAGE103

R4D16 RES_0402-27.4,1%,1/16W,CHIP,G2A
     1 CLK_100M_CPU1_PE_REFCLK_R_DN @BASEBOARD_FAB2_LIB.BASEBOARD_FAB2(SCH_1):CLK_100M_CPU1_PE_REFCLK_R_DN    I34 @BASEBOARD_FAB2_LIB.BASEBOARD_FAB2(SCH_1):PAGE103
     2 CLK_100M_CPU1_PE_REFCLK_DN @BASEBOARD_FAB2_LIB.BASEBOARD_FAB2(SCH_1):CLK_100M_CPU1_PE_REFCLK_DN    I34 @BASEBOARD_FAB2_LIB.BASEBOARD_FAB2(SCH_1):PAGE103

R4D17 RES_0402-27.4,1%,1/16W,CHIP,G2A
     1 CLK_100M_CPU0_BCLK2_R_DP @BASEBOARD_FAB2_LIB.BASEBOARD_FAB2(SCH_1):CLK_100M_CPU0_BCLK2_R_DP   I104 @BASEBOARD_FAB2_LIB.BASEBOARD_FAB2(SCH_1):PAGE103
     2 CLK_100M_CPU0_BCLK2_DP @BASEBOARD_FAB2_LIB.BASEBOARD_FAB2(SCH_1):CLK_100M_CPU0_BCLK2_DP   I104 @BASEBOARD_FAB2_LIB.BASEBOARD_FAB2(SCH_1):PAGE103

R4D18 RES_0402-42.2,1.0%,1/16W,EMPTYA
     1 CLK_100M_CPU0_BCLK1_DN @BASEBOARD_FAB2_LIB.BASEBOARD_FAB2(SCH_1):CLK_100M_CPU0_BCLK1_DN   I163 @BASEBOARD_FAB2_LIB.BASEBOARD_FAB2(SCH_1):PAGE103
     2    GND @BASEBOARD_FAB2_LIB.BASEBOARD_FAB2(SCH_1):GND   I163 @BASEBOARD_FAB2_LIB.BASEBOARD_FAB2(SCH_1):PAGE103

R4D19 RES_0402-27.4,1%,1/16W,CHIP,G2A
     1 CLK_100M_CPU1_RC_REFCLK0_R_DP @BASEBOARD_FAB2_LIB.BASEBOARD_FAB2(SCH_1):CLK_100M_CPU1_RC_REFCLK0_R_DP    I19 @BASEBOARD_FAB2_LIB.BASEBOARD_FAB2(SCH_1):PAGE103
     2 CLK_100M_CPU1_RC_REFCLK0_DP @BASEBOARD_FAB2_LIB.BASEBOARD_FAB2(SCH_1):CLK_100M_CPU1_RC_REFCLK0_DP    I19 @BASEBOARD_FAB2_LIB.BASEBOARD_FAB2(SCH_1):PAGE103

R4D20 RES_0402-27.4,1%,1/16W,CHIP,G2A
     1 CLK_100M_CPU0_BCLK1_R_DN @BASEBOARD_FAB2_LIB.BASEBOARD_FAB2(SCH_1):CLK_100M_CPU0_BCLK1_R_DN   I119 @BASEBOARD_FAB2_LIB.BASEBOARD_FAB2(SCH_1):PAGE103
     2 CLK_100M_CPU0_BCLK1_DN @BASEBOARD_FAB2_LIB.BASEBOARD_FAB2(SCH_1):CLK_100M_CPU0_BCLK1_DN   I119 @BASEBOARD_FAB2_LIB.BASEBOARD_FAB2(SCH_1):PAGE103

R4D21 RES_0402-27.4,1%,1/16W,CHIP,G2A
     1 CLK_100M_CPU1_RC_REFCLK0_R_DN @BASEBOARD_FAB2_LIB.BASEBOARD_FAB2(SCH_1):CLK_100M_CPU1_RC_REFCLK0_R_DN    I24 @BASEBOARD_FAB2_LIB.BASEBOARD_FAB2(SCH_1):PAGE103
     2 CLK_100M_CPU1_RC_REFCLK0_DN @BASEBOARD_FAB2_LIB.BASEBOARD_FAB2(SCH_1):CLK_100M_CPU1_RC_REFCLK0_DN    I24 @BASEBOARD_FAB2_LIB.BASEBOARD_FAB2(SCH_1):PAGE103

R4D22 RES_0402-27.4,1%,1/16W,CHIP,G2A
     1 CLK_100M_CPU0_BCLK1_R_DP @BASEBOARD_FAB2_LIB.BASEBOARD_FAB2(SCH_1):CLK_100M_CPU0_BCLK1_R_DP   I114 @BASEBOARD_FAB2_LIB.BASEBOARD_FAB2(SCH_1):PAGE103
     2 CLK_100M_CPU0_BCLK1_DP @BASEBOARD_FAB2_LIB.BASEBOARD_FAB2(SCH_1):CLK_100M_CPU0_BCLK1_DP   I114 @BASEBOARD_FAB2_LIB.BASEBOARD_FAB2(SCH_1):PAGE103

R4D23 RES_0402-27.4,1%,1/16W,CHIP,G2A
     1 CLK_100M_CPU1_RC_REFCLK1_R_DP @BASEBOARD_FAB2_LIB.BASEBOARD_FAB2(SCH_1):CLK_100M_CPU1_RC_REFCLK1_R_DP     I9 @BASEBOARD_FAB2_LIB.BASEBOARD_FAB2(SCH_1):PAGE103
     2 CLK_100M_CPU1_RC_REFCLK1_DP @BASEBOARD_FAB2_LIB.BASEBOARD_FAB2(SCH_1):CLK_100M_CPU1_RC_REFCLK1_DP     I9 @BASEBOARD_FAB2_LIB.BASEBOARD_FAB2(SCH_1):PAGE103

R4D24 RES_0402-42.2,1.0%,1/16W,EMPTYA
     1 CLK_100M_CPU0_BCLK1_DP @BASEBOARD_FAB2_LIB.BASEBOARD_FAB2(SCH_1):CLK_100M_CPU0_BCLK1_DP   I161 @BASEBOARD_FAB2_LIB.BASEBOARD_FAB2(SCH_1):PAGE103
     2    GND @BASEBOARD_FAB2_LIB.BASEBOARD_FAB2(SCH_1):GND   I161 @BASEBOARD_FAB2_LIB.BASEBOARD_FAB2(SCH_1):PAGE103

R4D25 RES_0402-27.4,1%,1/16W,CHIP,G2A
     1 CLK_100M_CPU0_BCLK0_R_DN @BASEBOARD_FAB2_LIB.BASEBOARD_FAB2(SCH_1):CLK_100M_CPU0_BCLK0_R_DN     I1 @BASEBOARD_FAB2_LIB.BASEBOARD_FAB2(SCH_1):PAGE103
     2 CLK_100M_CPU0_BCLK0_DN @BASEBOARD_FAB2_LIB.BASEBOARD_FAB2(SCH_1):CLK_100M_CPU0_BCLK0_DN     I1 @BASEBOARD_FAB2_LIB.BASEBOARD_FAB2(SCH_1):PAGE103

R4D26 RES_0402-0.0,5%,1/16W,CHIP,G21A
     1 P3V3_STBY @BASEBOARD_FAB2_LIB.BASEBOARD_FAB2(SCH_1):P3V3_STBY    I40 @BASEBOARD_FAB2_LIB.BASEBOARD_FAB2(SCH_1):PAGE201
     2 VR_PVCCIN_CPU0_VDD @BASEBOARD_FAB2_LIB.BASEBOARD_FAB2(SCH_1):VR_PVCCIN_CPU0_VDD    I40 @BASEBOARD_FAB2_LIB.BASEBOARD_FAB2(SCH_1):PAGE201

R4D27 RES_0402-100.0K,1%,1/16W,CHIP,B
     1 VR_FET_SW_P12V_STBY_PVCCIN_CPU0 @BASEBOARD_FAB2_LIB.BASEBOARD_FAB2(SCH_1):VR_FET_SW_P12V_STBY_PVCCIN_CPU0    I54 @BASEBOARD_FAB2_LIB.BASEBOARD_FAB2(SCH_1):PAGE201
     2 VR_PVCCIN_CPU0_AVINSEN @BASEBOARD_FAB2_LIB.BASEBOARD_FAB2(SCH_1):VR_PVCCIN_CPU0_AVINSEN    I54 @BASEBOARD_FAB2_LIB.BASEBOARD_FAB2(SCH_1):PAGE201

R4D28 RES_0402-27.4,1%,1/16W,CHIP,G2A
     1 CLK_100M_CPU1_RC_REFCLK1_R_DN @BASEBOARD_FAB2_LIB.BASEBOARD_FAB2(SCH_1):CLK_100M_CPU1_RC_REFCLK1_R_DN    I14 @BASEBOARD_FAB2_LIB.BASEBOARD_FAB2(SCH_1):PAGE103
     2 CLK_100M_CPU1_RC_REFCLK1_DN @BASEBOARD_FAB2_LIB.BASEBOARD_FAB2(SCH_1):CLK_100M_CPU1_RC_REFCLK1_DN    I14 @BASEBOARD_FAB2_LIB.BASEBOARD_FAB2(SCH_1):PAGE103

R4D29 RES_0402-27.4,1%,1/16W,CHIP,G2A
     1 CLK_100M_CPU0_BCLK0_R_DP @BASEBOARD_FAB2_LIB.BASEBOARD_FAB2(SCH_1):CLK_100M_CPU0_BCLK0_R_DP    I69 @BASEBOARD_FAB2_LIB.BASEBOARD_FAB2(SCH_1):PAGE103
     2 CLK_100M_CPU0_BCLK0_DP @BASEBOARD_FAB2_LIB.BASEBOARD_FAB2(SCH_1):CLK_100M_CPU0_BCLK0_DP    I69 @BASEBOARD_FAB2_LIB.BASEBOARD_FAB2(SCH_1):PAGE103

R4D31 RES_0402-2.26K,1.0%,1/16W,EMPTA
     1 P3V3_STBY @BASEBOARD_FAB2_LIB.BASEBOARD_FAB2(SCH_1):P3V3_STBY    I22 @BASEBOARD_FAB2_LIB.BASEBOARD_FAB2(SCH_1):PAGE201
     2 PU_VR_PVCCIN_CPU0_IMON @BASEBOARD_FAB2_LIB.BASEBOARD_FAB2(SCH_1):PU_VR_PVCCIN_CPU0_IMON    I22 @BASEBOARD_FAB2_LIB.BASEBOARD_FAB2(SCH_1):PAGE201

R4D32 RES_0402-1.5K,1%,1/16W,CHIP,G2A
     1 VR_PVCCIN_CPU0_AVINSEN @BASEBOARD_FAB2_LIB.BASEBOARD_FAB2(SCH_1):VR_PVCCIN_CPU0_AVINSEN    I55 @BASEBOARD_FAB2_LIB.BASEBOARD_FAB2(SCH_1):PAGE201
     2    GND @BASEBOARD_FAB2_LIB.BASEBOARD_FAB2(SCH_1):GND    I55 @BASEBOARD_FAB2_LIB.BASEBOARD_FAB2(SCH_1):PAGE201

R4D35 RES_0402-10.0K,1%,1/16W,EMPTY,A
     1 P3V3_DB1200 @BASEBOARD_FAB2_LIB.BASEBOARD_FAB2(SCH_1):P3V3_DB1200    I38 @BASEBOARD_FAB2_LIB.BASEBOARD_FAB2(SCH_1):PAGE102
     2 FM_DB1200_SMB_SA0 @BASEBOARD_FAB2_LIB.BASEBOARD_FAB2(SCH_1):FM_DB1200_SMB_SA0    I38 @BASEBOARD_FAB2_LIB.BASEBOARD_FAB2(SCH_1):PAGE102

R4D38 RES_0402-10.0K,1%,1/16W,EMPTY,A
     1 P3V3_DB1200 @BASEBOARD_FAB2_LIB.BASEBOARD_FAB2(SCH_1):P3V3_DB1200    I37 @BASEBOARD_FAB2_LIB.BASEBOARD_FAB2(SCH_1):PAGE102
     2 FM_DB1200_SMB_SA1 @BASEBOARD_FAB2_LIB.BASEBOARD_FAB2(SCH_1):FM_DB1200_SMB_SA1    I37 @BASEBOARD_FAB2_LIB.BASEBOARD_FAB2(SCH_1):PAGE102

R4D39 RES_0402-10.0,1%,1/16W,CHIP,G2A
     1 VSENSE_PVSA_CPU0_P @BASEBOARD_FAB2_LIB.BASEBOARD_FAB2(SCH_1):VSENSE_PVSA_CPU0_P   I110 @BASEBOARD_FAB2_LIB.BASEBOARD_FAB2(SCH_1):PAGE201
     2 VSENSE_PVSA_CPU0_BVSP @BASEBOARD_FAB2_LIB.BASEBOARD_FAB2(SCH_1):VSENSE_PVSA_CPU0_BVSP   I110 @BASEBOARD_FAB2_LIB.BASEBOARD_FAB2(SCH_1):PAGE201

R4D40 RES_0402-4.75K,1%,1/16W,CHIP,GA
     1 P3V3_DB1200 @BASEBOARD_FAB2_LIB.BASEBOARD_FAB2(SCH_1):P3V3_DB1200    I45 @BASEBOARD_FAB2_LIB.BASEBOARD_FAB2(SCH_1):PAGE102
     2 FM_100M_N @BASEBOARD_FAB2_LIB.BASEBOARD_FAB2(SCH_1):FM_100M_N    I45 @BASEBOARD_FAB2_LIB.BASEBOARD_FAB2(SCH_1):PAGE102

R4D41 RES_0402-4.75K,1%,1/16W,CHIP,GA
     1 P3V3_DB1200 @BASEBOARD_FAB2_LIB.BASEBOARD_FAB2(SCH_1):P3V3_DB1200    I53 @BASEBOARD_FAB2_LIB.BASEBOARD_FAB2(SCH_1):PAGE102
     2 FM_HBW_BYPASS_LOWBW_N @BASEBOARD_FAB2_LIB.BASEBOARD_FAB2(SCH_1):FM_HBW_BYPASS_LOWBW_N    I53 @BASEBOARD_FAB2_LIB.BASEBOARD_FAB2(SCH_1):PAGE102

R4D42 RES_0402-1.00K,1%,1/16W,CHIP,GA
     1 P3V3_STBY @BASEBOARD_FAB2_LIB.BASEBOARD_FAB2(SCH_1):P3V3_STBY    I15 @BASEBOARD_FAB2_LIB.BASEBOARD_FAB2(SCH_1):PAGE213
     2 PWRGD_PVCCIO_CPU1_R @BASEBOARD_FAB2_LIB.BASEBOARD_FAB2(SCH_1):PWRGD_PVCCIO_CPU1_R    I15 @BASEBOARD_FAB2_LIB.BASEBOARD_FAB2(SCH_1):PAGE213

R4D46 RES_0402-22.1,1.0%,1/16W,CHIP,A
     1 PWRGD_PVCCIO_CPU1_R @BASEBOARD_FAB2_LIB.BASEBOARD_FAB2(SCH_1):PWRGD_PVCCIO_CPU1_R    I13 @BASEBOARD_FAB2_LIB.BASEBOARD_FAB2(SCH_1):PAGE213
     2 PWRGD_PVCCIO_CPU1 @BASEBOARD_FAB2_LIB.BASEBOARD_FAB2(SCH_1):PWRGD_PVCCIO_CPU1    I13 @BASEBOARD_FAB2_LIB.BASEBOARD_FAB2(SCH_1):PAGE213

R4D47 RES_0402-0.0,5%,1/16W,CHIP,G21A
     1 P3V3_STBY @BASEBOARD_FAB2_LIB.BASEBOARD_FAB2(SCH_1):P3V3_STBY    I25 @BASEBOARD_FAB2_LIB.BASEBOARD_FAB2(SCH_1):PAGE213
     2 VR_PVCCIO_CPU1_VDD @BASEBOARD_FAB2_LIB.BASEBOARD_FAB2(SCH_1):VR_PVCCIO_CPU1_VDD    I25 @BASEBOARD_FAB2_LIB.BASEBOARD_FAB2(SCH_1):PAGE213

R4D49 RES_0402-1.00K,1%,1/16W,CHIP,GA
     1 P3V3_STBY @BASEBOARD_FAB2_LIB.BASEBOARD_FAB2(SCH_1):P3V3_STBY    I63 @BASEBOARD_FAB2_LIB.BASEBOARD_FAB2(SCH_1):PAGE213
     2 IRQ_PVCCIO_CPU1_VRHOT_N @BASEBOARD_FAB2_LIB.BASEBOARD_FAB2(SCH_1):IRQ_PVCCIO_CPU1_VRHOT_N    I63 @BASEBOARD_FAB2_LIB.BASEBOARD_FAB2(SCH_1):PAGE213

R4D51 RES_0402-150.0,1%,1/16W,CHIP,GA
     1 SVID_CLK0_CPU1_R @BASEBOARD_FAB2_LIB.BASEBOARD_FAB2(SCH_1):SVID_CLK0_CPU1_R    I46 @BASEBOARD_FAB2_LIB.BASEBOARD_FAB2(SCH_1):PAGE213
     2 SVID_CLK_PVCCIO_CPU1 @BASEBOARD_FAB2_LIB.BASEBOARD_FAB2(SCH_1):SVID_CLK_PVCCIO_CPU1    I46 @BASEBOARD_FAB2_LIB.BASEBOARD_FAB2(SCH_1):PAGE213

R4D54 RES_0402-0.0,5%,1/16W,CHIP,G21A
     1 SVID_DIO0_CPU1_R @BASEBOARD_FAB2_LIB.BASEBOARD_FAB2(SCH_1):SVID_DIO0_CPU1_R    I37 @BASEBOARD_FAB2_LIB.BASEBOARD_FAB2(SCH_1):PAGE213
     2 SVID_VDIO_PVCCIO_CPU1 @BASEBOARD_FAB2_LIB.BASEBOARD_FAB2(SCH_1):SVID_VDIO_PVCCIO_CPU1    I37 @BASEBOARD_FAB2_LIB.BASEBOARD_FAB2(SCH_1):PAGE213

R4D56 RES_0402-0.0,5%,1/16W,CHIP,G21A
     1 SVID_ALERT_PVCCIO_CPU1 @BASEBOARD_FAB2_LIB.BASEBOARD_FAB2(SCH_1):SVID_ALERT_PVCCIO_CPU1    I16 @BASEBOARD_FAB2_LIB.BASEBOARD_FAB2(SCH_1):PAGE213
     2 SVID_ALERT0_CPU1_R_N @BASEBOARD_FAB2_LIB.BASEBOARD_FAB2(SCH_1):SVID_ALERT0_CPU1_R_N    I16 @BASEBOARD_FAB2_LIB.BASEBOARD_FAB2(SCH_1):PAGE213

R4D57 RES_0402-1.5K,1%,1/16W,CHIP,G2A
     1 VR_PVCCIO_CPU1_VINSEN @BASEBOARD_FAB2_LIB.BASEBOARD_FAB2(SCH_1):VR_PVCCIO_CPU1_VINSEN    I32 @BASEBOARD_FAB2_LIB.BASEBOARD_FAB2(SCH_1):PAGE213
     2    GND @BASEBOARD_FAB2_LIB.BASEBOARD_FAB2(SCH_1):GND    I32 @BASEBOARD_FAB2_LIB.BASEBOARD_FAB2(SCH_1):PAGE213

R4D58 RES_0402-1.00K,1%,1/16W,CHIP,GA
     1 P3V3_STBY @BASEBOARD_FAB2_LIB.BASEBOARD_FAB2(SCH_1):P3V3_STBY    I25 @BASEBOARD_FAB2_LIB.BASEBOARD_FAB2(SCH_1):PAGE201
     2 VR_VRRDY_PVCCIN_CPU0 @BASEBOARD_FAB2_LIB.BASEBOARD_FAB2(SCH_1):VR_VRRDY_PVCCIN_CPU0    I25 @BASEBOARD_FAB2_LIB.BASEBOARD_FAB2(SCH_1):PAGE201

R4D60 RES_0402-100.0K,1%,1/16W,CHIP,B
     1 VR_FET_SW_P12V_STBY_PVCCIN_CPU0 @BASEBOARD_FAB2_LIB.BASEBOARD_FAB2(SCH_1):VR_FET_SW_P12V_STBY_PVCCIN_CPU0    I31 @BASEBOARD_FAB2_LIB.BASEBOARD_FAB2(SCH_1):PAGE213
     2 VR_PVCCIO_CPU1_VINSEN @BASEBOARD_FAB2_LIB.BASEBOARD_FAB2(SCH_1):VR_PVCCIO_CPU1_VINSEN    I31 @BASEBOARD_FAB2_LIB.BASEBOARD_FAB2(SCH_1):PAGE213

R4D63 RES_0402-22.1,1.0%,1/16W,CHIP,A
     1 VR_VRRDY_PVCCIN_CPU0 @BASEBOARD_FAB2_LIB.BASEBOARD_FAB2(SCH_1):VR_VRRDY_PVCCIN_CPU0   I124 @BASEBOARD_FAB2_LIB.BASEBOARD_FAB2(SCH_1):PAGE201
     2 PWRGD_PVCCIN_CPU0 @BASEBOARD_FAB2_LIB.BASEBOARD_FAB2(SCH_1):PWRGD_PVCCIN_CPU0   I124 @BASEBOARD_FAB2_LIB.BASEBOARD_FAB2(SCH_1):PAGE201

R4D64 RES_0402-3.16K,1%,1/16W,CHIP,GA
     1 VR_PVCCIO_CPU1_XADDR1 @BASEBOARD_FAB2_LIB.BASEBOARD_FAB2(SCH_1):VR_PVCCIO_CPU1_XADDR1   I104 @BASEBOARD_FAB2_LIB.BASEBOARD_FAB2(SCH_1):PAGE213
     2    GND @BASEBOARD_FAB2_LIB.BASEBOARD_FAB2(SCH_1):GND   I104 @BASEBOARD_FAB2_LIB.BASEBOARD_FAB2(SCH_1):PAGE213

R4D65 RES_0402-33.2,1%,1/16W,CHIP,G2A
     1 PWRGD_PVSA_CPU0_R @BASEBOARD_FAB2_LIB.BASEBOARD_FAB2(SCH_1):PWRGD_PVSA_CPU0_R   I127 @BASEBOARD_FAB2_LIB.BASEBOARD_FAB2(SCH_1):PAGE201
     2 PWRGD_PVSA_CPU0 @BASEBOARD_FAB2_LIB.BASEBOARD_FAB2(SCH_1):PWRGD_PVSA_CPU0   I127 @BASEBOARD_FAB2_LIB.BASEBOARD_FAB2(SCH_1):PAGE201

R4D66 RES_0402-0.0,5%,1/16W,CHIP,G21A
     1 SVID_VDIO_PVCCIN_CPU0 @BASEBOARD_FAB2_LIB.BASEBOARD_FAB2(SCH_1):SVID_VDIO_PVCCIN_CPU0    I98 @BASEBOARD_FAB2_LIB.BASEBOARD_FAB2(SCH_1):PAGE201
     2 SVID_DIO0_CPU0_R @BASEBOARD_FAB2_LIB.BASEBOARD_FAB2(SCH_1):SVID_DIO0_CPU0_R    I98 @BASEBOARD_FAB2_LIB.BASEBOARD_FAB2(SCH_1):PAGE201

R4D67 RES_0402-0.0,5%,1/16W,CHIP,G21A
     1 SVID_VALERT_VCCIN_CPU0 @BASEBOARD_FAB2_LIB.BASEBOARD_FAB2(SCH_1):SVID_VALERT_VCCIN_CPU0    I26 @BASEBOARD_FAB2_LIB.BASEBOARD_FAB2(SCH_1):PAGE201
     2 SVID_ALERT0_CPU0_R_N @BASEBOARD_FAB2_LIB.BASEBOARD_FAB2(SCH_1):SVID_ALERT0_CPU0_R_N    I26 @BASEBOARD_FAB2_LIB.BASEBOARD_FAB2(SCH_1):PAGE201

R4D68 RES_0402-68.1K,1%,1/16W,EMPTY,A
     1 VR_PVCCIN_CPU0_PH5_OCSET @BASEBOARD_FAB2_LIB.BASEBOARD_FAB2(SCH_1):VR_PVCCIN_CPU0_PH5_OCSET    I83 @BASEBOARD_FAB2_LIB.BASEBOARD_FAB2(SCH_1):PAGE204
     2    GND @BASEBOARD_FAB2_LIB.BASEBOARD_FAB2(SCH_1):GND    I83 @BASEBOARD_FAB2_LIB.BASEBOARD_FAB2(SCH_1):PAGE204

R4D69 RES_0402-4.75K,1%,1/16W,CHIP,GA
     1   P3V3 @BASEBOARD_FAB2_LIB.BASEBOARD_FAB2(SCH_1):P3V3    I93 @BASEBOARD_FAB2_LIB.BASEBOARD_FAB2(SCH_1):PAGE102
     2 FM_CPU1_MCP_CLK_EN_N @BASEBOARD_FAB2_LIB.BASEBOARD_FAB2(SCH_1):FM_CPU1_MCP_CLK_EN_N    I93 @BASEBOARD_FAB2_LIB.BASEBOARD_FAB2(SCH_1):PAGE102

R4D70 RES_0402-4.75K,1%,1/16W,CHIP,GA
     1   P3V3 @BASEBOARD_FAB2_LIB.BASEBOARD_FAB2(SCH_1):P3V3    I94 @BASEBOARD_FAB2_LIB.BASEBOARD_FAB2(SCH_1):PAGE102
     2 FM_CPU0_MCP_CLK_EN_N @BASEBOARD_FAB2_LIB.BASEBOARD_FAB2(SCH_1):FM_CPU0_MCP_CLK_EN_N    I94 @BASEBOARD_FAB2_LIB.BASEBOARD_FAB2(SCH_1):PAGE102

R4D71 RES_0402-68.1K,1%,1/16W,EMPTY,A
     1 VR_PVCCIN_CPU0_PH4_OCSET @BASEBOARD_FAB2_LIB.BASEBOARD_FAB2(SCH_1):VR_PVCCIN_CPU0_PH4_OCSET    I91 @BASEBOARD_FAB2_LIB.BASEBOARD_FAB2(SCH_1):PAGE203
     2    GND @BASEBOARD_FAB2_LIB.BASEBOARD_FAB2(SCH_1):GND    I91 @BASEBOARD_FAB2_LIB.BASEBOARD_FAB2(SCH_1):PAGE203

R4D72 RES_0402-68.1K,1%,1/16W,EMPTY,A
     1 VR_PVCCIN_CPU0_PH3_OCSET @BASEBOARD_FAB2_LIB.BASEBOARD_FAB2(SCH_1):VR_PVCCIN_CPU0_PH3_OCSET    I89 @BASEBOARD_FAB2_LIB.BASEBOARD_FAB2(SCH_1):PAGE203
     2    GND @BASEBOARD_FAB2_LIB.BASEBOARD_FAB2(SCH_1):GND    I89 @BASEBOARD_FAB2_LIB.BASEBOARD_FAB2(SCH_1):PAGE203

R4E2 RES_0402-3.16K,1%,1/16W,CHIP,GA
     1 VR_PVCCIO_CPU1_XADDR2 @BASEBOARD_FAB2_LIB.BASEBOARD_FAB2(SCH_1):VR_PVCCIO_CPU1_XADDR2   I103 @BASEBOARD_FAB2_LIB.BASEBOARD_FAB2(SCH_1):PAGE213
     2    GND @BASEBOARD_FAB2_LIB.BASEBOARD_FAB2(SCH_1):GND   I103 @BASEBOARD_FAB2_LIB.BASEBOARD_FAB2(SCH_1):PAGE213

R4E3 RES_0402-1.00K,1%,1/16W,CHIP,GA
     1 P3V3_STBY @BASEBOARD_FAB2_LIB.BASEBOARD_FAB2(SCH_1):P3V3_STBY   I111 @BASEBOARD_FAB2_LIB.BASEBOARD_FAB2(SCH_1):PAGE201
     2 IRQ_PVCCIN_CPU0_VRHOT_LVC3_R_N @BASEBOARD_FAB2_LIB.BASEBOARD_FAB2(SCH_1):IRQ_PVCCIN_CPU0_VRHOT_LVC3_R_N   I111 @BASEBOARD_FAB2_LIB.BASEBOARD_FAB2(SCH_1):PAGE201

R4E4 RES_0402-1.00K,1%,1/16W,CHIP,GA
     1 P3V3_STBY @BASEBOARD_FAB2_LIB.BASEBOARD_FAB2(SCH_1):P3V3_STBY   I187 @BASEBOARD_FAB2_LIB.BASEBOARD_FAB2(SCH_1):PAGE201
     2 FM_PVCCIN_CPU0_PWR_IN_ALERT_N @BASEBOARD_FAB2_LIB.BASEBOARD_FAB2(SCH_1):FM_PVCCIN_CPU0_PWR_IN_ALERT_N   I187 @BASEBOARD_FAB2_LIB.BASEBOARD_FAB2(SCH_1):PAGE201

R4E5 RES_0402-1.00K,1%,1/16W,CHIP,GA
     1 P3V3_STBY @BASEBOARD_FAB2_LIB.BASEBOARD_FAB2(SCH_1):P3V3_STBY    I27 @BASEBOARD_FAB2_LIB.BASEBOARD_FAB2(SCH_1):PAGE201
     2 PWRGD_PVSA_CPU0_R @BASEBOARD_FAB2_LIB.BASEBOARD_FAB2(SCH_1):PWRGD_PVSA_CPU0_R    I27 @BASEBOARD_FAB2_LIB.BASEBOARD_FAB2(SCH_1):PAGE201

R4E6 RES_0402-150.0,1%,1/16W,CHIP,GA
     1 SVID_CLK0_CPU0_R @BASEBOARD_FAB2_LIB.BASEBOARD_FAB2(SCH_1):SVID_CLK0_CPU0_R    I56 @BASEBOARD_FAB2_LIB.BASEBOARD_FAB2(SCH_1):PAGE201
     2 SVID_VCLK_PVCCIN_CPU0 @BASEBOARD_FAB2_LIB.BASEBOARD_FAB2(SCH_1):SVID_VCLK_PVCCIN_CPU0    I56 @BASEBOARD_FAB2_LIB.BASEBOARD_FAB2(SCH_1):PAGE201

R4E7 RES_0402-10.0,1%,1/16W,CHIP,G2A
     1 VSENSE_PVCCIO_CPU1_AVSP @BASEBOARD_FAB2_LIB.BASEBOARD_FAB2(SCH_1):VSENSE_PVCCIO_CPU1_AVSP    I84 @BASEBOARD_FAB2_LIB.BASEBOARD_FAB2(SCH_1):PAGE213
     2 VR_PVCCIO_CPU1_AVSP @BASEBOARD_FAB2_LIB.BASEBOARD_FAB2(SCH_1):VR_PVCCIO_CPU1_AVSP    I84 @BASEBOARD_FAB2_LIB.BASEBOARD_FAB2(SCH_1):PAGE213

R4E8 RES_0402-10.0,1%,1/16W,CHIP,G2A
     1 VSENSE_PVCCIN_CPU0_P @BASEBOARD_FAB2_LIB.BASEBOARD_FAB2(SCH_1):VSENSE_PVCCIN_CPU0_P   I109 @BASEBOARD_FAB2_LIB.BASEBOARD_FAB2(SCH_1):PAGE201
     2 VSENSE_PVCCIN_CPU0_AVSP @BASEBOARD_FAB2_LIB.BASEBOARD_FAB2(SCH_1):VSENSE_PVCCIN_CPU0_AVSP   I109 @BASEBOARD_FAB2_LIB.BASEBOARD_FAB2(SCH_1):PAGE201

R4E9 RES_0402-49.9,1%,1/16W,EMPTY,GA
     1 PVCCIO_CPU0 @BASEBOARD_FAB2_LIB.BASEBOARD_FAB2(SCH_1):PVCCIO_CPU0   I189 @BASEBOARD_FAB2_LIB.BASEBOARD_FAB2(SCH_1):PAGE201
     2 SVID_CLK0_CPU0_R @BASEBOARD_FAB2_LIB.BASEBOARD_FAB2(SCH_1):SVID_CLK0_CPU0_R   I189 @BASEBOARD_FAB2_LIB.BASEBOARD_FAB2(SCH_1):PAGE201

R4E10 RES_0402-100.0,1%,1/16W,EMPTY,A
     1 PVCCIO_CPU0 @BASEBOARD_FAB2_LIB.BASEBOARD_FAB2(SCH_1):PVCCIO_CPU0   I190 @BASEBOARD_FAB2_LIB.BASEBOARD_FAB2(SCH_1):PAGE201
     2 SVID_DIO0_CPU0_R @BASEBOARD_FAB2_LIB.BASEBOARD_FAB2(SCH_1):SVID_DIO0_CPU0_R   I190 @BASEBOARD_FAB2_LIB.BASEBOARD_FAB2(SCH_1):PAGE201

R4E13 RES_0603-100.0,1%,1/10W,CHIP,GA
     1 PVCCIN_CPU0 @BASEBOARD_FAB2_LIB.BASEBOARD_FAB2(SCH_1):PVCCIN_CPU0    I67 @BASEBOARD_FAB2_LIB.BASEBOARD_FAB2(SCH_1):PAGE203
     2    GND @BASEBOARD_FAB2_LIB.BASEBOARD_FAB2(SCH_1):GND    I67 @BASEBOARD_FAB2_LIB.BASEBOARD_FAB2(SCH_1):PAGE203

R4E14 RES_0402-100.0,1%,1/16W,CHIP,GA
     1 VSENSE_PVCCIN_CPU0_P @BASEBOARD_FAB2_LIB.BASEBOARD_FAB2(SCH_1):VSENSE_PVCCIN_CPU0_P    I60 @BASEBOARD_FAB2_LIB.BASEBOARD_FAB2(SCH_1):PAGE204
     2 PVCCIN_CPU0 @BASEBOARD_FAB2_LIB.BASEBOARD_FAB2(SCH_1):PVCCIN_CPU0    I60 @BASEBOARD_FAB2_LIB.BASEBOARD_FAB2(SCH_1):PAGE204

R4E15 RES_0402-1.00K,1%,1/16W,EMPTY,A
     1 VSENSE_PVCCIN_CPU0_P @BASEBOARD_FAB2_LIB.BASEBOARD_FAB2(SCH_1):VSENSE_PVCCIN_CPU0_P    I63 @BASEBOARD_FAB2_LIB.BASEBOARD_FAB2(SCH_1):PAGE204
     2 VSENSE_PVCCIN_CPU0_N @BASEBOARD_FAB2_LIB.BASEBOARD_FAB2(SCH_1):VSENSE_PVCCIN_CPU0_N    I63 @BASEBOARD_FAB2_LIB.BASEBOARD_FAB2(SCH_1):PAGE204

R4E16 RES_0402-0.0,5%,1/16W,CHIP,G21A
     1 VSENSE_PVCCIN_CPU0_P @BASEBOARD_FAB2_LIB.BASEBOARD_FAB2(SCH_1):VSENSE_PVCCIN_CPU0_P    I61 @BASEBOARD_FAB2_LIB.BASEBOARD_FAB2(SCH_1):PAGE204
     2 VSENSE_PVCCIN_CPU0_SKT_VSEN @BASEBOARD_FAB2_LIB.BASEBOARD_FAB2(SCH_1):VSENSE_PVCCIN_CPU0_SKT_VSEN    I61 @BASEBOARD_FAB2_LIB.BASEBOARD_FAB2(SCH_1):PAGE204

R4E17 RES_0402-0.0,5%,1/16W,CHIP,G21A
     1 VSENSE_PVCCIN_CPU0_N @BASEBOARD_FAB2_LIB.BASEBOARD_FAB2(SCH_1):VSENSE_PVCCIN_CPU0_N    I62 @BASEBOARD_FAB2_LIB.BASEBOARD_FAB2(SCH_1):PAGE204
     2 VSENSE_PVCCIN_CPU0_SKT_VRTN @BASEBOARD_FAB2_LIB.BASEBOARD_FAB2(SCH_1):VSENSE_PVCCIN_CPU0_SKT_VRTN    I62 @BASEBOARD_FAB2_LIB.BASEBOARD_FAB2(SCH_1):PAGE204

R4E18 RES_0402-100.0,1%,1/16W,CHIP,GA
     1 VSENSE_PVCCIN_CPU0_N @BASEBOARD_FAB2_LIB.BASEBOARD_FAB2(SCH_1):VSENSE_PVCCIN_CPU0_N    I64 @BASEBOARD_FAB2_LIB.BASEBOARD_FAB2(SCH_1):PAGE204
     2    GND @BASEBOARD_FAB2_LIB.BASEBOARD_FAB2(SCH_1):GND    I64 @BASEBOARD_FAB2_LIB.BASEBOARD_FAB2(SCH_1):PAGE204

R4E19 RES_0402-68.1K,1%,1/16W,EMPTY,A
     1 VR_PVCCIN_CPU0_PH2_OCSET @BASEBOARD_FAB2_LIB.BASEBOARD_FAB2(SCH_1):VR_PVCCIN_CPU0_PH2_OCSET    I67 @BASEBOARD_FAB2_LIB.BASEBOARD_FAB2(SCH_1):PAGE202
     2    GND @BASEBOARD_FAB2_LIB.BASEBOARD_FAB2(SCH_1):GND    I67 @BASEBOARD_FAB2_LIB.BASEBOARD_FAB2(SCH_1):PAGE202

R4E20 RES_0402-2.26K,1.0%,1/16W,EMPTA
     1 P3V3_STBY @BASEBOARD_FAB2_LIB.BASEBOARD_FAB2(SCH_1):P3V3_STBY   I116 @BASEBOARD_FAB2_LIB.BASEBOARD_FAB2(SCH_1):PAGE201
     2 PU_VR_PVCCIN_CPU0_FLT1_SMBALT_N @BASEBOARD_FAB2_LIB.BASEBOARD_FAB2(SCH_1):PU_VR_PVCCIN_CPU0_FLT1_SMBALT_N_IMON   I116 @BASEBOARD_FAB2_LIB.BASEBOARD_FAB2(SCH_1):PAGE201

R4E21 RES_0402-68.1K,1%,1/16W,EMPTY,A
     1 VR_PVCCIO_CPU1_OCSET @BASEBOARD_FAB2_LIB.BASEBOARD_FAB2(SCH_1):VR_PVCCIO_CPU1_OCSET   I127 @BASEBOARD_FAB2_LIB.BASEBOARD_FAB2(SCH_1):PAGE214
     2    GND @BASEBOARD_FAB2_LIB.BASEBOARD_FAB2(SCH_1):GND   I127 @BASEBOARD_FAB2_LIB.BASEBOARD_FAB2(SCH_1):PAGE214

R4E22 RES_0402-68.1K,1%,1/16W,EMPTY,A
     1 VR_PVCCIN_CPU0_PH1_OCSET @BASEBOARD_FAB2_LIB.BASEBOARD_FAB2(SCH_1):VR_PVCCIN_CPU0_PH1_OCSET    I65 @BASEBOARD_FAB2_LIB.BASEBOARD_FAB2(SCH_1):PAGE202
     2    GND @BASEBOARD_FAB2_LIB.BASEBOARD_FAB2(SCH_1):GND    I65 @BASEBOARD_FAB2_LIB.BASEBOARD_FAB2(SCH_1):PAGE202

R4F2 RES_1206-0.002,1%,1W,CHIP,G521A
     1 P12V_STBY @BASEBOARD_FAB2_LIB.BASEBOARD_FAB2(SCH_1):P12V_STBY    I14 @BASEBOARD_FAB2_LIB.BASEBOARD_FAB2(SCH_1):PAGE197
     2 P12V_NVDIMM_ABC @BASEBOARD_FAB2_LIB.BASEBOARD_FAB2(SCH_1):P12V_NVDIMM_ABC    I14 @BASEBOARD_FAB2_LIB.BASEBOARD_FAB2(SCH_1):PAGE197

R4F3 RES_0402-2,1.0%,1/16W,CHIP,G21A
     1 M_A_CPU_VREF @BASEBOARD_FAB2_LIB.BASEBOARD_FAB2(SCH_1):M_A_CPU_VREF     I5 @BASEBOARD_FAB2_LIB.BASEBOARD_FAB2(SCH_1):PAGE98
     2 M_A_VREF @BASEBOARD_FAB2_LIB.BASEBOARD_FAB2(SCH_1):M_A_VREF     I5 @BASEBOARD_FAB2_LIB.BASEBOARD_FAB2(SCH_1):PAGE98

R4F4 RES_0402-1.00K,1%,1/16W,CHIP,GA
     1 PVDDQ_ABC @BASEBOARD_FAB2_LIB.BASEBOARD_FAB2(SCH_1):PVDDQ_ABC    I36 @BASEBOARD_FAB2_LIB.BASEBOARD_FAB2(SCH_1):PAGE98
     2 M_A_VREF @BASEBOARD_FAB2_LIB.BASEBOARD_FAB2(SCH_1):M_A_VREF    I36 @BASEBOARD_FAB2_LIB.BASEBOARD_FAB2(SCH_1):PAGE98

R4F5 RES_0402-1.00K,1%,1/16W,CHIP,GA
     1 M_A_VREF @BASEBOARD_FAB2_LIB.BASEBOARD_FAB2(SCH_1):M_A_VREF     I4 @BASEBOARD_FAB2_LIB.BASEBOARD_FAB2(SCH_1):PAGE98
     2    GND @BASEBOARD_FAB2_LIB.BASEBOARD_FAB2(SCH_1):GND     I4 @BASEBOARD_FAB2_LIB.BASEBOARD_FAB2(SCH_1):PAGE98

R4F6 RES_0402-2.2,5%,1/16W,EMPTY,G2A
     1 VR_PVPP_GHJ_SNUB @BASEBOARD_FAB2_LIB.BASEBOARD_FAB2(SCH_1):VR_PVPP_GHJ_SNUB   I208 @BASEBOARD_FAB2_LIB.BASEBOARD_FAB2(SCH_1):PAGE233
     2    GND @BASEBOARD_FAB2_LIB.BASEBOARD_FAB2(SCH_1):GND   I208 @BASEBOARD_FAB2_LIB.BASEBOARD_FAB2(SCH_1):PAGE233

R4G1 RES_0402-2,1.0%,1/16W,CHIP,G21A
     1 M_B_CPU_VREF @BASEBOARD_FAB2_LIB.BASEBOARD_FAB2(SCH_1):M_B_CPU_VREF    I42 @BASEBOARD_FAB2_LIB.BASEBOARD_FAB2(SCH_1):PAGE98
     2 M_B_VREF @BASEBOARD_FAB2_LIB.BASEBOARD_FAB2(SCH_1):M_B_VREF    I42 @BASEBOARD_FAB2_LIB.BASEBOARD_FAB2(SCH_1):PAGE98

R4G2 RES_0402-1.00K,1%,1/16W,CHIP,GA
     1 PVDDQ_ABC @BASEBOARD_FAB2_LIB.BASEBOARD_FAB2(SCH_1):PVDDQ_ABC    I38 @BASEBOARD_FAB2_LIB.BASEBOARD_FAB2(SCH_1):PAGE98
     2 M_B_VREF @BASEBOARD_FAB2_LIB.BASEBOARD_FAB2(SCH_1):M_B_VREF    I38 @BASEBOARD_FAB2_LIB.BASEBOARD_FAB2(SCH_1):PAGE98

R4G3 RES_0402-1.00K,1%,1/16W,CHIP,GA
     1 M_B_VREF @BASEBOARD_FAB2_LIB.BASEBOARD_FAB2(SCH_1):M_B_VREF    I40 @BASEBOARD_FAB2_LIB.BASEBOARD_FAB2(SCH_1):PAGE98
     2    GND @BASEBOARD_FAB2_LIB.BASEBOARD_FAB2(SCH_1):GND    I40 @BASEBOARD_FAB2_LIB.BASEBOARD_FAB2(SCH_1):PAGE98

R4G4 RES_0402-0.0,5%,1/16W,CHIP,G21A
     1 FM_PVPP_CPU1_EN @BASEBOARD_FAB2_LIB.BASEBOARD_FAB2(SCH_1):FM_PVPP_CPU1_EN   I275 @BASEBOARD_FAB2_LIB.BASEBOARD_FAB2(SCH_1):PAGE233
     2 FM_PVPP_PVDDQ_CPU1_EN_GHJ @BASEBOARD_FAB2_LIB.BASEBOARD_FAB2(SCH_1):FM_PVPP_PVDDQ_CPU1_EN_GHJ   I275 @BASEBOARD_FAB2_LIB.BASEBOARD_FAB2(SCH_1):PAGE233

R4G5 RES_0402-10.0K,1%,1/16W,CHIP,GA
     1 FM_PVPP_CPU1_EN @BASEBOARD_FAB2_LIB.BASEBOARD_FAB2(SCH_1):FM_PVPP_CPU1_EN   I182 @BASEBOARD_FAB2_LIB.BASEBOARD_FAB2(SCH_1):PAGE233
     2    GND @BASEBOARD_FAB2_LIB.BASEBOARD_FAB2(SCH_1):GND   I182 @BASEBOARD_FAB2_LIB.BASEBOARD_FAB2(SCH_1):PAGE233

R4G6 RES_0603-120.0,1%,1/10W,CHIP,GA
     1 PVPP_GHJ @BASEBOARD_FAB2_LIB.BASEBOARD_FAB2(SCH_1):PVPP_GHJ   I211 @BASEBOARD_FAB2_LIB.BASEBOARD_FAB2(SCH_1):PAGE233
     2    GND @BASEBOARD_FAB2_LIB.BASEBOARD_FAB2(SCH_1):GND   I211 @BASEBOARD_FAB2_LIB.BASEBOARD_FAB2(SCH_1):PAGE233

R4G7 RES_0402-20.0K,1%,1/16W,CHIP,GA
     1 VSENSE_PVPP_GHJ @BASEBOARD_FAB2_LIB.BASEBOARD_FAB2(SCH_1):VSENSE_PVPP_GHJ   I270 @BASEBOARD_FAB2_LIB.BASEBOARD_FAB2(SCH_1):PAGE233
     2 VR_FB_PVPP_GHJ @BASEBOARD_FAB2_LIB.BASEBOARD_FAB2(SCH_1):VR_FB_PVPP_GHJ   I270 @BASEBOARD_FAB2_LIB.BASEBOARD_FAB2(SCH_1):PAGE233

R4G8 RES_0402-0.0,5%,1/16W,CHIP,G21A
     1 PVPP_GHJ @BASEBOARD_FAB2_LIB.BASEBOARD_FAB2(SCH_1):PVPP_GHJ   I271 @BASEBOARD_FAB2_LIB.BASEBOARD_FAB2(SCH_1):PAGE233
     2 VSENSE_PVPP_GHJ @BASEBOARD_FAB2_LIB.BASEBOARD_FAB2(SCH_1):VSENSE_PVPP_GHJ   I271 @BASEBOARD_FAB2_LIB.BASEBOARD_FAB2(SCH_1):PAGE233

R4G9 RES_0402-6.19K,1%,1/16W,CHIP,GA
     1 VR_FB_PVPP_GHJ @BASEBOARD_FAB2_LIB.BASEBOARD_FAB2(SCH_1):VR_FB_PVPP_GHJ   I283 @BASEBOARD_FAB2_LIB.BASEBOARD_FAB2(SCH_1):PAGE233
     2 AGND_PVPP_GHJ @BASEBOARD_FAB2_LIB.BASEBOARD_FAB2(SCH_1):AGND_PVPP_GHJ   I283 @BASEBOARD_FAB2_LIB.BASEBOARD_FAB2(SCH_1):PAGE233

R4G10 RES_0402-1.0K,0.1%,1/16W,CHIP,A
     1 VSENSE_PVPP_GHJ @BASEBOARD_FAB2_LIB.BASEBOARD_FAB2(SCH_1):VSENSE_PVPP_GHJ   I266 @BASEBOARD_FAB2_LIB.BASEBOARD_FAB2(SCH_1):PAGE233
     2 VR_COMP_PVPP_GHJ @BASEBOARD_FAB2_LIB.BASEBOARD_FAB2(SCH_1):VR_COMP_PVPP_GHJ   I266 @BASEBOARD_FAB2_LIB.BASEBOARD_FAB2(SCH_1):PAGE233

R4G11 RES_0402-7.87K,1.0%,1/16W,CHIPA
     1 VR_PVPP_GHJ_ISET @BASEBOARD_FAB2_LIB.BASEBOARD_FAB2(SCH_1):VR_PVPP_GHJ_ISET   I284 @BASEBOARD_FAB2_LIB.BASEBOARD_FAB2(SCH_1):PAGE233
     2 AGND_PVPP_GHJ @BASEBOARD_FAB2_LIB.BASEBOARD_FAB2(SCH_1):AGND_PVPP_GHJ   I284 @BASEBOARD_FAB2_LIB.BASEBOARD_FAB2(SCH_1):PAGE233

R4G12 RES_0402-22.1,1.0%,1/16W,CHIP,A
     1 PWRGD_PVPP_GHJ_R @BASEBOARD_FAB2_LIB.BASEBOARD_FAB2(SCH_1):PWRGD_PVPP_GHJ_R   I247 @BASEBOARD_FAB2_LIB.BASEBOARD_FAB2(SCH_1):PAGE233
     2 PWRGD_PVPP_GHJ @BASEBOARD_FAB2_LIB.BASEBOARD_FAB2(SCH_1):PWRGD_PVPP_GHJ   I247 @BASEBOARD_FAB2_LIB.BASEBOARD_FAB2(SCH_1):PAGE233

R4G13 RES_0402-7.87K,1.0%,1/16W,CHIPA
     1 VR_COMP_RC_PVPP_GHJ @BASEBOARD_FAB2_LIB.BASEBOARD_FAB2(SCH_1):VR_COMP_RC_PVPP_GHJ   I272 @BASEBOARD_FAB2_LIB.BASEBOARD_FAB2(SCH_1):PAGE233
     2 VR_FB_PVPP_GHJ @BASEBOARD_FAB2_LIB.BASEBOARD_FAB2(SCH_1):VR_FB_PVPP_GHJ   I272 @BASEBOARD_FAB2_LIB.BASEBOARD_FAB2(SCH_1):PAGE233

R4G14 RES_0402-1.00K,1%,1/16W,CHIP,GA
     1 P3V3_STBY @BASEBOARD_FAB2_LIB.BASEBOARD_FAB2(SCH_1):P3V3_STBY   I185 @BASEBOARD_FAB2_LIB.BASEBOARD_FAB2(SCH_1):PAGE233
     2 PWRGD_PVPP_GHJ_R @BASEBOARD_FAB2_LIB.BASEBOARD_FAB2(SCH_1):PWRGD_PVPP_GHJ_R   I185 @BASEBOARD_FAB2_LIB.BASEBOARD_FAB2(SCH_1):PAGE233

R4G15 RES_0402-33.2,1%,1/16W,CHIP,G2A
     1 PWRGD_PVTT_GHJ_CPU1_R @BASEBOARD_FAB2_LIB.BASEBOARD_FAB2(SCH_1):PWRGD_PVTT_GHJ_CPU1_R    I32 @BASEBOARD_FAB2_LIB.BASEBOARD_FAB2(SCH_1):PAGE229
     2 PWRGD_PVTT_CPU1 @BASEBOARD_FAB2_LIB.BASEBOARD_FAB2(SCH_1):PWRGD_PVTT_CPU1    I32 @BASEBOARD_FAB2_LIB.BASEBOARD_FAB2(SCH_1):PAGE229

R4G16 RES_0402-0.0,5%,1/16W,CHIP,G21A
     1 PWRGD_PVDDQ_GHJ_R @BASEBOARD_FAB2_LIB.BASEBOARD_FAB2(SCH_1):PWRGD_PVDDQ_GHJ_R     I4 @BASEBOARD_FAB2_LIB.BASEBOARD_FAB2(SCH_1):PAGE229
     2 FM_PVTT_GHJ_EN_R @BASEBOARD_FAB2_LIB.BASEBOARD_FAB2(SCH_1):FM_PVTT_GHJ_EN_R     I4 @BASEBOARD_FAB2_LIB.BASEBOARD_FAB2(SCH_1):PAGE229

R4G17 RES_0402-10.0K,1%,1/16W,CHIP,GA
     1   P3V3 @BASEBOARD_FAB2_LIB.BASEBOARD_FAB2(SCH_1):P3V3    I24 @BASEBOARD_FAB2_LIB.BASEBOARD_FAB2(SCH_1):PAGE229
     2 PWRGD_PVTT_GHJ_CPU1_R @BASEBOARD_FAB2_LIB.BASEBOARD_FAB2(SCH_1):PWRGD_PVTT_GHJ_CPU1_R    I24 @BASEBOARD_FAB2_LIB.BASEBOARD_FAB2(SCH_1):PAGE229

R4G18 RES_0402-10.0K,1%,1/16W,CHIP,GA
     1   P3V3 @BASEBOARD_FAB2_LIB.BASEBOARD_FAB2(SCH_1):P3V3    I25 @BASEBOARD_FAB2_LIB.BASEBOARD_FAB2(SCH_1):PAGE221
     2 PWRGD_PVTT_ABC_CPU0_R @BASEBOARD_FAB2_LIB.BASEBOARD_FAB2(SCH_1):PWRGD_PVTT_ABC_CPU0_R    I25 @BASEBOARD_FAB2_LIB.BASEBOARD_FAB2(SCH_1):PAGE221

R4G19 RES_0402-33.2,1%,1/16W,CHIP,G2A
     1 PWRGD_PVTT_ABC_CPU0_R @BASEBOARD_FAB2_LIB.BASEBOARD_FAB2(SCH_1):PWRGD_PVTT_ABC_CPU0_R    I33 @BASEBOARD_FAB2_LIB.BASEBOARD_FAB2(SCH_1):PAGE221
     2 PWRGD_PVTT_CPU0 @BASEBOARD_FAB2_LIB.BASEBOARD_FAB2(SCH_1):PWRGD_PVTT_CPU0    I33 @BASEBOARD_FAB2_LIB.BASEBOARD_FAB2(SCH_1):PAGE221

R4G20 RES_0402-2,1.0%,1/16W,CHIP,G21A
     1 M_C_CPU_VREF @BASEBOARD_FAB2_LIB.BASEBOARD_FAB2(SCH_1):M_C_CPU_VREF    I50 @BASEBOARD_FAB2_LIB.BASEBOARD_FAB2(SCH_1):PAGE98
     2 M_C_VREF @BASEBOARD_FAB2_LIB.BASEBOARD_FAB2(SCH_1):M_C_VREF    I50 @BASEBOARD_FAB2_LIB.BASEBOARD_FAB2(SCH_1):PAGE98

R4G21 RES_0402-1.00K,1%,1/16W,CHIP,GA
     1 PVDDQ_ABC @BASEBOARD_FAB2_LIB.BASEBOARD_FAB2(SCH_1):PVDDQ_ABC    I46 @BASEBOARD_FAB2_LIB.BASEBOARD_FAB2(SCH_1):PAGE98
     2 M_C_VREF @BASEBOARD_FAB2_LIB.BASEBOARD_FAB2(SCH_1):M_C_VREF    I46 @BASEBOARD_FAB2_LIB.BASEBOARD_FAB2(SCH_1):PAGE98

R4G22 RES_0402-1.00K,1%,1/16W,CHIP,GA
     1 M_C_VREF @BASEBOARD_FAB2_LIB.BASEBOARD_FAB2(SCH_1):M_C_VREF    I48 @BASEBOARD_FAB2_LIB.BASEBOARD_FAB2(SCH_1):PAGE98
     2    GND @BASEBOARD_FAB2_LIB.BASEBOARD_FAB2(SCH_1):GND    I48 @BASEBOARD_FAB2_LIB.BASEBOARD_FAB2(SCH_1):PAGE98

R4G23 RES_0402-0.0,5%,1/16W,CHIP,G21A
     1 PWRGD_PVDDQ_ABC_R @BASEBOARD_FAB2_LIB.BASEBOARD_FAB2(SCH_1):PWRGD_PVDDQ_ABC_R     I4 @BASEBOARD_FAB2_LIB.BASEBOARD_FAB2(SCH_1):PAGE221
     2 FM_PVTT_ABC_EN_R @BASEBOARD_FAB2_LIB.BASEBOARD_FAB2(SCH_1):FM_PVTT_ABC_EN_R     I4 @BASEBOARD_FAB2_LIB.BASEBOARD_FAB2(SCH_1):PAGE221

R4G24 RES_0603-0,5.0%,1/10W,CHIP,G22A
     1 VR_PVPP_GHJ_BOOT @BASEBOARD_FAB2_LIB.BASEBOARD_FAB2(SCH_1):VR_PVPP_GHJ_BOOT   I282 @BASEBOARD_FAB2_LIB.BASEBOARD_FAB2(SCH_1):PAGE233
     2 VR_PVPP_GHJ_BOOT_R @BASEBOARD_FAB2_LIB.BASEBOARD_FAB2(SCH_1):VR_PVPP_GHJ_BOOT_R   I282 @BASEBOARD_FAB2_LIB.BASEBOARD_FAB2(SCH_1):PAGE233

R4G25 RES_0402-0.0,5%,1/16W,CHIP,G21A
     1    GND @BASEBOARD_FAB2_LIB.BASEBOARD_FAB2(SCH_1):GND   I157 @BASEBOARD_FAB2_LIB.BASEBOARD_FAB2(SCH_1):PAGE233
     2 AGND_PVPP_GHJ @BASEBOARD_FAB2_LIB.BASEBOARD_FAB2(SCH_1):AGND_PVPP_GHJ   I157 @BASEBOARD_FAB2_LIB.BASEBOARD_FAB2(SCH_1):PAGE233

R4L2 RES_0402-100.0,1%,1/16W,EMPTY,A
     1 VSENSE_PVDDQ_DEF_P @BASEBOARD_FAB2_LIB.BASEBOARD_FAB2(SCH_1):VSENSE_PVDDQ_DEF_P    I74 @BASEBOARD_FAB2_LIB.BASEBOARD_FAB2(SCH_1):PAGE220
     2 VSENSE_PVDDQ_DEF_N @BASEBOARD_FAB2_LIB.BASEBOARD_FAB2(SCH_1):VSENSE_PVDDQ_DEF_N    I74 @BASEBOARD_FAB2_LIB.BASEBOARD_FAB2(SCH_1):PAGE220

R4L4 RES_0603-120.0,1%,1/10W,CHIP,GA
     1 PVDDQ_DEF @BASEBOARD_FAB2_LIB.BASEBOARD_FAB2(SCH_1):PVDDQ_DEF    I58 @BASEBOARD_FAB2_LIB.BASEBOARD_FAB2(SCH_1):PAGE220
     2    GND @BASEBOARD_FAB2_LIB.BASEBOARD_FAB2(SCH_1):GND    I58 @BASEBOARD_FAB2_LIB.BASEBOARD_FAB2(SCH_1):PAGE220

R4P1 RES_0402-240,1.0%,1/16W,EMPTY,A
     1    GND @BASEBOARD_FAB2_LIB.BASEBOARD_FAB2(SCH_1):GND    I98 @BASEBOARD_FAB2_LIB.BASEBOARD_FAB2(SCH_1):PAGE90
     2 PD_CPU0_BIST_ENABLE @BASEBOARD_FAB2_LIB.BASEBOARD_FAB2(SCH_1):PD_CPU0_BIST_ENABLE    I98 @BASEBOARD_FAB2_LIB.BASEBOARD_FAB2(SCH_1):PAGE90

R4P2 RES_0402-49.9,1%,1/16W,CHIP,G2A
     1 A_CPU0_PE3_RBIAS @BASEBOARD_FAB2_LIB.BASEBOARD_FAB2(SCH_1):A_CPU0_PE3_RBIAS   I188 @BASEBOARD_FAB2_LIB.BASEBOARD_FAB2(SCH_1):PAGE21
     2    GND @BASEBOARD_FAB2_LIB.BASEBOARD_FAB2(SCH_1):GND   I188 @BASEBOARD_FAB2_LIB.BASEBOARD_FAB2(SCH_1):PAGE21

R4P3 RES_0402-49.9,1%,1/16W,CHIP,G2A
     1 A_CPU0_PE012_RBIAS @BASEBOARD_FAB2_LIB.BASEBOARD_FAB2(SCH_1):A_CPU0_PE012_RBIAS   I186 @BASEBOARD_FAB2_LIB.BASEBOARD_FAB2(SCH_1):PAGE21
     2    GND @BASEBOARD_FAB2_LIB.BASEBOARD_FAB2(SCH_1):GND   I186 @BASEBOARD_FAB2_LIB.BASEBOARD_FAB2(SCH_1):PAGE21

R4P4 RES_0402-49.9,1%,1/16W,CHIP,G2A
     1 A_CPU0_UPI2_RBIAS @BASEBOARD_FAB2_LIB.BASEBOARD_FAB2(SCH_1):A_CPU0_UPI2_RBIAS   I189 @BASEBOARD_FAB2_LIB.BASEBOARD_FAB2(SCH_1):PAGE21
     2    GND @BASEBOARD_FAB2_LIB.BASEBOARD_FAB2(SCH_1):GND   I189 @BASEBOARD_FAB2_LIB.BASEBOARD_FAB2(SCH_1):PAGE21

R4P5 RES_0402-10.0K,1%,1/16W,CHIP,GA
     1    GND @BASEBOARD_FAB2_LIB.BASEBOARD_FAB2(SCH_1):GND    I80 @BASEBOARD_FAB2_LIB.BASEBOARD_FAB2(SCH_1):PAGE97
     2 PD_CPU0_MCP01_DMON @BASEBOARD_FAB2_LIB.BASEBOARD_FAB2(SCH_1):PD_CPU0_MCP01_DMON    I80 @BASEBOARD_FAB2_LIB.BASEBOARD_FAB2(SCH_1):PAGE97

R4P6 RES_0402-240,1.0%,1/16W,EMPTY,A
     1    GND @BASEBOARD_FAB2_LIB.BASEBOARD_FAB2(SCH_1):GND    I68 @BASEBOARD_FAB2_LIB.BASEBOARD_FAB2(SCH_1):PAGE90
     2 PD_CPU0_DMIMODE_OVERRIDE @BASEBOARD_FAB2_LIB.BASEBOARD_FAB2(SCH_1):PD_CPU0_DMIMODE_OVERRIDE    I68 @BASEBOARD_FAB2_LIB.BASEBOARD_FAB2(SCH_1):PAGE90

R4P7 RES_0402-240,1.0%,1/16W,EMPTY,A
     1    GND @BASEBOARD_FAB2_LIB.BASEBOARD_FAB2(SCH_1):GND    I72 @BASEBOARD_FAB2_LIB.BASEBOARD_FAB2(SCH_1):PAGE90
     2 PD_CPU0_KSFC_DIS @BASEBOARD_FAB2_LIB.BASEBOARD_FAB2(SCH_1):PD_CPU0_KSFC_DIS    I72 @BASEBOARD_FAB2_LIB.BASEBOARD_FAB2(SCH_1):PAGE90

R4P8 RES_0402-90.9,1%,1/16W,CHIP,G2A
     1 A_CPU0_ABC_RCOMP0 @BASEBOARD_FAB2_LIB.BASEBOARD_FAB2(SCH_1):A_CPU0_ABC_RCOMP0   I180 @BASEBOARD_FAB2_LIB.BASEBOARD_FAB2(SCH_1):PAGE21
     2    GND @BASEBOARD_FAB2_LIB.BASEBOARD_FAB2(SCH_1):GND   I180 @BASEBOARD_FAB2_LIB.BASEBOARD_FAB2(SCH_1):PAGE21

R4P10 RES_0402-90.9,1%,1/16W,CHIP,G2A
     1 A_CPU0_ABC_RCOMP1 @BASEBOARD_FAB2_LIB.BASEBOARD_FAB2(SCH_1):A_CPU0_ABC_RCOMP1   I181 @BASEBOARD_FAB2_LIB.BASEBOARD_FAB2(SCH_1):PAGE21
     2    GND @BASEBOARD_FAB2_LIB.BASEBOARD_FAB2(SCH_1):GND   I181 @BASEBOARD_FAB2_LIB.BASEBOARD_FAB2(SCH_1):PAGE21

R4P11 RES_0402-100.0,1%,1/16W,CHIP,GA
     1 A_CPU0_ABC_RCOMP2 @BASEBOARD_FAB2_LIB.BASEBOARD_FAB2(SCH_1):A_CPU0_ABC_RCOMP2   I182 @BASEBOARD_FAB2_LIB.BASEBOARD_FAB2(SCH_1):PAGE21
     2    GND @BASEBOARD_FAB2_LIB.BASEBOARD_FAB2(SCH_1):GND   I182 @BASEBOARD_FAB2_LIB.BASEBOARD_FAB2(SCH_1):PAGE21

R4P12 RES_0402-100.0,1%,1/16W,CHIP,GA
     1 PVCCIO_CPU0 @BASEBOARD_FAB2_LIB.BASEBOARD_FAB2(SCH_1):PVCCIO_CPU0    I57 @BASEBOARD_FAB2_LIB.BASEBOARD_FAB2(SCH_1):PAGE112
     2 XDP_CPU_MBP0_N @BASEBOARD_FAB2_LIB.BASEBOARD_FAB2(SCH_1):XDP_CPU_MBP0_N    I57 @BASEBOARD_FAB2_LIB.BASEBOARD_FAB2(SCH_1):PAGE112

R4P14 RES_0402-240,1.0%,1/16W,CHIP,GA
     1 PVCCIO_CPU0 @BASEBOARD_FAB2_LIB.BASEBOARD_FAB2(SCH_1):PVCCIO_CPU0    I53 @BASEBOARD_FAB2_LIB.BASEBOARD_FAB2(SCH_1):PAGE90
     2 PU_CPU0_LEGACY_SKT @BASEBOARD_FAB2_LIB.BASEBOARD_FAB2(SCH_1):PU_CPU0_LEGACY_SKT    I53 @BASEBOARD_FAB2_LIB.BASEBOARD_FAB2(SCH_1):PAGE90

R4P15 RES_0402-100.0,1%,1/16W,CHIP,GA
     1 PVCCIO_CPU0 @BASEBOARD_FAB2_LIB.BASEBOARD_FAB2(SCH_1):PVCCIO_CPU0    I53 @BASEBOARD_FAB2_LIB.BASEBOARD_FAB2(SCH_1):PAGE112
     2 XDP_CPU_MBP1_N @BASEBOARD_FAB2_LIB.BASEBOARD_FAB2(SCH_1):XDP_CPU_MBP1_N    I53 @BASEBOARD_FAB2_LIB.BASEBOARD_FAB2(SCH_1):PAGE112

R4P17 RES_0402-150.0,1%,1/16W,CHIP,GA
     1 H_CPU0_MEMABC_MEMHOT_G_N @BASEBOARD_FAB2_LIB.BASEBOARD_FAB2(SCH_1):H_CPU0_MEMABC_MEMHOT_G_N    I58 @BASEBOARD_FAB2_LIB.BASEBOARD_FAB2(SCH_1):PAGE152
     2 PVCCIO_CPU0 @BASEBOARD_FAB2_LIB.BASEBOARD_FAB2(SCH_1):PVCCIO_CPU0    I58 @BASEBOARD_FAB2_LIB.BASEBOARD_FAB2(SCH_1):PAGE152

R4P18 RES_0402-49.9,1%,1/16W,CHIP,G2A
     1 H_PM_SYNC_GTL_R1 @BASEBOARD_FAB2_LIB.BASEBOARD_FAB2(SCH_1):H_PM_SYNC_GTL_R1   I244 @BASEBOARD_FAB2_LIB.BASEBOARD_FAB2(SCH_1):PAGE21
     2 H_PM_SYNC_GTL @BASEBOARD_FAB2_LIB.BASEBOARD_FAB2(SCH_1):H_PM_SYNC_GTL   I244 @BASEBOARD_FAB2_LIB.BASEBOARD_FAB2(SCH_1):PAGE21

R4P19 RES_0402-49.9,1%,1/16W,CHIP,G2A
     1 H_PMSYNC_CLK_24M_CPU0 @BASEBOARD_FAB2_LIB.BASEBOARD_FAB2(SCH_1):H_PMSYNC_CLK_24M_CPU0   I219 @BASEBOARD_FAB2_LIB.BASEBOARD_FAB2(SCH_1):PAGE21
     2 H_PMSYNC_CLK_24M @BASEBOARD_FAB2_LIB.BASEBOARD_FAB2(SCH_1):H_PMSYNC_CLK_24M   I219 @BASEBOARD_FAB2_LIB.BASEBOARD_FAB2(SCH_1):PAGE21

R4P20 RES_0402-150.0,1%,1/16W,CHIP,GA
     1 H_CPU0_MEMDEF_MEMHOT_G_N @BASEBOARD_FAB2_LIB.BASEBOARD_FAB2(SCH_1):H_CPU0_MEMDEF_MEMHOT_G_N    I59 @BASEBOARD_FAB2_LIB.BASEBOARD_FAB2(SCH_1):PAGE152
     2 PVCCIO_CPU0 @BASEBOARD_FAB2_LIB.BASEBOARD_FAB2(SCH_1):PVCCIO_CPU0    I59 @BASEBOARD_FAB2_LIB.BASEBOARD_FAB2(SCH_1):PAGE152

R4P21 RES_0402-240,1.0%,1/16W,CHIP,GA
     1 PVCCIO_CPU0 @BASEBOARD_FAB2_LIB.BASEBOARD_FAB2(SCH_1):PVCCIO_CPU0    I72 @BASEBOARD_FAB2_LIB.BASEBOARD_FAB2(SCH_1):PAGE97
     2 PU_CPU0_TSC_SYNC @BASEBOARD_FAB2_LIB.BASEBOARD_FAB2(SCH_1):PU_CPU0_TSC_SYNC    I72 @BASEBOARD_FAB2_LIB.BASEBOARD_FAB2(SCH_1):PAGE97

R4P23 RES_0402-150.0,1%,1/16W,CHIP,GA
     1 PVCCIO_CPU0 @BASEBOARD_FAB2_LIB.BASEBOARD_FAB2(SCH_1):PVCCIO_CPU0    I58 @BASEBOARD_FAB2_LIB.BASEBOARD_FAB2(SCH_1):PAGE112
     2 XDP_CPU0_TDO @BASEBOARD_FAB2_LIB.BASEBOARD_FAB2(SCH_1):XDP_CPU0_TDO    I58 @BASEBOARD_FAB2_LIB.BASEBOARD_FAB2(SCH_1):PAGE112

R4P24 RES_0402-150.0,1%,1/16W,CHIP,GA
     1 PVCCIO_CPU0 @BASEBOARD_FAB2_LIB.BASEBOARD_FAB2(SCH_1):PVCCIO_CPU0    I59 @BASEBOARD_FAB2_LIB.BASEBOARD_FAB2(SCH_1):PAGE112
     2 XDP_CPU_TDI @BASEBOARD_FAB2_LIB.BASEBOARD_FAB2(SCH_1):XDP_CPU_TDI    I59 @BASEBOARD_FAB2_LIB.BASEBOARD_FAB2(SCH_1):PAGE112

R4R1 RES_0402-1.00K,1%,1/16W,CHIP,GA
     1 H_CPU0_FAST_WAKE_N @BASEBOARD_FAB2_LIB.BASEBOARD_FAB2(SCH_1):H_CPU0_FAST_WAKE_N   I368 @BASEBOARD_FAB2_LIB.BASEBOARD_FAB2(SCH_1):PAGE157
     2 H_CPU0_FAST_WAKE_B_N @BASEBOARD_FAB2_LIB.BASEBOARD_FAB2(SCH_1):H_CPU0_FAST_WAKE_B_N   I368 @BASEBOARD_FAB2_LIB.BASEBOARD_FAB2(SCH_1):PAGE157

R4R2 RES_0402-150.0,1%,1/16W,CHIP,GA
     1 PVCCIO_CPU0 @BASEBOARD_FAB2_LIB.BASEBOARD_FAB2(SCH_1):PVCCIO_CPU0   I101 @BASEBOARD_FAB2_LIB.BASEBOARD_FAB2(SCH_1):PAGE92
     2 H_CPU0_CATERR_G_N @BASEBOARD_FAB2_LIB.BASEBOARD_FAB2(SCH_1):H_CPU0_CATERR_G_N   I101 @BASEBOARD_FAB2_LIB.BASEBOARD_FAB2(SCH_1):PAGE92

R4R3 RES_0402-150.0,1%,1/16W,CHIP,GA
     1 PVCCIO_CPU0 @BASEBOARD_FAB2_LIB.BASEBOARD_FAB2(SCH_1):PVCCIO_CPU0    I79 @BASEBOARD_FAB2_LIB.BASEBOARD_FAB2(SCH_1):PAGE93
     2 H_CPU0_PROCHOT_G_N @BASEBOARD_FAB2_LIB.BASEBOARD_FAB2(SCH_1):H_CPU0_PROCHOT_G_N    I79 @BASEBOARD_FAB2_LIB.BASEBOARD_FAB2(SCH_1):PAGE93

R4R4 RES_0402-150.0,1%,1/16W,CHIP,GA
     1 PVCCIO_CPU0 @BASEBOARD_FAB2_LIB.BASEBOARD_FAB2(SCH_1):PVCCIO_CPU0    I42 @BASEBOARD_FAB2_LIB.BASEBOARD_FAB2(SCH_1):PAGE97
     2 H_CPU0_FAST_WAKE_N @BASEBOARD_FAB2_LIB.BASEBOARD_FAB2(SCH_1):H_CPU0_FAST_WAKE_N    I42 @BASEBOARD_FAB2_LIB.BASEBOARD_FAB2(SCH_1):PAGE97

R4R5 RES_0402-4.75K,1%,1/16W,CHIP,GA
     1 P3V3_STBY @BASEBOARD_FAB2_LIB.BASEBOARD_FAB2(SCH_1):P3V3_STBY   I258 @BASEBOARD_FAB2_LIB.BASEBOARD_FAB2(SCH_1):PAGE21
     2 FM_CPU0_SKTOCC_LVT3_N @BASEBOARD_FAB2_LIB.BASEBOARD_FAB2(SCH_1):FM_CPU0_SKTOCC_LVT3_N   I258 @BASEBOARD_FAB2_LIB.BASEBOARD_FAB2(SCH_1):PAGE21

R4R6 RES_0402-1.00K,1%,1/16W,CHIP,GA
     1 JTAG_MCP_CPU0_TDI_R @BASEBOARD_FAB2_LIB.BASEBOARD_FAB2(SCH_1):JTAG_MCP_CPU0_TDI_R   I270 @BASEBOARD_FAB2_LIB.BASEBOARD_FAB2(SCH_1):PAGE113
     2 JTAG_MCP_CPU0_TDI @BASEBOARD_FAB2_LIB.BASEBOARD_FAB2(SCH_1):JTAG_MCP_CPU0_TDI   I270 @BASEBOARD_FAB2_LIB.BASEBOARD_FAB2(SCH_1):PAGE113

R4T1 RES_0402-0.0,5%,1/16W,CHIP,G21A
     1 FM_ADR_COMPLETE_DLY @BASEBOARD_FAB2_LIB.BASEBOARD_FAB2(SCH_1):FM_ADR_COMPLETE_DLY     I2 @BASEBOARD_FAB2_LIB.BASEBOARD_FAB2(SCH_1):PAGE89
     2 FM_ADR_COMPLETE_R @BASEBOARD_FAB2_LIB.BASEBOARD_FAB2(SCH_1):FM_ADR_COMPLETE_R     I2 @BASEBOARD_FAB2_LIB.BASEBOARD_FAB2(SCH_1):PAGE89

R4T2 RES_0402-0.0,5%,1/16W,EMPTY,G2A
     1 FM_ADR_COMPLETE @BASEBOARD_FAB2_LIB.BASEBOARD_FAB2(SCH_1):FM_ADR_COMPLETE     I1 @BASEBOARD_FAB2_LIB.BASEBOARD_FAB2(SCH_1):PAGE89
     2 FM_ADR_COMPLETE_R @BASEBOARD_FAB2_LIB.BASEBOARD_FAB2(SCH_1):FM_ADR_COMPLETE_R     I1 @BASEBOARD_FAB2_LIB.BASEBOARD_FAB2(SCH_1):PAGE89

R4T3 RES_0402-10.0,1%,1/16W,CHIP,G2A
     1 SMB_DDR_ABC_SCL_G_R @BASEBOARD_FAB2_LIB.BASEBOARD_FAB2(SCH_1):SMB_DDR_ABC_SCL_G_R    I83 @BASEBOARD_FAB2_LIB.BASEBOARD_FAB2(SCH_1):PAGE99
     2 SMB_DDR_ABC_SCL_G @BASEBOARD_FAB2_LIB.BASEBOARD_FAB2(SCH_1):SMB_DDR_ABC_SCL_G    I83 @BASEBOARD_FAB2_LIB.BASEBOARD_FAB2(SCH_1):PAGE99

R4T4 RES_0402-10.0,1%,1/16W,CHIP,G2A
     1 SMB_DDR_ABC_SDA_G_R @BASEBOARD_FAB2_LIB.BASEBOARD_FAB2(SCH_1):SMB_DDR_ABC_SDA_G_R    I20 @BASEBOARD_FAB2_LIB.BASEBOARD_FAB2(SCH_1):PAGE99
     2 SMB_DDR_ABC_SDA_G @BASEBOARD_FAB2_LIB.BASEBOARD_FAB2(SCH_1):SMB_DDR_ABC_SDA_G    I20 @BASEBOARD_FAB2_LIB.BASEBOARD_FAB2(SCH_1):PAGE99

R4T5 RES_0402-240,1.0%,1/16W,CHIP,GA
     1 PVCCIO_CPU0 @BASEBOARD_FAB2_LIB.BASEBOARD_FAB2(SCH_1):PVCCIO_CPU0    I19 @BASEBOARD_FAB2_LIB.BASEBOARD_FAB2(SCH_1):PAGE99
     2 SMB_DDR_ABC_SCL_G @BASEBOARD_FAB2_LIB.BASEBOARD_FAB2(SCH_1):SMB_DDR_ABC_SCL_G    I19 @BASEBOARD_FAB2_LIB.BASEBOARD_FAB2(SCH_1):PAGE99

R4T6 RES_0402-240,1.0%,1/16W,CHIP,GA
     1 PVCCIO_CPU0 @BASEBOARD_FAB2_LIB.BASEBOARD_FAB2(SCH_1):PVCCIO_CPU0    I17 @BASEBOARD_FAB2_LIB.BASEBOARD_FAB2(SCH_1):PAGE99
     2 SMB_DDR_ABC_SDA_G @BASEBOARD_FAB2_LIB.BASEBOARD_FAB2(SCH_1):SMB_DDR_ABC_SDA_G    I17 @BASEBOARD_FAB2_LIB.BASEBOARD_FAB2(SCH_1):PAGE99

R4T7 RES_0402-665,1.0%,1/16W,CHIP,GA
     1 PVPP_ABC @BASEBOARD_FAB2_LIB.BASEBOARD_FAB2(SCH_1):PVPP_ABC    I13 @BASEBOARD_FAB2_LIB.BASEBOARD_FAB2(SCH_1):PAGE99
     2 SMB_DDR_ABC_VPP_SCL_R @BASEBOARD_FAB2_LIB.BASEBOARD_FAB2(SCH_1):SMB_DDR_ABC_VPP_SCL_R    I13 @BASEBOARD_FAB2_LIB.BASEBOARD_FAB2(SCH_1):PAGE99

R4T8 RES_0402-665,1.0%,1/16W,CHIP,GA
     1 PVPP_ABC @BASEBOARD_FAB2_LIB.BASEBOARD_FAB2(SCH_1):PVPP_ABC    I11 @BASEBOARD_FAB2_LIB.BASEBOARD_FAB2(SCH_1):PAGE99
     2 SMB_DDR_ABC_VPP_SDA_R @BASEBOARD_FAB2_LIB.BASEBOARD_FAB2(SCH_1):SMB_DDR_ABC_VPP_SDA_R    I11 @BASEBOARD_FAB2_LIB.BASEBOARD_FAB2(SCH_1):PAGE99

R4T9 RES_0402-20.0,1%,1/16W,CHIP,G2A
     1 SMB_DDR_ABC_VPP_SCL_R @BASEBOARD_FAB2_LIB.BASEBOARD_FAB2(SCH_1):SMB_DDR_ABC_VPP_SCL_R     I9 @BASEBOARD_FAB2_LIB.BASEBOARD_FAB2(SCH_1):PAGE99
     2 SMB_DDR_ABC_VPP_SCL @BASEBOARD_FAB2_LIB.BASEBOARD_FAB2(SCH_1):SMB_DDR_ABC_VPP_SCL     I9 @BASEBOARD_FAB2_LIB.BASEBOARD_FAB2(SCH_1):PAGE99

R4T10 RES_0402-20.0,1%,1/16W,CHIP,G2A
     1 SMB_DDR_ABC_VPP_SDA_R @BASEBOARD_FAB2_LIB.BASEBOARD_FAB2(SCH_1):SMB_DDR_ABC_VPP_SDA_R    I10 @BASEBOARD_FAB2_LIB.BASEBOARD_FAB2(SCH_1):PAGE99
     2 SMB_DDR_ABC_VPP_SDA @BASEBOARD_FAB2_LIB.BASEBOARD_FAB2(SCH_1):SMB_DDR_ABC_VPP_SDA    I10 @BASEBOARD_FAB2_LIB.BASEBOARD_FAB2(SCH_1):PAGE99

R4U1 RES_0402-4.75K,1%,1/16W,CHIP,GA
     1 P3V3_STBY @BASEBOARD_FAB2_LIB.BASEBOARD_FAB2(SCH_1):P3V3_STBY    I91 @BASEBOARD_FAB2_LIB.BASEBOARD_FAB2(SCH_1):PAGE94
     2 FM_MEM_THERM_EVENT_LVT3_N @BASEBOARD_FAB2_LIB.BASEBOARD_FAB2(SCH_1):FM_MEM_THERM_EVENT_LVT3_N    I91 @BASEBOARD_FAB2_LIB.BASEBOARD_FAB2(SCH_1):PAGE94

R4U2 RES_0402-2.21K,1%,1/16W,CHIP,GA
     1 PVPP_ABC @BASEBOARD_FAB2_LIB.BASEBOARD_FAB2(SCH_1):PVPP_ABC   I100 @BASEBOARD_FAB2_LIB.BASEBOARD_FAB2(SCH_1):PAGE94
     2 FM_DIMM_EVENT_COD_N @BASEBOARD_FAB2_LIB.BASEBOARD_FAB2(SCH_1):FM_DIMM_EVENT_COD_N   I100 @BASEBOARD_FAB2_LIB.BASEBOARD_FAB2(SCH_1):PAGE94

R4U3 RES_0402-4.75K,1%,1/16W,CHIP,GA
     1 PVPP_ABC @BASEBOARD_FAB2_LIB.BASEBOARD_FAB2(SCH_1):PVPP_ABC    I94 @BASEBOARD_FAB2_LIB.BASEBOARD_FAB2(SCH_1):PAGE94
     2 FM_DIMM_EVENT_FET @BASEBOARD_FAB2_LIB.BASEBOARD_FAB2(SCH_1):FM_DIMM_EVENT_FET    I94 @BASEBOARD_FAB2_LIB.BASEBOARD_FAB2(SCH_1):PAGE94

R4U4 RES_0402-33.0K,5%,1/16W,CHIP,GA
     1 FM_DIMM_EVENT_FET @BASEBOARD_FAB2_LIB.BASEBOARD_FAB2(SCH_1):FM_DIMM_EVENT_FET   I104 @BASEBOARD_FAB2_LIB.BASEBOARD_FAB2(SCH_1):PAGE94
     2    GND @BASEBOARD_FAB2_LIB.BASEBOARD_FAB2(SCH_1):GND   I104 @BASEBOARD_FAB2_LIB.BASEBOARD_FAB2(SCH_1):PAGE94

R4U6 RES_0402-100.0,1%,1/16W,EMPTY,A
     1 VSENSE_PVDDQ_ABC_P @BASEBOARD_FAB2_LIB.BASEBOARD_FAB2(SCH_1):VSENSE_PVDDQ_ABC_P    I74 @BASEBOARD_FAB2_LIB.BASEBOARD_FAB2(SCH_1):PAGE217
     2 VSENSE_PVDDQ_ABC_N @BASEBOARD_FAB2_LIB.BASEBOARD_FAB2(SCH_1):VSENSE_PVDDQ_ABC_N    I74 @BASEBOARD_FAB2_LIB.BASEBOARD_FAB2(SCH_1):PAGE217

R4W1 RES_0402-4.75K,1%,1/16W,CHIP,GA
     1 P3V3_STBY @BASEBOARD_FAB2_LIB.BASEBOARD_FAB2(SCH_1):P3V3_STBY   I195 @BASEBOARD_FAB2_LIB.BASEBOARD_FAB2(SCH_1):PAGE191
     2 PU_CPLD1_PT20D_PROGRAMN @BASEBOARD_FAB2_LIB.BASEBOARD_FAB2(SCH_1):PU_CPLD1_PT20D_PROGRAMN   I195 @BASEBOARD_FAB2_LIB.BASEBOARD_FAB2(SCH_1):PAGE191

R4W2 RES_0402-1.00K,1%,1/16W,CHIP,GA
     1 P3V3_DB1200 @BASEBOARD_FAB2_LIB.BASEBOARD_FAB2(SCH_1):P3V3_DB1200   I103 @BASEBOARD_FAB2_LIB.BASEBOARD_FAB2(SCH_1):PAGE102
     2 P3V3_DB1200_R1 @BASEBOARD_FAB2_LIB.BASEBOARD_FAB2(SCH_1):P3V3_DB1200_R1   I103 @BASEBOARD_FAB2_LIB.BASEBOARD_FAB2(SCH_1):PAGE102

R4W3 RES_0402-3.3K,5%,1/16W,CHIP,G2A
     1 P3V3_DB1200 @BASEBOARD_FAB2_LIB.BASEBOARD_FAB2(SCH_1):P3V3_DB1200   I105 @BASEBOARD_FAB2_LIB.BASEBOARD_FAB2(SCH_1):PAGE102
     2 SMB_HOST_STBY_LVC3_SDA_R2 @BASEBOARD_FAB2_LIB.BASEBOARD_FAB2(SCH_1):SMB_HOST_STBY_LVC3_SDA_R2   I105 @BASEBOARD_FAB2_LIB.BASEBOARD_FAB2(SCH_1):PAGE102

R4W4 RES_0402-3.3K,5%,1/16W,CHIP,G2A
     1 P3V3_DB1200 @BASEBOARD_FAB2_LIB.BASEBOARD_FAB2(SCH_1):P3V3_DB1200   I106 @BASEBOARD_FAB2_LIB.BASEBOARD_FAB2(SCH_1):PAGE102
     2 SMB_HOST_STBY_LVC3_SCL_R2 @BASEBOARD_FAB2_LIB.BASEBOARD_FAB2(SCH_1):SMB_HOST_STBY_LVC3_SCL_R2   I106 @BASEBOARD_FAB2_LIB.BASEBOARD_FAB2(SCH_1):PAGE102

R4W5 RES_0402-0.0,5%,1/16W,EMPTY,G2A
     1 FM_DB1200_PWRGD @BASEBOARD_FAB2_LIB.BASEBOARD_FAB2(SCH_1):FM_DB1200_PWRGD   I114 @BASEBOARD_FAB2_LIB.BASEBOARD_FAB2(SCH_1):PAGE102
     2 FM_DB1200_PWRGD_R @BASEBOARD_FAB2_LIB.BASEBOARD_FAB2(SCH_1):FM_DB1200_PWRGD_R   I114 @BASEBOARD_FAB2_LIB.BASEBOARD_FAB2(SCH_1):PAGE102

R4W6 RES_0402-4.75K,1%,1/16W,CHIP,GA
     1 P3V3_DB1200 @BASEBOARD_FAB2_LIB.BASEBOARD_FAB2(SCH_1):P3V3_DB1200   I109 @BASEBOARD_FAB2_LIB.BASEBOARD_FAB2(SCH_1):PAGE102
     2 FM_DB1200_PWRGD_R @BASEBOARD_FAB2_LIB.BASEBOARD_FAB2(SCH_1):FM_DB1200_PWRGD_R   I109 @BASEBOARD_FAB2_LIB.BASEBOARD_FAB2(SCH_1):PAGE102

R5D1 RES_0402-90.9,1%,1/16W,CHIP,G2A
     1 A_CPU0_DEF_RCOMP0 @BASEBOARD_FAB2_LIB.BASEBOARD_FAB2(SCH_1):A_CPU0_DEF_RCOMP0   I177 @BASEBOARD_FAB2_LIB.BASEBOARD_FAB2(SCH_1):PAGE21
     2    GND @BASEBOARD_FAB2_LIB.BASEBOARD_FAB2(SCH_1):GND   I177 @BASEBOARD_FAB2_LIB.BASEBOARD_FAB2(SCH_1):PAGE21

R5D2 RES_0402-90.9,1%,1/16W,CHIP,G2A
     1 A_CPU0_DEF_RCOMP1 @BASEBOARD_FAB2_LIB.BASEBOARD_FAB2(SCH_1):A_CPU0_DEF_RCOMP1   I178 @BASEBOARD_FAB2_LIB.BASEBOARD_FAB2(SCH_1):PAGE21
     2    GND @BASEBOARD_FAB2_LIB.BASEBOARD_FAB2(SCH_1):GND   I178 @BASEBOARD_FAB2_LIB.BASEBOARD_FAB2(SCH_1):PAGE21

R5D3 RES_0402-240,1.0%,1/16W,CHIP,GA
     1 PVCCIO_CPU0 @BASEBOARD_FAB2_LIB.BASEBOARD_FAB2(SCH_1):PVCCIO_CPU0    I29 @BASEBOARD_FAB2_LIB.BASEBOARD_FAB2(SCH_1):PAGE90
     2 PU_CPU0_FRMAGENT @BASEBOARD_FAB2_LIB.BASEBOARD_FAB2(SCH_1):PU_CPU0_FRMAGENT    I29 @BASEBOARD_FAB2_LIB.BASEBOARD_FAB2(SCH_1):PAGE90

R5D4 RES_0402-240,1.0%,1/16W,CHIP,GA
     1 PVCCIO_CPU0 @BASEBOARD_FAB2_LIB.BASEBOARD_FAB2(SCH_1):PVCCIO_CPU0    I96 @BASEBOARD_FAB2_LIB.BASEBOARD_FAB2(SCH_1):PAGE90
     2 PU_CPU0_TXT_AGENT @BASEBOARD_FAB2_LIB.BASEBOARD_FAB2(SCH_1):PU_CPU0_TXT_AGENT    I96 @BASEBOARD_FAB2_LIB.BASEBOARD_FAB2(SCH_1):PAGE90

R5D5 RES_0402-249,0.1%,1/16W,CHIP,GA
     1 VSENSE_PMAX_CPU0 @BASEBOARD_FAB2_LIB.BASEBOARD_FAB2(SCH_1):VSENSE_PMAX_CPU0   I303 @BASEBOARD_FAB2_LIB.BASEBOARD_FAB2(SCH_1):PAGE37
     2    GND @BASEBOARD_FAB2_LIB.BASEBOARD_FAB2(SCH_1):GND   I303 @BASEBOARD_FAB2_LIB.BASEBOARD_FAB2(SCH_1):PAGE37

R5D6 RES_0402-10.0,1%,1/16W,EMPTY,GA
     1 PVCCIO_CPU0 @BASEBOARD_FAB2_LIB.BASEBOARD_FAB2(SCH_1):PVCCIO_CPU0   I312 @BASEBOARD_FAB2_LIB.BASEBOARD_FAB2(SCH_1):PAGE37
     2 VSENSE_PMAX_CPU0 @BASEBOARD_FAB2_LIB.BASEBOARD_FAB2(SCH_1):VSENSE_PMAX_CPU0   I312 @BASEBOARD_FAB2_LIB.BASEBOARD_FAB2(SCH_1):PAGE37

R5N1 RES_0402-10.0K,1%,1/16W,CHIP,GA
     1 P3V3_STBY @BASEBOARD_FAB2_LIB.BASEBOARD_FAB2(SCH_1):P3V3_STBY   I238 @BASEBOARD_FAB2_LIB.BASEBOARD_FAB2(SCH_1):PAGE21
     2 FM_CPU0_PKGID0 @BASEBOARD_FAB2_LIB.BASEBOARD_FAB2(SCH_1):FM_CPU0_PKGID0   I238 @BASEBOARD_FAB2_LIB.BASEBOARD_FAB2(SCH_1):PAGE21

R5N2 RES_0402-1.8K,1%,1/16W,CHIP,G2A
     1 P3V3_STBY @BASEBOARD_FAB2_LIB.BASEBOARD_FAB2(SCH_1):P3V3_STBY   I227 @BASEBOARD_FAB2_LIB.BASEBOARD_FAB2(SCH_1):PAGE21
     2 FM_CPU0_PROC_ID1 @BASEBOARD_FAB2_LIB.BASEBOARD_FAB2(SCH_1):FM_CPU0_PROC_ID1   I227 @BASEBOARD_FAB2_LIB.BASEBOARD_FAB2(SCH_1):PAGE21

R5N3 RES_0402-10.0K,1%,1/16W,CHIP,GA
     1 P3V3_STBY @BASEBOARD_FAB2_LIB.BASEBOARD_FAB2(SCH_1):P3V3_STBY   I240 @BASEBOARD_FAB2_LIB.BASEBOARD_FAB2(SCH_1):PAGE21
     2 FM_CPU0_PKGID2 @BASEBOARD_FAB2_LIB.BASEBOARD_FAB2(SCH_1):FM_CPU0_PKGID2   I240 @BASEBOARD_FAB2_LIB.BASEBOARD_FAB2(SCH_1):PAGE21

R5N4 RES_0402-1.8K,1%,1/16W,CHIP,G2A
     1 P3V3_STBY @BASEBOARD_FAB2_LIB.BASEBOARD_FAB2(SCH_1):P3V3_STBY   I241 @BASEBOARD_FAB2_LIB.BASEBOARD_FAB2(SCH_1):PAGE21
     2 FM_CPU0_PROC_ID0 @BASEBOARD_FAB2_LIB.BASEBOARD_FAB2(SCH_1):FM_CPU0_PROC_ID0   I241 @BASEBOARD_FAB2_LIB.BASEBOARD_FAB2(SCH_1):PAGE21

R5N5 RES_0402-10.0K,1%,1/16W,CHIP,GA
     1 P3V3_STBY @BASEBOARD_FAB2_LIB.BASEBOARD_FAB2(SCH_1):P3V3_STBY   I239 @BASEBOARD_FAB2_LIB.BASEBOARD_FAB2(SCH_1):PAGE21
     2 FM_CPU0_PKGID1 @BASEBOARD_FAB2_LIB.BASEBOARD_FAB2(SCH_1):FM_CPU0_PKGID1   I239 @BASEBOARD_FAB2_LIB.BASEBOARD_FAB2(SCH_1):PAGE21

R5P1 RES_0603-100.0K,1%,1/10W,CHIP,A
     1 PVCCIN_CPU0 @BASEBOARD_FAB2_LIB.BASEBOARD_FAB2(SCH_1):PVCCIN_CPU0   I309 @BASEBOARD_FAB2_LIB.BASEBOARD_FAB2(SCH_1):PAGE37
     2 VSENSE_VCCINR2PMAX_CPU0 @BASEBOARD_FAB2_LIB.BASEBOARD_FAB2(SCH_1):VSENSE_VCCINR2PMAX_CPU0   I309 @BASEBOARD_FAB2_LIB.BASEBOARD_FAB2(SCH_1):PAGE37

R5P2 RES_0402-49.9,1%,1/16W,CHIP,G2A
     1 PD_CPU0_TEST14 @BASEBOARD_FAB2_LIB.BASEBOARD_FAB2(SCH_1):PD_CPU0_TEST14    I79 @BASEBOARD_FAB2_LIB.BASEBOARD_FAB2(SCH_1):PAGE90
     2    GND @BASEBOARD_FAB2_LIB.BASEBOARD_FAB2(SCH_1):GND    I79 @BASEBOARD_FAB2_LIB.BASEBOARD_FAB2(SCH_1):PAGE90

R5P3 RES_0402-49.9,1%,1/16W,CHIP,G2A
     1 PD_CPU0_TEST13 @BASEBOARD_FAB2_LIB.BASEBOARD_FAB2(SCH_1):PD_CPU0_TEST13    I80 @BASEBOARD_FAB2_LIB.BASEBOARD_FAB2(SCH_1):PAGE90
     2    GND @BASEBOARD_FAB2_LIB.BASEBOARD_FAB2(SCH_1):GND    I80 @BASEBOARD_FAB2_LIB.BASEBOARD_FAB2(SCH_1):PAGE90

R5P4 RES_0402-49.9,1%,1/16W,CHIP,G2A
     1 PD_CPU0_RSVD_TEST_2 @BASEBOARD_FAB2_LIB.BASEBOARD_FAB2(SCH_1):PD_CPU0_RSVD_TEST_2   I190 @BASEBOARD_FAB2_LIB.BASEBOARD_FAB2(SCH_1):PAGE22
     2    GND @BASEBOARD_FAB2_LIB.BASEBOARD_FAB2(SCH_1):GND   I190 @BASEBOARD_FAB2_LIB.BASEBOARD_FAB2(SCH_1):PAGE22

R5R1 RES_0402-49.9,1%,1/16W,CHIP,G2A
     1 PD_CPU0_RSVD_TEST_1 @BASEBOARD_FAB2_LIB.BASEBOARD_FAB2(SCH_1):PD_CPU0_RSVD_TEST_1   I188 @BASEBOARD_FAB2_LIB.BASEBOARD_FAB2(SCH_1):PAGE22
     2    GND @BASEBOARD_FAB2_LIB.BASEBOARD_FAB2(SCH_1):GND   I188 @BASEBOARD_FAB2_LIB.BASEBOARD_FAB2(SCH_1):PAGE22

R5W1 RES_0402-0.0,5%,1/16W,CHIP,G21A
     1 P1V8_MCP_CPU0 @BASEBOARD_FAB2_LIB.BASEBOARD_FAB2(SCH_1):P1V8_MCP_CPU0   I272 @BASEBOARD_FAB2_LIB.BASEBOARD_FAB2(SCH_1):PAGE113
     2 JTAG_MCP_CPU0_TDI_R @BASEBOARD_FAB2_LIB.BASEBOARD_FAB2(SCH_1):JTAG_MCP_CPU0_TDI_R   I272 @BASEBOARD_FAB2_LIB.BASEBOARD_FAB2(SCH_1):PAGE113

R5W2 RES_0402-0.0,5%,1/16W,CHIP,G21A
     1 P1V8_MCP_CPU1 @BASEBOARD_FAB2_LIB.BASEBOARD_FAB2(SCH_1):P1V8_MCP_CPU1   I273 @BASEBOARD_FAB2_LIB.BASEBOARD_FAB2(SCH_1):PAGE113
     2 JTAG_MCP_CPU1_TDI_R @BASEBOARD_FAB2_LIB.BASEBOARD_FAB2(SCH_1):JTAG_MCP_CPU1_TDI_R   I273 @BASEBOARD_FAB2_LIB.BASEBOARD_FAB2(SCH_1):PAGE113

R6B1 RES_0402-49.9,1%,1/16W,CHIP,G2A
     1 PVCCIO_CPU0 @BASEBOARD_FAB2_LIB.BASEBOARD_FAB2(SCH_1):PVCCIO_CPU0   I161 @BASEBOARD_FAB2_LIB.BASEBOARD_FAB2(SCH_1):PAGE21
     2 SVID_ALERT1_CPU0_R_N @BASEBOARD_FAB2_LIB.BASEBOARD_FAB2(SCH_1):SVID_ALERT1_CPU0_R_N   I161 @BASEBOARD_FAB2_LIB.BASEBOARD_FAB2(SCH_1):PAGE21

R6B2 RES_0402-100.0,1%,1/16W,CHIP,GA
     1 PVCCIO_CPU0 @BASEBOARD_FAB2_LIB.BASEBOARD_FAB2(SCH_1):PVCCIO_CPU0   I159 @BASEBOARD_FAB2_LIB.BASEBOARD_FAB2(SCH_1):PAGE21
     2 SVID_DIO1_CPU0_R @BASEBOARD_FAB2_LIB.BASEBOARD_FAB2(SCH_1):SVID_DIO1_CPU0_R   I159 @BASEBOARD_FAB2_LIB.BASEBOARD_FAB2(SCH_1):PAGE21

R6B3 RES_0402-221,1.0%,1/16W,CHIP,GA
     1 SVID_ALERT1_CPU0_N @BASEBOARD_FAB2_LIB.BASEBOARD_FAB2(SCH_1):SVID_ALERT1_CPU0_N   I152 @BASEBOARD_FAB2_LIB.BASEBOARD_FAB2(SCH_1):PAGE21
     2 SVID_ALERT1_CPU0_R_N @BASEBOARD_FAB2_LIB.BASEBOARD_FAB2(SCH_1):SVID_ALERT1_CPU0_R_N   I152 @BASEBOARD_FAB2_LIB.BASEBOARD_FAB2(SCH_1):PAGE21

R6B4 RES_0402-0.0,5%,1/16W,CHIP,G21A
     1 SVID_DIO1_CPU0 @BASEBOARD_FAB2_LIB.BASEBOARD_FAB2(SCH_1):SVID_DIO1_CPU0   I154 @BASEBOARD_FAB2_LIB.BASEBOARD_FAB2(SCH_1):PAGE21
     2 SVID_DIO1_CPU0_R @BASEBOARD_FAB2_LIB.BASEBOARD_FAB2(SCH_1):SVID_DIO1_CPU0_R   I154 @BASEBOARD_FAB2_LIB.BASEBOARD_FAB2(SCH_1):PAGE21

R6B5 RES_0402-0.0,5%,1/16W,CHIP,G21A
     1 SVID_CLK1_CPU0 @BASEBOARD_FAB2_LIB.BASEBOARD_FAB2(SCH_1):SVID_CLK1_CPU0   I153 @BASEBOARD_FAB2_LIB.BASEBOARD_FAB2(SCH_1):PAGE21
     2 SVID_CLK1_CPU0_R @BASEBOARD_FAB2_LIB.BASEBOARD_FAB2(SCH_1):SVID_CLK1_CPU0_R   I153 @BASEBOARD_FAB2_LIB.BASEBOARD_FAB2(SCH_1):PAGE21

R6D1 RES_0402-100.0,1%,1/16W,CHIP,GA
     1 A_CPU0_DEF_RCOMP2 @BASEBOARD_FAB2_LIB.BASEBOARD_FAB2(SCH_1):A_CPU0_DEF_RCOMP2   I179 @BASEBOARD_FAB2_LIB.BASEBOARD_FAB2(SCH_1):PAGE21
     2    GND @BASEBOARD_FAB2_LIB.BASEBOARD_FAB2(SCH_1):GND   I179 @BASEBOARD_FAB2_LIB.BASEBOARD_FAB2(SCH_1):PAGE21

R6D2 RES_0402-49.9,1%,1/16W,CHIP,G2A
     1 A_CPU0_MCP01_RBIAS @BASEBOARD_FAB2_LIB.BASEBOARD_FAB2(SCH_1):A_CPU0_MCP01_RBIAS   I204 @BASEBOARD_FAB2_LIB.BASEBOARD_FAB2(SCH_1):PAGE21
     2    GND @BASEBOARD_FAB2_LIB.BASEBOARD_FAB2(SCH_1):GND   I204 @BASEBOARD_FAB2_LIB.BASEBOARD_FAB2(SCH_1):PAGE21

R6D5 RES_0402-49.9,1%,1/16W,CHIP,G2A
     1 PD_CPU0_TEST12 @BASEBOARD_FAB2_LIB.BASEBOARD_FAB2(SCH_1):PD_CPU0_TEST12    I81 @BASEBOARD_FAB2_LIB.BASEBOARD_FAB2(SCH_1):PAGE90
     2    GND @BASEBOARD_FAB2_LIB.BASEBOARD_FAB2(SCH_1):GND    I81 @BASEBOARD_FAB2_LIB.BASEBOARD_FAB2(SCH_1):PAGE90

R6D6 RES_0402-240,1.0%,1/16W,EMPTY,A
     1    GND @BASEBOARD_FAB2_LIB.BASEBOARD_FAB2(SCH_1):GND   I101 @BASEBOARD_FAB2_LIB.BASEBOARD_FAB2(SCH_1):PAGE90
     2 PD_CPU0_TXT_PLTEN @BASEBOARD_FAB2_LIB.BASEBOARD_FAB2(SCH_1):PD_CPU0_TXT_PLTEN   I101 @BASEBOARD_FAB2_LIB.BASEBOARD_FAB2(SCH_1):PAGE90

R6D7 RES_0402-240,1.0%,1/16W,EMPTY,A
     1 PVCCIO_CPU0 @BASEBOARD_FAB2_LIB.BASEBOARD_FAB2(SCH_1):PVCCIO_CPU0    I31 @BASEBOARD_FAB2_LIB.BASEBOARD_FAB2(SCH_1):PAGE90
     2 H_CPU0_BMCINIT @BASEBOARD_FAB2_LIB.BASEBOARD_FAB2(SCH_1):H_CPU0_BMCINIT    I31 @BASEBOARD_FAB2_LIB.BASEBOARD_FAB2(SCH_1):PAGE90

R6D8 RES_0402-49.9,1%,1/16W,CHIP,G2A
     1 PVCCIO_CPU0 @BASEBOARD_FAB2_LIB.BASEBOARD_FAB2(SCH_1):PVCCIO_CPU0     I3 @BASEBOARD_FAB2_LIB.BASEBOARD_FAB2(SCH_1):PAGE96
     2 PWRGD_CPU0_G @BASEBOARD_FAB2_LIB.BASEBOARD_FAB2(SCH_1):PWRGD_CPU0_G     I3 @BASEBOARD_FAB2_LIB.BASEBOARD_FAB2(SCH_1):PAGE96

R6D9 RES_0402-150.0,1%,1/16W,CHIP,GA
     1 PVCCIO_CPU0 @BASEBOARD_FAB2_LIB.BASEBOARD_FAB2(SCH_1):PVCCIO_CPU0    I64 @BASEBOARD_FAB2_LIB.BASEBOARD_FAB2(SCH_1):PAGE92
     2 H_CPU0_MSMI_G_N @BASEBOARD_FAB2_LIB.BASEBOARD_FAB2(SCH_1):H_CPU0_MSMI_G_N    I64 @BASEBOARD_FAB2_LIB.BASEBOARD_FAB2(SCH_1):PAGE92

R6D10 RES_0402-240,1.0%,1/16W,EMPTY,A
     1 PVCCIO_CPU0 @BASEBOARD_FAB2_LIB.BASEBOARD_FAB2(SCH_1):PVCCIO_CPU0    I49 @BASEBOARD_FAB2_LIB.BASEBOARD_FAB2(SCH_1):PAGE90
     2 PU_CPU0_SOCKET_ID_1 @BASEBOARD_FAB2_LIB.BASEBOARD_FAB2(SCH_1):PU_CPU0_SOCKET_ID_1    I49 @BASEBOARD_FAB2_LIB.BASEBOARD_FAB2(SCH_1):PAGE90

R6D11 RES_0402-49.9,1%,1/16W,CHIP,G2A
     1 A_CPU0_UPI01_RBIAS @BASEBOARD_FAB2_LIB.BASEBOARD_FAB2(SCH_1):A_CPU0_UPI01_RBIAS   I184 @BASEBOARD_FAB2_LIB.BASEBOARD_FAB2(SCH_1):PAGE21
     2    GND @BASEBOARD_FAB2_LIB.BASEBOARD_FAB2(SCH_1):GND   I184 @BASEBOARD_FAB2_LIB.BASEBOARD_FAB2(SCH_1):PAGE21

R6D12 RES_0402-49.9,1%,1/16W,CHIP,G2A
     1 PVCCIO_CPU0 @BASEBOARD_FAB2_LIB.BASEBOARD_FAB2(SCH_1):PVCCIO_CPU0     I2 @BASEBOARD_FAB2_LIB.BASEBOARD_FAB2(SCH_1):PAGE96
     2 RST_CPU0_G_N @BASEBOARD_FAB2_LIB.BASEBOARD_FAB2(SCH_1):RST_CPU0_G_N     I2 @BASEBOARD_FAB2_LIB.BASEBOARD_FAB2(SCH_1):PAGE96

R6D13 RES_0402-240,1.0%,1/16W,EMPTY,A
     1 PVCCIO_CPU0 @BASEBOARD_FAB2_LIB.BASEBOARD_FAB2(SCH_1):PVCCIO_CPU0    I33 @BASEBOARD_FAB2_LIB.BASEBOARD_FAB2(SCH_1):PAGE90
     2 PU_CPU0_SAFE_MODE_BOOT @BASEBOARD_FAB2_LIB.BASEBOARD_FAB2(SCH_1):PU_CPU0_SAFE_MODE_BOOT    I33 @BASEBOARD_FAB2_LIB.BASEBOARD_FAB2(SCH_1):PAGE90

R6D14 RES_0402-240,1.0%,1/16W,EMPTY,A
     1    GND @BASEBOARD_FAB2_LIB.BASEBOARD_FAB2(SCH_1):GND    I52 @BASEBOARD_FAB2_LIB.BASEBOARD_FAB2(SCH_1):PAGE90
     2 PD_CPU0_EAR_N @BASEBOARD_FAB2_LIB.BASEBOARD_FAB2(SCH_1):PD_CPU0_EAR_N    I52 @BASEBOARD_FAB2_LIB.BASEBOARD_FAB2(SCH_1):PAGE90

R6D15 RES_0402-240,1.0%,1/16W,EMPTY,A
     1 PVCCIO_CPU0 @BASEBOARD_FAB2_LIB.BASEBOARD_FAB2(SCH_1):PVCCIO_CPU0    I48 @BASEBOARD_FAB2_LIB.BASEBOARD_FAB2(SCH_1):PAGE90
     2 PU_CPU0_SOCKET_ID_0 @BASEBOARD_FAB2_LIB.BASEBOARD_FAB2(SCH_1):PU_CPU0_SOCKET_ID_0    I48 @BASEBOARD_FAB2_LIB.BASEBOARD_FAB2(SCH_1):PAGE90

R6D16 RES_0402-0.0,5%,1/16W,EMPTY,G2A
     1 FM_CPU_BMC_INIT @BASEBOARD_FAB2_LIB.BASEBOARD_FAB2(SCH_1):FM_CPU_BMC_INIT   I299 @BASEBOARD_FAB2_LIB.BASEBOARD_FAB2(SCH_1):PAGE156
     2 H_CPU0_BMCINIT @BASEBOARD_FAB2_LIB.BASEBOARD_FAB2(SCH_1):H_CPU0_BMCINIT   I299 @BASEBOARD_FAB2_LIB.BASEBOARD_FAB2(SCH_1):PAGE156

R6F1 RES_0402-49.9,1%,1/16W,CHIP,G2A
     1 IRQ_DIMM_SAVE_N @BASEBOARD_FAB2_LIB.BASEBOARD_FAB2(SCH_1):IRQ_DIMM_SAVE_N     I4 @BASEBOARD_FAB2_LIB.BASEBOARD_FAB2(SCH_1):PAGE89
     2 FM_ADR_COMPLETE_DEF_N @BASEBOARD_FAB2_LIB.BASEBOARD_FAB2(SCH_1):FM_ADR_COMPLETE_DEF_N     I4 @BASEBOARD_FAB2_LIB.BASEBOARD_FAB2(SCH_1):PAGE89

R6F2 RES_0402-49.9,1%,1/16W,CHIP,G2A
     1 FM_ADR_COMPLETE_CPU1_N @BASEBOARD_FAB2_LIB.BASEBOARD_FAB2(SCH_1):FM_ADR_COMPLETE_CPU1_N     I6 @BASEBOARD_FAB2_LIB.BASEBOARD_FAB2(SCH_1):PAGE89
     2 FM_ADR_COMPLETE_KLM_N @BASEBOARD_FAB2_LIB.BASEBOARD_FAB2(SCH_1):FM_ADR_COMPLETE_KLM_N     I6 @BASEBOARD_FAB2_LIB.BASEBOARD_FAB2(SCH_1):PAGE89

R6F3 RES_0402-10.0K,1%,1/16W,CHIP,GA
     1 PVPP_ABC @BASEBOARD_FAB2_LIB.BASEBOARD_FAB2(SCH_1):PVPP_ABC     I7 @BASEBOARD_FAB2_LIB.BASEBOARD_FAB2(SCH_1):PAGE89
     2 IRQ_DIMM_SAVE_N @BASEBOARD_FAB2_LIB.BASEBOARD_FAB2(SCH_1):IRQ_DIMM_SAVE_N     I7 @BASEBOARD_FAB2_LIB.BASEBOARD_FAB2(SCH_1):PAGE89

R6F4 RES_0402-49.9,1%,1/16W,CHIP,G2A
     1 IRQ_DIMM_SAVE_N @BASEBOARD_FAB2_LIB.BASEBOARD_FAB2(SCH_1):IRQ_DIMM_SAVE_N     I3 @BASEBOARD_FAB2_LIB.BASEBOARD_FAB2(SCH_1):PAGE89
     2 FM_ADR_COMPLETE_ABC_N @BASEBOARD_FAB2_LIB.BASEBOARD_FAB2(SCH_1):FM_ADR_COMPLETE_ABC_N     I3 @BASEBOARD_FAB2_LIB.BASEBOARD_FAB2(SCH_1):PAGE89

R6F5 RES_0402-49.9,1%,1/16W,CHIP,G2A
     1 FM_ADR_COMPLETE_CPU1_N @BASEBOARD_FAB2_LIB.BASEBOARD_FAB2(SCH_1):FM_ADR_COMPLETE_CPU1_N     I5 @BASEBOARD_FAB2_LIB.BASEBOARD_FAB2(SCH_1):PAGE89
     2 FM_ADR_COMPLETE_GHJ_N @BASEBOARD_FAB2_LIB.BASEBOARD_FAB2(SCH_1):FM_ADR_COMPLETE_GHJ_N     I5 @BASEBOARD_FAB2_LIB.BASEBOARD_FAB2(SCH_1):PAGE89

R6F6 RES_0402-0.0,5%,1/16W,EMPTY,G2A
     1 CLK_322M_156M_CPU0_OSC_VRM_DN @BASEBOARD_FAB2_LIB.BASEBOARD_FAB2(SCH_1):CLK_322M_156M_CPU0_OSC_VRM_DN    I41 @BASEBOARD_FAB2_LIB.BASEBOARD_FAB2(SCH_1):PAGE104
     2 CLK_156M_OSC_CPU0_HFI_DN @BASEBOARD_FAB2_LIB.BASEBOARD_FAB2(SCH_1):CLK_156M_OSC_CPU0_HFI_DN    I41 @BASEBOARD_FAB2_LIB.BASEBOARD_FAB2(SCH_1):PAGE104

R6F7 RES_0402-0.0,5%,1/16W,CHIP,G21A
     1 CLK_156M_OSC_BRD_CPU0_DN @BASEBOARD_FAB2_LIB.BASEBOARD_FAB2(SCH_1):CLK_156M_OSC_BRD_CPU0_DN    I67 @BASEBOARD_FAB2_LIB.BASEBOARD_FAB2(SCH_1):PAGE104
     2 CLK_156M_OSC_CPU0_HFI_DN @BASEBOARD_FAB2_LIB.BASEBOARD_FAB2(SCH_1):CLK_156M_OSC_CPU0_HFI_DN    I67 @BASEBOARD_FAB2_LIB.BASEBOARD_FAB2(SCH_1):PAGE104

R6F8 RES_0402-0.0,5%,1/16W,EMPTY,G2A
     1 CLK_322M_156M_CPU0_OSC_VRM_DP @BASEBOARD_FAB2_LIB.BASEBOARD_FAB2(SCH_1):CLK_322M_156M_CPU0_OSC_VRM_DP    I37 @BASEBOARD_FAB2_LIB.BASEBOARD_FAB2(SCH_1):PAGE104
     2 CLK_156M_OSC_CPU0_HFI_DP @BASEBOARD_FAB2_LIB.BASEBOARD_FAB2(SCH_1):CLK_156M_OSC_CPU0_HFI_DP    I37 @BASEBOARD_FAB2_LIB.BASEBOARD_FAB2(SCH_1):PAGE104

R6F9 RES_0402-0.0,5%,1/16W,CHIP,G21A
     1 CLK_156M_OSC_BRD_CPU0_DP @BASEBOARD_FAB2_LIB.BASEBOARD_FAB2(SCH_1):CLK_156M_OSC_BRD_CPU0_DP    I68 @BASEBOARD_FAB2_LIB.BASEBOARD_FAB2(SCH_1):PAGE104
     2 CLK_156M_OSC_CPU0_HFI_DP @BASEBOARD_FAB2_LIB.BASEBOARD_FAB2(SCH_1):CLK_156M_OSC_CPU0_HFI_DP    I68 @BASEBOARD_FAB2_LIB.BASEBOARD_FAB2(SCH_1):PAGE104

R6F10 RES_0402-0.0,5%,1/16W,EMPTY,G2A
     1 CLK_322M_156M_CPU0_OSC_VRM_DN @BASEBOARD_FAB2_LIB.BASEBOARD_FAB2(SCH_1):CLK_322M_156M_CPU0_OSC_VRM_DN    I78 @BASEBOARD_FAB2_LIB.BASEBOARD_FAB2(SCH_1):PAGE104
     2 CLK_322M_OSC_CPU0_RC_DN @BASEBOARD_FAB2_LIB.BASEBOARD_FAB2(SCH_1):CLK_322M_OSC_CPU0_RC_DN    I78 @BASEBOARD_FAB2_LIB.BASEBOARD_FAB2(SCH_1):PAGE104

R6F11 RES_0402-0.0,5%,1/16W,EMPTY,G2A
     1 CLK_322M_156M_CPU0_OSC_VRM_DP @BASEBOARD_FAB2_LIB.BASEBOARD_FAB2(SCH_1):CLK_322M_156M_CPU0_OSC_VRM_DP    I79 @BASEBOARD_FAB2_LIB.BASEBOARD_FAB2(SCH_1):PAGE104
     2 CLK_322M_OSC_CPU0_RC_DP @BASEBOARD_FAB2_LIB.BASEBOARD_FAB2(SCH_1):CLK_322M_OSC_CPU0_RC_DP    I79 @BASEBOARD_FAB2_LIB.BASEBOARD_FAB2(SCH_1):PAGE104

R6L1 RES_0402-1.00K,1%,1/16W,CHIP,GA
     1 M_F_VREF @BASEBOARD_FAB2_LIB.BASEBOARD_FAB2(SCH_1):M_F_VREF    I64 @BASEBOARD_FAB2_LIB.BASEBOARD_FAB2(SCH_1):PAGE98
     2    GND @BASEBOARD_FAB2_LIB.BASEBOARD_FAB2(SCH_1):GND    I64 @BASEBOARD_FAB2_LIB.BASEBOARD_FAB2(SCH_1):PAGE98

R6L2 RES_0402-1.00K,1%,1/16W,CHIP,GA
     1 PVDDQ_DEF @BASEBOARD_FAB2_LIB.BASEBOARD_FAB2(SCH_1):PVDDQ_DEF    I62 @BASEBOARD_FAB2_LIB.BASEBOARD_FAB2(SCH_1):PAGE98
     2 M_F_VREF @BASEBOARD_FAB2_LIB.BASEBOARD_FAB2(SCH_1):M_F_VREF    I62 @BASEBOARD_FAB2_LIB.BASEBOARD_FAB2(SCH_1):PAGE98

R6L3 RES_0402-2,1.0%,1/16W,CHIP,G21A
     1 M_F_CPU_VREF @BASEBOARD_FAB2_LIB.BASEBOARD_FAB2(SCH_1):M_F_CPU_VREF    I66 @BASEBOARD_FAB2_LIB.BASEBOARD_FAB2(SCH_1):PAGE98
     2 M_F_VREF @BASEBOARD_FAB2_LIB.BASEBOARD_FAB2(SCH_1):M_F_VREF    I66 @BASEBOARD_FAB2_LIB.BASEBOARD_FAB2(SCH_1):PAGE98

R6L4 RES_0402-1.0M,1%,1/16W,EMPTY,GA
     1   P3V3 @BASEBOARD_FAB2_LIB.BASEBOARD_FAB2(SCH_1):P3V3     I5 @BASEBOARD_FAB2_LIB.BASEBOARD_FAB2(SCH_1):PAGE222
     2 FM_PVTT_DEF_EN_R @BASEBOARD_FAB2_LIB.BASEBOARD_FAB2(SCH_1):FM_PVTT_DEF_EN_R     I5 @BASEBOARD_FAB2_LIB.BASEBOARD_FAB2(SCH_1):PAGE222

R6L5 RES_0402-1.0M,1%,1/16W,EMPTY,GA
     1   P3V3 @BASEBOARD_FAB2_LIB.BASEBOARD_FAB2(SCH_1):P3V3     I5 @BASEBOARD_FAB2_LIB.BASEBOARD_FAB2(SCH_1):PAGE230
     2 FM_PVTT_KLM_EN_R @BASEBOARD_FAB2_LIB.BASEBOARD_FAB2(SCH_1):FM_PVTT_KLM_EN_R     I5 @BASEBOARD_FAB2_LIB.BASEBOARD_FAB2(SCH_1):PAGE230

R6L6 RES_0402-0.0,5%,1/16W,CHIP,G21A
     1 PVDDQ_KLM @BASEBOARD_FAB2_LIB.BASEBOARD_FAB2(SCH_1):PVDDQ_KLM     I6 @BASEBOARD_FAB2_LIB.BASEBOARD_FAB2(SCH_1):PAGE230
     2 VSENSE_PVDDQ_KLM_VTT @BASEBOARD_FAB2_LIB.BASEBOARD_FAB2(SCH_1):VSENSE_PVDDQ_KLM_VTT     I6 @BASEBOARD_FAB2_LIB.BASEBOARD_FAB2(SCH_1):PAGE230

R6L8 RES_0402-0.0,5%,1/16W,CHIP,G21A
     1   P3V3 @BASEBOARD_FAB2_LIB.BASEBOARD_FAB2(SCH_1):P3V3    I13 @BASEBOARD_FAB2_LIB.BASEBOARD_FAB2(SCH_1):PAGE230
     2 VR_PVTT_KLM_BIAS @BASEBOARD_FAB2_LIB.BASEBOARD_FAB2(SCH_1):VR_PVTT_KLM_BIAS    I13 @BASEBOARD_FAB2_LIB.BASEBOARD_FAB2(SCH_1):PAGE230

R6L9 RES_0402-10.0K,1%,1/16W,CHIP,GA
     1   P3V3 @BASEBOARD_FAB2_LIB.BASEBOARD_FAB2(SCH_1):P3V3    I23 @BASEBOARD_FAB2_LIB.BASEBOARD_FAB2(SCH_1):PAGE222
     2 PWRGD_PVTT_DEF_CPU0_R @BASEBOARD_FAB2_LIB.BASEBOARD_FAB2(SCH_1):PWRGD_PVTT_DEF_CPU0_R    I23 @BASEBOARD_FAB2_LIB.BASEBOARD_FAB2(SCH_1):PAGE222

R6L10 RES_0402-0.0,5%,1/16W,CHIP,G21A
     1 PVDDQ_DEF @BASEBOARD_FAB2_LIB.BASEBOARD_FAB2(SCH_1):PVDDQ_DEF     I6 @BASEBOARD_FAB2_LIB.BASEBOARD_FAB2(SCH_1):PAGE222
     2 VSENSE_PVDDQ_DEF_VTT @BASEBOARD_FAB2_LIB.BASEBOARD_FAB2(SCH_1):VSENSE_PVDDQ_DEF_VTT     I6 @BASEBOARD_FAB2_LIB.BASEBOARD_FAB2(SCH_1):PAGE222

R6L11 RES_0402-0.0,5%,1/16W,CHIP,G21A
     1   P3V3 @BASEBOARD_FAB2_LIB.BASEBOARD_FAB2(SCH_1):P3V3    I10 @BASEBOARD_FAB2_LIB.BASEBOARD_FAB2(SCH_1):PAGE222
     2 VR_PVTT_DEF_BIAS @BASEBOARD_FAB2_LIB.BASEBOARD_FAB2(SCH_1):VR_PVTT_DEF_BIAS    I10 @BASEBOARD_FAB2_LIB.BASEBOARD_FAB2(SCH_1):PAGE222

R6L12 RES_0402-1.00K,1%,1/16W,CHIP,GA
     1 M_E_VREF @BASEBOARD_FAB2_LIB.BASEBOARD_FAB2(SCH_1):M_E_VREF    I56 @BASEBOARD_FAB2_LIB.BASEBOARD_FAB2(SCH_1):PAGE98
     2    GND @BASEBOARD_FAB2_LIB.BASEBOARD_FAB2(SCH_1):GND    I56 @BASEBOARD_FAB2_LIB.BASEBOARD_FAB2(SCH_1):PAGE98

R6L13 RES_0402-1.00K,1%,1/16W,CHIP,GA
     1 PVDDQ_DEF @BASEBOARD_FAB2_LIB.BASEBOARD_FAB2(SCH_1):PVDDQ_DEF    I54 @BASEBOARD_FAB2_LIB.BASEBOARD_FAB2(SCH_1):PAGE98
     2 M_E_VREF @BASEBOARD_FAB2_LIB.BASEBOARD_FAB2(SCH_1):M_E_VREF    I54 @BASEBOARD_FAB2_LIB.BASEBOARD_FAB2(SCH_1):PAGE98

R6L14 RES_0402-2,1.0%,1/16W,CHIP,G21A
     1 M_E_CPU_VREF @BASEBOARD_FAB2_LIB.BASEBOARD_FAB2(SCH_1):M_E_CPU_VREF    I58 @BASEBOARD_FAB2_LIB.BASEBOARD_FAB2(SCH_1):PAGE98
     2 M_E_VREF @BASEBOARD_FAB2_LIB.BASEBOARD_FAB2(SCH_1):M_E_VREF    I58 @BASEBOARD_FAB2_LIB.BASEBOARD_FAB2(SCH_1):PAGE98

R6L16 RES_0402-1.00K,1%,1/16W,CHIP,GA
     1 M_D_VREF @BASEBOARD_FAB2_LIB.BASEBOARD_FAB2(SCH_1):M_D_VREF    I12 @BASEBOARD_FAB2_LIB.BASEBOARD_FAB2(SCH_1):PAGE98
     2    GND @BASEBOARD_FAB2_LIB.BASEBOARD_FAB2(SCH_1):GND    I12 @BASEBOARD_FAB2_LIB.BASEBOARD_FAB2(SCH_1):PAGE98

R6M1 RES_0402-1.00K,1%,1/16W,CHIP,GA
     1 PVDDQ_DEF @BASEBOARD_FAB2_LIB.BASEBOARD_FAB2(SCH_1):PVDDQ_DEF     I9 @BASEBOARD_FAB2_LIB.BASEBOARD_FAB2(SCH_1):PAGE98
     2 M_D_VREF @BASEBOARD_FAB2_LIB.BASEBOARD_FAB2(SCH_1):M_D_VREF     I9 @BASEBOARD_FAB2_LIB.BASEBOARD_FAB2(SCH_1):PAGE98

R6M2 RES_0402-2,1.0%,1/16W,CHIP,G21A
     1 M_D_CPU_VREF @BASEBOARD_FAB2_LIB.BASEBOARD_FAB2(SCH_1):M_D_CPU_VREF    I14 @BASEBOARD_FAB2_LIB.BASEBOARD_FAB2(SCH_1):PAGE98
     2 M_D_VREF @BASEBOARD_FAB2_LIB.BASEBOARD_FAB2(SCH_1):M_D_VREF    I14 @BASEBOARD_FAB2_LIB.BASEBOARD_FAB2(SCH_1):PAGE98

R6M4 RES_0402-4.75K,1%,1/16W,CHIP,GA
     1   P3V3 @BASEBOARD_FAB2_LIB.BASEBOARD_FAB2(SCH_1):P3V3    I82 @BASEBOARD_FAB2_LIB.BASEBOARD_FAB2(SCH_1):PAGE94
     2 H_CPU1_MEMKLM_MEMHOT @BASEBOARD_FAB2_LIB.BASEBOARD_FAB2(SCH_1):H_CPU1_MEMKLM_MEMHOT    I82 @BASEBOARD_FAB2_LIB.BASEBOARD_FAB2(SCH_1):PAGE94

R6M8 RES_0402-1.00K,1%,1/16W,CHIP,GA
     1 JTAG_MCP_CPU1_TDI_R @BASEBOARD_FAB2_LIB.BASEBOARD_FAB2(SCH_1):JTAG_MCP_CPU1_TDI_R   I271 @BASEBOARD_FAB2_LIB.BASEBOARD_FAB2(SCH_1):PAGE113
     2 JTAG_MCP_CPU1_TDI @BASEBOARD_FAB2_LIB.BASEBOARD_FAB2(SCH_1):JTAG_MCP_CPU1_TDI   I271 @BASEBOARD_FAB2_LIB.BASEBOARD_FAB2(SCH_1):PAGE113

R6M9 RES_0402-4.75K,1%,1/16W,CHIP,GA
     1 PVPP_KLM @BASEBOARD_FAB2_LIB.BASEBOARD_FAB2(SCH_1):PVPP_KLM    I49 @BASEBOARD_FAB2_LIB.BASEBOARD_FAB2(SCH_1):PAGE192
     2 RST_CD_CPU1_POR_N @BASEBOARD_FAB2_LIB.BASEBOARD_FAB2(SCH_1):RST_CD_CPU1_POR_N    I49 @BASEBOARD_FAB2_LIB.BASEBOARD_FAB2(SCH_1):PAGE192

R6N1 RES_0402-49.9,1%,1/16W,CHIP,G2A
     1 SVID_ALERT0_CPU0_R_N @BASEBOARD_FAB2_LIB.BASEBOARD_FAB2(SCH_1):SVID_ALERT0_CPU0_R_N   I164 @BASEBOARD_FAB2_LIB.BASEBOARD_FAB2(SCH_1):PAGE21
     2 PVCCIO_CPU0 @BASEBOARD_FAB2_LIB.BASEBOARD_FAB2(SCH_1):PVCCIO_CPU0   I164 @BASEBOARD_FAB2_LIB.BASEBOARD_FAB2(SCH_1):PAGE21

R6N2 RES_0402-100.0,1%,1/16W,CHIP,GA
     1 SVID_DIO0_CPU0_R @BASEBOARD_FAB2_LIB.BASEBOARD_FAB2(SCH_1):SVID_DIO0_CPU0_R   I163 @BASEBOARD_FAB2_LIB.BASEBOARD_FAB2(SCH_1):PAGE21
     2 PVCCIO_CPU0 @BASEBOARD_FAB2_LIB.BASEBOARD_FAB2(SCH_1):PVCCIO_CPU0   I163 @BASEBOARD_FAB2_LIB.BASEBOARD_FAB2(SCH_1):PAGE21

R6N3 RES_0402-0.0,5%,1/16W,CHIP,G21A
     1 VR_PVSA_CPU0_VCIN @BASEBOARD_FAB2_LIB.BASEBOARD_FAB2(SCH_1):VR_PVSA_CPU0_VCIN    I81 @BASEBOARD_FAB2_LIB.BASEBOARD_FAB2(SCH_1):PAGE205
     2 P5V_STBY @BASEBOARD_FAB2_LIB.BASEBOARD_FAB2(SCH_1):P5V_STBY    I81 @BASEBOARD_FAB2_LIB.BASEBOARD_FAB2(SCH_1):PAGE205

R6N4 RES_0402-51.1,1.0%,1/16W,CHIP,A
     1 PVSA_CPU0 @BASEBOARD_FAB2_LIB.BASEBOARD_FAB2(SCH_1):PVSA_CPU0    I45 @BASEBOARD_FAB2_LIB.BASEBOARD_FAB2(SCH_1):PAGE205
     2    GND @BASEBOARD_FAB2_LIB.BASEBOARD_FAB2(SCH_1):GND    I45 @BASEBOARD_FAB2_LIB.BASEBOARD_FAB2(SCH_1):PAGE205

R6N8 RES_0402-10.0,1%,1/16W,CHIP,G2A
     1 SMB_CPU1_PE_HP_GTL_SCL @BASEBOARD_FAB2_LIB.BASEBOARD_FAB2(SCH_1):SMB_CPU1_PE_HP_GTL_SCL     I2 @BASEBOARD_FAB2_LIB.BASEBOARD_FAB2(SCH_1):PAGE163
     2 SMB_CPU1_PE_HP_GTL_R_SCL @BASEBOARD_FAB2_LIB.BASEBOARD_FAB2(SCH_1):SMB_CPU1_PE_HP_GTL_R_SCL     I2 @BASEBOARD_FAB2_LIB.BASEBOARD_FAB2(SCH_1):PAGE163

R6N9 RES_0402-10.0,1%,1/16W,CHIP,G2A
     1 SMB_CPU1_PE_HP_GTL_SDA @BASEBOARD_FAB2_LIB.BASEBOARD_FAB2(SCH_1):SMB_CPU1_PE_HP_GTL_SDA     I3 @BASEBOARD_FAB2_LIB.BASEBOARD_FAB2(SCH_1):PAGE163
     2 SMB_CPU1_PE_HP_GTL_R_SDA @BASEBOARD_FAB2_LIB.BASEBOARD_FAB2(SCH_1):SMB_CPU1_PE_HP_GTL_R_SDA     I3 @BASEBOARD_FAB2_LIB.BASEBOARD_FAB2(SCH_1):PAGE163

R6N10 RES_0402-221,1.0%,1/16W,CHIP,GA
     1 SVID_ALERT0_CPU0_N @BASEBOARD_FAB2_LIB.BASEBOARD_FAB2(SCH_1):SVID_ALERT0_CPU0_N   I149 @BASEBOARD_FAB2_LIB.BASEBOARD_FAB2(SCH_1):PAGE21
     2 SVID_ALERT0_CPU0_R_N @BASEBOARD_FAB2_LIB.BASEBOARD_FAB2(SCH_1):SVID_ALERT0_CPU0_R_N   I149 @BASEBOARD_FAB2_LIB.BASEBOARD_FAB2(SCH_1):PAGE21

R6N11 RES_0402-0.0,5%,1/16W,CHIP,G21A
     1 SVID_DIO0_CPU0 @BASEBOARD_FAB2_LIB.BASEBOARD_FAB2(SCH_1):SVID_DIO0_CPU0   I151 @BASEBOARD_FAB2_LIB.BASEBOARD_FAB2(SCH_1):PAGE21
     2 SVID_DIO0_CPU0_R @BASEBOARD_FAB2_LIB.BASEBOARD_FAB2(SCH_1):SVID_DIO0_CPU0_R   I151 @BASEBOARD_FAB2_LIB.BASEBOARD_FAB2(SCH_1):PAGE21

R6N12 RES_0402-0.0,5%,1/16W,CHIP,G21A
     1 SVID_CLK0_CPU0 @BASEBOARD_FAB2_LIB.BASEBOARD_FAB2(SCH_1):SVID_CLK0_CPU0   I150 @BASEBOARD_FAB2_LIB.BASEBOARD_FAB2(SCH_1):PAGE21
     2 SVID_CLK0_CPU0_R @BASEBOARD_FAB2_LIB.BASEBOARD_FAB2(SCH_1):SVID_CLK0_CPU0_R   I150 @BASEBOARD_FAB2_LIB.BASEBOARD_FAB2(SCH_1):PAGE21

R6N13 RES_0402-1.00K,1%,1/16W,CHIP,GA
     1    GND @BASEBOARD_FAB2_LIB.BASEBOARD_FAB2(SCH_1):GND   I303 @BASEBOARD_FAB2_LIB.BASEBOARD_FAB2(SCH_1):PAGE156
     2 PD_PIROM_CPU0_ADDR1 @BASEBOARD_FAB2_LIB.BASEBOARD_FAB2(SCH_1):PD_PIROM_CPU0_ADDR1   I303 @BASEBOARD_FAB2_LIB.BASEBOARD_FAB2(SCH_1):PAGE156

R6N14 RES_0402-1.00K,1%,1/16W,CHIP,GA
     1    GND @BASEBOARD_FAB2_LIB.BASEBOARD_FAB2(SCH_1):GND   I302 @BASEBOARD_FAB2_LIB.BASEBOARD_FAB2(SCH_1):PAGE156
     2 PD_PIROM_CPU0_ADDR0 @BASEBOARD_FAB2_LIB.BASEBOARD_FAB2(SCH_1):PD_PIROM_CPU0_ADDR0   I302 @BASEBOARD_FAB2_LIB.BASEBOARD_FAB2(SCH_1):PAGE156

R6N15 RES_0402-1.00K,1%,1/16W,CHIP,GA
     1    GND @BASEBOARD_FAB2_LIB.BASEBOARD_FAB2(SCH_1):GND   I304 @BASEBOARD_FAB2_LIB.BASEBOARD_FAB2(SCH_1):PAGE156
     2 PD_PIROM_CPU0_ADDR2 @BASEBOARD_FAB2_LIB.BASEBOARD_FAB2(SCH_1):PD_PIROM_CPU0_ADDR2   I304 @BASEBOARD_FAB2_LIB.BASEBOARD_FAB2(SCH_1):PAGE156

R6P1 RES_0402-42.2,1.0%,1/16W,EMPTYA
     1 CLK_100M_CPU0_RC_REFCLK0_DP @BASEBOARD_FAB2_LIB.BASEBOARD_FAB2(SCH_1):CLK_100M_CPU0_RC_REFCLK0_DP   I149 @BASEBOARD_FAB2_LIB.BASEBOARD_FAB2(SCH_1):PAGE103
     2    GND @BASEBOARD_FAB2_LIB.BASEBOARD_FAB2(SCH_1):GND   I149 @BASEBOARD_FAB2_LIB.BASEBOARD_FAB2(SCH_1):PAGE103

R6P2 RES_0402-42.2,1.0%,1/16W,EMPTYA
     1 CLK_100M_CPU0_RC_REFCLK0_DN @BASEBOARD_FAB2_LIB.BASEBOARD_FAB2(SCH_1):CLK_100M_CPU0_RC_REFCLK0_DN   I151 @BASEBOARD_FAB2_LIB.BASEBOARD_FAB2(SCH_1):PAGE103
     2    GND @BASEBOARD_FAB2_LIB.BASEBOARD_FAB2(SCH_1):GND   I151 @BASEBOARD_FAB2_LIB.BASEBOARD_FAB2(SCH_1):PAGE103

R6P3 RES_0402-42.2,1.0%,1/16W,EMPTYA
     1 CLK_100M_CPU0_RC_REFCLK1_DP @BASEBOARD_FAB2_LIB.BASEBOARD_FAB2(SCH_1):CLK_100M_CPU0_RC_REFCLK1_DP   I145 @BASEBOARD_FAB2_LIB.BASEBOARD_FAB2(SCH_1):PAGE103
     2    GND @BASEBOARD_FAB2_LIB.BASEBOARD_FAB2(SCH_1):GND   I145 @BASEBOARD_FAB2_LIB.BASEBOARD_FAB2(SCH_1):PAGE103

R6P4 RES_0402-42.2,1.0%,1/16W,EMPTYA
     1 CLK_100M_CPU0_RC_REFCLK1_DN @BASEBOARD_FAB2_LIB.BASEBOARD_FAB2(SCH_1):CLK_100M_CPU0_RC_REFCLK1_DN   I147 @BASEBOARD_FAB2_LIB.BASEBOARD_FAB2(SCH_1):PAGE103
     2    GND @BASEBOARD_FAB2_LIB.BASEBOARD_FAB2(SCH_1):GND   I147 @BASEBOARD_FAB2_LIB.BASEBOARD_FAB2(SCH_1):PAGE103

R6P5 RES_0402-42.2,1.0%,1/16W,EMPTYA
     1 CLK_100M_CPU1_BCLK0_DP @BASEBOARD_FAB2_LIB.BASEBOARD_FAB2(SCH_1):CLK_100M_CPU1_BCLK0_DP   I141 @BASEBOARD_FAB2_LIB.BASEBOARD_FAB2(SCH_1):PAGE103
     2    GND @BASEBOARD_FAB2_LIB.BASEBOARD_FAB2(SCH_1):GND   I141 @BASEBOARD_FAB2_LIB.BASEBOARD_FAB2(SCH_1):PAGE103

R6P6 RES_0402-42.2,1.0%,1/16W,EMPTYA
     1 CLK_100M_CPU1_BCLK0_DN @BASEBOARD_FAB2_LIB.BASEBOARD_FAB2(SCH_1):CLK_100M_CPU1_BCLK0_DN   I143 @BASEBOARD_FAB2_LIB.BASEBOARD_FAB2(SCH_1):PAGE103
     2    GND @BASEBOARD_FAB2_LIB.BASEBOARD_FAB2(SCH_1):GND   I143 @BASEBOARD_FAB2_LIB.BASEBOARD_FAB2(SCH_1):PAGE103

R6P7 RES_0402-42.2,1.0%,1/16W,EMPTYA
     1 CLK_100M_CPU1_BCLK1_DP @BASEBOARD_FAB2_LIB.BASEBOARD_FAB2(SCH_1):CLK_100M_CPU1_BCLK1_DP   I137 @BASEBOARD_FAB2_LIB.BASEBOARD_FAB2(SCH_1):PAGE103
     2    GND @BASEBOARD_FAB2_LIB.BASEBOARD_FAB2(SCH_1):GND   I137 @BASEBOARD_FAB2_LIB.BASEBOARD_FAB2(SCH_1):PAGE103

R6P8 RES_0402-42.2,1.0%,1/16W,EMPTYA
     1 CLK_100M_CPU1_BCLK1_DN @BASEBOARD_FAB2_LIB.BASEBOARD_FAB2(SCH_1):CLK_100M_CPU1_BCLK1_DN   I139 @BASEBOARD_FAB2_LIB.BASEBOARD_FAB2(SCH_1):PAGE103
     2    GND @BASEBOARD_FAB2_LIB.BASEBOARD_FAB2(SCH_1):GND   I139 @BASEBOARD_FAB2_LIB.BASEBOARD_FAB2(SCH_1):PAGE103

R6P9 RES_0402-42.2,1.0%,1/16W,EMPTYA
     1 CLK_100M_CPU0_PE_REFCLK_DN @BASEBOARD_FAB2_LIB.BASEBOARD_FAB2(SCH_1):CLK_100M_CPU0_PE_REFCLK_DN   I155 @BASEBOARD_FAB2_LIB.BASEBOARD_FAB2(SCH_1):PAGE103
     2    GND @BASEBOARD_FAB2_LIB.BASEBOARD_FAB2(SCH_1):GND   I155 @BASEBOARD_FAB2_LIB.BASEBOARD_FAB2(SCH_1):PAGE103

R6P10 RES_0402-0.0,5%,1/16W,CHIP,G21A
     1 VR_PVCCIN_CPU0_PH4_VCIN @BASEBOARD_FAB2_LIB.BASEBOARD_FAB2(SCH_1):VR_PVCCIN_CPU0_PH4_VCIN   I129 @BASEBOARD_FAB2_LIB.BASEBOARD_FAB2(SCH_1):PAGE203
     2 P5V_STBY @BASEBOARD_FAB2_LIB.BASEBOARD_FAB2(SCH_1):P5V_STBY   I129 @BASEBOARD_FAB2_LIB.BASEBOARD_FAB2(SCH_1):PAGE203

R6P11 RES_0402-42.2,1.0%,1/16W,EMPTYA
     1 CLK_100M_CPU0_PE_REFCLK_DP @BASEBOARD_FAB2_LIB.BASEBOARD_FAB2(SCH_1):CLK_100M_CPU0_PE_REFCLK_DP   I153 @BASEBOARD_FAB2_LIB.BASEBOARD_FAB2(SCH_1):PAGE103
     2    GND @BASEBOARD_FAB2_LIB.BASEBOARD_FAB2(SCH_1):GND   I153 @BASEBOARD_FAB2_LIB.BASEBOARD_FAB2(SCH_1):PAGE103

R6P12 RES_0402-42.2,1.0%,1/16W,EMPTYA
     1 CLK_100M_CPU0_BCLK2_DN @BASEBOARD_FAB2_LIB.BASEBOARD_FAB2(SCH_1):CLK_100M_CPU0_BCLK2_DN   I159 @BASEBOARD_FAB2_LIB.BASEBOARD_FAB2(SCH_1):PAGE103
     2    GND @BASEBOARD_FAB2_LIB.BASEBOARD_FAB2(SCH_1):GND   I159 @BASEBOARD_FAB2_LIB.BASEBOARD_FAB2(SCH_1):PAGE103

R6P13 RES_0402-42.2,1.0%,1/16W,EMPTYA
     1 CLK_100M_CPU0_BCLK2_DP @BASEBOARD_FAB2_LIB.BASEBOARD_FAB2(SCH_1):CLK_100M_CPU0_BCLK2_DP   I157 @BASEBOARD_FAB2_LIB.BASEBOARD_FAB2(SCH_1):PAGE103
     2    GND @BASEBOARD_FAB2_LIB.BASEBOARD_FAB2(SCH_1):GND   I157 @BASEBOARD_FAB2_LIB.BASEBOARD_FAB2(SCH_1):PAGE103

R6P15 RES_0402-42.2,1.0%,1/16W,EMPTYA
     1 CLK_100M_CPU0_BCLK0_DN @BASEBOARD_FAB2_LIB.BASEBOARD_FAB2(SCH_1):CLK_100M_CPU0_BCLK0_DN   I167 @BASEBOARD_FAB2_LIB.BASEBOARD_FAB2(SCH_1):PAGE103
     2    GND @BASEBOARD_FAB2_LIB.BASEBOARD_FAB2(SCH_1):GND   I167 @BASEBOARD_FAB2_LIB.BASEBOARD_FAB2(SCH_1):PAGE103

R6P16 RES_0402-1.00K,1%,1/16W,CHIP,GA
     1 PVCCIO_CPU0 @BASEBOARD_FAB2_LIB.BASEBOARD_FAB2(SCH_1):PVCCIO_CPU0   I132 @BASEBOARD_FAB2_LIB.BASEBOARD_FAB2(SCH_1):PAGE201
     2 VR_PVCCIN_CPU0_VREN @BASEBOARD_FAB2_LIB.BASEBOARD_FAB2(SCH_1):VR_PVCCIN_CPU0_VREN   I132 @BASEBOARD_FAB2_LIB.BASEBOARD_FAB2(SCH_1):PAGE201

R6P17 RES_0402-42.2,1.0%,1/16W,EMPTYA
     1 CLK_100M_CPU0_BCLK0_DP @BASEBOARD_FAB2_LIB.BASEBOARD_FAB2(SCH_1):CLK_100M_CPU0_BCLK0_DP   I165 @BASEBOARD_FAB2_LIB.BASEBOARD_FAB2(SCH_1):PAGE103
     2    GND @BASEBOARD_FAB2_LIB.BASEBOARD_FAB2(SCH_1):GND   I165 @BASEBOARD_FAB2_LIB.BASEBOARD_FAB2(SCH_1):PAGE103

R6P18 RES_0402-0.0,5%,1/16W,CHIP,G21A
     1 FM_PVCCIN_PVCCSA_CPU0_EN_LVC1 @BASEBOARD_FAB2_LIB.BASEBOARD_FAB2(SCH_1):FM_PVCCIN_PVCCSA_CPU0_EN_LVC1   I131 @BASEBOARD_FAB2_LIB.BASEBOARD_FAB2(SCH_1):PAGE201
     2 VR_PVCCIN_CPU0_VREN @BASEBOARD_FAB2_LIB.BASEBOARD_FAB2(SCH_1):VR_PVCCIN_CPU0_VREN   I131 @BASEBOARD_FAB2_LIB.BASEBOARD_FAB2(SCH_1):PAGE201

R6P19 RES_0402-0.0,5%,1/16W,CHIP,G21A
     1 VR_PVCCIN_CPU0_PH3_VCIN @BASEBOARD_FAB2_LIB.BASEBOARD_FAB2(SCH_1):VR_PVCCIN_CPU0_PH3_VCIN   I128 @BASEBOARD_FAB2_LIB.BASEBOARD_FAB2(SCH_1):PAGE203
     2 P5V_STBY @BASEBOARD_FAB2_LIB.BASEBOARD_FAB2(SCH_1):P5V_STBY   I128 @BASEBOARD_FAB2_LIB.BASEBOARD_FAB2(SCH_1):PAGE203

R6P20 RES_0402-1.00K,1%,1/16W,CHIP,GA
     1 FM_DB1200_SMB_SA1 @BASEBOARD_FAB2_LIB.BASEBOARD_FAB2(SCH_1):FM_DB1200_SMB_SA1    I81 @BASEBOARD_FAB2_LIB.BASEBOARD_FAB2(SCH_1):PAGE102
     2    GND @BASEBOARD_FAB2_LIB.BASEBOARD_FAB2(SCH_1):GND    I81 @BASEBOARD_FAB2_LIB.BASEBOARD_FAB2(SCH_1):PAGE102

R6P21 RES_0402-1.00K,1%,1/16W,CHIP,GA
     1 FM_DB1200_SMB_SA0 @BASEBOARD_FAB2_LIB.BASEBOARD_FAB2(SCH_1):FM_DB1200_SMB_SA0    I80 @BASEBOARD_FAB2_LIB.BASEBOARD_FAB2(SCH_1):PAGE102
     2    GND @BASEBOARD_FAB2_LIB.BASEBOARD_FAB2(SCH_1):GND    I80 @BASEBOARD_FAB2_LIB.BASEBOARD_FAB2(SCH_1):PAGE102

R6P22 RES_0402-4.75K,1%,1/16W,EMPTY,A
     1 FM_HBW_BYPASS_LOWBW_N @BASEBOARD_FAB2_LIB.BASEBOARD_FAB2(SCH_1):FM_HBW_BYPASS_LOWBW_N    I47 @BASEBOARD_FAB2_LIB.BASEBOARD_FAB2(SCH_1):PAGE102
     2    GND @BASEBOARD_FAB2_LIB.BASEBOARD_FAB2(SCH_1):GND    I47 @BASEBOARD_FAB2_LIB.BASEBOARD_FAB2(SCH_1):PAGE102

R6P23 RES_0402-4.75K,1%,1/16W,EMPTY,A
     1 FM_100M_N @BASEBOARD_FAB2_LIB.BASEBOARD_FAB2(SCH_1):FM_100M_N    I46 @BASEBOARD_FAB2_LIB.BASEBOARD_FAB2(SCH_1):PAGE102
     2    GND @BASEBOARD_FAB2_LIB.BASEBOARD_FAB2(SCH_1):GND    I46 @BASEBOARD_FAB2_LIB.BASEBOARD_FAB2(SCH_1):PAGE102

R6P25 RES_0603-2.2,1.0%,1/10W,CHIP,GA
     1 P3V3_DB1200 @BASEBOARD_FAB2_LIB.BASEBOARD_FAB2(SCH_1):P3V3_DB1200    I26 @BASEBOARD_FAB2_LIB.BASEBOARD_FAB2(SCH_1):PAGE102
     2 P3V3_DB1200_R @BASEBOARD_FAB2_LIB.BASEBOARD_FAB2(SCH_1):P3V3_DB1200_R    I26 @BASEBOARD_FAB2_LIB.BASEBOARD_FAB2(SCH_1):PAGE102

R6P27 RES_0402-4.02K,1%,1/16W,CHIP,GA
     1 VR_PVCCIN_CPU0_XADDR2 @BASEBOARD_FAB2_LIB.BASEBOARD_FAB2(SCH_1):VR_PVCCIN_CPU0_XADDR2   I120 @BASEBOARD_FAB2_LIB.BASEBOARD_FAB2(SCH_1):PAGE201
     2    GND @BASEBOARD_FAB2_LIB.BASEBOARD_FAB2(SCH_1):GND   I120 @BASEBOARD_FAB2_LIB.BASEBOARD_FAB2(SCH_1):PAGE201

R6P28 RES_0402-4.02K,1%,1/16W,CHIP,GA
     1 VR_PVCCIN_CPU0_XADDR1 @BASEBOARD_FAB2_LIB.BASEBOARD_FAB2(SCH_1):VR_PVCCIN_CPU0_XADDR1   I121 @BASEBOARD_FAB2_LIB.BASEBOARD_FAB2(SCH_1):PAGE201
     2    GND @BASEBOARD_FAB2_LIB.BASEBOARD_FAB2(SCH_1):GND   I121 @BASEBOARD_FAB2_LIB.BASEBOARD_FAB2(SCH_1):PAGE201

R6P32 RES_0402-2.0K,1%,1/16W,EMPTY,GA
     1 P3V3_STBY @BASEBOARD_FAB2_LIB.BASEBOARD_FAB2(SCH_1):P3V3_STBY   I102 @BASEBOARD_FAB2_LIB.BASEBOARD_FAB2(SCH_1):PAGE201
     2 SMB_VR_STBY_LVC3_SDA @BASEBOARD_FAB2_LIB.BASEBOARD_FAB2(SCH_1):SMB_VR_STBY_LVC3_SDA   I102 @BASEBOARD_FAB2_LIB.BASEBOARD_FAB2(SCH_1):PAGE201

R6P33 RES_0402-110,1%,1/16W,EMPTY,G2A
     1 PVCCIO_CPU1 @BASEBOARD_FAB2_LIB.BASEBOARD_FAB2(SCH_1):PVCCIO_CPU1    I30 @BASEBOARD_FAB2_LIB.BASEBOARD_FAB2(SCH_1):PAGE213
     2 SVID_CLK0_CPU1_R @BASEBOARD_FAB2_LIB.BASEBOARD_FAB2(SCH_1):SVID_CLK0_CPU1_R    I30 @BASEBOARD_FAB2_LIB.BASEBOARD_FAB2(SCH_1):PAGE213

R6P35 RES_0402-100.0,1%,1/16W,EMPTY,A
     1 PVCCIO_CPU1 @BASEBOARD_FAB2_LIB.BASEBOARD_FAB2(SCH_1):PVCCIO_CPU1    I27 @BASEBOARD_FAB2_LIB.BASEBOARD_FAB2(SCH_1):PAGE213
     2 SVID_DIO0_CPU1_R @BASEBOARD_FAB2_LIB.BASEBOARD_FAB2(SCH_1):SVID_DIO0_CPU1_R    I27 @BASEBOARD_FAB2_LIB.BASEBOARD_FAB2(SCH_1):PAGE213

R6P37 RES_0402-2.0K,1%,1/16W,EMPTY,GA
     1 P3V3_STBY @BASEBOARD_FAB2_LIB.BASEBOARD_FAB2(SCH_1):P3V3_STBY   I103 @BASEBOARD_FAB2_LIB.BASEBOARD_FAB2(SCH_1):PAGE201
     2 SMB_VR_STBY_LVC3_SCL @BASEBOARD_FAB2_LIB.BASEBOARD_FAB2(SCH_1):SMB_VR_STBY_LVC3_SCL   I103 @BASEBOARD_FAB2_LIB.BASEBOARD_FAB2(SCH_1):PAGE201

R6P39 RES_0402-4.75K,1%,1/16W,CHIP,GA
     1 P3V3_STBY @BASEBOARD_FAB2_LIB.BASEBOARD_FAB2(SCH_1):P3V3_STBY   I181 @BASEBOARD_FAB2_LIB.BASEBOARD_FAB2(SCH_1):PAGE55
     2 FM_CPU1_SKTOCC_LVT3_N @BASEBOARD_FAB2_LIB.BASEBOARD_FAB2(SCH_1):FM_CPU1_SKTOCC_LVT3_N   I181 @BASEBOARD_FAB2_LIB.BASEBOARD_FAB2(SCH_1):PAGE55

R6P40 RES_0402-100.0K,1%,1/16W,EMPTYA
     1 P3V3_STBY @BASEBOARD_FAB2_LIB.BASEBOARD_FAB2(SCH_1):P3V3_STBY    I91 @BASEBOARD_FAB2_LIB.BASEBOARD_FAB2(SCH_1):PAGE213
     2 VR_PVCCIO_CPU1_EN @BASEBOARD_FAB2_LIB.BASEBOARD_FAB2(SCH_1):VR_PVCCIO_CPU1_EN    I91 @BASEBOARD_FAB2_LIB.BASEBOARD_FAB2(SCH_1):PAGE213

R6P41 RES_0402-0.0,5%,1/16W,CHIP,G21A
     1 FM_PVCCIO_CPU1_EN @BASEBOARD_FAB2_LIB.BASEBOARD_FAB2(SCH_1):FM_PVCCIO_CPU1_EN    I90 @BASEBOARD_FAB2_LIB.BASEBOARD_FAB2(SCH_1):PAGE213
     2 VR_PVCCIO_CPU1_EN @BASEBOARD_FAB2_LIB.BASEBOARD_FAB2(SCH_1):VR_PVCCIO_CPU1_EN    I90 @BASEBOARD_FAB2_LIB.BASEBOARD_FAB2(SCH_1):PAGE213

R6P45 RES_0402-33.2,1%,1/16W,CHIP,G2A
     1 IRQ_PVCCIN_CPU0_VRHOT_LVC3_R_N @BASEBOARD_FAB2_LIB.BASEBOARD_FAB2(SCH_1):IRQ_PVCCIN_CPU0_VRHOT_LVC3_R_N   I128 @BASEBOARD_FAB2_LIB.BASEBOARD_FAB2(SCH_1):PAGE201
     2 IRQ_PVCCIN_CPU0_VRHOT_LVC3_N @BASEBOARD_FAB2_LIB.BASEBOARD_FAB2(SCH_1):IRQ_PVCCIN_CPU0_VRHOT_LVC3_N   I128 @BASEBOARD_FAB2_LIB.BASEBOARD_FAB2(SCH_1):PAGE201

R6P46 RES_0402-100.0,1%,1/16W,CHIP,GA
     1 PVCCIO_CPU0 @BASEBOARD_FAB2_LIB.BASEBOARD_FAB2(SCH_1):PVCCIO_CPU0    I49 @BASEBOARD_FAB2_LIB.BASEBOARD_FAB2(SCH_1):PAGE112
     2 XDP_CPU_MBP1_N @BASEBOARD_FAB2_LIB.BASEBOARD_FAB2(SCH_1):XDP_CPU_MBP1_N    I49 @BASEBOARD_FAB2_LIB.BASEBOARD_FAB2(SCH_1):PAGE112

R6P47 RES_0402-0.0,5%,1/16W,CHIP,G21A
     1 VR_PVCCIN_CPU0_PH5_VCIN @BASEBOARD_FAB2_LIB.BASEBOARD_FAB2(SCH_1):VR_PVCCIN_CPU0_PH5_VCIN   I103 @BASEBOARD_FAB2_LIB.BASEBOARD_FAB2(SCH_1):PAGE204
     2 P5V_STBY @BASEBOARD_FAB2_LIB.BASEBOARD_FAB2(SCH_1):P5V_STBY   I103 @BASEBOARD_FAB2_LIB.BASEBOARD_FAB2(SCH_1):PAGE204

R6P48 RES_0402-1.00K,1%,1/16W,CHIP,GA
     1   P3V3 @BASEBOARD_FAB2_LIB.BASEBOARD_FAB2(SCH_1):P3V3   I115 @BASEBOARD_FAB2_LIB.BASEBOARD_FAB2(SCH_1):PAGE102
     2 FM_DB1200ZL_BCLKS_EN_N @BASEBOARD_FAB2_LIB.BASEBOARD_FAB2(SCH_1):FM_DB1200ZL_BCLKS_EN_N   I115 @BASEBOARD_FAB2_LIB.BASEBOARD_FAB2(SCH_1):PAGE102

R6P49 RES_0402-2.26K,1.0%,1/16W,EMPTA
     1 P3V3_STBY @BASEBOARD_FAB2_LIB.BASEBOARD_FAB2(SCH_1):P3V3_STBY    I14 @BASEBOARD_FAB2_LIB.BASEBOARD_FAB2(SCH_1):PAGE213
     2 PU_VR_PVCCIO_CPU1_FAULT1 @BASEBOARD_FAB2_LIB.BASEBOARD_FAB2(SCH_1):PU_VR_PVCCIO_CPU1_FAULT1    I14 @BASEBOARD_FAB2_LIB.BASEBOARD_FAB2(SCH_1):PAGE213

R6R2 RES_0402-0.0,5%,1/16W,CHIP,G21A
     1 VR_PVCCIN_CPU0_PH1_VCIN @BASEBOARD_FAB2_LIB.BASEBOARD_FAB2(SCH_1):VR_PVCCIN_CPU0_PH1_VCIN   I107 @BASEBOARD_FAB2_LIB.BASEBOARD_FAB2(SCH_1):PAGE202
     2 P5V_STBY @BASEBOARD_FAB2_LIB.BASEBOARD_FAB2(SCH_1):P5V_STBY   I107 @BASEBOARD_FAB2_LIB.BASEBOARD_FAB2(SCH_1):PAGE202

R6R5 RES_0402-0.0,5%,1/16W,CHIP,G21A
     1 VR_PVCCIO_CPU1_PH1_VCIN @BASEBOARD_FAB2_LIB.BASEBOARD_FAB2(SCH_1):VR_PVCCIO_CPU1_PH1_VCIN   I173 @BASEBOARD_FAB2_LIB.BASEBOARD_FAB2(SCH_1):PAGE214
     2 P5V_STBY @BASEBOARD_FAB2_LIB.BASEBOARD_FAB2(SCH_1):P5V_STBY   I173 @BASEBOARD_FAB2_LIB.BASEBOARD_FAB2(SCH_1):PAGE214

R6R6 RES_0402-0.0,5%,1/16W,CHIP,G21A
     1 VR_PVCCIN_CPU0_PH2_VCIN @BASEBOARD_FAB2_LIB.BASEBOARD_FAB2(SCH_1):VR_PVCCIN_CPU0_PH2_VCIN   I108 @BASEBOARD_FAB2_LIB.BASEBOARD_FAB2(SCH_1):PAGE202
     2 P5V_STBY @BASEBOARD_FAB2_LIB.BASEBOARD_FAB2(SCH_1):P5V_STBY   I108 @BASEBOARD_FAB2_LIB.BASEBOARD_FAB2(SCH_1):PAGE202

R6T1 RES_0402-240,1.0%,1/16W,CHIP,GA
     1 PVCCIO_CPU1 @BASEBOARD_FAB2_LIB.BASEBOARD_FAB2(SCH_1):PVCCIO_CPU1    I70 @BASEBOARD_FAB2_LIB.BASEBOARD_FAB2(SCH_1):PAGE99
     2 SMB_DDR_GHJ_SDA_G @BASEBOARD_FAB2_LIB.BASEBOARD_FAB2(SCH_1):SMB_DDR_GHJ_SDA_G    I70 @BASEBOARD_FAB2_LIB.BASEBOARD_FAB2(SCH_1):PAGE99

R6T2 RES_0402-240,1.0%,1/16W,CHIP,GA
     1 PVCCIO_CPU1 @BASEBOARD_FAB2_LIB.BASEBOARD_FAB2(SCH_1):PVCCIO_CPU1    I72 @BASEBOARD_FAB2_LIB.BASEBOARD_FAB2(SCH_1):PAGE99
     2 SMB_DDR_GHJ_SCL_G @BASEBOARD_FAB2_LIB.BASEBOARD_FAB2(SCH_1):SMB_DDR_GHJ_SCL_G    I72 @BASEBOARD_FAB2_LIB.BASEBOARD_FAB2(SCH_1):PAGE99

R6T3 RES_0402-10.0,1%,1/16W,CHIP,G2A
     1 SMB_DDR_GHJ_SCL_G_R @BASEBOARD_FAB2_LIB.BASEBOARD_FAB2(SCH_1):SMB_DDR_GHJ_SCL_G_R    I92 @BASEBOARD_FAB2_LIB.BASEBOARD_FAB2(SCH_1):PAGE99
     2 SMB_DDR_GHJ_SCL_G @BASEBOARD_FAB2_LIB.BASEBOARD_FAB2(SCH_1):SMB_DDR_GHJ_SCL_G    I92 @BASEBOARD_FAB2_LIB.BASEBOARD_FAB2(SCH_1):PAGE99

R6T4 RES_0402-10.0,1%,1/16W,CHIP,G2A
     1 SMB_DDR_GHJ_SDA_G_R @BASEBOARD_FAB2_LIB.BASEBOARD_FAB2(SCH_1):SMB_DDR_GHJ_SDA_G_R   I111 @BASEBOARD_FAB2_LIB.BASEBOARD_FAB2(SCH_1):PAGE99
     2 SMB_DDR_GHJ_SDA_G @BASEBOARD_FAB2_LIB.BASEBOARD_FAB2(SCH_1):SMB_DDR_GHJ_SDA_G   I111 @BASEBOARD_FAB2_LIB.BASEBOARD_FAB2(SCH_1):PAGE99

R6T5 RES_0402-1.00K,1%,1/16W,CHIP,GA
     1 XDP_CPU_TRST_N @BASEBOARD_FAB2_LIB.BASEBOARD_FAB2(SCH_1):XDP_CPU_TRST_N    I62 @BASEBOARD_FAB2_LIB.BASEBOARD_FAB2(SCH_1):PAGE112
     2    GND @BASEBOARD_FAB2_LIB.BASEBOARD_FAB2(SCH_1):GND    I62 @BASEBOARD_FAB2_LIB.BASEBOARD_FAB2(SCH_1):PAGE112

R6T6 RES_0402-150.0,1%,1/16W,CHIP,GA
     1 PVCCIO_CPU1 @BASEBOARD_FAB2_LIB.BASEBOARD_FAB2(SCH_1):PVCCIO_CPU1    I56 @BASEBOARD_FAB2_LIB.BASEBOARD_FAB2(SCH_1):PAGE112
     2 XDP_CPU1_TDI @BASEBOARD_FAB2_LIB.BASEBOARD_FAB2(SCH_1):XDP_CPU1_TDI    I56 @BASEBOARD_FAB2_LIB.BASEBOARD_FAB2(SCH_1):PAGE112

R6T7 RES_0402-150.0,1%,1/16W,CHIP,GA
     1 PVCCIO_CPU1 @BASEBOARD_FAB2_LIB.BASEBOARD_FAB2(SCH_1):PVCCIO_CPU1    I55 @BASEBOARD_FAB2_LIB.BASEBOARD_FAB2(SCH_1):PAGE112
     2 XDP_CPU1_TDO @BASEBOARD_FAB2_LIB.BASEBOARD_FAB2(SCH_1):XDP_CPU1_TDO    I55 @BASEBOARD_FAB2_LIB.BASEBOARD_FAB2(SCH_1):PAGE112

R6T8 RES_0402-100.0,1%,1/16W,CHIP,GA
     1 PVCCIO_CPU0 @BASEBOARD_FAB2_LIB.BASEBOARD_FAB2(SCH_1):PVCCIO_CPU0   I121 @BASEBOARD_FAB2_LIB.BASEBOARD_FAB2(SCH_1):PAGE112
     2 XDP_CPU_OBSFN_B0_MBP6_N @BASEBOARD_FAB2_LIB.BASEBOARD_FAB2(SCH_1):XDP_CPU_OBSFN_B0_MBP6_N   I121 @BASEBOARD_FAB2_LIB.BASEBOARD_FAB2(SCH_1):PAGE112

R6T9 RES_0402-100.0,1%,1/16W,CHIP,GA
     1 PVCCIO_CPU0 @BASEBOARD_FAB2_LIB.BASEBOARD_FAB2(SCH_1):PVCCIO_CPU0   I120 @BASEBOARD_FAB2_LIB.BASEBOARD_FAB2(SCH_1):PAGE112
     2 XDP_CPU_OBSFN_B1_MBP7_N @BASEBOARD_FAB2_LIB.BASEBOARD_FAB2(SCH_1):XDP_CPU_OBSFN_B1_MBP7_N   I120 @BASEBOARD_FAB2_LIB.BASEBOARD_FAB2(SCH_1):PAGE112

R6U3 RES_0402-1.0M,1%,1/16W,EMPTY,GA
     1   P3V3 @BASEBOARD_FAB2_LIB.BASEBOARD_FAB2(SCH_1):P3V3     I5 @BASEBOARD_FAB2_LIB.BASEBOARD_FAB2(SCH_1):PAGE229
     2 FM_PVTT_GHJ_EN_R @BASEBOARD_FAB2_LIB.BASEBOARD_FAB2(SCH_1):FM_PVTT_GHJ_EN_R     I5 @BASEBOARD_FAB2_LIB.BASEBOARD_FAB2(SCH_1):PAGE229

R6U4 RES_0402-0.0,5%,1/16W,CHIP,G21A
     1   P3V3 @BASEBOARD_FAB2_LIB.BASEBOARD_FAB2(SCH_1):P3V3    I14 @BASEBOARD_FAB2_LIB.BASEBOARD_FAB2(SCH_1):PAGE221
     2 VR_PVTT_ABC_BIAS @BASEBOARD_FAB2_LIB.BASEBOARD_FAB2(SCH_1):VR_PVTT_ABC_BIAS    I14 @BASEBOARD_FAB2_LIB.BASEBOARD_FAB2(SCH_1):PAGE221

R6U5 RES_0402-0.0,5%,1/16W,CHIP,G21A
     1 PVDDQ_ABC @BASEBOARD_FAB2_LIB.BASEBOARD_FAB2(SCH_1):PVDDQ_ABC     I6 @BASEBOARD_FAB2_LIB.BASEBOARD_FAB2(SCH_1):PAGE221
     2 VSENSE_PVDDQ_ABC_VTT @BASEBOARD_FAB2_LIB.BASEBOARD_FAB2(SCH_1):VSENSE_PVDDQ_ABC_VTT     I6 @BASEBOARD_FAB2_LIB.BASEBOARD_FAB2(SCH_1):PAGE221

R6U6 RES_0402-0.0,5%,1/16W,CHIP,G21A
     1 PVDDQ_GHJ @BASEBOARD_FAB2_LIB.BASEBOARD_FAB2(SCH_1):PVDDQ_GHJ     I6 @BASEBOARD_FAB2_LIB.BASEBOARD_FAB2(SCH_1):PAGE229
     2 VSENSE_PVDDQ_GHJ_VTT @BASEBOARD_FAB2_LIB.BASEBOARD_FAB2(SCH_1):VSENSE_PVDDQ_GHJ_VTT     I6 @BASEBOARD_FAB2_LIB.BASEBOARD_FAB2(SCH_1):PAGE229

R6U7 RES_0402-0.0,5%,1/16W,CHIP,G21A
     1   P3V3 @BASEBOARD_FAB2_LIB.BASEBOARD_FAB2(SCH_1):P3V3     I9 @BASEBOARD_FAB2_LIB.BASEBOARD_FAB2(SCH_1):PAGE229
     2 VR_PVTT_GHJ_BIAS @BASEBOARD_FAB2_LIB.BASEBOARD_FAB2(SCH_1):VR_PVTT_GHJ_BIAS     I9 @BASEBOARD_FAB2_LIB.BASEBOARD_FAB2(SCH_1):PAGE229

R6U13 RES_0402-20.0,1%,1/16W,CHIP,G2A
     1 SMB_DDR_GHJ_VPP_SCL_R @BASEBOARD_FAB2_LIB.BASEBOARD_FAB2(SCH_1):SMB_DDR_GHJ_VPP_SCL_R    I42 @BASEBOARD_FAB2_LIB.BASEBOARD_FAB2(SCH_1):PAGE99
     2 SMB_DDR_GHJ_VPP_SCL @BASEBOARD_FAB2_LIB.BASEBOARD_FAB2(SCH_1):SMB_DDR_GHJ_VPP_SCL    I42 @BASEBOARD_FAB2_LIB.BASEBOARD_FAB2(SCH_1):PAGE99

R6U14 RES_0402-20.0,1%,1/16W,CHIP,G2A
     1 SMB_DDR_GHJ_VPP_SDA_R @BASEBOARD_FAB2_LIB.BASEBOARD_FAB2(SCH_1):SMB_DDR_GHJ_VPP_SDA_R   I115 @BASEBOARD_FAB2_LIB.BASEBOARD_FAB2(SCH_1):PAGE99
     2 SMB_DDR_GHJ_VPP_SDA @BASEBOARD_FAB2_LIB.BASEBOARD_FAB2(SCH_1):SMB_DDR_GHJ_VPP_SDA   I115 @BASEBOARD_FAB2_LIB.BASEBOARD_FAB2(SCH_1):PAGE99

R6U15 RES_0402-1.0M,1%,1/16W,EMPTY,GA
     1   P3V3 @BASEBOARD_FAB2_LIB.BASEBOARD_FAB2(SCH_1):P3V3     I5 @BASEBOARD_FAB2_LIB.BASEBOARD_FAB2(SCH_1):PAGE221
     2 FM_PVTT_ABC_EN_R @BASEBOARD_FAB2_LIB.BASEBOARD_FAB2(SCH_1):FM_PVTT_ABC_EN_R     I5 @BASEBOARD_FAB2_LIB.BASEBOARD_FAB2(SCH_1):PAGE221

R6U17 RES_0402-665,1.0%,1/16W,CHIP,GA
     1 PVPP_GHJ @BASEBOARD_FAB2_LIB.BASEBOARD_FAB2(SCH_1):PVPP_GHJ   I106 @BASEBOARD_FAB2_LIB.BASEBOARD_FAB2(SCH_1):PAGE99
     2 SMB_DDR_GHJ_VPP_SCL_R @BASEBOARD_FAB2_LIB.BASEBOARD_FAB2(SCH_1):SMB_DDR_GHJ_VPP_SCL_R   I106 @BASEBOARD_FAB2_LIB.BASEBOARD_FAB2(SCH_1):PAGE99

R6U18 RES_0402-665,1.0%,1/16W,CHIP,GA
     1 PVPP_GHJ @BASEBOARD_FAB2_LIB.BASEBOARD_FAB2(SCH_1):PVPP_GHJ   I104 @BASEBOARD_FAB2_LIB.BASEBOARD_FAB2(SCH_1):PAGE99
     2 SMB_DDR_GHJ_VPP_SDA_R @BASEBOARD_FAB2_LIB.BASEBOARD_FAB2(SCH_1):SMB_DDR_GHJ_VPP_SDA_R   I104 @BASEBOARD_FAB2_LIB.BASEBOARD_FAB2(SCH_1):PAGE99

R6W1 RES_0402-4.75K,1%,1/16W,CHIP,GA
     1 P3V3_STBY @BASEBOARD_FAB2_LIB.BASEBOARD_FAB2(SCH_1):P3V3_STBY   I149 @BASEBOARD_FAB2_LIB.BASEBOARD_FAB2(SCH_1):PAGE137
     2 PU_UV_HIGH_SET @BASEBOARD_FAB2_LIB.BASEBOARD_FAB2(SCH_1):PU_UV_HIGH_SET   I149 @BASEBOARD_FAB2_LIB.BASEBOARD_FAB2(SCH_1):PAGE137

R6W2 RES_0402-10.0K,1%,1/16W,CHIP,GA
     1 PD_UV_HIGH_SET @BASEBOARD_FAB2_LIB.BASEBOARD_FAB2(SCH_1):PD_UV_HIGH_SET   I144 @BASEBOARD_FAB2_LIB.BASEBOARD_FAB2(SCH_1):PAGE137
     2    GND @BASEBOARD_FAB2_LIB.BASEBOARD_FAB2(SCH_1):GND   I144 @BASEBOARD_FAB2_LIB.BASEBOARD_FAB2(SCH_1):PAGE137

R6W3 232KR2F-2-GP_SMD-RG1-232KR2F-2A
     1 UV_HIGH_SET_N @BASEBOARD_FAB2_LIB.BASEBOARD_FAB2(SCH_1):UV_HIGH_SET_N   I250 @BASEBOARD_FAB2_LIB.BASEBOARD_FAB2(SCH_1):PAGE200
     2 A_P12V_STBY_FP_TRIGGER @BASEBOARD_FAB2_LIB.BASEBOARD_FAB2(SCH_1):A_P12V_STBY_FP_TRIGGER   I250 @BASEBOARD_FAB2_LIB.BASEBOARD_FAB2(SCH_1):PAGE200

R6W4 RES_0402-4.75K,1%,1/16W,CHIP,GA
     1 P3V3_STBY @BASEBOARD_FAB2_LIB.BASEBOARD_FAB2(SCH_1):P3V3_STBY   I159 @BASEBOARD_FAB2_LIB.BASEBOARD_FAB2(SCH_1):PAGE247
     2 PCA9555_A2 @BASEBOARD_FAB2_LIB.BASEBOARD_FAB2(SCH_1):PCA9555_A2   I159 @BASEBOARD_FAB2_LIB.BASEBOARD_FAB2(SCH_1):PAGE247

R6W5 RES_0402-4.75K,1%,1/16W,CHIP,GA
     1 P3V3_STBY @BASEBOARD_FAB2_LIB.BASEBOARD_FAB2(SCH_1):P3V3_STBY   I160 @BASEBOARD_FAB2_LIB.BASEBOARD_FAB2(SCH_1):PAGE247
     2 PCA9555_A1 @BASEBOARD_FAB2_LIB.BASEBOARD_FAB2(SCH_1):PCA9555_A1   I160 @BASEBOARD_FAB2_LIB.BASEBOARD_FAB2(SCH_1):PAGE247

R6W6 RES_0402-4.75K,1%,1/16W,CHIP,GA
     1 P3V3_STBY @BASEBOARD_FAB2_LIB.BASEBOARD_FAB2(SCH_1):P3V3_STBY   I161 @BASEBOARD_FAB2_LIB.BASEBOARD_FAB2(SCH_1):PAGE247
     2 PCA9555_A0 @BASEBOARD_FAB2_LIB.BASEBOARD_FAB2(SCH_1):PCA9555_A0   I161 @BASEBOARD_FAB2_LIB.BASEBOARD_FAB2(SCH_1):PAGE247

R6W7 RES_0402-4.75K,1%,1/16W,EMPTY,A
     1 PCA9555_A2 @BASEBOARD_FAB2_LIB.BASEBOARD_FAB2(SCH_1):PCA9555_A2   I164 @BASEBOARD_FAB2_LIB.BASEBOARD_FAB2(SCH_1):PAGE247
     2    GND @BASEBOARD_FAB2_LIB.BASEBOARD_FAB2(SCH_1):GND   I164 @BASEBOARD_FAB2_LIB.BASEBOARD_FAB2(SCH_1):PAGE247

R6W8 RES_0402-4.75K,1%,1/16W,EMPTY,A
     1 PCA9555_A1 @BASEBOARD_FAB2_LIB.BASEBOARD_FAB2(SCH_1):PCA9555_A1   I163 @BASEBOARD_FAB2_LIB.BASEBOARD_FAB2(SCH_1):PAGE247
     2    GND @BASEBOARD_FAB2_LIB.BASEBOARD_FAB2(SCH_1):GND   I163 @BASEBOARD_FAB2_LIB.BASEBOARD_FAB2(SCH_1):PAGE247

R6W9 RES_0402-4.75K,1%,1/16W,EMPTY,A
     1 PCA9555_A0 @BASEBOARD_FAB2_LIB.BASEBOARD_FAB2(SCH_1):PCA9555_A0   I162 @BASEBOARD_FAB2_LIB.BASEBOARD_FAB2(SCH_1):PAGE247
     2    GND @BASEBOARD_FAB2_LIB.BASEBOARD_FAB2(SCH_1):GND   I162 @BASEBOARD_FAB2_LIB.BASEBOARD_FAB2(SCH_1):PAGE247

R6W10 RES_0402-4.75K,1%,1/16W,CHIP,GA
     1 P3V3_STBY @BASEBOARD_FAB2_LIB.BASEBOARD_FAB2(SCH_1):P3V3_STBY     I1 @BASEBOARD_FAB2_LIB.BASEBOARD_FAB2(SCH_1):PAGE247
     2 PCA9555_INT_N @BASEBOARD_FAB2_LIB.BASEBOARD_FAB2(SCH_1):PCA9555_INT_N     I1 @BASEBOARD_FAB2_LIB.BASEBOARD_FAB2(SCH_1):PAGE247

R6W11 RES_0402-4.75K,1%,1/16W,CHIP,GA
     1 SMB_DEBUG_STBY_LVC3_SCL @BASEBOARD_FAB2_LIB.BASEBOARD_FAB2(SCH_1):SMB_DEBUG_STBY_LVC3_SCL    I98 @BASEBOARD_FAB2_LIB.BASEBOARD_FAB2(SCH_1):PAGE247
     2 P3V3_STBY @BASEBOARD_FAB2_LIB.BASEBOARD_FAB2(SCH_1):P3V3_STBY    I98 @BASEBOARD_FAB2_LIB.BASEBOARD_FAB2(SCH_1):PAGE247

R6W12 RES_0402-4.75K,1%,1/16W,CHIP,GA
     1 SMB_DEBUG_STBY_LVC3_SDA @BASEBOARD_FAB2_LIB.BASEBOARD_FAB2(SCH_1):SMB_DEBUG_STBY_LVC3_SDA    I99 @BASEBOARD_FAB2_LIB.BASEBOARD_FAB2(SCH_1):PAGE247
     2 P3V3_STBY @BASEBOARD_FAB2_LIB.BASEBOARD_FAB2(SCH_1):P3V3_STBY    I99 @BASEBOARD_FAB2_LIB.BASEBOARD_FAB2(SCH_1):PAGE247

R6W16 RES_0402-1.00K,1%,1/16W,CHIP,GA
     1 P3V3_STBY @BASEBOARD_FAB2_LIB.BASEBOARD_FAB2(SCH_1):P3V3_STBY    I46 @BASEBOARD_FAB2_LIB.BASEBOARD_FAB2(SCH_1):PAGE168
     2 FM_SOL_UART_CH_SEL @BASEBOARD_FAB2_LIB.BASEBOARD_FAB2(SCH_1):FM_SOL_UART_CH_SEL    I46 @BASEBOARD_FAB2_LIB.BASEBOARD_FAB2(SCH_1):PAGE168

R6W17 RES_0402-0.0,5%,1/16W,CHIP,G21A
     1 SMB_DEBUG_STBY_LVC3_SCL @BASEBOARD_FAB2_LIB.BASEBOARD_FAB2(SCH_1):SMB_DEBUG_STBY_LVC3_SCL   I120 @BASEBOARD_FAB2_LIB.BASEBOARD_FAB2(SCH_1):PAGE145
     2 SMB_DEBUG_STBY_LVC3_SCL_R @BASEBOARD_FAB2_LIB.BASEBOARD_FAB2(SCH_1):SMB_DEBUG_STBY_LVC3_SCL_R   I120 @BASEBOARD_FAB2_LIB.BASEBOARD_FAB2(SCH_1):PAGE145

R6W18 RES_0402-0.0,5%,1/16W,CHIP,G21A
     1 SMB_DEBUG_STBY_LVC3_SDA @BASEBOARD_FAB2_LIB.BASEBOARD_FAB2(SCH_1):SMB_DEBUG_STBY_LVC3_SDA   I119 @BASEBOARD_FAB2_LIB.BASEBOARD_FAB2(SCH_1):PAGE145
     2 SMB_DEBUG_STBY_LVC3_SDA_R @BASEBOARD_FAB2_LIB.BASEBOARD_FAB2(SCH_1):SMB_DEBUG_STBY_LVC3_SDA_R   I119 @BASEBOARD_FAB2_LIB.BASEBOARD_FAB2(SCH_1):PAGE145

R6W19 RES_0402-0.0,5%,1/16W,CHIP,G21A
     1 SPA_5V_SIN_SW_D @BASEBOARD_FAB2_LIB.BASEBOARD_FAB2(SCH_1):SPA_5V_SIN_SW_D   I196 @BASEBOARD_FAB2_LIB.BASEBOARD_FAB2(SCH_1):PAGE155
     2 SPA_SIN_SW_R @BASEBOARD_FAB2_LIB.BASEBOARD_FAB2(SCH_1):SPA_SIN_SW_R   I196 @BASEBOARD_FAB2_LIB.BASEBOARD_FAB2(SCH_1):PAGE155

R6W20 RES_0402-20.0,1%,1/16W,CHIP,G2A
     1 SMB_HOST_STBY_LVC3_SDA_R3 @BASEBOARD_FAB2_LIB.BASEBOARD_FAB2(SCH_1):SMB_HOST_STBY_LVC3_SDA_R3    I87 @BASEBOARD_FAB2_LIB.BASEBOARD_FAB2(SCH_1):PAGE247
     2 SMB_HOST_STBY_LVC3_SDA @BASEBOARD_FAB2_LIB.BASEBOARD_FAB2(SCH_1):SMB_HOST_STBY_LVC3_SDA    I87 @BASEBOARD_FAB2_LIB.BASEBOARD_FAB2(SCH_1):PAGE247

R6W21 RES_0402-1.00K,1%,1/16W,CHIP,GA
     1 P3V3_STBY @BASEBOARD_FAB2_LIB.BASEBOARD_FAB2(SCH_1):P3V3_STBY    I90 @BASEBOARD_FAB2_LIB.BASEBOARD_FAB2(SCH_1):PAGE247
     2 PU_ID_EEPROM_A0 @BASEBOARD_FAB2_LIB.BASEBOARD_FAB2(SCH_1):PU_ID_EEPROM_A0    I90 @BASEBOARD_FAB2_LIB.BASEBOARD_FAB2(SCH_1):PAGE247

R6W22 RES_0402-20.0,1%,1/16W,CHIP,G2A
     1 SMB_HOST_STBY_LVC3_SCL @BASEBOARD_FAB2_LIB.BASEBOARD_FAB2(SCH_1):SMB_HOST_STBY_LVC3_SCL    I94 @BASEBOARD_FAB2_LIB.BASEBOARD_FAB2(SCH_1):PAGE247
     2 SMB_HOST_STBY_LVC3_SCL_R3 @BASEBOARD_FAB2_LIB.BASEBOARD_FAB2(SCH_1):SMB_HOST_STBY_LVC3_SCL_R3    I94 @BASEBOARD_FAB2_LIB.BASEBOARD_FAB2(SCH_1):PAGE247

R6W23 RES_0402-1.00K,1%,1/16W,CHIP,GA
     1 PD_ID_EEPROM_WP @BASEBOARD_FAB2_LIB.BASEBOARD_FAB2(SCH_1):PD_ID_EEPROM_WP    I92 @BASEBOARD_FAB2_LIB.BASEBOARD_FAB2(SCH_1):PAGE247
     2    GND @BASEBOARD_FAB2_LIB.BASEBOARD_FAB2(SCH_1):GND    I92 @BASEBOARD_FAB2_LIB.BASEBOARD_FAB2(SCH_1):PAGE247

R6W24 RES_0402-4.75K,1%,1/16W,CHIP,GA
     1 P3V3_STBY @BASEBOARD_FAB2_LIB.BASEBOARD_FAB2(SCH_1):P3V3_STBY   I100 @BASEBOARD_FAB2_LIB.BASEBOARD_FAB2(SCH_1):PAGE247
     2 SMB_PMBUS_BMC_STBY_LVC3_SDA_R1 @BASEBOARD_FAB2_LIB.BASEBOARD_FAB2(SCH_1):SMB_PMBUS_BMC_STBY_LVC3_SDA_R1   I100 @BASEBOARD_FAB2_LIB.BASEBOARD_FAB2(SCH_1):PAGE247

R6W25 RES_0402-4.75K,1%,1/16W,CHIP,GA
     1 P3V3_STBY @BASEBOARD_FAB2_LIB.BASEBOARD_FAB2(SCH_1):P3V3_STBY   I101 @BASEBOARD_FAB2_LIB.BASEBOARD_FAB2(SCH_1):PAGE247
     2 SMB_PMBUS_BMC_STBY_LVC3_SCL_R1 @BASEBOARD_FAB2_LIB.BASEBOARD_FAB2(SCH_1):SMB_PMBUS_BMC_STBY_LVC3_SCL_R1   I101 @BASEBOARD_FAB2_LIB.BASEBOARD_FAB2(SCH_1):PAGE247

R6W26 RES_0402-10.0,1%,1/16W,CHIP,G2A
     1 SMB_CPU0_PE_HP_GTL_SCL @BASEBOARD_FAB2_LIB.BASEBOARD_FAB2(SCH_1):SMB_CPU0_PE_HP_GTL_SCL    I24 @BASEBOARD_FAB2_LIB.BASEBOARD_FAB2(SCH_1):PAGE248
     2 SMB_CPU0_PE_HP_GTL_R_SCL @BASEBOARD_FAB2_LIB.BASEBOARD_FAB2(SCH_1):SMB_CPU0_PE_HP_GTL_R_SCL    I24 @BASEBOARD_FAB2_LIB.BASEBOARD_FAB2(SCH_1):PAGE248

R6W27 RES_0402-10.0,1%,1/16W,CHIP,G2A
     1 SMB_CPU0_PE_HP_GTL_SDA @BASEBOARD_FAB2_LIB.BASEBOARD_FAB2(SCH_1):SMB_CPU0_PE_HP_GTL_SDA    I25 @BASEBOARD_FAB2_LIB.BASEBOARD_FAB2(SCH_1):PAGE248
     2 SMB_CPU0_PE_HP_GTL_R_SDA @BASEBOARD_FAB2_LIB.BASEBOARD_FAB2(SCH_1):SMB_CPU0_PE_HP_GTL_R_SDA    I25 @BASEBOARD_FAB2_LIB.BASEBOARD_FAB2(SCH_1):PAGE248

R6W28 RES_0402-4.75K,1%,1/16W,CHIP,GA
     1 P3V3_STBY @BASEBOARD_FAB2_LIB.BASEBOARD_FAB2(SCH_1):P3V3_STBY   I112 @BASEBOARD_FAB2_LIB.BASEBOARD_FAB2(SCH_1):PAGE247
     2 HSC_SMBUS_SWITCH_EN @BASEBOARD_FAB2_LIB.BASEBOARD_FAB2(SCH_1):HSC_SMBUS_SWITCH_EN   I112 @BASEBOARD_FAB2_LIB.BASEBOARD_FAB2(SCH_1):PAGE247

R6W29 RES_0402-10.0K,1%,1/16W,CHIP,GA
     1 PVPP_ABC @BASEBOARD_FAB2_LIB.BASEBOARD_FAB2(SCH_1):PVPP_ABC    I40 @BASEBOARD_FAB2_LIB.BASEBOARD_FAB2(SCH_1):PAGE89
     2 FM_ADR_COMPLETE_CPU1_N @BASEBOARD_FAB2_LIB.BASEBOARD_FAB2(SCH_1):FM_ADR_COMPLETE_CPU1_N    I40 @BASEBOARD_FAB2_LIB.BASEBOARD_FAB2(SCH_1):PAGE89

R6W30 RES_0603-100.0K,1%,1/10W,CHIP,A
     1 P3V3_STBY @BASEBOARD_FAB2_LIB.BASEBOARD_FAB2(SCH_1):P3V3_STBY   I147 @BASEBOARD_FAB2_LIB.BASEBOARD_FAB2(SCH_1):PAGE176
     2 SPA_MID_DBG2_RX_BUF @BASEBOARD_FAB2_LIB.BASEBOARD_FAB2(SCH_1):SPA_MID_DBG2_RX_BUF   I147 @BASEBOARD_FAB2_LIB.BASEBOARD_FAB2(SCH_1):PAGE176

R6W35 RES_0402-100.0K,1%,1/16W,CHIP,A
     1 P3V3_STBY @BASEBOARD_FAB2_LIB.BASEBOARD_FAB2(SCH_1):P3V3_STBY   I165 @BASEBOARD_FAB2_LIB.BASEBOARD_FAB2(SCH_1):PAGE247
     2 FM_CPU_CATERR_MSMI_LVT3_N @BASEBOARD_FAB2_LIB.BASEBOARD_FAB2(SCH_1):FM_CPU_CATERR_MSMI_LVT3_N   I165 @BASEBOARD_FAB2_LIB.BASEBOARD_FAB2(SCH_1):PAGE247

R6W36 RES_0402-10.0,1%,1/16W,CHIP,G2A
     1 SPA_MID_DBG1_TX_R @BASEBOARD_FAB2_LIB.BASEBOARD_FAB2(SCH_1):SPA_MID_DBG1_TX_R   I161 @BASEBOARD_FAB2_LIB.BASEBOARD_FAB2(SCH_1):PAGE176
     2 SPA_MID_DBG1_TX @BASEBOARD_FAB2_LIB.BASEBOARD_FAB2(SCH_1):SPA_MID_DBG1_TX   I161 @BASEBOARD_FAB2_LIB.BASEBOARD_FAB2(SCH_1):PAGE176

R6W37 RES_0402-10.0,1%,1/16W,CHIP,G2A
     1 SPA_MID_DBG2_TX_R @BASEBOARD_FAB2_LIB.BASEBOARD_FAB2(SCH_1):SPA_MID_DBG2_TX_R   I160 @BASEBOARD_FAB2_LIB.BASEBOARD_FAB2(SCH_1):PAGE176
     2 SPA_MID_DBG2_TX @BASEBOARD_FAB2_LIB.BASEBOARD_FAB2(SCH_1):SPA_MID_DBG2_TX   I160 @BASEBOARD_FAB2_LIB.BASEBOARD_FAB2(SCH_1):PAGE176

R6W38 RES_0402-20.0K,1%,1/16W,CHIP,GA
     1 DEBUG_CARD2_PRSNT @BASEBOARD_FAB2_LIB.BASEBOARD_FAB2(SCH_1):DEBUG_CARD2_PRSNT   I156 @BASEBOARD_FAB2_LIB.BASEBOARD_FAB2(SCH_1):PAGE176
     2    GND @BASEBOARD_FAB2_LIB.BASEBOARD_FAB2(SCH_1):GND   I156 @BASEBOARD_FAB2_LIB.BASEBOARD_FAB2(SCH_1):PAGE176

R6W39 RES_0402-10.0K,1%,1/16W,CHIP,GA
     1 SPA_MID_DBG1_TX_EN @BASEBOARD_FAB2_LIB.BASEBOARD_FAB2(SCH_1):SPA_MID_DBG1_TX_EN   I158 @BASEBOARD_FAB2_LIB.BASEBOARD_FAB2(SCH_1):PAGE176
     2 P3V3_STBY @BASEBOARD_FAB2_LIB.BASEBOARD_FAB2(SCH_1):P3V3_STBY   I158 @BASEBOARD_FAB2_LIB.BASEBOARD_FAB2(SCH_1):PAGE176

R6W40 RES_0402-10.0K,1%,1/16W,CHIP,GA
     1 P3V3_STBY @BASEBOARD_FAB2_LIB.BASEBOARD_FAB2(SCH_1):P3V3_STBY   I201 @BASEBOARD_FAB2_LIB.BASEBOARD_FAB2(SCH_1):PAGE155
     2 SPA_5V_SIN_SW_D @BASEBOARD_FAB2_LIB.BASEBOARD_FAB2(SCH_1):SPA_5V_SIN_SW_D   I201 @BASEBOARD_FAB2_LIB.BASEBOARD_FAB2(SCH_1):PAGE155

R6W41 RES_0402-4.75K,1%,1/16W,CHIP,GA
     1 P3V3_STBY @BASEBOARD_FAB2_LIB.BASEBOARD_FAB2(SCH_1):P3V3_STBY    I87 @BASEBOARD_FAB2_LIB.BASEBOARD_FAB2(SCH_1):PAGE164
     2 PCA9554_INT_N @BASEBOARD_FAB2_LIB.BASEBOARD_FAB2(SCH_1):PCA9554_INT_N    I87 @BASEBOARD_FAB2_LIB.BASEBOARD_FAB2(SCH_1):PAGE164

R6W42 RES_0402-4.75K,1%,1/16W,EMPTY,A
     1 P3V3_STBY @BASEBOARD_FAB2_LIB.BASEBOARD_FAB2(SCH_1):P3V3_STBY    I95 @BASEBOARD_FAB2_LIB.BASEBOARD_FAB2(SCH_1):PAGE164
     2 PCA9554_A2 @BASEBOARD_FAB2_LIB.BASEBOARD_FAB2(SCH_1):PCA9554_A2    I95 @BASEBOARD_FAB2_LIB.BASEBOARD_FAB2(SCH_1):PAGE164

R6W43 RES_0402-4.75K,1%,1/16W,EMPTY,A
     1 P3V3_STBY @BASEBOARD_FAB2_LIB.BASEBOARD_FAB2(SCH_1):P3V3_STBY    I96 @BASEBOARD_FAB2_LIB.BASEBOARD_FAB2(SCH_1):PAGE164
     2 PCA9554_A1 @BASEBOARD_FAB2_LIB.BASEBOARD_FAB2(SCH_1):PCA9554_A1    I96 @BASEBOARD_FAB2_LIB.BASEBOARD_FAB2(SCH_1):PAGE164

R6W44 RES_0402-4.75K,1%,1/16W,CHIP,GA
     1 P3V3_STBY @BASEBOARD_FAB2_LIB.BASEBOARD_FAB2(SCH_1):P3V3_STBY    I78 @BASEBOARD_FAB2_LIB.BASEBOARD_FAB2(SCH_1):PAGE164
     2 PCA9554_A0 @BASEBOARD_FAB2_LIB.BASEBOARD_FAB2(SCH_1):PCA9554_A0    I78 @BASEBOARD_FAB2_LIB.BASEBOARD_FAB2(SCH_1):PAGE164

R6W45 RES_0402-4.75K,1%,1/16W,CHIP,GA
     1 PCA9554_A2 @BASEBOARD_FAB2_LIB.BASEBOARD_FAB2(SCH_1):PCA9554_A2    I94 @BASEBOARD_FAB2_LIB.BASEBOARD_FAB2(SCH_1):PAGE164
     2    GND @BASEBOARD_FAB2_LIB.BASEBOARD_FAB2(SCH_1):GND    I94 @BASEBOARD_FAB2_LIB.BASEBOARD_FAB2(SCH_1):PAGE164

R6W46 RES_0402-4.75K,1%,1/16W,CHIP,GA
     1 PCA9554_A1 @BASEBOARD_FAB2_LIB.BASEBOARD_FAB2(SCH_1):PCA9554_A1    I93 @BASEBOARD_FAB2_LIB.BASEBOARD_FAB2(SCH_1):PAGE164
     2    GND @BASEBOARD_FAB2_LIB.BASEBOARD_FAB2(SCH_1):GND    I93 @BASEBOARD_FAB2_LIB.BASEBOARD_FAB2(SCH_1):PAGE164

R6W47 RES_0402-4.75K,1%,1/16W,EMPTY,A
     1 PCA9554_A0 @BASEBOARD_FAB2_LIB.BASEBOARD_FAB2(SCH_1):PCA9554_A0    I76 @BASEBOARD_FAB2_LIB.BASEBOARD_FAB2(SCH_1):PAGE164
     2    GND @BASEBOARD_FAB2_LIB.BASEBOARD_FAB2(SCH_1):GND    I76 @BASEBOARD_FAB2_LIB.BASEBOARD_FAB2(SCH_1):PAGE164

R6W49 RES_0402-40.2K,1%,1/16W,CHIP,GA
     1 FM_UART_SWITCH_N @BASEBOARD_FAB2_LIB.BASEBOARD_FAB2(SCH_1):FM_UART_SWITCH_N    I48 @BASEBOARD_FAB2_LIB.BASEBOARD_FAB2(SCH_1):PAGE168
     2 FM_UART_SEL_N @BASEBOARD_FAB2_LIB.BASEBOARD_FAB2(SCH_1):FM_UART_SEL_N    I48 @BASEBOARD_FAB2_LIB.BASEBOARD_FAB2(SCH_1):PAGE168

R6W50 RES_0402-4.75K,1%,1/16W,CHIP,GA
     1 P3V3_STBY @BASEBOARD_FAB2_LIB.BASEBOARD_FAB2(SCH_1):P3V3_STBY   I178 @BASEBOARD_FAB2_LIB.BASEBOARD_FAB2(SCH_1):PAGE176
     2 SPA_MID_DBG2_RX @BASEBOARD_FAB2_LIB.BASEBOARD_FAB2(SCH_1):SPA_MID_DBG2_RX   I178 @BASEBOARD_FAB2_LIB.BASEBOARD_FAB2(SCH_1):PAGE176

R7A7 RES_0402-10.0,1%,1/16W,CHIP,G2A
     1 VSENSE_PVDDQ_DEF_P @BASEBOARD_FAB2_LIB.BASEBOARD_FAB2(SCH_1):VSENSE_PVDDQ_DEF_P    I13 @BASEBOARD_FAB2_LIB.BASEBOARD_FAB2(SCH_1):PAGE218
     2 VR_PVDDQ_DEF_AVSP @BASEBOARD_FAB2_LIB.BASEBOARD_FAB2(SCH_1):VR_PVDDQ_DEF_AVSP    I13 @BASEBOARD_FAB2_LIB.BASEBOARD_FAB2(SCH_1):PAGE218

R7A8 RES_0402-2.26K,1.0%,1/16W,CHIPA
     1 VR_PVDDQ_DEF_XADDR2 @BASEBOARD_FAB2_LIB.BASEBOARD_FAB2(SCH_1):VR_PVDDQ_DEF_XADDR2    I74 @BASEBOARD_FAB2_LIB.BASEBOARD_FAB2(SCH_1):PAGE218
     2    GND @BASEBOARD_FAB2_LIB.BASEBOARD_FAB2(SCH_1):GND    I74 @BASEBOARD_FAB2_LIB.BASEBOARD_FAB2(SCH_1):PAGE218

R7A9 RES_0402-2.26K,1.0%,1/16W,CHIPA
     1 P3V3_STBY @BASEBOARD_FAB2_LIB.BASEBOARD_FAB2(SCH_1):P3V3_STBY    I76 @BASEBOARD_FAB2_LIB.BASEBOARD_FAB2(SCH_1):PAGE218
     2 PWRGD_PVDDQ_DEF @BASEBOARD_FAB2_LIB.BASEBOARD_FAB2(SCH_1):PWRGD_PVDDQ_DEF    I76 @BASEBOARD_FAB2_LIB.BASEBOARD_FAB2(SCH_1):PAGE218

R7A10 RES_0402-16K,1.0%,1/16W,CHIP,GA
     1 VR_PVDDQ_DEF_XADDR1 @BASEBOARD_FAB2_LIB.BASEBOARD_FAB2(SCH_1):VR_PVDDQ_DEF_XADDR1    I73 @BASEBOARD_FAB2_LIB.BASEBOARD_FAB2(SCH_1):PAGE218
     2    GND @BASEBOARD_FAB2_LIB.BASEBOARD_FAB2(SCH_1):GND    I73 @BASEBOARD_FAB2_LIB.BASEBOARD_FAB2(SCH_1):PAGE218

R7A11 RES_0402-0.0,5%,1/16W,CHIP,G21A
     1 SVID_ALERT_PVDDQ_DEF @BASEBOARD_FAB2_LIB.BASEBOARD_FAB2(SCH_1):SVID_ALERT_PVDDQ_DEF    I56 @BASEBOARD_FAB2_LIB.BASEBOARD_FAB2(SCH_1):PAGE218
     2 SVID_ALERT1_CPU0_R_N @BASEBOARD_FAB2_LIB.BASEBOARD_FAB2(SCH_1):SVID_ALERT1_CPU0_R_N    I56 @BASEBOARD_FAB2_LIB.BASEBOARD_FAB2(SCH_1):PAGE218

R7A12 RES_0402-0.0,5%,1/16W,CHIP,G21A
     1 SVID_VDIO_PVDDQ_DEF @BASEBOARD_FAB2_LIB.BASEBOARD_FAB2(SCH_1):SVID_VDIO_PVDDQ_DEF    I45 @BASEBOARD_FAB2_LIB.BASEBOARD_FAB2(SCH_1):PAGE218
     2 SVID_DIO1_CPU0_R @BASEBOARD_FAB2_LIB.BASEBOARD_FAB2(SCH_1):SVID_DIO1_CPU0_R    I45 @BASEBOARD_FAB2_LIB.BASEBOARD_FAB2(SCH_1):PAGE218

R7A13 RES_0402-100.0,1%,1/16W,CHIP,GA
     1 VSENSE_PVNN_PCH_STBY_AVSP @BASEBOARD_FAB2_LIB.BASEBOARD_FAB2(SCH_1):VSENSE_PVNN_PCH_STBY_AVSP    I90 @BASEBOARD_FAB2_LIB.BASEBOARD_FAB2(SCH_1):PAGE236
     2 PVNN_PCH_STBY @BASEBOARD_FAB2_LIB.BASEBOARD_FAB2(SCH_1):PVNN_PCH_STBY    I90 @BASEBOARD_FAB2_LIB.BASEBOARD_FAB2(SCH_1):PAGE236

R7A14 RES_0402-10.0,1%,1/16W,CHIP,G2A
     1 VSENSE_PVNN_PCH_STBY_FPK @BASEBOARD_FAB2_LIB.BASEBOARD_FAB2(SCH_1):VSENSE_PVNN_PCH_STBY_FPK    I94 @BASEBOARD_FAB2_LIB.BASEBOARD_FAB2(SCH_1):PAGE236
     2 VSENSE_PVNN_PCH_STBY_AVSP @BASEBOARD_FAB2_LIB.BASEBOARD_FAB2(SCH_1):VSENSE_PVNN_PCH_STBY_AVSP    I94 @BASEBOARD_FAB2_LIB.BASEBOARD_FAB2(SCH_1):PAGE236

R7A15 RES_0402-2.2,5%,1/16W,EMPTY,G2A
     1 VR_PVPP_DEF_SNUB @BASEBOARD_FAB2_LIB.BASEBOARD_FAB2(SCH_1):VR_PVPP_DEF_SNUB   I218 @BASEBOARD_FAB2_LIB.BASEBOARD_FAB2(SCH_1):PAGE232
     2    GND @BASEBOARD_FAB2_LIB.BASEBOARD_FAB2(SCH_1):GND   I218 @BASEBOARD_FAB2_LIB.BASEBOARD_FAB2(SCH_1):PAGE232

R7A17 RES_0402-150.0,1%,1/16W,CHIP,GA
     1 SVID_CLK1_CPU0_R @BASEBOARD_FAB2_LIB.BASEBOARD_FAB2(SCH_1):SVID_CLK1_CPU0_R    I21 @BASEBOARD_FAB2_LIB.BASEBOARD_FAB2(SCH_1):PAGE218
     2 SVID_CLK_PVDDQ_DEF @BASEBOARD_FAB2_LIB.BASEBOARD_FAB2(SCH_1):SVID_CLK_PVDDQ_DEF    I21 @BASEBOARD_FAB2_LIB.BASEBOARD_FAB2(SCH_1):PAGE218

R7A18 RES_0402-0.0,5%,1/16W,CHIP,G21A
     1    GND @BASEBOARD_FAB2_LIB.BASEBOARD_FAB2(SCH_1):GND    I92 @BASEBOARD_FAB2_LIB.BASEBOARD_FAB2(SCH_1):PAGE236
     2 VSENSE_PVNN_PCH_STBY_AVSN @BASEBOARD_FAB2_LIB.BASEBOARD_FAB2(SCH_1):VSENSE_PVNN_PCH_STBY_AVSN    I92 @BASEBOARD_FAB2_LIB.BASEBOARD_FAB2(SCH_1):PAGE236

R7A19 RES_0402-10.0,1%,1/16W,CHIP,G2A
     1 VSENSE_PVNN_PCH_STBY_QAT @BASEBOARD_FAB2_LIB.BASEBOARD_FAB2(SCH_1):VSENSE_PVNN_PCH_STBY_QAT    I93 @BASEBOARD_FAB2_LIB.BASEBOARD_FAB2(SCH_1):PAGE236
     2 VSENSE_PVNN_PCH_STBY_AVSP @BASEBOARD_FAB2_LIB.BASEBOARD_FAB2(SCH_1):VSENSE_PVNN_PCH_STBY_AVSP    I93 @BASEBOARD_FAB2_LIB.BASEBOARD_FAB2(SCH_1):PAGE236

R7A20 RES_0402-68.1K,1%,1/16W,EMPTY,A
     1 VR_PVDDQ_DEF_PH1_OCSET @BASEBOARD_FAB2_LIB.BASEBOARD_FAB2(SCH_1):VR_PVDDQ_DEF_PH1_OCSET   I108 @BASEBOARD_FAB2_LIB.BASEBOARD_FAB2(SCH_1):PAGE219
     2    GND @BASEBOARD_FAB2_LIB.BASEBOARD_FAB2(SCH_1):GND   I108 @BASEBOARD_FAB2_LIB.BASEBOARD_FAB2(SCH_1):PAGE219

R7A21 RES_0402-68.1K,1%,1/16W,EMPTY,A
     1 VR_PVDDQ_DEF_PH2_OCSET @BASEBOARD_FAB2_LIB.BASEBOARD_FAB2(SCH_1):VR_PVDDQ_DEF_PH2_OCSET   I110 @BASEBOARD_FAB2_LIB.BASEBOARD_FAB2(SCH_1):PAGE219
     2    GND @BASEBOARD_FAB2_LIB.BASEBOARD_FAB2(SCH_1):GND   I110 @BASEBOARD_FAB2_LIB.BASEBOARD_FAB2(SCH_1):PAGE219

R7B1 RES_0402-33.2,1%,1/16W,CHIP,G2A
     1 IRQ_PVDDQ_DEF_VRHOT_LVT3_R_N @BASEBOARD_FAB2_LIB.BASEBOARD_FAB2(SCH_1):IRQ_PVDDQ_DEF_VRHOT_LVT3_R_N    I59 @BASEBOARD_FAB2_LIB.BASEBOARD_FAB2(SCH_1):PAGE218
     2 IRQ_PVDDQ_DEF_VRHOT_LVT3_N @BASEBOARD_FAB2_LIB.BASEBOARD_FAB2(SCH_1):IRQ_PVDDQ_DEF_VRHOT_LVT3_N    I59 @BASEBOARD_FAB2_LIB.BASEBOARD_FAB2(SCH_1):PAGE218

R7B4 RES_0402-1.00K,1%,1/16W,CHIP,GA
     1 P3V3_STBY @BASEBOARD_FAB2_LIB.BASEBOARD_FAB2(SCH_1):P3V3_STBY    I57 @BASEBOARD_FAB2_LIB.BASEBOARD_FAB2(SCH_1):PAGE218
     2 IRQ_PVDDQ_DEF_VRHOT_LVT3_R_N @BASEBOARD_FAB2_LIB.BASEBOARD_FAB2(SCH_1):IRQ_PVDDQ_DEF_VRHOT_LVT3_R_N    I57 @BASEBOARD_FAB2_LIB.BASEBOARD_FAB2(SCH_1):PAGE218

R7B5 RES_0402-1.00K,1%,1/16W,CHIP,GA
     1 P3V3_STBY @BASEBOARD_FAB2_LIB.BASEBOARD_FAB2(SCH_1):P3V3_STBY    I58 @BASEBOARD_FAB2_LIB.BASEBOARD_FAB2(SCH_1):PAGE218
     2 PWRGD_PVDDQ_DEF_R @BASEBOARD_FAB2_LIB.BASEBOARD_FAB2(SCH_1):PWRGD_PVDDQ_DEF_R    I58 @BASEBOARD_FAB2_LIB.BASEBOARD_FAB2(SCH_1):PAGE218

R7B6 RES_0402-10.0K,1%,1/16W,CHIP,GA
     1 P3V3_STBY @BASEBOARD_FAB2_LIB.BASEBOARD_FAB2(SCH_1):P3V3_STBY   I295 @BASEBOARD_FAB2_LIB.BASEBOARD_FAB2(SCH_1):PAGE133
     2 FM_PCH_PRSNT_N @BASEBOARD_FAB2_LIB.BASEBOARD_FAB2(SCH_1):FM_PCH_PRSNT_N   I295 @BASEBOARD_FAB2_LIB.BASEBOARD_FAB2(SCH_1):PAGE133

R7B7 RES_0402-10.0K,1%,1/16W,EMPTY,A
     1 A_EXTCLKP @BASEBOARD_FAB2_LIB.BASEBOARD_FAB2(SCH_1):A_EXTCLKP   I230 @BASEBOARD_FAB2_LIB.BASEBOARD_FAB2(SCH_1):PAGE116
     2    GND @BASEBOARD_FAB2_LIB.BASEBOARD_FAB2(SCH_1):GND   I230 @BASEBOARD_FAB2_LIB.BASEBOARD_FAB2(SCH_1):PAGE116

R7B8 RES_0402-10.0K,1%,1/16W,EMPTY,A
     1 A_EXTCLKN @BASEBOARD_FAB2_LIB.BASEBOARD_FAB2(SCH_1):A_EXTCLKN   I229 @BASEBOARD_FAB2_LIB.BASEBOARD_FAB2(SCH_1):PAGE116
     2    GND @BASEBOARD_FAB2_LIB.BASEBOARD_FAB2(SCH_1):GND   I229 @BASEBOARD_FAB2_LIB.BASEBOARD_FAB2(SCH_1):PAGE116

R7B9 RES_0402-0.0,5%,1/16W,CHIP,G21A
     1 FM_PVPP_CPU0_EN @BASEBOARD_FAB2_LIB.BASEBOARD_FAB2(SCH_1):FM_PVPP_CPU0_EN   I307 @BASEBOARD_FAB2_LIB.BASEBOARD_FAB2(SCH_1):PAGE232
     2 FM_PVPP_PVDDQ_CPU0_EN_DEF @BASEBOARD_FAB2_LIB.BASEBOARD_FAB2(SCH_1):FM_PVPP_PVDDQ_CPU0_EN_DEF   I307 @BASEBOARD_FAB2_LIB.BASEBOARD_FAB2(SCH_1):PAGE232

R7B10 RES_0603-120.0,1%,1/10W,CHIP,GA
     1 PVPP_DEF @BASEBOARD_FAB2_LIB.BASEBOARD_FAB2(SCH_1):PVPP_DEF   I227 @BASEBOARD_FAB2_LIB.BASEBOARD_FAB2(SCH_1):PAGE232
     2    GND @BASEBOARD_FAB2_LIB.BASEBOARD_FAB2(SCH_1):GND   I227 @BASEBOARD_FAB2_LIB.BASEBOARD_FAB2(SCH_1):PAGE232

R7B11 RES_0402-0.0,5%,1/16W,CHIP,G21A
     1 PVPP_DEF @BASEBOARD_FAB2_LIB.BASEBOARD_FAB2(SCH_1):PVPP_DEF   I299 @BASEBOARD_FAB2_LIB.BASEBOARD_FAB2(SCH_1):PAGE232
     2 VSENSE_PVPP_DEF @BASEBOARD_FAB2_LIB.BASEBOARD_FAB2(SCH_1):VSENSE_PVPP_DEF   I299 @BASEBOARD_FAB2_LIB.BASEBOARD_FAB2(SCH_1):PAGE232

R7B12 RES_0402-22.1,1.0%,1/16W,CHIP,A
     1 PWRGD_PVPP_DEF_R @BASEBOARD_FAB2_LIB.BASEBOARD_FAB2(SCH_1):PWRGD_PVPP_DEF_R   I257 @BASEBOARD_FAB2_LIB.BASEBOARD_FAB2(SCH_1):PAGE232
     2 PWRGD_PVPP_DEF @BASEBOARD_FAB2_LIB.BASEBOARD_FAB2(SCH_1):PWRGD_PVPP_DEF   I257 @BASEBOARD_FAB2_LIB.BASEBOARD_FAB2(SCH_1):PAGE232

R7B13 RES_0402-6.19K,1%,1/16W,CHIP,GA
     1 VR_FB_PVPP_DEF @BASEBOARD_FAB2_LIB.BASEBOARD_FAB2(SCH_1):VR_FB_PVPP_DEF   I314 @BASEBOARD_FAB2_LIB.BASEBOARD_FAB2(SCH_1):PAGE232
     2 AGND_PVPP_DEF @BASEBOARD_FAB2_LIB.BASEBOARD_FAB2(SCH_1):AGND_PVPP_DEF   I314 @BASEBOARD_FAB2_LIB.BASEBOARD_FAB2(SCH_1):PAGE232

R7B14 RES_0402-7.87K,1.0%,1/16W,CHIPA
     1 VR_PVPP_DEF_ISET @BASEBOARD_FAB2_LIB.BASEBOARD_FAB2(SCH_1):VR_PVPP_DEF_ISET   I315 @BASEBOARD_FAB2_LIB.BASEBOARD_FAB2(SCH_1):PAGE232
     2 AGND_PVPP_DEF @BASEBOARD_FAB2_LIB.BASEBOARD_FAB2(SCH_1):AGND_PVPP_DEF   I315 @BASEBOARD_FAB2_LIB.BASEBOARD_FAB2(SCH_1):PAGE232

R7B15 RES_0402-20.0K,1%,1/16W,CHIP,GA
     1 VSENSE_PVPP_DEF @BASEBOARD_FAB2_LIB.BASEBOARD_FAB2(SCH_1):VSENSE_PVPP_DEF   I303 @BASEBOARD_FAB2_LIB.BASEBOARD_FAB2(SCH_1):PAGE232
     2 VR_FB_PVPP_DEF @BASEBOARD_FAB2_LIB.BASEBOARD_FAB2(SCH_1):VR_FB_PVPP_DEF   I303 @BASEBOARD_FAB2_LIB.BASEBOARD_FAB2(SCH_1):PAGE232

R7B16 RES_0402-7.87K,1.0%,1/16W,CHIPA
     1 VR_COMP_RC_PVPP_DEF @BASEBOARD_FAB2_LIB.BASEBOARD_FAB2(SCH_1):VR_COMP_RC_PVPP_DEF   I300 @BASEBOARD_FAB2_LIB.BASEBOARD_FAB2(SCH_1):PAGE232
     2 VR_FB_PVPP_DEF @BASEBOARD_FAB2_LIB.BASEBOARD_FAB2(SCH_1):VR_FB_PVPP_DEF   I300 @BASEBOARD_FAB2_LIB.BASEBOARD_FAB2(SCH_1):PAGE232

R7B17 RES_0402-1.00K,1%,1/16W,CHIP,GA
     1 P3V3_STBY @BASEBOARD_FAB2_LIB.BASEBOARD_FAB2(SCH_1):P3V3_STBY   I210 @BASEBOARD_FAB2_LIB.BASEBOARD_FAB2(SCH_1):PAGE232
     2 PWRGD_PVPP_DEF_R @BASEBOARD_FAB2_LIB.BASEBOARD_FAB2(SCH_1):PWRGD_PVPP_DEF_R   I210 @BASEBOARD_FAB2_LIB.BASEBOARD_FAB2(SCH_1):PAGE232

R7B18 RES_0402-1.0K,0.1%,1/16W,CHIP,A
     1 VSENSE_PVPP_DEF @BASEBOARD_FAB2_LIB.BASEBOARD_FAB2(SCH_1):VSENSE_PVPP_DEF   I298 @BASEBOARD_FAB2_LIB.BASEBOARD_FAB2(SCH_1):PAGE232
     2 VR_COMP_PVPP_DEF @BASEBOARD_FAB2_LIB.BASEBOARD_FAB2(SCH_1):VR_COMP_PVPP_DEF   I298 @BASEBOARD_FAB2_LIB.BASEBOARD_FAB2(SCH_1):PAGE232

R7B19 RES_0603-0,5.0%,1/10W,CHIP,G22A
     1 VR_PVPP_DEF_BOOT @BASEBOARD_FAB2_LIB.BASEBOARD_FAB2(SCH_1):VR_PVPP_DEF_BOOT   I313 @BASEBOARD_FAB2_LIB.BASEBOARD_FAB2(SCH_1):PAGE232
     2 VR_PVPP_DEF_BOOT_R @BASEBOARD_FAB2_LIB.BASEBOARD_FAB2(SCH_1):VR_PVPP_DEF_BOOT_R   I313 @BASEBOARD_FAB2_LIB.BASEBOARD_FAB2(SCH_1):PAGE232

R7B20 RES_0402-0.0,5%,1/16W,CHIP,G21A
     1    GND @BASEBOARD_FAB2_LIB.BASEBOARD_FAB2(SCH_1):GND   I150 @BASEBOARD_FAB2_LIB.BASEBOARD_FAB2(SCH_1):PAGE232
     2 AGND_PVPP_DEF @BASEBOARD_FAB2_LIB.BASEBOARD_FAB2(SCH_1):AGND_PVPP_DEF   I150 @BASEBOARD_FAB2_LIB.BASEBOARD_FAB2(SCH_1):PAGE232

R7C1 RES_0603-200K,0.1%,1/10W,CHIP,A
     1 XTAL_PCH_48M_IN @BASEBOARD_FAB2_LIB.BASEBOARD_FAB2(SCH_1):XTAL_PCH_48M_IN    I48 @BASEBOARD_FAB2_LIB.BASEBOARD_FAB2(SCH_1):PAGE114
     2 XTAL_PCH_48M_OUT @BASEBOARD_FAB2_LIB.BASEBOARD_FAB2(SCH_1):XTAL_PCH_48M_OUT    I48 @BASEBOARD_FAB2_LIB.BASEBOARD_FAB2(SCH_1):PAGE114

R7C2 RES_0402-0.0,5%,1/16W,CHIP,G21A
     1 CLK_100M_BMC_PE_R_DN @BASEBOARD_FAB2_LIB.BASEBOARD_FAB2(SCH_1):CLK_100M_BMC_PE_R_DN   I192 @BASEBOARD_FAB2_LIB.BASEBOARD_FAB2(SCH_1):PAGE114
     2 CLK_100M_BMC_PE_DN @BASEBOARD_FAB2_LIB.BASEBOARD_FAB2(SCH_1):CLK_100M_BMC_PE_DN   I192 @BASEBOARD_FAB2_LIB.BASEBOARD_FAB2(SCH_1):PAGE114

R7C3 RES_0402-51.1,1.0%,1/16W,CHIP,A
     1 PVCCIO_CPU0 @BASEBOARD_FAB2_LIB.BASEBOARD_FAB2(SCH_1):PVCCIO_CPU0    I78 @BASEBOARD_FAB2_LIB.BASEBOARD_FAB2(SCH_1):PAGE212
     2    GND @BASEBOARD_FAB2_LIB.BASEBOARD_FAB2(SCH_1):GND    I78 @BASEBOARD_FAB2_LIB.BASEBOARD_FAB2(SCH_1):PAGE212

R7C4 RES_0402-0.0,5%,1/16W,CHIP,G21A
     1 CLK_100M_BMC_PE_R_DP @BASEBOARD_FAB2_LIB.BASEBOARD_FAB2(SCH_1):CLK_100M_BMC_PE_R_DP   I191 @BASEBOARD_FAB2_LIB.BASEBOARD_FAB2(SCH_1):PAGE114
     2 CLK_100M_BMC_PE_DP @BASEBOARD_FAB2_LIB.BASEBOARD_FAB2(SCH_1):CLK_100M_BMC_PE_DP   I191 @BASEBOARD_FAB2_LIB.BASEBOARD_FAB2(SCH_1):PAGE114

R7C5 RES_0402-10.0K,1%,1/16W,CHIP,GA
     1 P3V3_STBY @BASEBOARD_FAB2_LIB.BASEBOARD_FAB2(SCH_1):P3V3_STBY   I297 @BASEBOARD_FAB2_LIB.BASEBOARD_FAB2(SCH_1):PAGE133
     2 FM_SINT_PRSNT_N @BASEBOARD_FAB2_LIB.BASEBOARD_FAB2(SCH_1):FM_SINT_PRSNT_N   I297 @BASEBOARD_FAB2_LIB.BASEBOARD_FAB2(SCH_1):PAGE133

R7C6 RES_0603-10M,1.0%,1/10W,CHIP,GA
     1 XTAL_33K_RTC1 @BASEBOARD_FAB2_LIB.BASEBOARD_FAB2(SCH_1):XTAL_33K_RTC1    I54 @BASEBOARD_FAB2_LIB.BASEBOARD_FAB2(SCH_1):PAGE114
     2 XTAL_33K_RTC2 @BASEBOARD_FAB2_LIB.BASEBOARD_FAB2(SCH_1):XTAL_33K_RTC2    I54 @BASEBOARD_FAB2_LIB.BASEBOARD_FAB2(SCH_1):PAGE114

R7C8 RES_0402-10.0K,1%,1/16W,CHIP,GA
     1 P3V3_STBY @BASEBOARD_FAB2_LIB.BASEBOARD_FAB2(SCH_1):P3V3_STBY   I296 @BASEBOARD_FAB2_LIB.BASEBOARD_FAB2(SCH_1):PAGE133
     2 FM_WBG_PRSNT_N @BASEBOARD_FAB2_LIB.BASEBOARD_FAB2(SCH_1):FM_WBG_PRSNT_N   I296 @BASEBOARD_FAB2_LIB.BASEBOARD_FAB2(SCH_1):PAGE133

R7C10 RES_0402-20.0K,1%,1/16W,CHIP,GA
     1 P3V3_RTC_STBY @BASEBOARD_FAB2_LIB.BASEBOARD_FAB2(SCH_1):P3V3_RTC_STBY    I13 @BASEBOARD_FAB2_LIB.BASEBOARD_FAB2(SCH_1):PAGE137
     2 RST_RTCRST_N @BASEBOARD_FAB2_LIB.BASEBOARD_FAB2(SCH_1):RST_RTCRST_N    I13 @BASEBOARD_FAB2_LIB.BASEBOARD_FAB2(SCH_1):PAGE137

R7C11 RES_0402-1.0M,1%,1/16W,EMPTY,GA
     1    GND @BASEBOARD_FAB2_LIB.BASEBOARD_FAB2(SCH_1):GND    I11 @BASEBOARD_FAB2_LIB.BASEBOARD_FAB2(SCH_1):PAGE137
     2 RST_RTCRST_N @BASEBOARD_FAB2_LIB.BASEBOARD_FAB2(SCH_1):RST_RTCRST_N    I11 @BASEBOARD_FAB2_LIB.BASEBOARD_FAB2(SCH_1):PAGE137

R7C13 RES_0402-10.0K,1%,1/16W,CHIP,GA
     1 P3V3_STBY @BASEBOARD_FAB2_LIB.BASEBOARD_FAB2(SCH_1):P3V3_STBY    I67 @BASEBOARD_FAB2_LIB.BASEBOARD_FAB2(SCH_1):PAGE137
     2 FM_UART_PRES_N @BASEBOARD_FAB2_LIB.BASEBOARD_FAB2(SCH_1):FM_UART_PRES_N    I67 @BASEBOARD_FAB2_LIB.BASEBOARD_FAB2(SCH_1):PAGE137

R7C14 RES_0402-33.2,1%,1/16W,CHIP,G2A
     1 RMII_BMC_PCH_SPRNGVLLE_RXER @BASEBOARD_FAB2_LIB.BASEBOARD_FAB2(SCH_1):RMII_BMC_PCH_SPRNGVLLE_RXER    I98 @BASEBOARD_FAB2_LIB.BASEBOARD_FAB2(SCH_1):PAGE121
     2 RMII_BMC_PCH_SPRNGVLLE_RXER_R @BASEBOARD_FAB2_LIB.BASEBOARD_FAB2(SCH_1):RMII_BMC_PCH_SPRNGVLLE_RXER_R    I98 @BASEBOARD_FAB2_LIB.BASEBOARD_FAB2(SCH_1):PAGE121

R7C15 RES_0402-0.0,5%,1/16W,CHIP,G21A
     1 SPI_PCH_MOSI_R @BASEBOARD_FAB2_LIB.BASEBOARD_FAB2(SCH_1):SPI_PCH_MOSI_R    I31 @BASEBOARD_FAB2_LIB.BASEBOARD_FAB2(SCH_1):PAGE121
     2 SPI_PCH_MOSI @BASEBOARD_FAB2_LIB.BASEBOARD_FAB2(SCH_1):SPI_PCH_MOSI    I31 @BASEBOARD_FAB2_LIB.BASEBOARD_FAB2(SCH_1):PAGE121

R7C16 RES_0402-33.2,1%,1/16W,CHIP,G2A
     1 SPI_PCH_CS0_R_N @BASEBOARD_FAB2_LIB.BASEBOARD_FAB2(SCH_1):SPI_PCH_CS0_R_N    I33 @BASEBOARD_FAB2_LIB.BASEBOARD_FAB2(SCH_1):PAGE121
     2 SPI_PCH_CS0_N @BASEBOARD_FAB2_LIB.BASEBOARD_FAB2(SCH_1):SPI_PCH_CS0_N    I33 @BASEBOARD_FAB2_LIB.BASEBOARD_FAB2(SCH_1):PAGE121

R7C17 RES_0402-4.75K,1%,1/16W,CHIP,GA
     1 PVCCIO_CPU0 @BASEBOARD_FAB2_LIB.BASEBOARD_FAB2(SCH_1):PVCCIO_CPU0    I28 @BASEBOARD_FAB2_LIB.BASEBOARD_FAB2(SCH_1):PAGE166
     2 PECI_BMC @BASEBOARD_FAB2_LIB.BASEBOARD_FAB2(SCH_1):PECI_BMC    I28 @BASEBOARD_FAB2_LIB.BASEBOARD_FAB2(SCH_1):PAGE166

R7C20 RES_0402-10.0K,1%,1/16W,CHIP,GA
     1 CLK_50M_CKMNG_PCH_10GBE @BASEBOARD_FAB2_LIB.BASEBOARD_FAB2(SCH_1):CLK_50M_CKMNG_PCH_10GBE    I73 @BASEBOARD_FAB2_LIB.BASEBOARD_FAB2(SCH_1):PAGE121
     2    GND @BASEBOARD_FAB2_LIB.BASEBOARD_FAB2(SCH_1):GND    I73 @BASEBOARD_FAB2_LIB.BASEBOARD_FAB2(SCH_1):PAGE121

R7C21 RES_0402-10.0K,1%,1/16W,CHIP,GA
     1 P1V05_PCH_STBY @BASEBOARD_FAB2_LIB.BASEBOARD_FAB2(SCH_1):P1V05_PCH_STBY     I9 @BASEBOARD_FAB2_LIB.BASEBOARD_FAB2(SCH_1):PAGE134
     2 FM_PCH_LVC1_THERMTRIP_N @BASEBOARD_FAB2_LIB.BASEBOARD_FAB2(SCH_1):FM_PCH_LVC1_THERMTRIP_N     I9 @BASEBOARD_FAB2_LIB.BASEBOARD_FAB2(SCH_1):PAGE134

R7C23 RES_0402-10.0K,1%,1/16W,CHIP,GA
     1 P3V3_STBY @BASEBOARD_FAB2_LIB.BASEBOARD_FAB2(SCH_1):P3V3_STBY   I144 @BASEBOARD_FAB2_LIB.BASEBOARD_FAB2(SCH_1):PAGE118
     2 XDP_PCH_PWR_DEBUG_N @BASEBOARD_FAB2_LIB.BASEBOARD_FAB2(SCH_1):XDP_PCH_PWR_DEBUG_N   I144 @BASEBOARD_FAB2_LIB.BASEBOARD_FAB2(SCH_1):PAGE118

R7C24 RES_0402-4.02K,1%,1/16W,CHIP,GA
     1 VR_PVCCMCP_CPU0_XADDR2 @BASEBOARD_FAB2_LIB.BASEBOARD_FAB2(SCH_1):VR_PVCCMCP_CPU0_XADDR2   I155 @BASEBOARD_FAB2_LIB.BASEBOARD_FAB2(SCH_1):PAGE194
     2    GND @BASEBOARD_FAB2_LIB.BASEBOARD_FAB2(SCH_1):GND   I155 @BASEBOARD_FAB2_LIB.BASEBOARD_FAB2(SCH_1):PAGE194

R7C25 RES_0402-68.1K,1%,1/16W,EMPTY,A
     1 VR_PVCCIO_CPU0_OCSET @BASEBOARD_FAB2_LIB.BASEBOARD_FAB2(SCH_1):VR_PVCCIO_CPU0_OCSET   I103 @BASEBOARD_FAB2_LIB.BASEBOARD_FAB2(SCH_1):PAGE212
     2    GND @BASEBOARD_FAB2_LIB.BASEBOARD_FAB2(SCH_1):GND   I103 @BASEBOARD_FAB2_LIB.BASEBOARD_FAB2(SCH_1):PAGE212

R7C26 RES_0402-33.2,1%,1/16W,CHIP,G2A
     1 CLK_24M_BMC_LPC @BASEBOARD_FAB2_LIB.BASEBOARD_FAB2(SCH_1):CLK_24M_BMC_LPC   I189 @BASEBOARD_FAB2_LIB.BASEBOARD_FAB2(SCH_1):PAGE119
     2 CLK_24M_BMC_LPC_R @BASEBOARD_FAB2_LIB.BASEBOARD_FAB2(SCH_1):CLK_24M_BMC_LPC_R   I189 @BASEBOARD_FAB2_LIB.BASEBOARD_FAB2(SCH_1):PAGE119

R7D1 RES_0402-1.00K,1%,1/16W,EMPTY,A
     1 RMII_PCH_SPRNGVLLE_ARB_OUT @BASEBOARD_FAB2_LIB.BASEBOARD_FAB2(SCH_1):RMII_PCH_SPRNGVLLE_ARB_OUT    I86 @BASEBOARD_FAB2_LIB.BASEBOARD_FAB2(SCH_1):PAGE125
     2    GND @BASEBOARD_FAB2_LIB.BASEBOARD_FAB2(SCH_1):GND    I86 @BASEBOARD_FAB2_LIB.BASEBOARD_FAB2(SCH_1):PAGE125

R7D2 RES_0402-1.00K,1%,1/16W,CHIP,GA
     1 P3V3_STBY @BASEBOARD_FAB2_LIB.BASEBOARD_FAB2(SCH_1):P3V3_STBY   I332 @BASEBOARD_FAB2_LIB.BASEBOARD_FAB2(SCH_1):PAGE133
     2 PU_FM_RCIN_N @BASEBOARD_FAB2_LIB.BASEBOARD_FAB2(SCH_1):PU_FM_RCIN_N   I332 @BASEBOARD_FAB2_LIB.BASEBOARD_FAB2(SCH_1):PAGE133

R7D3 RES_0402-4.75K,1%,1/16W,CHIP,GA
     1 P3V3_STBY @BASEBOARD_FAB2_LIB.BASEBOARD_FAB2(SCH_1):P3V3_STBY   I243 @BASEBOARD_FAB2_LIB.BASEBOARD_FAB2(SCH_1):PAGE133
     2 IRQ_LPC_SERIRQ_N @BASEBOARD_FAB2_LIB.BASEBOARD_FAB2(SCH_1):IRQ_LPC_SERIRQ_N   I243 @BASEBOARD_FAB2_LIB.BASEBOARD_FAB2(SCH_1):PAGE133

R7D4 RES_0402-10.0K,1%,1/16W,CHIP,GA
     1 P3V3_STBY @BASEBOARD_FAB2_LIB.BASEBOARD_FAB2(SCH_1):P3V3_STBY   I245 @BASEBOARD_FAB2_LIB.BASEBOARD_FAB2(SCH_1):PAGE133
     2 PU_IRQ_PCH_SCI_WHEA_N @BASEBOARD_FAB2_LIB.BASEBOARD_FAB2(SCH_1):PU_IRQ_PCH_SCI_WHEA_N   I245 @BASEBOARD_FAB2_LIB.BASEBOARD_FAB2(SCH_1):PAGE133

R7D5 RES_0402-2.26K,1.0%,1/16W,CHIPA
     1 P3V3_STBY @BASEBOARD_FAB2_LIB.BASEBOARD_FAB2(SCH_1):P3V3_STBY    I82 @BASEBOARD_FAB2_LIB.BASEBOARD_FAB2(SCH_1):PAGE181
     2 FM_MB_SLOT_ID0 @BASEBOARD_FAB2_LIB.BASEBOARD_FAB2(SCH_1):FM_MB_SLOT_ID0    I82 @BASEBOARD_FAB2_LIB.BASEBOARD_FAB2(SCH_1):PAGE181

R7D6 RES_0402-4.75K,1%,1/16W,CHIP,GA
     1 P3V3_STBY @BASEBOARD_FAB2_LIB.BASEBOARD_FAB2(SCH_1):P3V3_STBY   I306 @BASEBOARD_FAB2_LIB.BASEBOARD_FAB2(SCH_1):PAGE133
     2 FM_BMC_READY_N @BASEBOARD_FAB2_LIB.BASEBOARD_FAB2(SCH_1):FM_BMC_READY_N   I306 @BASEBOARD_FAB2_LIB.BASEBOARD_FAB2(SCH_1):PAGE133

R7D7 RES_0402-1.00K,1%,1/16W,CHIP,GA
     1 P3V3_STBY @BASEBOARD_FAB2_LIB.BASEBOARD_FAB2(SCH_1):P3V3_STBY   I331 @BASEBOARD_FAB2_LIB.BASEBOARD_FAB2(SCH_1):PAGE133
     2 IRQ_PIRQA_SPI_TPM_N @BASEBOARD_FAB2_LIB.BASEBOARD_FAB2(SCH_1):IRQ_PIRQA_SPI_TPM_N   I331 @BASEBOARD_FAB2_LIB.BASEBOARD_FAB2(SCH_1):PAGE133

R7D8 RES_0402-10.0K,1%,1/16W,CHIP,GA
     1 P3V3_STBY @BASEBOARD_FAB2_LIB.BASEBOARD_FAB2(SCH_1):P3V3_STBY   I200 @BASEBOARD_FAB2_LIB.BASEBOARD_FAB2(SCH_1):PAGE133
     2 PU_LPC_CLKRUN_N @BASEBOARD_FAB2_LIB.BASEBOARD_FAB2(SCH_1):PU_LPC_CLKRUN_N   I200 @BASEBOARD_FAB2_LIB.BASEBOARD_FAB2(SCH_1):PAGE133

R7D9 RES_0402-2.26K,1.0%,1/16W,CHIPA
     1 P3V3_STBY @BASEBOARD_FAB2_LIB.BASEBOARD_FAB2(SCH_1):P3V3_STBY    I80 @BASEBOARD_FAB2_LIB.BASEBOARD_FAB2(SCH_1):PAGE181
     2 FM_MB_SLOT_ID1 @BASEBOARD_FAB2_LIB.BASEBOARD_FAB2(SCH_1):FM_MB_SLOT_ID1    I80 @BASEBOARD_FAB2_LIB.BASEBOARD_FAB2(SCH_1):PAGE181

R7D10 RES_0402-10.0K,1%,1/16W,CHIP,GA
     1 P3V3_STBY @BASEBOARD_FAB2_LIB.BASEBOARD_FAB2(SCH_1):P3V3_STBY   I202 @BASEBOARD_FAB2_LIB.BASEBOARD_FAB2(SCH_1):PAGE133
     2 PU_LPC_PME_N @BASEBOARD_FAB2_LIB.BASEBOARD_FAB2(SCH_1):PU_LPC_PME_N   I202 @BASEBOARD_FAB2_LIB.BASEBOARD_FAB2(SCH_1):PAGE133

R7D12 RES_0402-10.0K,1%,1/16W,CHIP,GA
     1 P3V3_STBY @BASEBOARD_FAB2_LIB.BASEBOARD_FAB2(SCH_1):P3V3_STBY   I237 @BASEBOARD_FAB2_LIB.BASEBOARD_FAB2(SCH_1):PAGE133
     2 FM_OCP_MEZZA_PRES @BASEBOARD_FAB2_LIB.BASEBOARD_FAB2(SCH_1):FM_OCP_MEZZA_PRES   I237 @BASEBOARD_FAB2_LIB.BASEBOARD_FAB2(SCH_1):PAGE133

R7D13 RES_0402-8.2K,1%,1/16W,EMPTY,GA
     1 P3V3_STBY @BASEBOARD_FAB2_LIB.BASEBOARD_FAB2(SCH_1):P3V3_STBY    I60 @BASEBOARD_FAB2_LIB.BASEBOARD_FAB2(SCH_1):PAGE125
     2 RMII_BMC_PCH_SPRNGVLLE_RXER @BASEBOARD_FAB2_LIB.BASEBOARD_FAB2(SCH_1):RMII_BMC_PCH_SPRNGVLLE_RXER    I60 @BASEBOARD_FAB2_LIB.BASEBOARD_FAB2(SCH_1):PAGE125

R7D15 RES_0402-348,1%,1/16W,CHIP,G21A
     1 PECI_PCH @BASEBOARD_FAB2_LIB.BASEBOARD_FAB2(SCH_1):PECI_PCH    I32 @BASEBOARD_FAB2_LIB.BASEBOARD_FAB2(SCH_1):PAGE166
     2    GND @BASEBOARD_FAB2_LIB.BASEBOARD_FAB2(SCH_1):GND    I32 @BASEBOARD_FAB2_LIB.BASEBOARD_FAB2(SCH_1):PAGE166

R7D18 RES_0402-1.00K,1%,1/16W,CHIP,GA
     1 FM_THERMTRIP_DLY @BASEBOARD_FAB2_LIB.BASEBOARD_FAB2(SCH_1):FM_THERMTRIP_DLY    I11 @BASEBOARD_FAB2_LIB.BASEBOARD_FAB2(SCH_1):PAGE134
     2 FM_THERMTRIP_DLY_R @BASEBOARD_FAB2_LIB.BASEBOARD_FAB2(SCH_1):FM_THERMTRIP_DLY_R    I11 @BASEBOARD_FAB2_LIB.BASEBOARD_FAB2(SCH_1):PAGE134

R7D19 RES_0402-1.00K,1%,1/16W,EMPTY,A
     1 FM_OC_DETECT_EN_N @BASEBOARD_FAB2_LIB.BASEBOARD_FAB2(SCH_1):FM_OC_DETECT_EN_N     I6 @BASEBOARD_FAB2_LIB.BASEBOARD_FAB2(SCH_1):PAGE126
     2    GND @BASEBOARD_FAB2_LIB.BASEBOARD_FAB2(SCH_1):GND     I6 @BASEBOARD_FAB2_LIB.BASEBOARD_FAB2(SCH_1):PAGE126

R7D23 RES_0402-0.0,5%,1/16W,CHIP,G21A
     1 RST_BMC_SRST_N @BASEBOARD_FAB2_LIB.BASEBOARD_FAB2(SCH_1):RST_BMC_SRST_N   I131 @BASEBOARD_FAB2_LIB.BASEBOARD_FAB2(SCH_1):PAGE118
     2 RST_BMC_SRST_R_N @BASEBOARD_FAB2_LIB.BASEBOARD_FAB2(SCH_1):RST_BMC_SRST_R_N   I131 @BASEBOARD_FAB2_LIB.BASEBOARD_FAB2(SCH_1):PAGE118

R7D24 RES_0402-33.2,1%,1/16W,CHIP,G2A
     1 FM_CPU1_PROCHOT_LVT3_K_N @BASEBOARD_FAB2_LIB.BASEBOARD_FAB2(SCH_1):FM_CPU1_PROCHOT_LVT3_K_N    I62 @BASEBOARD_FAB2_LIB.BASEBOARD_FAB2(SCH_1):PAGE93
     2 FM_CPU1_PROCHOT_LVT3_N @BASEBOARD_FAB2_LIB.BASEBOARD_FAB2(SCH_1):FM_CPU1_PROCHOT_LVT3_N    I62 @BASEBOARD_FAB2_LIB.BASEBOARD_FAB2(SCH_1):PAGE93

R7D25 RES_0402-33.2,1%,1/16W,CHIP,G2A
     1 FM_CPU_MSMI_LVT3_R_N @BASEBOARD_FAB2_LIB.BASEBOARD_FAB2(SCH_1):FM_CPU_MSMI_LVT3_R_N    I70 @BASEBOARD_FAB2_LIB.BASEBOARD_FAB2(SCH_1):PAGE92
     2 FM_CPU_MSMI_LVT3_N @BASEBOARD_FAB2_LIB.BASEBOARD_FAB2(SCH_1):FM_CPU_MSMI_LVT3_N    I70 @BASEBOARD_FAB2_LIB.BASEBOARD_FAB2(SCH_1):PAGE92

R7D26 RES_0402-1.00K,1%,1/16W,CHIP,GA
     1 PD_GTL2104_DIR_0 @BASEBOARD_FAB2_LIB.BASEBOARD_FAB2(SCH_1):PD_GTL2104_DIR_0    I54 @BASEBOARD_FAB2_LIB.BASEBOARD_FAB2(SCH_1):PAGE92
     2    GND @BASEBOARD_FAB2_LIB.BASEBOARD_FAB2(SCH_1):GND    I54 @BASEBOARD_FAB2_LIB.BASEBOARD_FAB2(SCH_1):PAGE92

R7D27 RES_0402-0.0,5%,1/16W,CHIP,G21A
     1 H_CPU0_MSMI_G_N @BASEBOARD_FAB2_LIB.BASEBOARD_FAB2(SCH_1):H_CPU0_MSMI_G_N    I68 @BASEBOARD_FAB2_LIB.BASEBOARD_FAB2(SCH_1):PAGE92
     2 H_CPU_MSMI_G_N @BASEBOARD_FAB2_LIB.BASEBOARD_FAB2(SCH_1):H_CPU_MSMI_G_N    I68 @BASEBOARD_FAB2_LIB.BASEBOARD_FAB2(SCH_1):PAGE92

R7D28 RES_0402-0.0,5%,1/16W,CHIP,G21A
     1 H_CPU1_MSMI_G_N @BASEBOARD_FAB2_LIB.BASEBOARD_FAB2(SCH_1):H_CPU1_MSMI_G_N    I67 @BASEBOARD_FAB2_LIB.BASEBOARD_FAB2(SCH_1):PAGE92
     2 H_CPU_MSMI_G_N @BASEBOARD_FAB2_LIB.BASEBOARD_FAB2(SCH_1):H_CPU_MSMI_G_N    I67 @BASEBOARD_FAB2_LIB.BASEBOARD_FAB2(SCH_1):PAGE92

R7D29 RES_0402-33.2,1%,1/16W,CHIP,G2A
     1 FM_CPU0_FIVR_FAULT_R_LVT3 @BASEBOARD_FAB2_LIB.BASEBOARD_FAB2(SCH_1):FM_CPU0_FIVR_FAULT_R_LVT3    I30 @BASEBOARD_FAB2_LIB.BASEBOARD_FAB2(SCH_1):PAGE92
     2 FM_CPU0_FIVR_FAULT_LVT3 @BASEBOARD_FAB2_LIB.BASEBOARD_FAB2(SCH_1):FM_CPU0_FIVR_FAULT_LVT3    I30 @BASEBOARD_FAB2_LIB.BASEBOARD_FAB2(SCH_1):PAGE92

R7D30 RES_0402-4.75K,1%,1/16W,CHIP,GA
     1 P3V3_STBY @BASEBOARD_FAB2_LIB.BASEBOARD_FAB2(SCH_1):P3V3_STBY   I121 @BASEBOARD_FAB2_LIB.BASEBOARD_FAB2(SCH_1):PAGE135
     2 FM_CPLD_UART_CH_LOCK_N @BASEBOARD_FAB2_LIB.BASEBOARD_FAB2(SCH_1):FM_CPLD_UART_CH_LOCK_N   I121 @BASEBOARD_FAB2_LIB.BASEBOARD_FAB2(SCH_1):PAGE135

R7D31 RES_0402-33.2,1%,1/16W,CHIP,G2A
     1 FM_CPU_ERR2_LVT3_R_N @BASEBOARD_FAB2_LIB.BASEBOARD_FAB2(SCH_1):FM_CPU_ERR2_LVT3_R_N    I29 @BASEBOARD_FAB2_LIB.BASEBOARD_FAB2(SCH_1):PAGE92
     2 FM_CPU_ERR2_LVT3_N @BASEBOARD_FAB2_LIB.BASEBOARD_FAB2(SCH_1):FM_CPU_ERR2_LVT3_N    I29 @BASEBOARD_FAB2_LIB.BASEBOARD_FAB2(SCH_1):PAGE92

R7D32 RES_0402-100.0,1%,1/16W,CHIP,GA
     1 P0V7_GTL2104_VREF_0 @BASEBOARD_FAB2_LIB.BASEBOARD_FAB2(SCH_1):P0V7_GTL2104_VREF_0    I48 @BASEBOARD_FAB2_LIB.BASEBOARD_FAB2(SCH_1):PAGE92
     2    GND @BASEBOARD_FAB2_LIB.BASEBOARD_FAB2(SCH_1):GND    I48 @BASEBOARD_FAB2_LIB.BASEBOARD_FAB2(SCH_1):PAGE92

R7D33 374R2F-1-GP_SMD-RG-374R2F-1-GPA
     1   P3V3 @BASEBOARD_FAB2_LIB.BASEBOARD_FAB2(SCH_1):P3V3   I111 @BASEBOARD_FAB2_LIB.BASEBOARD_FAB2(SCH_1):PAGE92
     2 P0V7_GTL2104_VREF_0 @BASEBOARD_FAB2_LIB.BASEBOARD_FAB2(SCH_1):P0V7_GTL2104_VREF_0   I111 @BASEBOARD_FAB2_LIB.BASEBOARD_FAB2(SCH_1):PAGE92

R7D34 RES_0402-33.2,1%,1/16W,CHIP,G2A
     1 FM_CPU0_THERMTRIP_LVT3_R_N @BASEBOARD_FAB2_LIB.BASEBOARD_FAB2(SCH_1):FM_CPU0_THERMTRIP_LVT3_R_N    I24 @BASEBOARD_FAB2_LIB.BASEBOARD_FAB2(SCH_1):PAGE92
     2 FM_CPU0_THERMTRIP_LVT3_N @BASEBOARD_FAB2_LIB.BASEBOARD_FAB2(SCH_1):FM_CPU0_THERMTRIP_LVT3_N    I24 @BASEBOARD_FAB2_LIB.BASEBOARD_FAB2(SCH_1):PAGE92

R7D36 RES_0402-0.0,5%,1/16W,CHIP,G21A
     1 FM_156M_CPU1_BRD_OSC_EN @BASEBOARD_FAB2_LIB.BASEBOARD_FAB2(SCH_1):FM_156M_CPU1_BRD_OSC_EN    I96 @BASEBOARD_FAB2_LIB.BASEBOARD_FAB2(SCH_1):PAGE104
     2 FM_CPU1_STL_BRD_OSC_EN @BASEBOARD_FAB2_LIB.BASEBOARD_FAB2(SCH_1):FM_CPU1_STL_BRD_OSC_EN    I96 @BASEBOARD_FAB2_LIB.BASEBOARD_FAB2(SCH_1):PAGE104

R7D37 RES_0402-0.0,5%,1/16W,CHIP,G21A
     1 FM_CPU1_VRM_OSC_EN @BASEBOARD_FAB2_LIB.BASEBOARD_FAB2(SCH_1):FM_CPU1_VRM_OSC_EN   I104 @BASEBOARD_FAB2_LIB.BASEBOARD_FAB2(SCH_1):PAGE104
     2 FM_CPU1_VRM_322M_156M_OSC_EN @BASEBOARD_FAB2_LIB.BASEBOARD_FAB2(SCH_1):FM_CPU1_VRM_322M_156M_OSC_EN   I104 @BASEBOARD_FAB2_LIB.BASEBOARD_FAB2(SCH_1):PAGE104

R7D38 RES_0402-0.0,5%,1/16W,EMPTY,G2A
     1 FM_CPU1_VRM_OSC_EN @BASEBOARD_FAB2_LIB.BASEBOARD_FAB2(SCH_1):FM_CPU1_VRM_OSC_EN    I97 @BASEBOARD_FAB2_LIB.BASEBOARD_FAB2(SCH_1):PAGE104
     2 FM_CPU1_STL_BRD_OSC_EN @BASEBOARD_FAB2_LIB.BASEBOARD_FAB2(SCH_1):FM_CPU1_STL_BRD_OSC_EN    I97 @BASEBOARD_FAB2_LIB.BASEBOARD_FAB2(SCH_1):PAGE104

R7D39 RES_0402-0.0,5%,1/16W,CHIP,G21A
     1 FM_CPU0_VRM_OSC_EN @BASEBOARD_FAB2_LIB.BASEBOARD_FAB2(SCH_1):FM_CPU0_VRM_OSC_EN   I103 @BASEBOARD_FAB2_LIB.BASEBOARD_FAB2(SCH_1):PAGE104
     2 FM_CPU0_VRM_322M_156M_OSC_EN @BASEBOARD_FAB2_LIB.BASEBOARD_FAB2(SCH_1):FM_CPU0_VRM_322M_156M_OSC_EN   I103 @BASEBOARD_FAB2_LIB.BASEBOARD_FAB2(SCH_1):PAGE104

R7D40 RES_0402-0.0,5%,1/16W,EMPTY,G2A
     1 FM_CPU0_VRM_OSC_EN @BASEBOARD_FAB2_LIB.BASEBOARD_FAB2(SCH_1):FM_CPU0_VRM_OSC_EN    I94 @BASEBOARD_FAB2_LIB.BASEBOARD_FAB2(SCH_1):PAGE104
     2 FM_CPU0_STL_BRD_OSC_EN @BASEBOARD_FAB2_LIB.BASEBOARD_FAB2(SCH_1):FM_CPU0_STL_BRD_OSC_EN    I94 @BASEBOARD_FAB2_LIB.BASEBOARD_FAB2(SCH_1):PAGE104

R7D41 RES_0402-0.0,5%,1/16W,CHIP,G21A
     1 FM_CPU1_PROCHOT_LVT3_R_N @BASEBOARD_FAB2_LIB.BASEBOARD_FAB2(SCH_1):FM_CPU1_PROCHOT_LVT3_R_N   I114 @BASEBOARD_FAB2_LIB.BASEBOARD_FAB2(SCH_1):PAGE93
     2 FM_CPU1_PROCHOT_LVT3_K_N @BASEBOARD_FAB2_LIB.BASEBOARD_FAB2(SCH_1):FM_CPU1_PROCHOT_LVT3_K_N   I114 @BASEBOARD_FAB2_LIB.BASEBOARD_FAB2(SCH_1):PAGE93

R7D42 RES_0402-4.75K,1%,1/16W,CHIP,GA
     1 P3V3_STBY @BASEBOARD_FAB2_LIB.BASEBOARD_FAB2(SCH_1):P3V3_STBY   I193 @BASEBOARD_FAB2_LIB.BASEBOARD_FAB2(SCH_1):PAGE191
     2 PU_FAB2_MARKER_CPLD @BASEBOARD_FAB2_LIB.BASEBOARD_FAB2(SCH_1):PU_FAB2_MARKER_CPLD   I193 @BASEBOARD_FAB2_LIB.BASEBOARD_FAB2(SCH_1):PAGE191

R7D43 RES_0402-0.0,5%,1/16W,EMPTY,G2A
     1 FM_CPU1_PROCHOT_LVT3_K_N @BASEBOARD_FAB2_LIB.BASEBOARD_FAB2(SCH_1):FM_CPU1_PROCHOT_LVT3_K_N   I110 @BASEBOARD_FAB2_LIB.BASEBOARD_FAB2(SCH_1):PAGE93
     2 H_CPU1_PROCHOT_G_PCH_N @BASEBOARD_FAB2_LIB.BASEBOARD_FAB2(SCH_1):H_CPU1_PROCHOT_G_PCH_N   I110 @BASEBOARD_FAB2_LIB.BASEBOARD_FAB2(SCH_1):PAGE93

R7D44 RES_0402-4.75K,1%,1/16W,CHIP,GA
     1 P1V05_PCH_STBY @BASEBOARD_FAB2_LIB.BASEBOARD_FAB2(SCH_1):P1V05_PCH_STBY   I356 @BASEBOARD_FAB2_LIB.BASEBOARD_FAB2(SCH_1):PAGE133
     2 FM_OCP_MEZZB_PRES_1V05_PCH_N @BASEBOARD_FAB2_LIB.BASEBOARD_FAB2(SCH_1):FM_OCP_MEZZB_PRES_1V05_PCH_N   I356 @BASEBOARD_FAB2_LIB.BASEBOARD_FAB2(SCH_1):PAGE133

R7E2 RES_0402-75,1.0%,1/16W,CHIP,G2A
     1 PVCCIO_CPU0 @BASEBOARD_FAB2_LIB.BASEBOARD_FAB2(SCH_1):PVCCIO_CPU0    I19 @BASEBOARD_FAB2_LIB.BASEBOARD_FAB2(SCH_1):PAGE92
     2 H_CPU0_THERMTRIP_G_N @BASEBOARD_FAB2_LIB.BASEBOARD_FAB2(SCH_1):H_CPU0_THERMTRIP_G_N    I19 @BASEBOARD_FAB2_LIB.BASEBOARD_FAB2(SCH_1):PAGE92

R7E5 RES_0402-10.0K,1%,1/16W,CHIP,GA
     1 P3V3_STBY @BASEBOARD_FAB2_LIB.BASEBOARD_FAB2(SCH_1):P3V3_STBY    I38 @BASEBOARD_FAB2_LIB.BASEBOARD_FAB2(SCH_1):PAGE192
     2 PU_THERMTRIP_FORCE_N @BASEBOARD_FAB2_LIB.BASEBOARD_FAB2(SCH_1):PU_THERMTRIP_FORCE_N    I38 @BASEBOARD_FAB2_LIB.BASEBOARD_FAB2(SCH_1):PAGE192

R7E6 RES_0402-10.0K,1%,1/16W,CHIP,GA
     1 P3V3_STBY @BASEBOARD_FAB2_LIB.BASEBOARD_FAB2(SCH_1):P3V3_STBY    I33 @BASEBOARD_FAB2_LIB.BASEBOARD_FAB2(SCH_1):PAGE192
     2 PU_RST_PERST_BIT1 @BASEBOARD_FAB2_LIB.BASEBOARD_FAB2(SCH_1):PU_RST_PERST_BIT1    I33 @BASEBOARD_FAB2_LIB.BASEBOARD_FAB2(SCH_1):PAGE192

R7E7 RES_0402-4.75K,1%,1/16W,CHIP,GA
     1   P3V3 @BASEBOARD_FAB2_LIB.BASEBOARD_FAB2(SCH_1):P3V3   I106 @BASEBOARD_FAB2_LIB.BASEBOARD_FAB2(SCH_1):PAGE95
     2 FM_SYS_THROTTLE_LVC3 @BASEBOARD_FAB2_LIB.BASEBOARD_FAB2(SCH_1):FM_SYS_THROTTLE_LVC3   I106 @BASEBOARD_FAB2_LIB.BASEBOARD_FAB2(SCH_1):PAGE95

R7E9 RES_0402-0.0,5%,1/16W,CHIP,G21A
     1 FM_THROTTLE_N @BASEBOARD_FAB2_LIB.BASEBOARD_FAB2(SCH_1):FM_THROTTLE_N   I108 @BASEBOARD_FAB2_LIB.BASEBOARD_FAB2(SCH_1):PAGE95
     2 FM_THROTTLE_R_N @BASEBOARD_FAB2_LIB.BASEBOARD_FAB2(SCH_1):FM_THROTTLE_R_N   I108 @BASEBOARD_FAB2_LIB.BASEBOARD_FAB2(SCH_1):PAGE95

R7E10 RES_0402-4.75K,1%,1/16W,CHIP,GA
     1   P3V3 @BASEBOARD_FAB2_LIB.BASEBOARD_FAB2(SCH_1):P3V3    I62 @BASEBOARD_FAB2_LIB.BASEBOARD_FAB2(SCH_1):PAGE95
     2 IRQ_CPU0_VRHOT @BASEBOARD_FAB2_LIB.BASEBOARD_FAB2(SCH_1):IRQ_CPU0_VRHOT    I62 @BASEBOARD_FAB2_LIB.BASEBOARD_FAB2(SCH_1):PAGE95

R7E11 RES_0402-4.75K,1%,1/16W,CHIP,GA
     1   P3V3 @BASEBOARD_FAB2_LIB.BASEBOARD_FAB2(SCH_1):P3V3    I72 @BASEBOARD_FAB2_LIB.BASEBOARD_FAB2(SCH_1):PAGE95
     2 IRQ_CPU1_VRHOT @BASEBOARD_FAB2_LIB.BASEBOARD_FAB2(SCH_1):IRQ_CPU1_VRHOT    I72 @BASEBOARD_FAB2_LIB.BASEBOARD_FAB2(SCH_1):PAGE95

R7E12 RES_0402-1.00K,1%,1/16W,CHIP,GA
     1 P5V_STBY @BASEBOARD_FAB2_LIB.BASEBOARD_FAB2(SCH_1):P5V_STBY    I11 @BASEBOARD_FAB2_LIB.BASEBOARD_FAB2(SCH_1):PAGE241
     2 PWRGD_P5V_STBY_R @BASEBOARD_FAB2_LIB.BASEBOARD_FAB2(SCH_1):PWRGD_P5V_STBY_R    I11 @BASEBOARD_FAB2_LIB.BASEBOARD_FAB2(SCH_1):PAGE241

R7E13 RES_0402-0.0,5%,1/16W,CHIP,G21A
     1    GND @BASEBOARD_FAB2_LIB.BASEBOARD_FAB2(SCH_1):GND    I58 @BASEBOARD_FAB2_LIB.BASEBOARD_FAB2(SCH_1):PAGE241
     2 AGND_P5V_STBY @BASEBOARD_FAB2_LIB.BASEBOARD_FAB2(SCH_1):AGND_P5V_STBY    I58 @BASEBOARD_FAB2_LIB.BASEBOARD_FAB2(SCH_1):PAGE241

R7E14 RES_0402-75K,1%,1/16W,CHIP,G21A
     1 VR_P5V_STBY_RT @BASEBOARD_FAB2_LIB.BASEBOARD_FAB2(SCH_1):VR_P5V_STBY_RT    I18 @BASEBOARD_FAB2_LIB.BASEBOARD_FAB2(SCH_1):PAGE241
     2 AGND_P5V_STBY @BASEBOARD_FAB2_LIB.BASEBOARD_FAB2(SCH_1):AGND_P5V_STBY    I18 @BASEBOARD_FAB2_LIB.BASEBOARD_FAB2(SCH_1):PAGE241

R7E15 RES_0402-22.1,1.0%,1/16W,CHIP,A
     1 PWRGD_P5V_STBY_R @BASEBOARD_FAB2_LIB.BASEBOARD_FAB2(SCH_1):PWRGD_P5V_STBY_R    I89 @BASEBOARD_FAB2_LIB.BASEBOARD_FAB2(SCH_1):PAGE241
     2 PWRGD_P5V_STBY @BASEBOARD_FAB2_LIB.BASEBOARD_FAB2(SCH_1):PWRGD_P5V_STBY    I89 @BASEBOARD_FAB2_LIB.BASEBOARD_FAB2(SCH_1):PAGE241

R7E16 RES_0402-1.37K,1%,1/16W,CHIP,GA
     1 VR_P5V_STBY_VSENSE @BASEBOARD_FAB2_LIB.BASEBOARD_FAB2(SCH_1):VR_P5V_STBY_VSENSE    I51 @BASEBOARD_FAB2_LIB.BASEBOARD_FAB2(SCH_1):PAGE241
     2 AGND_P5V_STBY @BASEBOARD_FAB2_LIB.BASEBOARD_FAB2(SCH_1):AGND_P5V_STBY    I51 @BASEBOARD_FAB2_LIB.BASEBOARD_FAB2(SCH_1):PAGE241

R7E17 RES_0402-0.0,5%,1/16W,CHIP,G21A
     1 VR_FET_SW_P5V_STBY_PVIN @BASEBOARD_FAB2_LIB.BASEBOARD_FAB2(SCH_1):VR_FET_SW_P5V_STBY_PVIN    I37 @BASEBOARD_FAB2_LIB.BASEBOARD_FAB2(SCH_1):PAGE241
     2 VR_P5V_STBY_VIN @BASEBOARD_FAB2_LIB.BASEBOARD_FAB2(SCH_1):VR_P5V_STBY_VIN    I37 @BASEBOARD_FAB2_LIB.BASEBOARD_FAB2(SCH_1):PAGE241

R7E18 RES_0402-4.75K,1%,1/16W,CHIP,GA
     1 P3V3_STBY @BASEBOARD_FAB2_LIB.BASEBOARD_FAB2(SCH_1):P3V3_STBY    I55 @BASEBOARD_FAB2_LIB.BASEBOARD_FAB2(SCH_1):PAGE192
     2 RST_RSMRST_N @BASEBOARD_FAB2_LIB.BASEBOARD_FAB2(SCH_1):RST_RSMRST_N    I55 @BASEBOARD_FAB2_LIB.BASEBOARD_FAB2(SCH_1):PAGE192

R7E19 RES_0402-1.00K,1%,1/16W,EMPTY,A
     1 P3V3_STBY @BASEBOARD_FAB2_LIB.BASEBOARD_FAB2(SCH_1):P3V3_STBY    I57 @BASEBOARD_FAB2_LIB.BASEBOARD_FAB2(SCH_1):PAGE192
     2 FM_MEM_EVENT_FUNC @BASEBOARD_FAB2_LIB.BASEBOARD_FAB2(SCH_1):FM_MEM_EVENT_FUNC    I57 @BASEBOARD_FAB2_LIB.BASEBOARD_FAB2(SCH_1):PAGE192

R7E20 RES_0402-1.00K,1%,1/16W,CHIP,GA
     1 FM_MEM_EVENT_FUNC @BASEBOARD_FAB2_LIB.BASEBOARD_FAB2(SCH_1):FM_MEM_EVENT_FUNC    I59 @BASEBOARD_FAB2_LIB.BASEBOARD_FAB2(SCH_1):PAGE192
     2    GND @BASEBOARD_FAB2_LIB.BASEBOARD_FAB2(SCH_1):GND    I59 @BASEBOARD_FAB2_LIB.BASEBOARD_FAB2(SCH_1):PAGE192

R7E21 RES_0402-4.75K,1%,1/16W,CHIP,GA
     1   P3V3 @BASEBOARD_FAB2_LIB.BASEBOARD_FAB2(SCH_1):P3V3   I343 @BASEBOARD_FAB2_LIB.BASEBOARD_FAB2(SCH_1):PAGE108
     2 FM_PWRBRK_N @BASEBOARD_FAB2_LIB.BASEBOARD_FAB2(SCH_1):FM_PWRBRK_N   I343 @BASEBOARD_FAB2_LIB.BASEBOARD_FAB2(SCH_1):PAGE108

R7E22 RES_0402-0.0,5%,1/16W,CHIP,G21A
     1 FM_PWRBRK_N @BASEBOARD_FAB2_LIB.BASEBOARD_FAB2(SCH_1):FM_PWRBRK_N   I341 @BASEBOARD_FAB2_LIB.BASEBOARD_FAB2(SCH_1):PAGE108
     2 FM_PWRBRK_SLOT_N @BASEBOARD_FAB2_LIB.BASEBOARD_FAB2(SCH_1):FM_PWRBRK_SLOT_N   I341 @BASEBOARD_FAB2_LIB.BASEBOARD_FAB2(SCH_1):PAGE108

R7F1 RES_0402-10.0K,1%,1/16W,CHIP,GA
     1 VR_P5V_STBY_VSENSE_R @BASEBOARD_FAB2_LIB.BASEBOARD_FAB2(SCH_1):VR_P5V_STBY_VSENSE_R    I50 @BASEBOARD_FAB2_LIB.BASEBOARD_FAB2(SCH_1):PAGE241
     2 VR_P5V_STBY_VSENSE @BASEBOARD_FAB2_LIB.BASEBOARD_FAB2(SCH_1):VR_P5V_STBY_VSENSE    I50 @BASEBOARD_FAB2_LIB.BASEBOARD_FAB2(SCH_1):PAGE241

R7F3 RES_0402-33.2,1%,1/16W,CHIP,G2A
     1 SPI_BIOS_SOCKET_IO3 @BASEBOARD_FAB2_LIB.BASEBOARD_FAB2(SCH_1):SPI_BIOS_SOCKET_IO3   I109 @BASEBOARD_FAB2_LIB.BASEBOARD_FAB2(SCH_1):PAGE153
     2 PU_BIOS_SPI_HOLD0_N @BASEBOARD_FAB2_LIB.BASEBOARD_FAB2(SCH_1):PU_BIOS_SPI_HOLD0_N   I109 @BASEBOARD_FAB2_LIB.BASEBOARD_FAB2(SCH_1):PAGE153

R7F4 RES_0402-33.2,1%,1/16W,CHIP,G2A
     1 SPI_SWITCH_MISO @BASEBOARD_FAB2_LIB.BASEBOARD_FAB2(SCH_1):SPI_SWITCH_MISO    I98 @BASEBOARD_FAB2_LIB.BASEBOARD_FAB2(SCH_1):PAGE153
     2 SPI_MISO_R0 @BASEBOARD_FAB2_LIB.BASEBOARD_FAB2(SCH_1):SPI_MISO_R0    I98 @BASEBOARD_FAB2_LIB.BASEBOARD_FAB2(SCH_1):PAGE153

R7F5 RES_0402-4.75K,1%,1/16W,CHIP,GA
     1 P3V3_STBY @BASEBOARD_FAB2_LIB.BASEBOARD_FAB2(SCH_1):P3V3_STBY    I94 @BASEBOARD_FAB2_LIB.BASEBOARD_FAB2(SCH_1):PAGE153
     2 SPI_CS0_PRIMARY_R_N @BASEBOARD_FAB2_LIB.BASEBOARD_FAB2(SCH_1):SPI_CS0_PRIMARY_R_N    I94 @BASEBOARD_FAB2_LIB.BASEBOARD_FAB2(SCH_1):PAGE153

R7F6 RES_0402-4.75K,1%,1/16W,EMPTY,A
     1 P3V3_STBY @BASEBOARD_FAB2_LIB.BASEBOARD_FAB2(SCH_1):P3V3_STBY    I90 @BASEBOARD_FAB2_LIB.BASEBOARD_FAB2(SCH_1):PAGE153
     2 PU_SPI0_RST @BASEBOARD_FAB2_LIB.BASEBOARD_FAB2(SCH_1):PU_SPI0_RST    I90 @BASEBOARD_FAB2_LIB.BASEBOARD_FAB2(SCH_1):PAGE153

R7F7 RES_0402-2.2,5%,1/16W,EMPTY,G2A
     1 VR_PVPP_ABC_SNUB @BASEBOARD_FAB2_LIB.BASEBOARD_FAB2(SCH_1):VR_PVPP_ABC_SNUB   I174 @BASEBOARD_FAB2_LIB.BASEBOARD_FAB2(SCH_1):PAGE231
     2    GND @BASEBOARD_FAB2_LIB.BASEBOARD_FAB2(SCH_1):GND   I174 @BASEBOARD_FAB2_LIB.BASEBOARD_FAB2(SCH_1):PAGE231

R7F8 RES_0603-0,5.0%,1/10W,CHIP,G22A
     1 VR_PVPP_ABC_BOOT @BASEBOARD_FAB2_LIB.BASEBOARD_FAB2(SCH_1):VR_PVPP_ABC_BOOT   I229 @BASEBOARD_FAB2_LIB.BASEBOARD_FAB2(SCH_1):PAGE231
     2 VR_PVPP_ABC_BOOT_R @BASEBOARD_FAB2_LIB.BASEBOARD_FAB2(SCH_1):VR_PVPP_ABC_BOOT_R   I229 @BASEBOARD_FAB2_LIB.BASEBOARD_FAB2(SCH_1):PAGE231

R7F9 RES_0402-0.0,5%,1/16W,CHIP,G21A
     1 FM_PVPP_CPU0_EN @BASEBOARD_FAB2_LIB.BASEBOARD_FAB2(SCH_1):FM_PVPP_CPU0_EN   I220 @BASEBOARD_FAB2_LIB.BASEBOARD_FAB2(SCH_1):PAGE231
     2 FM_PVPP_PVDDQ_CPU0_EN_ABC @BASEBOARD_FAB2_LIB.BASEBOARD_FAB2(SCH_1):FM_PVPP_PVDDQ_CPU0_EN_ABC   I220 @BASEBOARD_FAB2_LIB.BASEBOARD_FAB2(SCH_1):PAGE231

R7F10 RES_0603-120.0,1%,1/10W,CHIP,GA
     1 PVPP_ABC @BASEBOARD_FAB2_LIB.BASEBOARD_FAB2(SCH_1):PVPP_ABC   I177 @BASEBOARD_FAB2_LIB.BASEBOARD_FAB2(SCH_1):PAGE231
     2    GND @BASEBOARD_FAB2_LIB.BASEBOARD_FAB2(SCH_1):GND   I177 @BASEBOARD_FAB2_LIB.BASEBOARD_FAB2(SCH_1):PAGE231

R7F11 RES_0402-6.19K,1%,1/16W,CHIP,GA
     1 VR_FB_PVPP_ABC @BASEBOARD_FAB2_LIB.BASEBOARD_FAB2(SCH_1):VR_FB_PVPP_ABC   I230 @BASEBOARD_FAB2_LIB.BASEBOARD_FAB2(SCH_1):PAGE231
     2 AGND_PVPP_ABC @BASEBOARD_FAB2_LIB.BASEBOARD_FAB2(SCH_1):AGND_PVPP_ABC   I230 @BASEBOARD_FAB2_LIB.BASEBOARD_FAB2(SCH_1):PAGE231

R7F12 RES_0402-0.0,5%,1/16W,CHIP,G21A
     1 PVPP_ABC @BASEBOARD_FAB2_LIB.BASEBOARD_FAB2(SCH_1):PVPP_ABC   I168 @BASEBOARD_FAB2_LIB.BASEBOARD_FAB2(SCH_1):PAGE231
     2 VSENSE_PVPP_ABC @BASEBOARD_FAB2_LIB.BASEBOARD_FAB2(SCH_1):VSENSE_PVPP_ABC   I168 @BASEBOARD_FAB2_LIB.BASEBOARD_FAB2(SCH_1):PAGE231

R7F13 RES_0402-20.0K,1%,1/16W,CHIP,GA
     1 VSENSE_PVPP_ABC @BASEBOARD_FAB2_LIB.BASEBOARD_FAB2(SCH_1):VSENSE_PVPP_ABC   I167 @BASEBOARD_FAB2_LIB.BASEBOARD_FAB2(SCH_1):PAGE231
     2 VR_FB_PVPP_ABC @BASEBOARD_FAB2_LIB.BASEBOARD_FAB2(SCH_1):VR_FB_PVPP_ABC   I167 @BASEBOARD_FAB2_LIB.BASEBOARD_FAB2(SCH_1):PAGE231

R7F14 RES_0402-10.0K,1%,1/16W,CHIP,GA
     1 FM_PVPP_CPU0_EN @BASEBOARD_FAB2_LIB.BASEBOARD_FAB2(SCH_1):FM_PVPP_CPU0_EN   I136 @BASEBOARD_FAB2_LIB.BASEBOARD_FAB2(SCH_1):PAGE231
     2    GND @BASEBOARD_FAB2_LIB.BASEBOARD_FAB2(SCH_1):GND   I136 @BASEBOARD_FAB2_LIB.BASEBOARD_FAB2(SCH_1):PAGE231

R7F15 RES_0402-7.87K,1.0%,1/16W,CHIPA
     1 VR_PVPP_ABC_ISET @BASEBOARD_FAB2_LIB.BASEBOARD_FAB2(SCH_1):VR_PVPP_ABC_ISET   I134 @BASEBOARD_FAB2_LIB.BASEBOARD_FAB2(SCH_1):PAGE231
     2 AGND_PVPP_ABC @BASEBOARD_FAB2_LIB.BASEBOARD_FAB2(SCH_1):AGND_PVPP_ABC   I134 @BASEBOARD_FAB2_LIB.BASEBOARD_FAB2(SCH_1):PAGE231

R7F16 RES_0402-22.1,1.0%,1/16W,CHIP,A
     1 PWRGD_PVPP_ABC_R @BASEBOARD_FAB2_LIB.BASEBOARD_FAB2(SCH_1):PWRGD_PVPP_ABC_R   I208 @BASEBOARD_FAB2_LIB.BASEBOARD_FAB2(SCH_1):PAGE231
     2 PWRGD_PVPP_ABC @BASEBOARD_FAB2_LIB.BASEBOARD_FAB2(SCH_1):PWRGD_PVPP_ABC   I208 @BASEBOARD_FAB2_LIB.BASEBOARD_FAB2(SCH_1):PAGE231

R7F17 RES_0402-1.0K,0.1%,1/16W,CHIP,A
     1 VSENSE_PVPP_ABC @BASEBOARD_FAB2_LIB.BASEBOARD_FAB2(SCH_1):VSENSE_PVPP_ABC   I218 @BASEBOARD_FAB2_LIB.BASEBOARD_FAB2(SCH_1):PAGE231
     2 VR_COMP_PVPP_ABC @BASEBOARD_FAB2_LIB.BASEBOARD_FAB2(SCH_1):VR_COMP_PVPP_ABC   I218 @BASEBOARD_FAB2_LIB.BASEBOARD_FAB2(SCH_1):PAGE231

R7F18 RES_0402-7.87K,1.0%,1/16W,CHIPA
     1 VR_COMP_RC_PVPP_ABC @BASEBOARD_FAB2_LIB.BASEBOARD_FAB2(SCH_1):VR_COMP_RC_PVPP_ABC   I201 @BASEBOARD_FAB2_LIB.BASEBOARD_FAB2(SCH_1):PAGE231
     2 VR_FB_PVPP_ABC @BASEBOARD_FAB2_LIB.BASEBOARD_FAB2(SCH_1):VR_FB_PVPP_ABC   I201 @BASEBOARD_FAB2_LIB.BASEBOARD_FAB2(SCH_1):PAGE231

R7F19 RES_0402-1.00K,1%,1/16W,CHIP,GA
     1 P3V3_STBY @BASEBOARD_FAB2_LIB.BASEBOARD_FAB2(SCH_1):P3V3_STBY   I143 @BASEBOARD_FAB2_LIB.BASEBOARD_FAB2(SCH_1):PAGE231
     2 PWRGD_PVPP_ABC_R @BASEBOARD_FAB2_LIB.BASEBOARD_FAB2(SCH_1):PWRGD_PVPP_ABC_R   I143 @BASEBOARD_FAB2_LIB.BASEBOARD_FAB2(SCH_1):PAGE231

R7F20 RES_0402-100.0K,1%,1/16W,EMPTYA
     1 P3V3_STBY @BASEBOARD_FAB2_LIB.BASEBOARD_FAB2(SCH_1):P3V3_STBY    I29 @BASEBOARD_FAB2_LIB.BASEBOARD_FAB2(SCH_1):PAGE215
     2 VR_PVDDQ_ABC_VREN @BASEBOARD_FAB2_LIB.BASEBOARD_FAB2(SCH_1):VR_PVDDQ_ABC_VREN    I29 @BASEBOARD_FAB2_LIB.BASEBOARD_FAB2(SCH_1):PAGE215

R7F21 RES_0402-0.0,5%,1/16W,CHIP,G21A
     1 FM_PVDDQ_ABC_EN @BASEBOARD_FAB2_LIB.BASEBOARD_FAB2(SCH_1):FM_PVDDQ_ABC_EN    I13 @BASEBOARD_FAB2_LIB.BASEBOARD_FAB2(SCH_1):PAGE215
     2 VR_PVDDQ_ABC_VREN @BASEBOARD_FAB2_LIB.BASEBOARD_FAB2(SCH_1):VR_PVDDQ_ABC_VREN    I13 @BASEBOARD_FAB2_LIB.BASEBOARD_FAB2(SCH_1):PAGE215

R7F22 RES_0402-1.00K,1%,1/16W,CHIP,GA
     1 P3V3_STBY @BASEBOARD_FAB2_LIB.BASEBOARD_FAB2(SCH_1):P3V3_STBY    I51 @BASEBOARD_FAB2_LIB.BASEBOARD_FAB2(SCH_1):PAGE215
     2 PWRGD_PVDDQ_ABC_R @BASEBOARD_FAB2_LIB.BASEBOARD_FAB2(SCH_1):PWRGD_PVDDQ_ABC_R    I51 @BASEBOARD_FAB2_LIB.BASEBOARD_FAB2(SCH_1):PAGE215

R7F23 RES_0402-33.2,1%,1/16W,CHIP,G2A
     1 IRQ_PVDDQ_ABC_VRHOT_LVT3_R_N @BASEBOARD_FAB2_LIB.BASEBOARD_FAB2(SCH_1):IRQ_PVDDQ_ABC_VRHOT_LVT3_R_N    I53 @BASEBOARD_FAB2_LIB.BASEBOARD_FAB2(SCH_1):PAGE215
     2 IRQ_PVDDQ_ABC_VRHOT_LVT3_N @BASEBOARD_FAB2_LIB.BASEBOARD_FAB2(SCH_1):IRQ_PVDDQ_ABC_VRHOT_LVT3_N    I53 @BASEBOARD_FAB2_LIB.BASEBOARD_FAB2(SCH_1):PAGE215

R7F24 RES_0402-22.1,1.0%,1/16W,CHIP,A
     1 PWRGD_PVDDQ_ABC_R @BASEBOARD_FAB2_LIB.BASEBOARD_FAB2(SCH_1):PWRGD_PVDDQ_ABC_R    I56 @BASEBOARD_FAB2_LIB.BASEBOARD_FAB2(SCH_1):PAGE215
     2 PWRGD_PVDDQ_ABC @BASEBOARD_FAB2_LIB.BASEBOARD_FAB2(SCH_1):PWRGD_PVDDQ_ABC    I56 @BASEBOARD_FAB2_LIB.BASEBOARD_FAB2(SCH_1):PAGE215

R7F27 RES_0402-1.00K,1%,1/16W,CHIP,GA
     1 P3V3_STBY @BASEBOARD_FAB2_LIB.BASEBOARD_FAB2(SCH_1):P3V3_STBY    I50 @BASEBOARD_FAB2_LIB.BASEBOARD_FAB2(SCH_1):PAGE215
     2 IRQ_PVDDQ_ABC_VRHOT_LVT3_R_N @BASEBOARD_FAB2_LIB.BASEBOARD_FAB2(SCH_1):IRQ_PVDDQ_ABC_VRHOT_LVT3_R_N    I50 @BASEBOARD_FAB2_LIB.BASEBOARD_FAB2(SCH_1):PAGE215

R7F28 RES_0402-10.0K,1%,1/16W,CHIP,GA
     1 P3V3_STBY @BASEBOARD_FAB2_LIB.BASEBOARD_FAB2(SCH_1):P3V3_STBY   I168 @BASEBOARD_FAB2_LIB.BASEBOARD_FAB2(SCH_1):PAGE153
     2 PU_BIOS_SPI_WP0_N @BASEBOARD_FAB2_LIB.BASEBOARD_FAB2(SCH_1):PU_BIOS_SPI_WP0_N   I168 @BASEBOARD_FAB2_LIB.BASEBOARD_FAB2(SCH_1):PAGE153

R7F29 RES_0402-33.2,1%,1/16W,CHIP,G2A
     1 SPI_SWITCH_MOSI @BASEBOARD_FAB2_LIB.BASEBOARD_FAB2(SCH_1):SPI_SWITCH_MOSI   I181 @BASEBOARD_FAB2_LIB.BASEBOARD_FAB2(SCH_1):PAGE153
     2 SPI_SWITCH_MOSI_R0 @BASEBOARD_FAB2_LIB.BASEBOARD_FAB2(SCH_1):SPI_SWITCH_MOSI_R0   I181 @BASEBOARD_FAB2_LIB.BASEBOARD_FAB2(SCH_1):PAGE153

R7F30 RES_0402-10.0K,1%,1/16W,EMPTY,A
     1 PU_BIOS_SPI_WP0_N @BASEBOARD_FAB2_LIB.BASEBOARD_FAB2(SCH_1):PU_BIOS_SPI_WP0_N   I170 @BASEBOARD_FAB2_LIB.BASEBOARD_FAB2(SCH_1):PAGE153
     2    GND @BASEBOARD_FAB2_LIB.BASEBOARD_FAB2(SCH_1):GND   I170 @BASEBOARD_FAB2_LIB.BASEBOARD_FAB2(SCH_1):PAGE153

R7F32 RES_0402-10.0K,1%,1/16W,CHIP,GA
     1 P3V3_STBY @BASEBOARD_FAB2_LIB.BASEBOARD_FAB2(SCH_1):P3V3_STBY   I140 @BASEBOARD_FAB2_LIB.BASEBOARD_FAB2(SCH_1):PAGE153
     2 PU_BIOS_SPI_HOLD0_N @BASEBOARD_FAB2_LIB.BASEBOARD_FAB2(SCH_1):PU_BIOS_SPI_HOLD0_N   I140 @BASEBOARD_FAB2_LIB.BASEBOARD_FAB2(SCH_1):PAGE153

R7F33 RES_0402-4.75K,1%,1/16W,CHIP,GA
     1 P5V_STBY @BASEBOARD_FAB2_LIB.BASEBOARD_FAB2(SCH_1):P5V_STBY    I65 @BASEBOARD_FAB2_LIB.BASEBOARD_FAB2(SCH_1):PAGE161
     2 FAN_PWM_OUT_SYS1_R @BASEBOARD_FAB2_LIB.BASEBOARD_FAB2(SCH_1):FAN_PWM_OUT_SYS1_R    I65 @BASEBOARD_FAB2_LIB.BASEBOARD_FAB2(SCH_1):PAGE161

R7F35 RES_0402-0.0,5%,1/16W,CHIP,G21A
     1    GND @BASEBOARD_FAB2_LIB.BASEBOARD_FAB2(SCH_1):GND   I170 @BASEBOARD_FAB2_LIB.BASEBOARD_FAB2(SCH_1):PAGE231
     2 AGND_PVPP_ABC @BASEBOARD_FAB2_LIB.BASEBOARD_FAB2(SCH_1):AGND_PVPP_ABC   I170 @BASEBOARD_FAB2_LIB.BASEBOARD_FAB2(SCH_1):PAGE231

R7F36 RES_0402-2.26K,1.0%,1/16W,CHIPA
     1 P3V3_STBY @BASEBOARD_FAB2_LIB.BASEBOARD_FAB2(SCH_1):P3V3_STBY    I75 @BASEBOARD_FAB2_LIB.BASEBOARD_FAB2(SCH_1):PAGE215
     2 PWRGD_PVDDQ_ABC @BASEBOARD_FAB2_LIB.BASEBOARD_FAB2(SCH_1):PWRGD_PVDDQ_ABC    I75 @BASEBOARD_FAB2_LIB.BASEBOARD_FAB2(SCH_1):PAGE215

R7F37 RES_0402-33.2,1%,1/16W,CHIP,G2A
     1 SPI_BIOS_SOCKET_IO2 @BASEBOARD_FAB2_LIB.BASEBOARD_FAB2(SCH_1):SPI_BIOS_SOCKET_IO2   I108 @BASEBOARD_FAB2_LIB.BASEBOARD_FAB2(SCH_1):PAGE153
     2 PU_BIOS_SPI_WP0_N @BASEBOARD_FAB2_LIB.BASEBOARD_FAB2(SCH_1):PU_BIOS_SPI_WP0_N   I108 @BASEBOARD_FAB2_LIB.BASEBOARD_FAB2(SCH_1):PAGE153

R7G2 RES_0402-0.0,5%,1/16W,CHIP,G21A
     1 SVID_VDIO_PVDDQ_ABC @BASEBOARD_FAB2_LIB.BASEBOARD_FAB2(SCH_1):SVID_VDIO_PVDDQ_ABC    I41 @BASEBOARD_FAB2_LIB.BASEBOARD_FAB2(SCH_1):PAGE215
     2 SVID_DIO1_CPU0_R @BASEBOARD_FAB2_LIB.BASEBOARD_FAB2(SCH_1):SVID_DIO1_CPU0_R    I41 @BASEBOARD_FAB2_LIB.BASEBOARD_FAB2(SCH_1):PAGE215

R7G4 RES_0402-0.0,5%,1/16W,CHIP,G21A
     1 SVID_ALERT_PVDDQ_ABC @BASEBOARD_FAB2_LIB.BASEBOARD_FAB2(SCH_1):SVID_ALERT_PVDDQ_ABC    I49 @BASEBOARD_FAB2_LIB.BASEBOARD_FAB2(SCH_1):PAGE215
     2 SVID_ALERT1_CPU0_R_N @BASEBOARD_FAB2_LIB.BASEBOARD_FAB2(SCH_1):SVID_ALERT1_CPU0_R_N    I49 @BASEBOARD_FAB2_LIB.BASEBOARD_FAB2(SCH_1):PAGE215

R7G7 RES_0402-4.75K,1%,1/16W,CHIP,GA
     1   P3V3 @BASEBOARD_FAB2_LIB.BASEBOARD_FAB2(SCH_1):P3V3    I51 @BASEBOARD_FAB2_LIB.BASEBOARD_FAB2(SCH_1):PAGE94
     2 H_CPU0_MEMABC_MEMHOT @BASEBOARD_FAB2_LIB.BASEBOARD_FAB2(SCH_1):H_CPU0_MEMABC_MEMHOT    I51 @BASEBOARD_FAB2_LIB.BASEBOARD_FAB2(SCH_1):PAGE94

R7G8 RES_0402-2.26K,1.0%,1/16W,CHIPA
     1 VR_PVDDQ_ABC_XADDR1 @BASEBOARD_FAB2_LIB.BASEBOARD_FAB2(SCH_1):VR_PVDDQ_ABC_XADDR1    I72 @BASEBOARD_FAB2_LIB.BASEBOARD_FAB2(SCH_1):PAGE215
     2    GND @BASEBOARD_FAB2_LIB.BASEBOARD_FAB2(SCH_1):GND    I72 @BASEBOARD_FAB2_LIB.BASEBOARD_FAB2(SCH_1):PAGE215

R7G9 RES_0402-10.0,1%,1/16W,CHIP,G2A
     1 VSENSE_PVDDQ_ABC_P @BASEBOARD_FAB2_LIB.BASEBOARD_FAB2(SCH_1):VSENSE_PVDDQ_ABC_P    I12 @BASEBOARD_FAB2_LIB.BASEBOARD_FAB2(SCH_1):PAGE215
     2 VR_PVDDQ_ABC_AVSP @BASEBOARD_FAB2_LIB.BASEBOARD_FAB2(SCH_1):VR_PVDDQ_ABC_AVSP    I12 @BASEBOARD_FAB2_LIB.BASEBOARD_FAB2(SCH_1):PAGE215

R7G10 RES_0402-2.26K,1.0%,1/16W,CHIPA
     1 VR_PVDDQ_ABC_XADDR2 @BASEBOARD_FAB2_LIB.BASEBOARD_FAB2(SCH_1):VR_PVDDQ_ABC_XADDR2    I73 @BASEBOARD_FAB2_LIB.BASEBOARD_FAB2(SCH_1):PAGE215
     2    GND @BASEBOARD_FAB2_LIB.BASEBOARD_FAB2(SCH_1):GND    I73 @BASEBOARD_FAB2_LIB.BASEBOARD_FAB2(SCH_1):PAGE215

R7G14 RES_0402-0.0,5%,1/16W,CHIP,G21A
     1 JTAG_PLD_TDO_MUX_R @BASEBOARD_FAB2_LIB.BASEBOARD_FAB2(SCH_1):JTAG_PLD_TDO_MUX_R    I38 @BASEBOARD_FAB2_LIB.BASEBOARD_FAB2(SCH_1):PAGE189
     2 JTAG_PLD_TDO_MUX @BASEBOARD_FAB2_LIB.BASEBOARD_FAB2(SCH_1):JTAG_PLD_TDO_MUX    I38 @BASEBOARD_FAB2_LIB.BASEBOARD_FAB2(SCH_1):PAGE189

R7G15 RES_0402-0.0,5%,1/16W,EMPTY,G2A
     1 JTAG_PCH_PLD_TDO @BASEBOARD_FAB2_LIB.BASEBOARD_FAB2(SCH_1):JTAG_PCH_PLD_TDO    I36 @BASEBOARD_FAB2_LIB.BASEBOARD_FAB2(SCH_1):PAGE189
     2 JTAG_TDO @BASEBOARD_FAB2_LIB.BASEBOARD_FAB2(SCH_1):JTAG_TDO    I36 @BASEBOARD_FAB2_LIB.BASEBOARD_FAB2(SCH_1):PAGE189

R7G16 RES_0402-0.0,5%,1/16W,EMPTY,G2A
     1 JTAG_PCH_GBE_TDO @BASEBOARD_FAB2_LIB.BASEBOARD_FAB2(SCH_1):JTAG_PCH_GBE_TDO    I27 @BASEBOARD_FAB2_LIB.BASEBOARD_FAB2(SCH_1):PAGE189
     2 JTAG_TDO @BASEBOARD_FAB2_LIB.BASEBOARD_FAB2(SCH_1):JTAG_TDO    I27 @BASEBOARD_FAB2_LIB.BASEBOARD_FAB2(SCH_1):PAGE189

R7G17 RES_0402-0.0,5%,1/16W,CHIP,G21A
     1 JTAG_BMC_TDO @BASEBOARD_FAB2_LIB.BASEBOARD_FAB2(SCH_1):JTAG_BMC_TDO    I37 @BASEBOARD_FAB2_LIB.BASEBOARD_FAB2(SCH_1):PAGE189
     2 JTAG_TDO @BASEBOARD_FAB2_LIB.BASEBOARD_FAB2(SCH_1):JTAG_TDO    I37 @BASEBOARD_FAB2_LIB.BASEBOARD_FAB2(SCH_1):PAGE189

R7G18 RES_0402-0.0,5%,1/16W,EMPTY,G2A
     1 JTAG_PCH_PLD_TDI @BASEBOARD_FAB2_LIB.BASEBOARD_FAB2(SCH_1):JTAG_PCH_PLD_TDI    I13 @BASEBOARD_FAB2_LIB.BASEBOARD_FAB2(SCH_1):PAGE189
     2 JTAG_TDI @BASEBOARD_FAB2_LIB.BASEBOARD_FAB2(SCH_1):JTAG_TDI    I13 @BASEBOARD_FAB2_LIB.BASEBOARD_FAB2(SCH_1):PAGE189

R7G19 RES_0402-0.0,5%,1/16W,EMPTY,G2A
     1 JTAG_PCH_GBE_TDI @BASEBOARD_FAB2_LIB.BASEBOARD_FAB2(SCH_1):JTAG_PCH_GBE_TDI     I8 @BASEBOARD_FAB2_LIB.BASEBOARD_FAB2(SCH_1):PAGE189
     2 JTAG_TDI @BASEBOARD_FAB2_LIB.BASEBOARD_FAB2(SCH_1):JTAG_TDI     I8 @BASEBOARD_FAB2_LIB.BASEBOARD_FAB2(SCH_1):PAGE189

R7G21 RES_0402-0.0,5%,1/16W,CHIP,G21A
     1 JTAG_TDO @BASEBOARD_FAB2_LIB.BASEBOARD_FAB2(SCH_1):JTAG_TDO    I63 @BASEBOARD_FAB2_LIB.BASEBOARD_FAB2(SCH_1):PAGE189
     2 JTAG_TDO_R @BASEBOARD_FAB2_LIB.BASEBOARD_FAB2(SCH_1):JTAG_TDO_R    I63 @BASEBOARD_FAB2_LIB.BASEBOARD_FAB2(SCH_1):PAGE189

R7G22 RES_0402-10.0K,1%,1/16W,CHIP,GA
     1 P3V3_STBY @BASEBOARD_FAB2_LIB.BASEBOARD_FAB2(SCH_1):P3V3_STBY    I53 @BASEBOARD_FAB2_LIB.BASEBOARD_FAB2(SCH_1):PAGE189
     2 JTAG_TDO_R @BASEBOARD_FAB2_LIB.BASEBOARD_FAB2(SCH_1):JTAG_TDO_R    I53 @BASEBOARD_FAB2_LIB.BASEBOARD_FAB2(SCH_1):PAGE189

R7G23 RES_0402-10.0K,1%,1/16W,CHIP,GA
     1 P3V3_STBY @BASEBOARD_FAB2_LIB.BASEBOARD_FAB2(SCH_1):P3V3_STBY    I51 @BASEBOARD_FAB2_LIB.BASEBOARD_FAB2(SCH_1):PAGE189
     2 JTAG_TDI_R @BASEBOARD_FAB2_LIB.BASEBOARD_FAB2(SCH_1):JTAG_TDI_R    I51 @BASEBOARD_FAB2_LIB.BASEBOARD_FAB2(SCH_1):PAGE189

R7G24 RES_0402-150.0,1%,1/16W,CHIP,GA
     1 SVID_CLK1_CPU0_R @BASEBOARD_FAB2_LIB.BASEBOARD_FAB2(SCH_1):SVID_CLK1_CPU0_R    I28 @BASEBOARD_FAB2_LIB.BASEBOARD_FAB2(SCH_1):PAGE215
     2 SVID_CLK_PVDDQ_ABC @BASEBOARD_FAB2_LIB.BASEBOARD_FAB2(SCH_1):SVID_CLK_PVDDQ_ABC    I28 @BASEBOARD_FAB2_LIB.BASEBOARD_FAB2(SCH_1):PAGE215

R7G25 RES_0402-68.1K,1%,1/16W,EMPTY,A
     1 VR_PVDDQ_ABC_PH1_OCSET @BASEBOARD_FAB2_LIB.BASEBOARD_FAB2(SCH_1):VR_PVDDQ_ABC_PH1_OCSET   I104 @BASEBOARD_FAB2_LIB.BASEBOARD_FAB2(SCH_1):PAGE216
     2    GND @BASEBOARD_FAB2_LIB.BASEBOARD_FAB2(SCH_1):GND   I104 @BASEBOARD_FAB2_LIB.BASEBOARD_FAB2(SCH_1):PAGE216

R7G26 RES_0402-10.0K,1%,1/16W,CHIP,GA
     1 P3V3_STBY @BASEBOARD_FAB2_LIB.BASEBOARD_FAB2(SCH_1):P3V3_STBY   I101 @BASEBOARD_FAB2_LIB.BASEBOARD_FAB2(SCH_1):PAGE136
     2 FM_ME_RECOVER_N @BASEBOARD_FAB2_LIB.BASEBOARD_FAB2(SCH_1):FM_ME_RECOVER_N   I101 @BASEBOARD_FAB2_LIB.BASEBOARD_FAB2(SCH_1):PAGE136

R7G27 RES_0402-1.00K,1%,1/16W,CHIP,GA
     1 P3V3_STBY @BASEBOARD_FAB2_LIB.BASEBOARD_FAB2(SCH_1):P3V3_STBY   I155 @BASEBOARD_FAB2_LIB.BASEBOARD_FAB2(SCH_1):PAGE136
     2 PU_BIOS_USB_RECOVERY @BASEBOARD_FAB2_LIB.BASEBOARD_FAB2(SCH_1):PU_BIOS_USB_RECOVERY   I155 @BASEBOARD_FAB2_LIB.BASEBOARD_FAB2(SCH_1):PAGE136

R7G28 RES_0402-1.00K,1%,1/16W,CHIP,GA
     1 PD_ME_RCVR_N @BASEBOARD_FAB2_LIB.BASEBOARD_FAB2(SCH_1):PD_ME_RCVR_N   I102 @BASEBOARD_FAB2_LIB.BASEBOARD_FAB2(SCH_1):PAGE136
     2    GND @BASEBOARD_FAB2_LIB.BASEBOARD_FAB2(SCH_1):GND   I102 @BASEBOARD_FAB2_LIB.BASEBOARD_FAB2(SCH_1):PAGE136

R7G29 RES_0402-1.00K,1%,1/16W,CHIP,GA
     1 PD_PASSWORD_CLEAR @BASEBOARD_FAB2_LIB.BASEBOARD_FAB2(SCH_1):PD_PASSWORD_CLEAR   I148 @BASEBOARD_FAB2_LIB.BASEBOARD_FAB2(SCH_1):PAGE136
     2    GND @BASEBOARD_FAB2_LIB.BASEBOARD_FAB2(SCH_1):GND   I148 @BASEBOARD_FAB2_LIB.BASEBOARD_FAB2(SCH_1):PAGE136

R7G30 RES_0402-68.1K,1%,1/16W,EMPTY,A
     1 VR_PVDDQ_ABC_PH2_OCSET @BASEBOARD_FAB2_LIB.BASEBOARD_FAB2(SCH_1):VR_PVDDQ_ABC_PH2_OCSET   I106 @BASEBOARD_FAB2_LIB.BASEBOARD_FAB2(SCH_1):PAGE216
     2    GND @BASEBOARD_FAB2_LIB.BASEBOARD_FAB2(SCH_1):GND   I106 @BASEBOARD_FAB2_LIB.BASEBOARD_FAB2(SCH_1):PAGE216

R7G31 RES_0402-1.00K,1%,1/16W,CHIP,GA
     1 P3V3_STBY @BASEBOARD_FAB2_LIB.BASEBOARD_FAB2(SCH_1):P3V3_STBY   I139 @BASEBOARD_FAB2_LIB.BASEBOARD_FAB2(SCH_1):PAGE136
     2 PU_BIOS_RECOVER_BOOT @BASEBOARD_FAB2_LIB.BASEBOARD_FAB2(SCH_1):PU_BIOS_RECOVER_BOOT   I139 @BASEBOARD_FAB2_LIB.BASEBOARD_FAB2(SCH_1):PAGE136

R7G114 RES_0402-0.0,5%,1/16W,CHIP,G21A
     1 BMC_JTAG_SEL_N @BASEBOARD_FAB2_LIB.BASEBOARD_FAB2(SCH_1):BMC_JTAG_SEL_N    I76 @BASEBOARD_FAB2_LIB.BASEBOARD_FAB2(SCH_1):PAGE189
     2 BMC_JTAG_SEL_N_MUX @BASEBOARD_FAB2_LIB.BASEBOARD_FAB2(SCH_1):BMC_JTAG_SEL_N_MUX    I76 @BASEBOARD_FAB2_LIB.BASEBOARD_FAB2(SCH_1):PAGE189

R7L2 RES_0402-100.0,1%,1/16W,EMPTY,A
     1 VSENSE_PVDDQ_KLM_P @BASEBOARD_FAB2_LIB.BASEBOARD_FAB2(SCH_1):VSENSE_PVDDQ_KLM_P    I74 @BASEBOARD_FAB2_LIB.BASEBOARD_FAB2(SCH_1):PAGE228
     2 VSENSE_PVDDQ_KLM_N @BASEBOARD_FAB2_LIB.BASEBOARD_FAB2(SCH_1):VSENSE_PVDDQ_KLM_N    I74 @BASEBOARD_FAB2_LIB.BASEBOARD_FAB2(SCH_1):PAGE228

R7M1 RES_0402-665,1.0%,1/16W,CHIP,GA
     1 PVPP_KLM @BASEBOARD_FAB2_LIB.BASEBOARD_FAB2(SCH_1):PVPP_KLM   I109 @BASEBOARD_FAB2_LIB.BASEBOARD_FAB2(SCH_1):PAGE99
     2 SMB_DDR_KLM_VPP_SCL_R @BASEBOARD_FAB2_LIB.BASEBOARD_FAB2(SCH_1):SMB_DDR_KLM_VPP_SCL_R   I109 @BASEBOARD_FAB2_LIB.BASEBOARD_FAB2(SCH_1):PAGE99

R7M2 RES_0402-240,1.0%,1/16W,CHIP,GA
     1 PVCCIO_CPU1 @BASEBOARD_FAB2_LIB.BASEBOARD_FAB2(SCH_1):PVCCIO_CPU1    I79 @BASEBOARD_FAB2_LIB.BASEBOARD_FAB2(SCH_1):PAGE99
     2 SMB_DDR_KLM_SCL_G @BASEBOARD_FAB2_LIB.BASEBOARD_FAB2(SCH_1):SMB_DDR_KLM_SCL_G    I79 @BASEBOARD_FAB2_LIB.BASEBOARD_FAB2(SCH_1):PAGE99

R7M3 RES_0402-10.0,1%,1/16W,CHIP,G2A
     1 SMB_DDR_KLM_SCL_G_R @BASEBOARD_FAB2_LIB.BASEBOARD_FAB2(SCH_1):SMB_DDR_KLM_SCL_G_R    I98 @BASEBOARD_FAB2_LIB.BASEBOARD_FAB2(SCH_1):PAGE99
     2 SMB_DDR_KLM_SCL_G @BASEBOARD_FAB2_LIB.BASEBOARD_FAB2(SCH_1):SMB_DDR_KLM_SCL_G    I98 @BASEBOARD_FAB2_LIB.BASEBOARD_FAB2(SCH_1):PAGE99

R7M4 RES_0402-20.0,1%,1/16W,CHIP,G2A
     1 SMB_DDR_KLM_VPP_SCL_R @BASEBOARD_FAB2_LIB.BASEBOARD_FAB2(SCH_1):SMB_DDR_KLM_VPP_SCL_R    I56 @BASEBOARD_FAB2_LIB.BASEBOARD_FAB2(SCH_1):PAGE99
     2 SMB_DDR_KLM_VPP_SCL @BASEBOARD_FAB2_LIB.BASEBOARD_FAB2(SCH_1):SMB_DDR_KLM_VPP_SCL    I56 @BASEBOARD_FAB2_LIB.BASEBOARD_FAB2(SCH_1):PAGE99

R7M5 RES_0402-20.0,1%,1/16W,CHIP,G2A
     1 SMB_DDR_KLM_VPP_SDA_R @BASEBOARD_FAB2_LIB.BASEBOARD_FAB2(SCH_1):SMB_DDR_KLM_VPP_SDA_R    I55 @BASEBOARD_FAB2_LIB.BASEBOARD_FAB2(SCH_1):PAGE99
     2 SMB_DDR_KLM_VPP_SDA @BASEBOARD_FAB2_LIB.BASEBOARD_FAB2(SCH_1):SMB_DDR_KLM_VPP_SDA    I55 @BASEBOARD_FAB2_LIB.BASEBOARD_FAB2(SCH_1):PAGE99

R7M6 RES_0402-665,1.0%,1/16W,CHIP,GA
     1 PVPP_KLM @BASEBOARD_FAB2_LIB.BASEBOARD_FAB2(SCH_1):PVPP_KLM   I107 @BASEBOARD_FAB2_LIB.BASEBOARD_FAB2(SCH_1):PAGE99
     2 SMB_DDR_KLM_VPP_SDA_R @BASEBOARD_FAB2_LIB.BASEBOARD_FAB2(SCH_1):SMB_DDR_KLM_VPP_SDA_R   I107 @BASEBOARD_FAB2_LIB.BASEBOARD_FAB2(SCH_1):PAGE99

R7M7 RES_0402-240,1.0%,1/16W,CHIP,GA
     1 PVCCIO_CPU1 @BASEBOARD_FAB2_LIB.BASEBOARD_FAB2(SCH_1):PVCCIO_CPU1    I77 @BASEBOARD_FAB2_LIB.BASEBOARD_FAB2(SCH_1):PAGE99
     2 SMB_DDR_KLM_SDA_G @BASEBOARD_FAB2_LIB.BASEBOARD_FAB2(SCH_1):SMB_DDR_KLM_SDA_G    I77 @BASEBOARD_FAB2_LIB.BASEBOARD_FAB2(SCH_1):PAGE99

R7M8 RES_0402-10.0,1%,1/16W,CHIP,G2A
     1 SMB_DDR_KLM_SDA_G_R @BASEBOARD_FAB2_LIB.BASEBOARD_FAB2(SCH_1):SMB_DDR_KLM_SDA_G_R   I112 @BASEBOARD_FAB2_LIB.BASEBOARD_FAB2(SCH_1):PAGE99
     2 SMB_DDR_KLM_SDA_G @BASEBOARD_FAB2_LIB.BASEBOARD_FAB2(SCH_1):SMB_DDR_KLM_SDA_G   I112 @BASEBOARD_FAB2_LIB.BASEBOARD_FAB2(SCH_1):PAGE99

R7M9 RES_0402-64.9,1.0%,1/16W,CHIP,A
     1 PVDDQ_KLM @BASEBOARD_FAB2_LIB.BASEBOARD_FAB2(SCH_1):PVDDQ_KLM    I28 @BASEBOARD_FAB2_LIB.BASEBOARD_FAB2(SCH_1):PAGE96
     2 PWRGD_CPU1_DRAMPWROK_KLM_G @BASEBOARD_FAB2_LIB.BASEBOARD_FAB2(SCH_1):PWRGD_CPU1_DRAMPWROK_KLM_G    I28 @BASEBOARD_FAB2_LIB.BASEBOARD_FAB2(SCH_1):PAGE96

R7P1 RES_0402-42.2,1.0%,1/16W,EMPTYA
     1 CLK_100M_CPU1_BCLK2_DP @BASEBOARD_FAB2_LIB.BASEBOARD_FAB2(SCH_1):CLK_100M_CPU1_BCLK2_DP   I133 @BASEBOARD_FAB2_LIB.BASEBOARD_FAB2(SCH_1):PAGE103
     2    GND @BASEBOARD_FAB2_LIB.BASEBOARD_FAB2(SCH_1):GND   I133 @BASEBOARD_FAB2_LIB.BASEBOARD_FAB2(SCH_1):PAGE103

R7P2 RES_0402-42.2,1.0%,1/16W,EMPTYA
     1 CLK_100M_CPU1_BCLK2_DN @BASEBOARD_FAB2_LIB.BASEBOARD_FAB2(SCH_1):CLK_100M_CPU1_BCLK2_DN   I135 @BASEBOARD_FAB2_LIB.BASEBOARD_FAB2(SCH_1):PAGE103
     2    GND @BASEBOARD_FAB2_LIB.BASEBOARD_FAB2(SCH_1):GND   I135 @BASEBOARD_FAB2_LIB.BASEBOARD_FAB2(SCH_1):PAGE103

R7P3 RES_0402-42.2,1.0%,1/16W,EMPTYA
     1 CLK_100M_CPU1_PE_REFCLK_DP @BASEBOARD_FAB2_LIB.BASEBOARD_FAB2(SCH_1):CLK_100M_CPU1_PE_REFCLK_DP   I129 @BASEBOARD_FAB2_LIB.BASEBOARD_FAB2(SCH_1):PAGE103
     2    GND @BASEBOARD_FAB2_LIB.BASEBOARD_FAB2(SCH_1):GND   I129 @BASEBOARD_FAB2_LIB.BASEBOARD_FAB2(SCH_1):PAGE103

R7P4 RES_0402-42.2,1.0%,1/16W,EMPTYA
     1 CLK_100M_CPU1_PE_REFCLK_DN @BASEBOARD_FAB2_LIB.BASEBOARD_FAB2(SCH_1):CLK_100M_CPU1_PE_REFCLK_DN   I131 @BASEBOARD_FAB2_LIB.BASEBOARD_FAB2(SCH_1):PAGE103
     2    GND @BASEBOARD_FAB2_LIB.BASEBOARD_FAB2(SCH_1):GND   I131 @BASEBOARD_FAB2_LIB.BASEBOARD_FAB2(SCH_1):PAGE103

R7P5 RES_0402-150.0,1%,1/16W,CHIP,GA
     1 H_CPU1_MEMGHJ_MEMHOT_G_N @BASEBOARD_FAB2_LIB.BASEBOARD_FAB2(SCH_1):H_CPU1_MEMGHJ_MEMHOT_G_N    I61 @BASEBOARD_FAB2_LIB.BASEBOARD_FAB2(SCH_1):PAGE152
     2 PVCCIO_CPU1 @BASEBOARD_FAB2_LIB.BASEBOARD_FAB2(SCH_1):PVCCIO_CPU1    I61 @BASEBOARD_FAB2_LIB.BASEBOARD_FAB2(SCH_1):PAGE152

R7P6 RES_0402-42.2,1.0%,1/16W,EMPTYA
     1 CLK_100M_CPU1_RC_REFCLK0_DP @BASEBOARD_FAB2_LIB.BASEBOARD_FAB2(SCH_1):CLK_100M_CPU1_RC_REFCLK0_DP   I125 @BASEBOARD_FAB2_LIB.BASEBOARD_FAB2(SCH_1):PAGE103
     2    GND @BASEBOARD_FAB2_LIB.BASEBOARD_FAB2(SCH_1):GND   I125 @BASEBOARD_FAB2_LIB.BASEBOARD_FAB2(SCH_1):PAGE103

R7P7 RES_0402-42.2,1.0%,1/16W,EMPTYA
     1 CLK_100M_CPU1_RC_REFCLK0_DN @BASEBOARD_FAB2_LIB.BASEBOARD_FAB2(SCH_1):CLK_100M_CPU1_RC_REFCLK0_DN   I127 @BASEBOARD_FAB2_LIB.BASEBOARD_FAB2(SCH_1):PAGE103
     2    GND @BASEBOARD_FAB2_LIB.BASEBOARD_FAB2(SCH_1):GND   I127 @BASEBOARD_FAB2_LIB.BASEBOARD_FAB2(SCH_1):PAGE103

R7P8 RES_0402-49.9,1%,1/16W,CHIP,G2A
     1 A_CPU1_PE3_RBIAS @BASEBOARD_FAB2_LIB.BASEBOARD_FAB2(SCH_1):A_CPU1_PE3_RBIAS   I123 @BASEBOARD_FAB2_LIB.BASEBOARD_FAB2(SCH_1):PAGE55
     2    GND @BASEBOARD_FAB2_LIB.BASEBOARD_FAB2(SCH_1):GND   I123 @BASEBOARD_FAB2_LIB.BASEBOARD_FAB2(SCH_1):PAGE55

R7P9 RES_0402-42.2,1.0%,1/16W,EMPTYA
     1 CLK_100M_CPU1_RC_REFCLK1_DP @BASEBOARD_FAB2_LIB.BASEBOARD_FAB2(SCH_1):CLK_100M_CPU1_RC_REFCLK1_DP   I121 @BASEBOARD_FAB2_LIB.BASEBOARD_FAB2(SCH_1):PAGE103
     2    GND @BASEBOARD_FAB2_LIB.BASEBOARD_FAB2(SCH_1):GND   I121 @BASEBOARD_FAB2_LIB.BASEBOARD_FAB2(SCH_1):PAGE103

R7P10 RES_0402-49.9,1%,1/16W,CHIP,G2A
     1 A_CPU1_PE012_RBIAS @BASEBOARD_FAB2_LIB.BASEBOARD_FAB2(SCH_1):A_CPU1_PE012_RBIAS   I124 @BASEBOARD_FAB2_LIB.BASEBOARD_FAB2(SCH_1):PAGE55
     2    GND @BASEBOARD_FAB2_LIB.BASEBOARD_FAB2(SCH_1):GND   I124 @BASEBOARD_FAB2_LIB.BASEBOARD_FAB2(SCH_1):PAGE55

R7P11 RES_0402-49.9,1%,1/16W,CHIP,G2A
     1 A_CPU1_UPI2_RBIAS @BASEBOARD_FAB2_LIB.BASEBOARD_FAB2(SCH_1):A_CPU1_UPI2_RBIAS   I126 @BASEBOARD_FAB2_LIB.BASEBOARD_FAB2(SCH_1):PAGE55
     2    GND @BASEBOARD_FAB2_LIB.BASEBOARD_FAB2(SCH_1):GND   I126 @BASEBOARD_FAB2_LIB.BASEBOARD_FAB2(SCH_1):PAGE55

R7P12 RES_0402-42.2,1.0%,1/16W,EMPTYA
     1 CLK_100M_CPU1_RC_REFCLK1_DN @BASEBOARD_FAB2_LIB.BASEBOARD_FAB2(SCH_1):CLK_100M_CPU1_RC_REFCLK1_DN   I123 @BASEBOARD_FAB2_LIB.BASEBOARD_FAB2(SCH_1):PAGE103
     2    GND @BASEBOARD_FAB2_LIB.BASEBOARD_FAB2(SCH_1):GND   I123 @BASEBOARD_FAB2_LIB.BASEBOARD_FAB2(SCH_1):PAGE103

R7P13 RES_0402-10.0K,1%,1/16W,CHIP,GA
     1    GND @BASEBOARD_FAB2_LIB.BASEBOARD_FAB2(SCH_1):GND    I81 @BASEBOARD_FAB2_LIB.BASEBOARD_FAB2(SCH_1):PAGE97
     2 PD_CPU1_MCP01_DMON @BASEBOARD_FAB2_LIB.BASEBOARD_FAB2(SCH_1):PD_CPU1_MCP01_DMON    I81 @BASEBOARD_FAB2_LIB.BASEBOARD_FAB2(SCH_1):PAGE97

R7P14 RES_0402-240,1.0%,1/16W,CHIP,GA
     1    GND @BASEBOARD_FAB2_LIB.BASEBOARD_FAB2(SCH_1):GND   I100 @BASEBOARD_FAB2_LIB.BASEBOARD_FAB2(SCH_1):PAGE90
     2 PD_CPU1_DMIMODE_OVERRIDE @BASEBOARD_FAB2_LIB.BASEBOARD_FAB2(SCH_1):PD_CPU1_DMIMODE_OVERRIDE   I100 @BASEBOARD_FAB2_LIB.BASEBOARD_FAB2(SCH_1):PAGE90

R7P15 RES_0402-240,1.0%,1/16W,EMPTY,A
     1    GND @BASEBOARD_FAB2_LIB.BASEBOARD_FAB2(SCH_1):GND    I74 @BASEBOARD_FAB2_LIB.BASEBOARD_FAB2(SCH_1):PAGE90
     2 PD_CPU1_KSFC_DIS @BASEBOARD_FAB2_LIB.BASEBOARD_FAB2(SCH_1):PD_CPU1_KSFC_DIS    I74 @BASEBOARD_FAB2_LIB.BASEBOARD_FAB2(SCH_1):PAGE90

R7P16 RES_0402-90.9,1%,1/16W,CHIP,G2A
     1 A_CPU1_GHJ_RCOMP0 @BASEBOARD_FAB2_LIB.BASEBOARD_FAB2(SCH_1):A_CPU1_GHJ_RCOMP0   I119 @BASEBOARD_FAB2_LIB.BASEBOARD_FAB2(SCH_1):PAGE55
     2    GND @BASEBOARD_FAB2_LIB.BASEBOARD_FAB2(SCH_1):GND   I119 @BASEBOARD_FAB2_LIB.BASEBOARD_FAB2(SCH_1):PAGE55

R7P17 RES_0402-90.9,1%,1/16W,CHIP,G2A
     1 A_CPU1_GHJ_RCOMP1 @BASEBOARD_FAB2_LIB.BASEBOARD_FAB2(SCH_1):A_CPU1_GHJ_RCOMP1   I140 @BASEBOARD_FAB2_LIB.BASEBOARD_FAB2(SCH_1):PAGE55
     2    GND @BASEBOARD_FAB2_LIB.BASEBOARD_FAB2(SCH_1):GND   I140 @BASEBOARD_FAB2_LIB.BASEBOARD_FAB2(SCH_1):PAGE55

R7P18 RES_0402-150.0,1%,1/16W,CHIP,GA
     1 PVCCIO_CPU0 @BASEBOARD_FAB2_LIB.BASEBOARD_FAB2(SCH_1):PVCCIO_CPU0   I100 @BASEBOARD_FAB2_LIB.BASEBOARD_FAB2(SCH_1):PAGE92
     2 H_CPU1_CATERR_G_N @BASEBOARD_FAB2_LIB.BASEBOARD_FAB2(SCH_1):H_CPU1_CATERR_G_N   I100 @BASEBOARD_FAB2_LIB.BASEBOARD_FAB2(SCH_1):PAGE92

R7P19 RES_0402-100.0,1%,1/16W,CHIP,GA
     1 A_CPU1_GHJ_RCOMP2 @BASEBOARD_FAB2_LIB.BASEBOARD_FAB2(SCH_1):A_CPU1_GHJ_RCOMP2   I115 @BASEBOARD_FAB2_LIB.BASEBOARD_FAB2(SCH_1):PAGE55
     2    GND @BASEBOARD_FAB2_LIB.BASEBOARD_FAB2(SCH_1):GND   I115 @BASEBOARD_FAB2_LIB.BASEBOARD_FAB2(SCH_1):PAGE55

R7P20 RES_0402-150.0,1%,1/16W,CHIP,GA
     1 PVCCIO_CPU0 @BASEBOARD_FAB2_LIB.BASEBOARD_FAB2(SCH_1):PVCCIO_CPU0    I44 @BASEBOARD_FAB2_LIB.BASEBOARD_FAB2(SCH_1):PAGE97
     2 H_CPU1_FAST_WAKE_N @BASEBOARD_FAB2_LIB.BASEBOARD_FAB2(SCH_1):H_CPU1_FAST_WAKE_N    I44 @BASEBOARD_FAB2_LIB.BASEBOARD_FAB2(SCH_1):PAGE97

R7P21 RES_0402-150.0,1%,1/16W,CHIP,GA
     1 H_CPU1_MEMKLM_MEMHOT_G_N @BASEBOARD_FAB2_LIB.BASEBOARD_FAB2(SCH_1):H_CPU1_MEMKLM_MEMHOT_G_N    I62 @BASEBOARD_FAB2_LIB.BASEBOARD_FAB2(SCH_1):PAGE152
     2 PVCCIO_CPU1 @BASEBOARD_FAB2_LIB.BASEBOARD_FAB2(SCH_1):PVCCIO_CPU1    I62 @BASEBOARD_FAB2_LIB.BASEBOARD_FAB2(SCH_1):PAGE152

R7P22 RES_0402-240,1.0%,1/16W,EMPTY,A
     1 PVCCIO_CPU1 @BASEBOARD_FAB2_LIB.BASEBOARD_FAB2(SCH_1):PVCCIO_CPU1    I76 @BASEBOARD_FAB2_LIB.BASEBOARD_FAB2(SCH_1):PAGE90
     2 PU_CPU1_LEGACY_SKT @BASEBOARD_FAB2_LIB.BASEBOARD_FAB2(SCH_1):PU_CPU1_LEGACY_SKT    I76 @BASEBOARD_FAB2_LIB.BASEBOARD_FAB2(SCH_1):PAGE90

R7P25 RES_0402-49.9,1%,1/16W,CHIP,G2A
     1 H_PM_SYNC_GTL_R2 @BASEBOARD_FAB2_LIB.BASEBOARD_FAB2(SCH_1):H_PM_SYNC_GTL_R2   I170 @BASEBOARD_FAB2_LIB.BASEBOARD_FAB2(SCH_1):PAGE55
     2 H_PM_SYNC_GTL @BASEBOARD_FAB2_LIB.BASEBOARD_FAB2(SCH_1):H_PM_SYNC_GTL   I170 @BASEBOARD_FAB2_LIB.BASEBOARD_FAB2(SCH_1):PAGE55

R7P26 RES_0402-49.9,1%,1/16W,CHIP,G2A
     1 H_PMSYNC_CLK_24M_CPU1 @BASEBOARD_FAB2_LIB.BASEBOARD_FAB2(SCH_1):H_PMSYNC_CLK_24M_CPU1   I156 @BASEBOARD_FAB2_LIB.BASEBOARD_FAB2(SCH_1):PAGE55
     2 H_PMSYNC_CLK_24M @BASEBOARD_FAB2_LIB.BASEBOARD_FAB2(SCH_1):H_PMSYNC_CLK_24M   I156 @BASEBOARD_FAB2_LIB.BASEBOARD_FAB2(SCH_1):PAGE55

R7P27 RES_0402-150.0,1%,1/16W,CHIP,GA
     1 PVCCIO_CPU0 @BASEBOARD_FAB2_LIB.BASEBOARD_FAB2(SCH_1):PVCCIO_CPU0    I65 @BASEBOARD_FAB2_LIB.BASEBOARD_FAB2(SCH_1):PAGE92
     2 H_CPU1_MSMI_G_N @BASEBOARD_FAB2_LIB.BASEBOARD_FAB2(SCH_1):H_CPU1_MSMI_G_N    I65 @BASEBOARD_FAB2_LIB.BASEBOARD_FAB2(SCH_1):PAGE92

R7P28 RES_0402-150.0,1%,1/16W,CHIP,GA
     1 PVCCIO_CPU1 @BASEBOARD_FAB2_LIB.BASEBOARD_FAB2(SCH_1):PVCCIO_CPU1   I106 @BASEBOARD_FAB2_LIB.BASEBOARD_FAB2(SCH_1):PAGE93
     2 H_CPU1_PROCHOT_G_N @BASEBOARD_FAB2_LIB.BASEBOARD_FAB2(SCH_1):H_CPU1_PROCHOT_G_N   I106 @BASEBOARD_FAB2_LIB.BASEBOARD_FAB2(SCH_1):PAGE93

R7P29 RES_0402-51.1,1.0%,1/16W,CHIP,A
     1 XDP_CPU_TCK0 @BASEBOARD_FAB2_LIB.BASEBOARD_FAB2(SCH_1):XDP_CPU_TCK0    I61 @BASEBOARD_FAB2_LIB.BASEBOARD_FAB2(SCH_1):PAGE112
     2    GND @BASEBOARD_FAB2_LIB.BASEBOARD_FAB2(SCH_1):GND    I61 @BASEBOARD_FAB2_LIB.BASEBOARD_FAB2(SCH_1):PAGE112

R7P30 RES_0402-100.0,1%,1/16W,CHIP,GA
     1 PVCCIO_CPU0 @BASEBOARD_FAB2_LIB.BASEBOARD_FAB2(SCH_1):PVCCIO_CPU0    I50 @BASEBOARD_FAB2_LIB.BASEBOARD_FAB2(SCH_1):PAGE112
     2 XDP_CPU_MBP0_N @BASEBOARD_FAB2_LIB.BASEBOARD_FAB2(SCH_1):XDP_CPU_MBP0_N    I50 @BASEBOARD_FAB2_LIB.BASEBOARD_FAB2(SCH_1):PAGE112

R7R1 RES_0402-51.1,1.0%,1/16W,CHIP,A
     1 PVCCIO_CPU1 @BASEBOARD_FAB2_LIB.BASEBOARD_FAB2(SCH_1):PVCCIO_CPU1   I109 @BASEBOARD_FAB2_LIB.BASEBOARD_FAB2(SCH_1):PAGE214
     2    GND @BASEBOARD_FAB2_LIB.BASEBOARD_FAB2(SCH_1):GND   I109 @BASEBOARD_FAB2_LIB.BASEBOARD_FAB2(SCH_1):PAGE214

R7U2 RES_0402-100.0,1%,1/16W,EMPTY,A
     1 VSENSE_PVDDQ_GHJ_P @BASEBOARD_FAB2_LIB.BASEBOARD_FAB2(SCH_1):VSENSE_PVDDQ_GHJ_P    I74 @BASEBOARD_FAB2_LIB.BASEBOARD_FAB2(SCH_1):PAGE225
     2 VSENSE_PVDDQ_GHJ_N @BASEBOARD_FAB2_LIB.BASEBOARD_FAB2(SCH_1):VSENSE_PVDDQ_GHJ_N    I74 @BASEBOARD_FAB2_LIB.BASEBOARD_FAB2(SCH_1):PAGE225

R7W1 RES_0402-0.0,5%,1/16W,CHIP,G21A
     1 FM_SLPS3_N @BASEBOARD_FAB2_LIB.BASEBOARD_FAB2(SCH_1):FM_SLPS3_N   I167 @BASEBOARD_FAB2_LIB.BASEBOARD_FAB2(SCH_1):PAGE118
     2 FM_SLPS3_R_N @BASEBOARD_FAB2_LIB.BASEBOARD_FAB2(SCH_1):FM_SLPS3_R_N   I167 @BASEBOARD_FAB2_LIB.BASEBOARD_FAB2(SCH_1):PAGE118

R7W2 RES_0402-10.0K,1%,1/16W,EMPTY,A
     1 PECI_CPU_G @BASEBOARD_FAB2_LIB.BASEBOARD_FAB2(SCH_1):PECI_CPU_G    I42 @BASEBOARD_FAB2_LIB.BASEBOARD_FAB2(SCH_1):PAGE166
     2    GND @BASEBOARD_FAB2_LIB.BASEBOARD_FAB2(SCH_1):GND    I42 @BASEBOARD_FAB2_LIB.BASEBOARD_FAB2(SCH_1):PAGE166

R7W3 RES_0402-10.0K,1%,1/16W,EMPTY,A
     1 P3V3_STBY @BASEBOARD_FAB2_LIB.BASEBOARD_FAB2(SCH_1):P3V3_STBY    I46 @BASEBOARD_FAB2_LIB.BASEBOARD_FAB2(SCH_1):PAGE166
     2 PECI_SEL @BASEBOARD_FAB2_LIB.BASEBOARD_FAB2(SCH_1):PECI_SEL    I46 @BASEBOARD_FAB2_LIB.BASEBOARD_FAB2(SCH_1):PAGE166

R7W4 RES_0402-49.9,1%,1/16W,EMPTY,GA
     1 PVCCIO_CPU0 @BASEBOARD_FAB2_LIB.BASEBOARD_FAB2(SCH_1):PVCCIO_CPU0   I106 @BASEBOARD_FAB2_LIB.BASEBOARD_FAB2(SCH_1):PAGE92
     2 P0V7_GTL2104_VREF_0 @BASEBOARD_FAB2_LIB.BASEBOARD_FAB2(SCH_1):P0V7_GTL2104_VREF_0   I106 @BASEBOARD_FAB2_LIB.BASEBOARD_FAB2(SCH_1):PAGE92

R7W5 RES_0402-0.0,5%,1/16W,CHIP,G21A
     1 SPI_SWITCH_CS0_N @BASEBOARD_FAB2_LIB.BASEBOARD_FAB2(SCH_1):SPI_SWITCH_CS0_N   I187 @BASEBOARD_FAB2_LIB.BASEBOARD_FAB2(SCH_1):PAGE153
     2 SPI_CS0_PRIMARY_R_N @BASEBOARD_FAB2_LIB.BASEBOARD_FAB2(SCH_1):SPI_CS0_PRIMARY_R_N   I187 @BASEBOARD_FAB2_LIB.BASEBOARD_FAB2(SCH_1):PAGE153

R7W6 RES_0402-0.0,5%,1/16W,CHIP,G21A
     1 FM_BATTERY_SENSE_EN_N @BASEBOARD_FAB2_LIB.BASEBOARD_FAB2(SCH_1):FM_BATTERY_SENSE_EN_N   I176 @BASEBOARD_FAB2_LIB.BASEBOARD_FAB2(SCH_1):PAGE118
     2 FM_BATTERY_SENSE_EN_R_N @BASEBOARD_FAB2_LIB.BASEBOARD_FAB2(SCH_1):FM_BATTERY_SENSE_EN_R_N   I176 @BASEBOARD_FAB2_LIB.BASEBOARD_FAB2(SCH_1):PAGE118

R7W8 RES_0402-0.0,5%,1/16W,CHIP,G21A
     1 FM_POST_CARD_PRES_BMC_N @BASEBOARD_FAB2_LIB.BASEBOARD_FAB2(SCH_1):FM_POST_CARD_PRES_BMC_N   I269 @BASEBOARD_FAB2_LIB.BASEBOARD_FAB2(SCH_1):PAGE120
     2 FM_POST_CARD_PRES_BMC_R1_N @BASEBOARD_FAB2_LIB.BASEBOARD_FAB2(SCH_1):FM_POST_CARD_PRES_BMC_R1_N   I269 @BASEBOARD_FAB2_LIB.BASEBOARD_FAB2(SCH_1):PAGE120

R7W9 RES_0402-0.0,5%,1/16W,CHIP,G21A
     1 FM_CPU0_RC_ERROR_N @BASEBOARD_FAB2_LIB.BASEBOARD_FAB2(SCH_1):FM_CPU0_RC_ERROR_N   I177 @BASEBOARD_FAB2_LIB.BASEBOARD_FAB2(SCH_1):PAGE118
     2 FM_CPU0_RC_ERROR_R_N @BASEBOARD_FAB2_LIB.BASEBOARD_FAB2(SCH_1):FM_CPU0_RC_ERROR_R_N   I177 @BASEBOARD_FAB2_LIB.BASEBOARD_FAB2(SCH_1):PAGE118

R7W10 RES_0402-0.0,5%,1/16W,CHIP,G21A
     1 FM_CPU0_RC_ERROR_N @BASEBOARD_FAB2_LIB.BASEBOARD_FAB2(SCH_1):FM_CPU0_RC_ERROR_N   I270 @BASEBOARD_FAB2_LIB.BASEBOARD_FAB2(SCH_1):PAGE120
     2 FM_CPU0_RC_ERROR_R1_N @BASEBOARD_FAB2_LIB.BASEBOARD_FAB2(SCH_1):FM_CPU0_RC_ERROR_R1_N   I270 @BASEBOARD_FAB2_LIB.BASEBOARD_FAB2(SCH_1):PAGE120

R7W11 RES_0402-0.0,5%,1/16W,CHIP,G21A
     1 FM_CPU1_RC_ERROR_R_N @BASEBOARD_FAB2_LIB.BASEBOARD_FAB2(SCH_1):FM_CPU1_RC_ERROR_R_N   I273 @BASEBOARD_FAB2_LIB.BASEBOARD_FAB2(SCH_1):PAGE120
     2 FM_CPU1_RC_ERROR_N @BASEBOARD_FAB2_LIB.BASEBOARD_FAB2(SCH_1):FM_CPU1_RC_ERROR_N   I273 @BASEBOARD_FAB2_LIB.BASEBOARD_FAB2(SCH_1):PAGE120

R7W12 RES_0402-0.0,5%,1/16W,CHIP,G21A
     1 FM_CPU1_RC_ERROR_N @BASEBOARD_FAB2_LIB.BASEBOARD_FAB2(SCH_1):FM_CPU1_RC_ERROR_N   I271 @BASEBOARD_FAB2_LIB.BASEBOARD_FAB2(SCH_1):PAGE120
     2 FM_CPU1_RC_ERROR_R1_N @BASEBOARD_FAB2_LIB.BASEBOARD_FAB2(SCH_1):FM_CPU1_RC_ERROR_R1_N   I271 @BASEBOARD_FAB2_LIB.BASEBOARD_FAB2(SCH_1):PAGE120

R7W13 RES_0402-0.0,5%,1/16W,CHIP,G21A
     1 FM_BMC_READY_N @BASEBOARD_FAB2_LIB.BASEBOARD_FAB2(SCH_1):FM_BMC_READY_N   I226 @BASEBOARD_FAB2_LIB.BASEBOARD_FAB2(SCH_1):PAGE119
     2 FM_BMC_READY_R_N @BASEBOARD_FAB2_LIB.BASEBOARD_FAB2(SCH_1):FM_BMC_READY_R_N   I226 @BASEBOARD_FAB2_LIB.BASEBOARD_FAB2(SCH_1):PAGE119

R7W14 RES_0402-0.0,5%,1/16W,CHIP,G21A
     1 FM_BMC_READY_N @BASEBOARD_FAB2_LIB.BASEBOARD_FAB2(SCH_1):FM_BMC_READY_N   I274 @BASEBOARD_FAB2_LIB.BASEBOARD_FAB2(SCH_1):PAGE120
     2 FM_BMC_READY_R1_N @BASEBOARD_FAB2_LIB.BASEBOARD_FAB2(SCH_1):FM_BMC_READY_R1_N   I274 @BASEBOARD_FAB2_LIB.BASEBOARD_FAB2(SCH_1):PAGE120

R7W15 RES_0402-0.0,5%,1/16W,CHIP,G21A
     1 FM_OCP_MEZZA_PRES @BASEBOARD_FAB2_LIB.BASEBOARD_FAB2(SCH_1):FM_OCP_MEZZA_PRES   I227 @BASEBOARD_FAB2_LIB.BASEBOARD_FAB2(SCH_1):PAGE119
     2 FM_OCP_MEZZA_PRES_R @BASEBOARD_FAB2_LIB.BASEBOARD_FAB2(SCH_1):FM_OCP_MEZZA_PRES_R   I227 @BASEBOARD_FAB2_LIB.BASEBOARD_FAB2(SCH_1):PAGE119

R7W16 RES_0402-0.0,5%,1/16W,CHIP,G21A
     1 IRQ_DIMM_SAVE_LVT3_R_N @BASEBOARD_FAB2_LIB.BASEBOARD_FAB2(SCH_1):IRQ_DIMM_SAVE_LVT3_R_N   I276 @BASEBOARD_FAB2_LIB.BASEBOARD_FAB2(SCH_1):PAGE120
     2 IRQ_DIMM_SAVE_LVT3_N @BASEBOARD_FAB2_LIB.BASEBOARD_FAB2(SCH_1):IRQ_DIMM_SAVE_LVT3_N   I276 @BASEBOARD_FAB2_LIB.BASEBOARD_FAB2(SCH_1):PAGE120

R7W17 RES_0402-0.0,5%,1/16W,CHIP,G21A
     1 FM_THROTTLE_R2_N @BASEBOARD_FAB2_LIB.BASEBOARD_FAB2(SCH_1):FM_THROTTLE_R2_N   I229 @BASEBOARD_FAB2_LIB.BASEBOARD_FAB2(SCH_1):PAGE119
     2 FM_THROTTLE_N @BASEBOARD_FAB2_LIB.BASEBOARD_FAB2(SCH_1):FM_THROTTLE_N   I229 @BASEBOARD_FAB2_LIB.BASEBOARD_FAB2(SCH_1):PAGE119

R7W18 RES_0402-0.0,5%,1/16W,CHIP,G21A
     1 IRQ_SML1_PMBUS_ALERT_N @BASEBOARD_FAB2_LIB.BASEBOARD_FAB2(SCH_1):IRQ_SML1_PMBUS_ALERT_N   I277 @BASEBOARD_FAB2_LIB.BASEBOARD_FAB2(SCH_1):PAGE120
     2 IRQ_SML1_PMBUS_ALERT_R1_N @BASEBOARD_FAB2_LIB.BASEBOARD_FAB2(SCH_1):IRQ_SML1_PMBUS_ALERT_R1_N   I277 @BASEBOARD_FAB2_LIB.BASEBOARD_FAB2(SCH_1):PAGE120

R7W19 RES_0402-4.75K,1%,1/16W,CHIP,GA
     1 P3V3_STBY @BASEBOARD_FAB2_LIB.BASEBOARD_FAB2(SCH_1):P3V3_STBY   I180 @BASEBOARD_FAB2_LIB.BASEBOARD_FAB2(SCH_1):PAGE118
     2 FM_BATTERY_SENSE_EN_R_N @BASEBOARD_FAB2_LIB.BASEBOARD_FAB2(SCH_1):FM_BATTERY_SENSE_EN_R_N   I180 @BASEBOARD_FAB2_LIB.BASEBOARD_FAB2(SCH_1):PAGE118

R7W20 RES_0402-4.75K,1%,1/16W,CHIP,GA
     1 P3V3_STBY @BASEBOARD_FAB2_LIB.BASEBOARD_FAB2(SCH_1):P3V3_STBY   I278 @BASEBOARD_FAB2_LIB.BASEBOARD_FAB2(SCH_1):PAGE120
     2 FM_POST_CARD_PRES_BMC_R1_N @BASEBOARD_FAB2_LIB.BASEBOARD_FAB2(SCH_1):FM_POST_CARD_PRES_BMC_R1_N   I278 @BASEBOARD_FAB2_LIB.BASEBOARD_FAB2(SCH_1):PAGE120

R7W21 RES_0402-4.75K,1%,1/16W,CHIP,GA
     1 P3V3_STBY @BASEBOARD_FAB2_LIB.BASEBOARD_FAB2(SCH_1):P3V3_STBY   I183 @BASEBOARD_FAB2_LIB.BASEBOARD_FAB2(SCH_1):PAGE118
     2 RST_BMC_SRST_R_N @BASEBOARD_FAB2_LIB.BASEBOARD_FAB2(SCH_1):RST_BMC_SRST_R_N   I183 @BASEBOARD_FAB2_LIB.BASEBOARD_FAB2(SCH_1):PAGE118

R7W22 RES_0402-4.75K,1%,1/16W,CHIP,GA
     1 P3V3_STBY @BASEBOARD_FAB2_LIB.BASEBOARD_FAB2(SCH_1):P3V3_STBY   I230 @BASEBOARD_FAB2_LIB.BASEBOARD_FAB2(SCH_1):PAGE119
     2 FM_BMC_ENABLE_N @BASEBOARD_FAB2_LIB.BASEBOARD_FAB2(SCH_1):FM_BMC_ENABLE_N   I230 @BASEBOARD_FAB2_LIB.BASEBOARD_FAB2(SCH_1):PAGE119

R8A1 RES_0402-10.0,1%,1/16W,CHIP,G2A
     1 VSENSE_PVNN_PCH_STBY_AVSP @BASEBOARD_FAB2_LIB.BASEBOARD_FAB2(SCH_1):VSENSE_PVNN_PCH_STBY_AVSP   I210 @BASEBOARD_FAB2_LIB.BASEBOARD_FAB2(SCH_1):PAGE235
     2 VR_PVNN_PCH_AVSP @BASEBOARD_FAB2_LIB.BASEBOARD_FAB2(SCH_1):VR_PVNN_PCH_AVSP   I210 @BASEBOARD_FAB2_LIB.BASEBOARD_FAB2(SCH_1):PAGE235

R8A2 RES_0402-2.67K,1%,1/16W,CHIP,GA
     1 VR_PVNN_PCH_XADDR2 @BASEBOARD_FAB2_LIB.BASEBOARD_FAB2(SCH_1):VR_PVNN_PCH_XADDR2   I217 @BASEBOARD_FAB2_LIB.BASEBOARD_FAB2(SCH_1):PAGE235
     2    GND @BASEBOARD_FAB2_LIB.BASEBOARD_FAB2(SCH_1):GND   I217 @BASEBOARD_FAB2_LIB.BASEBOARD_FAB2(SCH_1):PAGE235

R8A4 RES_0402-100.0K,1%,1/16W,CHIP,B
     1 VR_FET_SW_P12V_STBY_PVDDQ_DEF @BASEBOARD_FAB2_LIB.BASEBOARD_FAB2(SCH_1):VR_FET_SW_P12V_STBY_PVDDQ_DEF   I165 @BASEBOARD_FAB2_LIB.BASEBOARD_FAB2(SCH_1):PAGE235
     2 VR_PVNN_PCH_VINSEN @BASEBOARD_FAB2_LIB.BASEBOARD_FAB2(SCH_1):VR_PVNN_PCH_VINSEN   I165 @BASEBOARD_FAB2_LIB.BASEBOARD_FAB2(SCH_1):PAGE235

R8A5 RES_0402-1.00K,1%,1/16W,CHIP,GA
     1 P3V3_STBY @BASEBOARD_FAB2_LIB.BASEBOARD_FAB2(SCH_1):P3V3_STBY   I216 @BASEBOARD_FAB2_LIB.BASEBOARD_FAB2(SCH_1):PAGE235
     2 IRQ_PVNN_PCH_VRHOT_N @BASEBOARD_FAB2_LIB.BASEBOARD_FAB2(SCH_1):IRQ_PVNN_PCH_VRHOT_N   I216 @BASEBOARD_FAB2_LIB.BASEBOARD_FAB2(SCH_1):PAGE235

R8A6 RES_0402-1.00K,1%,1/16W,CHIP,GA
     1 P3V3_STBY @BASEBOARD_FAB2_LIB.BASEBOARD_FAB2(SCH_1):P3V3_STBY   I149 @BASEBOARD_FAB2_LIB.BASEBOARD_FAB2(SCH_1):PAGE235
     2 PWRGD_PVNN_PCH_R @BASEBOARD_FAB2_LIB.BASEBOARD_FAB2(SCH_1):PWRGD_PVNN_PCH_R   I149 @BASEBOARD_FAB2_LIB.BASEBOARD_FAB2(SCH_1):PAGE235

R8A7 RES_0402-100.0K,1%,1/16W,EMPTYA
     1 P3V3_STBY @BASEBOARD_FAB2_LIB.BASEBOARD_FAB2(SCH_1):P3V3_STBY   I222 @BASEBOARD_FAB2_LIB.BASEBOARD_FAB2(SCH_1):PAGE235
     2 VR_PVNN_PCH_VREN @BASEBOARD_FAB2_LIB.BASEBOARD_FAB2(SCH_1):VR_PVNN_PCH_VREN   I222 @BASEBOARD_FAB2_LIB.BASEBOARD_FAB2(SCH_1):PAGE235

R8A10 RES_0402-5.11K,1%,1/16W,CHIP,GA
     1 P3V3_STBY @BASEBOARD_FAB2_LIB.BASEBOARD_FAB2(SCH_1):P3V3_STBY     I3 @BASEBOARD_FAB2_LIB.BASEBOARD_FAB2(SCH_1):PAGE237
     2 PWRGD_P1V8_PCH_STBY_R @BASEBOARD_FAB2_LIB.BASEBOARD_FAB2(SCH_1):PWRGD_P1V8_PCH_STBY_R     I3 @BASEBOARD_FAB2_LIB.BASEBOARD_FAB2(SCH_1):PAGE237

R8A11 RES_0402-22.1,1.0%,1/16W,CHIP,A
     1 PWRGD_P1V8_PCH_STBY_R @BASEBOARD_FAB2_LIB.BASEBOARD_FAB2(SCH_1):PWRGD_P1V8_PCH_STBY_R    I90 @BASEBOARD_FAB2_LIB.BASEBOARD_FAB2(SCH_1):PAGE237
     2 PWRGD_P1V8_PCH_STBY @BASEBOARD_FAB2_LIB.BASEBOARD_FAB2(SCH_1):PWRGD_P1V8_PCH_STBY    I90 @BASEBOARD_FAB2_LIB.BASEBOARD_FAB2(SCH_1):PAGE237

R8A12 RES_0603-475.0,1%,1/10W,CHIP,GA
     1 P1V8_PCH_STBY @BASEBOARD_FAB2_LIB.BASEBOARD_FAB2(SCH_1):P1V8_PCH_STBY    I15 @BASEBOARD_FAB2_LIB.BASEBOARD_FAB2(SCH_1):PAGE237
     2    GND @BASEBOARD_FAB2_LIB.BASEBOARD_FAB2(SCH_1):GND    I15 @BASEBOARD_FAB2_LIB.BASEBOARD_FAB2(SCH_1):PAGE237

R8A13 RES_0402-150.0,1%,1/16W,CHIP,GA
     1 P1V05_PCH_STBY @BASEBOARD_FAB2_LIB.BASEBOARD_FAB2(SCH_1):P1V05_PCH_STBY    I79 @BASEBOARD_FAB2_LIB.BASEBOARD_FAB2(SCH_1):PAGE112
     2 XDP_TDI @BASEBOARD_FAB2_LIB.BASEBOARD_FAB2(SCH_1):XDP_TDI    I79 @BASEBOARD_FAB2_LIB.BASEBOARD_FAB2(SCH_1):PAGE112

R8A14 RES_0402-150.0,1%,1/16W,CHIP,GA
     1 P1V05_PCH_STBY @BASEBOARD_FAB2_LIB.BASEBOARD_FAB2(SCH_1):P1V05_PCH_STBY    I80 @BASEBOARD_FAB2_LIB.BASEBOARD_FAB2(SCH_1):PAGE112
     2 XDP_TMS @BASEBOARD_FAB2_LIB.BASEBOARD_FAB2(SCH_1):XDP_TMS    I80 @BASEBOARD_FAB2_LIB.BASEBOARD_FAB2(SCH_1):PAGE112

R8B1 RES_0402-51.1,1.0%,1/16W,CHIP,A
     1 XDP_PCH_TCK1 @BASEBOARD_FAB2_LIB.BASEBOARD_FAB2(SCH_1):XDP_PCH_TCK1    I95 @BASEBOARD_FAB2_LIB.BASEBOARD_FAB2(SCH_1):PAGE112
     2    GND @BASEBOARD_FAB2_LIB.BASEBOARD_FAB2(SCH_1):GND    I95 @BASEBOARD_FAB2_LIB.BASEBOARD_FAB2(SCH_1):PAGE112

R8B2 RES_0402-1.00K,1%,1/16W,CHIP,GA
     1 XDP_TRST_N @BASEBOARD_FAB2_LIB.BASEBOARD_FAB2(SCH_1):XDP_TRST_N    I94 @BASEBOARD_FAB2_LIB.BASEBOARD_FAB2(SCH_1):PAGE112
     2    GND @BASEBOARD_FAB2_LIB.BASEBOARD_FAB2(SCH_1):GND    I94 @BASEBOARD_FAB2_LIB.BASEBOARD_FAB2(SCH_1):PAGE112

R8B3 RES_0402-4.75K,1%,1/16W,CHIP,GA
     1 PVPP_ABC @BASEBOARD_FAB2_LIB.BASEBOARD_FAB2(SCH_1):PVPP_ABC    I24 @BASEBOARD_FAB2_LIB.BASEBOARD_FAB2(SCH_1):PAGE91
     2 FM_MODPRST_HFI0_CPU0_LVT2_N @BASEBOARD_FAB2_LIB.BASEBOARD_FAB2(SCH_1):FM_MODPRST_HFI0_CPU0_LVT2_N    I24 @BASEBOARD_FAB2_LIB.BASEBOARD_FAB2(SCH_1):PAGE91

R8B4 RES_0402-100.0K,1%,1/16W,CHIP,A
     1 FM_CTNR_PS_ON @BASEBOARD_FAB2_LIB.BASEBOARD_FAB2(SCH_1):FM_CTNR_PS_ON    I83 @BASEBOARD_FAB2_LIB.BASEBOARD_FAB2(SCH_1):PAGE198
     2    GND @BASEBOARD_FAB2_LIB.BASEBOARD_FAB2(SCH_1):GND    I83 @BASEBOARD_FAB2_LIB.BASEBOARD_FAB2(SCH_1):PAGE198

R8B5 RES_0402-4.75K,1%,1/16W,CHIP,GA
     1 PVPP_ABC @BASEBOARD_FAB2_LIB.BASEBOARD_FAB2(SCH_1):PVPP_ABC    I22 @BASEBOARD_FAB2_LIB.BASEBOARD_FAB2(SCH_1):PAGE91
     2 LED_HFI0_CPU0_N @BASEBOARD_FAB2_LIB.BASEBOARD_FAB2(SCH_1):LED_HFI0_CPU0_N    I22 @BASEBOARD_FAB2_LIB.BASEBOARD_FAB2(SCH_1):PAGE91

R8B6 RES_0402-1.8K,1%,1/16W,CHIP,G2A
     1 PVPP_ABC @BASEBOARD_FAB2_LIB.BASEBOARD_FAB2(SCH_1):PVPP_ABC    I37 @BASEBOARD_FAB2_LIB.BASEBOARD_FAB2(SCH_1):PAGE91
     2 SMB_HFI0_CPU0_LVC2_SCL @BASEBOARD_FAB2_LIB.BASEBOARD_FAB2(SCH_1):SMB_HFI0_CPU0_LVC2_SCL    I37 @BASEBOARD_FAB2_LIB.BASEBOARD_FAB2(SCH_1):PAGE91

R8B7 RES_0402-1.8K,1%,1/16W,CHIP,G2A
     1 PVPP_ABC @BASEBOARD_FAB2_LIB.BASEBOARD_FAB2(SCH_1):PVPP_ABC    I36 @BASEBOARD_FAB2_LIB.BASEBOARD_FAB2(SCH_1):PAGE91
     2 SMB_HFI0_CPU0_LVC2_SDA @BASEBOARD_FAB2_LIB.BASEBOARD_FAB2(SCH_1):SMB_HFI0_CPU0_LVC2_SDA    I36 @BASEBOARD_FAB2_LIB.BASEBOARD_FAB2(SCH_1):PAGE91

R8B8 RES_0402-4.75K,1%,1/16W,CHIP,GA
     1 PVPP_ABC @BASEBOARD_FAB2_LIB.BASEBOARD_FAB2(SCH_1):PVPP_ABC    I14 @BASEBOARD_FAB2_LIB.BASEBOARD_FAB2(SCH_1):PAGE91
     2 RST_HFI0_CPU0_LVT2_N @BASEBOARD_FAB2_LIB.BASEBOARD_FAB2(SCH_1):RST_HFI0_CPU0_LVT2_N    I14 @BASEBOARD_FAB2_LIB.BASEBOARD_FAB2(SCH_1):PAGE91

R8B9 RES_0402-113,1%,1/16W,CHIP,G21A
     1 A_USB2_COMP @BASEBOARD_FAB2_LIB.BASEBOARD_FAB2(SCH_1):A_USB2_COMP    I90 @BASEBOARD_FAB2_LIB.BASEBOARD_FAB2(SCH_1):PAGE115
     2    GND @BASEBOARD_FAB2_LIB.BASEBOARD_FAB2(SCH_1):GND    I90 @BASEBOARD_FAB2_LIB.BASEBOARD_FAB2(SCH_1):PAGE115

R8B10 RES_0402-4.75K,1%,1/16W,CHIP,GA
     1 PVPP_ABC @BASEBOARD_FAB2_LIB.BASEBOARD_FAB2(SCH_1):PVPP_ABC    I16 @BASEBOARD_FAB2_LIB.BASEBOARD_FAB2(SCH_1):PAGE91
     2 IRQ_HFI0_CPU0_LVT2_N @BASEBOARD_FAB2_LIB.BASEBOARD_FAB2(SCH_1):IRQ_HFI0_CPU0_LVT2_N    I16 @BASEBOARD_FAB2_LIB.BASEBOARD_FAB2(SCH_1):PAGE91

R8B11 RES_0402-1.8K,1%,1/16W,CHIP,G2A
     1 PVPP_ABC @BASEBOARD_FAB2_LIB.BASEBOARD_FAB2(SCH_1):PVPP_ABC    I35 @BASEBOARD_FAB2_LIB.BASEBOARD_FAB2(SCH_1):PAGE91
     2 SMB_HFI1_CPU0_LVC2_SCL @BASEBOARD_FAB2_LIB.BASEBOARD_FAB2(SCH_1):SMB_HFI1_CPU0_LVC2_SCL    I35 @BASEBOARD_FAB2_LIB.BASEBOARD_FAB2(SCH_1):PAGE91

R8B12 RES_0402-0.0,5%,1/16W,CHIP,G21A
     1 VSENSE_P1V05_PCH_STBY_AVSN @BASEBOARD_FAB2_LIB.BASEBOARD_FAB2(SCH_1):VSENSE_P1V05_PCH_STBY_AVSN    I59 @BASEBOARD_FAB2_LIB.BASEBOARD_FAB2(SCH_1):PAGE236
     2    GND @BASEBOARD_FAB2_LIB.BASEBOARD_FAB2(SCH_1):GND    I59 @BASEBOARD_FAB2_LIB.BASEBOARD_FAB2(SCH_1):PAGE236

R8B13 RES_0402-1.8K,1%,1/16W,CHIP,G2A
     1 PVPP_ABC @BASEBOARD_FAB2_LIB.BASEBOARD_FAB2(SCH_1):PVPP_ABC    I34 @BASEBOARD_FAB2_LIB.BASEBOARD_FAB2(SCH_1):PAGE91
     2 SMB_HFI1_CPU0_LVC2_SDA @BASEBOARD_FAB2_LIB.BASEBOARD_FAB2(SCH_1):SMB_HFI1_CPU0_LVC2_SDA    I34 @BASEBOARD_FAB2_LIB.BASEBOARD_FAB2(SCH_1):PAGE91

R8B14 RES_0402-0.0,5%,1/16W,CHIP,G21A
     1 VSENSE_P1V05_PCH_STBY_AVSP @BASEBOARD_FAB2_LIB.BASEBOARD_FAB2(SCH_1):VSENSE_P1V05_PCH_STBY_AVSP    I56 @BASEBOARD_FAB2_LIB.BASEBOARD_FAB2(SCH_1):PAGE236
     2 P1V05_PCH_STBY @BASEBOARD_FAB2_LIB.BASEBOARD_FAB2(SCH_1):P1V05_PCH_STBY    I56 @BASEBOARD_FAB2_LIB.BASEBOARD_FAB2(SCH_1):PAGE236

R8B15 RES_0402-100.0,1%,1/16W,EMPTY,A
     1 VSENSE_P1V05_PCH_STBY_AVSP @BASEBOARD_FAB2_LIB.BASEBOARD_FAB2(SCH_1):VSENSE_P1V05_PCH_STBY_AVSP    I57 @BASEBOARD_FAB2_LIB.BASEBOARD_FAB2(SCH_1):PAGE236
     2 VSENSE_P1V05_PCH_STBY_AVSN @BASEBOARD_FAB2_LIB.BASEBOARD_FAB2(SCH_1):VSENSE_P1V05_PCH_STBY_AVSN    I57 @BASEBOARD_FAB2_LIB.BASEBOARD_FAB2(SCH_1):PAGE236

R8B16 RES_0402-4.75K,1%,1/16W,CHIP,GA
     1 PVPP_ABC @BASEBOARD_FAB2_LIB.BASEBOARD_FAB2(SCH_1):PVPP_ABC    I17 @BASEBOARD_FAB2_LIB.BASEBOARD_FAB2(SCH_1):PAGE91
     2 RST_HFI1_CPU0_LVT2_N @BASEBOARD_FAB2_LIB.BASEBOARD_FAB2(SCH_1):RST_HFI1_CPU0_LVT2_N    I17 @BASEBOARD_FAB2_LIB.BASEBOARD_FAB2(SCH_1):PAGE91

R8B17 RES_0402-4.75K,1%,1/16W,CHIP,GA
     1 PVPP_ABC @BASEBOARD_FAB2_LIB.BASEBOARD_FAB2(SCH_1):PVPP_ABC    I18 @BASEBOARD_FAB2_LIB.BASEBOARD_FAB2(SCH_1):PAGE91
     2 IRQ_HFI1_CPU0_LVT2_N @BASEBOARD_FAB2_LIB.BASEBOARD_FAB2(SCH_1):IRQ_HFI1_CPU0_LVT2_N    I18 @BASEBOARD_FAB2_LIB.BASEBOARD_FAB2(SCH_1):PAGE91

R8B18 RES_0402-4.75K,1%,1/16W,CHIP,GA
     1 PVPP_ABC @BASEBOARD_FAB2_LIB.BASEBOARD_FAB2(SCH_1):PVPP_ABC    I20 @BASEBOARD_FAB2_LIB.BASEBOARD_FAB2(SCH_1):PAGE91
     2 LED_HFI1_CPU0_N @BASEBOARD_FAB2_LIB.BASEBOARD_FAB2(SCH_1):LED_HFI1_CPU0_N    I20 @BASEBOARD_FAB2_LIB.BASEBOARD_FAB2(SCH_1):PAGE91

R8B19 RES_0402-4.75K,1%,1/16W,CHIP,GA
     1 PVPP_ABC @BASEBOARD_FAB2_LIB.BASEBOARD_FAB2(SCH_1):PVPP_ABC    I21 @BASEBOARD_FAB2_LIB.BASEBOARD_FAB2(SCH_1):PAGE91
     2 FM_MODPRST_HFI1_CPU0_LVT2_N @BASEBOARD_FAB2_LIB.BASEBOARD_FAB2(SCH_1):FM_MODPRST_HFI1_CPU0_LVT2_N    I21 @BASEBOARD_FAB2_LIB.BASEBOARD_FAB2(SCH_1):PAGE91

R8B20 RES_0402-10.0,1%,1/16W,CHIP,G2A
     1 H_PMSYNC_CLK_24M_R @BASEBOARD_FAB2_LIB.BASEBOARD_FAB2(SCH_1):H_PMSYNC_CLK_24M_R   I110 @BASEBOARD_FAB2_LIB.BASEBOARD_FAB2(SCH_1):PAGE114
     2 H_PMSYNC_CLK_24M @BASEBOARD_FAB2_LIB.BASEBOARD_FAB2(SCH_1):H_PMSYNC_CLK_24M   I110 @BASEBOARD_FAB2_LIB.BASEBOARD_FAB2(SCH_1):PAGE114

R8B21 RES_0402-49.9,1%,1/16W,EMPTY,GA
     1 H_PMSYNC_CLK_24M @BASEBOARD_FAB2_LIB.BASEBOARD_FAB2(SCH_1):H_PMSYNC_CLK_24M   I124 @BASEBOARD_FAB2_LIB.BASEBOARD_FAB2(SCH_1):PAGE114
     2    GND @BASEBOARD_FAB2_LIB.BASEBOARD_FAB2(SCH_1):GND   I124 @BASEBOARD_FAB2_LIB.BASEBOARD_FAB2(SCH_1):PAGE114

R8B23 RES_0402-1.00K,1%,1/16W,CHIP,GA
     1 P3V3_STBY @BASEBOARD_FAB2_LIB.BASEBOARD_FAB2(SCH_1):P3V3_STBY   I280 @BASEBOARD_FAB2_LIB.BASEBOARD_FAB2(SCH_1):PAGE133
     2 FM_XRC_PRESENT_N @BASEBOARD_FAB2_LIB.BASEBOARD_FAB2(SCH_1):FM_XRC_PRESENT_N   I280 @BASEBOARD_FAB2_LIB.BASEBOARD_FAB2(SCH_1):PAGE133

R8B24 RES_0402-3.3K,5%,1/16W,CHIP,G2A
     1 P3V3_STBY @BASEBOARD_FAB2_LIB.BASEBOARD_FAB2(SCH_1):P3V3_STBY   I186 @BASEBOARD_FAB2_LIB.BASEBOARD_FAB2(SCH_1):PAGE138
     2 SMB_HOST_STBY_LVC3_SDA_R5 @BASEBOARD_FAB2_LIB.BASEBOARD_FAB2(SCH_1):SMB_HOST_STBY_LVC3_SDA_R5   I186 @BASEBOARD_FAB2_LIB.BASEBOARD_FAB2(SCH_1):PAGE138

R8B25 RES_0402-4.75K,1%,1/16W,CHIP,GA
     1 P3V3_STBY @BASEBOARD_FAB2_LIB.BASEBOARD_FAB2(SCH_1):P3V3_STBY   I175 @BASEBOARD_FAB2_LIB.BASEBOARD_FAB2(SCH_1):PAGE151
     2 FM_BMC_HEARTBEAT_N @BASEBOARD_FAB2_LIB.BASEBOARD_FAB2(SCH_1):FM_BMC_HEARTBEAT_N   I175 @BASEBOARD_FAB2_LIB.BASEBOARD_FAB2(SCH_1):PAGE151

R8B26 RES_0402-3.3K,5%,1/16W,CHIP,G2A
     1 P3V3_STBY @BASEBOARD_FAB2_LIB.BASEBOARD_FAB2(SCH_1):P3V3_STBY   I187 @BASEBOARD_FAB2_LIB.BASEBOARD_FAB2(SCH_1):PAGE138
     2 SMB_HOST_STBY_LVC3_SCL_R5 @BASEBOARD_FAB2_LIB.BASEBOARD_FAB2(SCH_1):SMB_HOST_STBY_LVC3_SCL_R5   I187 @BASEBOARD_FAB2_LIB.BASEBOARD_FAB2(SCH_1):PAGE138

R8B29 RES_0402-49.9,1%,1/16W,CHIP,G2A
     1 SGPIO_PCH_SSATA_DOUT0 @BASEBOARD_FAB2_LIB.BASEBOARD_FAB2(SCH_1):SGPIO_PCH_SSATA_DOUT0    I21 @BASEBOARD_FAB2_LIB.BASEBOARD_FAB2(SCH_1):PAGE178
     2 SGPIO_PCH_SSATA_DOUT0_R @BASEBOARD_FAB2_LIB.BASEBOARD_FAB2(SCH_1):SGPIO_PCH_SSATA_DOUT0_R    I21 @BASEBOARD_FAB2_LIB.BASEBOARD_FAB2(SCH_1):PAGE178

R8B30 RES_0402-1.00K,1%,1/16W,CHIP,GA
     1 P3V3_STBY @BASEBOARD_FAB2_LIB.BASEBOARD_FAB2(SCH_1):P3V3_STBY   I282 @BASEBOARD_FAB2_LIB.BASEBOARD_FAB2(SCH_1):PAGE133
     2 FM_XRC_READY_N @BASEBOARD_FAB2_LIB.BASEBOARD_FAB2(SCH_1):FM_XRC_READY_N   I282 @BASEBOARD_FAB2_LIB.BASEBOARD_FAB2(SCH_1):PAGE133

R8B31 RES_0402-4.75K,1%,1/16W,CHIP,GA
     1 P3V3_STBY @BASEBOARD_FAB2_LIB.BASEBOARD_FAB2(SCH_1):P3V3_STBY   I307 @BASEBOARD_FAB2_LIB.BASEBOARD_FAB2(SCH_1):PAGE133
     2 FM_THROTTLE_N @BASEBOARD_FAB2_LIB.BASEBOARD_FAB2(SCH_1):FM_THROTTLE_N   I307 @BASEBOARD_FAB2_LIB.BASEBOARD_FAB2(SCH_1):PAGE133

R8B32 RES_0402-10.0K,1%,1/16W,CHIP,GA
     1 A_USB2_VBUS @BASEBOARD_FAB2_LIB.BASEBOARD_FAB2(SCH_1):A_USB2_VBUS   I114 @BASEBOARD_FAB2_LIB.BASEBOARD_FAB2(SCH_1):PAGE115
     2    GND @BASEBOARD_FAB2_LIB.BASEBOARD_FAB2(SCH_1):GND   I114 @BASEBOARD_FAB2_LIB.BASEBOARD_FAB2(SCH_1):PAGE115

R8C1 RES_0402-4.75K,1%,1/16W,CHIP,GA
     1 P3V3_STBY @BASEBOARD_FAB2_LIB.BASEBOARD_FAB2(SCH_1):P3V3_STBY   I326 @BASEBOARD_FAB2_LIB.BASEBOARD_FAB2(SCH_1):PAGE133
     2 FM_SLT_CFG1 @BASEBOARD_FAB2_LIB.BASEBOARD_FAB2(SCH_1):FM_SLT_CFG1   I326 @BASEBOARD_FAB2_LIB.BASEBOARD_FAB2(SCH_1):PAGE133

R8C2 RES_0402-4.75K,1%,1/16W,CHIP,GA
     1 P3V3_STBY @BASEBOARD_FAB2_LIB.BASEBOARD_FAB2(SCH_1):P3V3_STBY   I304 @BASEBOARD_FAB2_LIB.BASEBOARD_FAB2(SCH_1):PAGE133
     2 IRQ_BMC_PCH_SCI_LPC_N @BASEBOARD_FAB2_LIB.BASEBOARD_FAB2(SCH_1):IRQ_BMC_PCH_SCI_LPC_N   I304 @BASEBOARD_FAB2_LIB.BASEBOARD_FAB2(SCH_1):PAGE133

R8C4 RES_0402-1.00K,1%,1/16W,CHIP,GA
     1 P3V3_STBY @BASEBOARD_FAB2_LIB.BASEBOARD_FAB2(SCH_1):P3V3_STBY   I286 @BASEBOARD_FAB2_LIB.BASEBOARD_FAB2(SCH_1):PAGE133
     2 IRQ_BMC_PCH_SMI_LPC_N @BASEBOARD_FAB2_LIB.BASEBOARD_FAB2(SCH_1):IRQ_BMC_PCH_SMI_LPC_N   I286 @BASEBOARD_FAB2_LIB.BASEBOARD_FAB2(SCH_1):PAGE133

R8C6 RES_0402-4.75K,1%,1/16W,CHIP,GA
     1 P3V3_STBY @BASEBOARD_FAB2_LIB.BASEBOARD_FAB2(SCH_1):P3V3_STBY   I303 @BASEBOARD_FAB2_LIB.BASEBOARD_FAB2(SCH_1):PAGE133
     2 FM_BIOS_POST_CMPLT_N @BASEBOARD_FAB2_LIB.BASEBOARD_FAB2(SCH_1):FM_BIOS_POST_CMPLT_N   I303 @BASEBOARD_FAB2_LIB.BASEBOARD_FAB2(SCH_1):PAGE133

R8C7 RES_0402-4.75K,1%,1/16W,CHIP,GA
     1 P3V3_STBY @BASEBOARD_FAB2_LIB.BASEBOARD_FAB2(SCH_1):P3V3_STBY   I327 @BASEBOARD_FAB2_LIB.BASEBOARD_FAB2(SCH_1):PAGE133
     2 FM_SLT_CFG0 @BASEBOARD_FAB2_LIB.BASEBOARD_FAB2(SCH_1):FM_SLT_CFG0   I327 @BASEBOARD_FAB2_LIB.BASEBOARD_FAB2(SCH_1):PAGE133

R8C9 RES_0402-4.75K,1%,1/16W,CHIP,GA
     1 P3V3_STBY @BASEBOARD_FAB2_LIB.BASEBOARD_FAB2(SCH_1):P3V3_STBY    I20 @BASEBOARD_FAB2_LIB.BASEBOARD_FAB2(SCH_1):PAGE126
     2 IRQ_SML0_ALERT_N @BASEBOARD_FAB2_LIB.BASEBOARD_FAB2(SCH_1):IRQ_SML0_ALERT_N    I20 @BASEBOARD_FAB2_LIB.BASEBOARD_FAB2(SCH_1):PAGE126

R8C11 RES_0402-20.0,1%,1/16W,CHIP,G2A
     1 SMB_SMLINK0_STBY_LVC3_SDA_R1 @BASEBOARD_FAB2_LIB.BASEBOARD_FAB2(SCH_1):SMB_SMLINK0_STBY_LVC3_SDA_R1   I169 @BASEBOARD_FAB2_LIB.BASEBOARD_FAB2(SCH_1):PAGE138
     2 SMB_SMLINK0_STBY_LVC3_SDA @BASEBOARD_FAB2_LIB.BASEBOARD_FAB2(SCH_1):SMB_SMLINK0_STBY_LVC3_SDA   I169 @BASEBOARD_FAB2_LIB.BASEBOARD_FAB2(SCH_1):PAGE138

R8C12 RES_0402-20.0,1%,1/16W,CHIP,G2A
     1 SMB_SMLINK0_STBY_LVC3_SCL_R1 @BASEBOARD_FAB2_LIB.BASEBOARD_FAB2(SCH_1):SMB_SMLINK0_STBY_LVC3_SCL_R1   I170 @BASEBOARD_FAB2_LIB.BASEBOARD_FAB2(SCH_1):PAGE138
     2 SMB_SMLINK0_STBY_LVC3_SCL @BASEBOARD_FAB2_LIB.BASEBOARD_FAB2(SCH_1):SMB_SMLINK0_STBY_LVC3_SCL   I170 @BASEBOARD_FAB2_LIB.BASEBOARD_FAB2(SCH_1):PAGE138

R8C14 RES_0402-20.0,1%,1/16W,CHIP,G2A
     1 SMB_HOST_STBY_LVC3_SCL_R1 @BASEBOARD_FAB2_LIB.BASEBOARD_FAB2(SCH_1):SMB_HOST_STBY_LVC3_SCL_R1   I168 @BASEBOARD_FAB2_LIB.BASEBOARD_FAB2(SCH_1):PAGE138
     2 SMB_HOST_STBY_LVC3_SCL @BASEBOARD_FAB2_LIB.BASEBOARD_FAB2(SCH_1):SMB_HOST_STBY_LVC3_SCL   I168 @BASEBOARD_FAB2_LIB.BASEBOARD_FAB2(SCH_1):PAGE138

R8C15 RES_0402-2.0K,1%,1/16W,CHIP,G2A
     1 P3V3_STBY @BASEBOARD_FAB2_LIB.BASEBOARD_FAB2(SCH_1):P3V3_STBY   I235 @BASEBOARD_FAB2_LIB.BASEBOARD_FAB2(SCH_1):PAGE159
     2 SMB_HOST_STBY_LVC3_SCL_R @BASEBOARD_FAB2_LIB.BASEBOARD_FAB2(SCH_1):SMB_HOST_STBY_LVC3_SCL_R   I235 @BASEBOARD_FAB2_LIB.BASEBOARD_FAB2(SCH_1):PAGE159

R8C16 RES_0402-2.0K,1%,1/16W,CHIP,G2A
     1 P3V3_STBY @BASEBOARD_FAB2_LIB.BASEBOARD_FAB2(SCH_1):P3V3_STBY   I237 @BASEBOARD_FAB2_LIB.BASEBOARD_FAB2(SCH_1):PAGE159
     2 SMB_HOST_STBY_LVC3_SDA_R @BASEBOARD_FAB2_LIB.BASEBOARD_FAB2(SCH_1):SMB_HOST_STBY_LVC3_SDA_R   I237 @BASEBOARD_FAB2_LIB.BASEBOARD_FAB2(SCH_1):PAGE159

R8C17 RES_0402-1.00K,1%,1/16W,EMPTY,A
     1 PU_PCH_TLS_ENABLE_STRAP @BASEBOARD_FAB2_LIB.BASEBOARD_FAB2(SCH_1):PU_PCH_TLS_ENABLE_STRAP    I41 @BASEBOARD_FAB2_LIB.BASEBOARD_FAB2(SCH_1):PAGE125
     2    GND @BASEBOARD_FAB2_LIB.BASEBOARD_FAB2(SCH_1):GND    I41 @BASEBOARD_FAB2_LIB.BASEBOARD_FAB2(SCH_1):PAGE125

R8C18 RES_0402-1.00K,1%,1/16W,CHIP,GA
     1 P3V3_STBY @BASEBOARD_FAB2_LIB.BASEBOARD_FAB2(SCH_1):P3V3_STBY    I40 @BASEBOARD_FAB2_LIB.BASEBOARD_FAB2(SCH_1):PAGE125
     2 PU_PCH_TLS_ENABLE_STRAP @BASEBOARD_FAB2_LIB.BASEBOARD_FAB2(SCH_1):PU_PCH_TLS_ENABLE_STRAP    I40 @BASEBOARD_FAB2_LIB.BASEBOARD_FAB2(SCH_1):PAGE125

R8C20 RES_0402-20.0,1%,1/16W,CHIP,G2A
     1 SMB_HOST_STBY_LVC3_SDA_R1 @BASEBOARD_FAB2_LIB.BASEBOARD_FAB2(SCH_1):SMB_HOST_STBY_LVC3_SDA_R1   I167 @BASEBOARD_FAB2_LIB.BASEBOARD_FAB2(SCH_1):PAGE138
     2 SMB_HOST_STBY_LVC3_SDA @BASEBOARD_FAB2_LIB.BASEBOARD_FAB2(SCH_1):SMB_HOST_STBY_LVC3_SDA   I167 @BASEBOARD_FAB2_LIB.BASEBOARD_FAB2(SCH_1):PAGE138

R8C21 RES_0402-100.0,1%,1/16W,CHIP,GA
     1 A_RCOMP_3P3 @BASEBOARD_FAB2_LIB.BASEBOARD_FAB2(SCH_1):A_RCOMP_3P3   I275 @BASEBOARD_FAB2_LIB.BASEBOARD_FAB2(SCH_1):PAGE120
     2    GND @BASEBOARD_FAB2_LIB.BASEBOARD_FAB2(SCH_1):GND   I275 @BASEBOARD_FAB2_LIB.BASEBOARD_FAB2(SCH_1):PAGE120

R8C23 RES_0402-0.0,5%,1/16W,EMPTY,G2A
     1 FM_GBE_LOM_DISABLE_N @BASEBOARD_FAB2_LIB.BASEBOARD_FAB2(SCH_1):FM_GBE_LOM_DISABLE_N   I125 @BASEBOARD_FAB2_LIB.BASEBOARD_FAB2(SCH_1):PAGE118
     2 FM_10GBE_LOM_DISABLE_N @BASEBOARD_FAB2_LIB.BASEBOARD_FAB2(SCH_1):FM_10GBE_LOM_DISABLE_N   I125 @BASEBOARD_FAB2_LIB.BASEBOARD_FAB2(SCH_1):PAGE118

R8C24 RES_0402-0.0,5%,1/16W,CHIP,G21A
     1 FM_GBE_LOM_DISABLE_N @BASEBOARD_FAB2_LIB.BASEBOARD_FAB2(SCH_1):FM_GBE_LOM_DISABLE_N   I120 @BASEBOARD_FAB2_LIB.BASEBOARD_FAB2(SCH_1):PAGE118
     2 FM_1GB_LOM_DISABLE_N @BASEBOARD_FAB2_LIB.BASEBOARD_FAB2(SCH_1):FM_1GB_LOM_DISABLE_N   I120 @BASEBOARD_FAB2_LIB.BASEBOARD_FAB2(SCH_1):PAGE118

R8C25 RES_0402-4.75K,1%,1/16W,CHIP,GA
     1 P3V3_STBY @BASEBOARD_FAB2_LIB.BASEBOARD_FAB2(SCH_1):P3V3_STBY   I333 @BASEBOARD_FAB2_LIB.BASEBOARD_FAB2(SCH_1):PAGE133
     2 IRQ_PCH_NIC_ALERT_N @BASEBOARD_FAB2_LIB.BASEBOARD_FAB2(SCH_1):IRQ_PCH_NIC_ALERT_N   I333 @BASEBOARD_FAB2_LIB.BASEBOARD_FAB2(SCH_1):PAGE133

R8C26 RES_0402-100.0,1%,1/16W,CHIP,GA
     1 A_1P8_3P3_RCOMP @BASEBOARD_FAB2_LIB.BASEBOARD_FAB2(SCH_1):A_1P8_3P3_RCOMP    I35 @BASEBOARD_FAB2_LIB.BASEBOARD_FAB2(SCH_1):PAGE121
     2    GND @BASEBOARD_FAB2_LIB.BASEBOARD_FAB2(SCH_1):GND    I35 @BASEBOARD_FAB2_LIB.BASEBOARD_FAB2(SCH_1):PAGE121

R8D4 RES_0402-20.0,1%,1/16W,CHIP,G2A
     1 SMB_VR_STBY_LVC3_SCL_R1 @BASEBOARD_FAB2_LIB.BASEBOARD_FAB2(SCH_1):SMB_VR_STBY_LVC3_SCL_R1   I164 @BASEBOARD_FAB2_LIB.BASEBOARD_FAB2(SCH_1):PAGE138
     2 SMB_VR_STBY_LVC3_SCL @BASEBOARD_FAB2_LIB.BASEBOARD_FAB2(SCH_1):SMB_VR_STBY_LVC3_SCL   I164 @BASEBOARD_FAB2_LIB.BASEBOARD_FAB2(SCH_1):PAGE138

R8D5 RES_0402-1.00K,1%,1/16W,EMPTY,A
     1 PU_ADR_TIMER_HOLD_OFF_N @BASEBOARD_FAB2_LIB.BASEBOARD_FAB2(SCH_1):PU_ADR_TIMER_HOLD_OFF_N    I50 @BASEBOARD_FAB2_LIB.BASEBOARD_FAB2(SCH_1):PAGE125
     2    GND @BASEBOARD_FAB2_LIB.BASEBOARD_FAB2(SCH_1):GND    I50 @BASEBOARD_FAB2_LIB.BASEBOARD_FAB2(SCH_1):PAGE125

R8D7 RES_0402-20.0,1%,1/16W,CHIP,G2A
     1 SMB_VR_STBY_LVC3_SDA_R1 @BASEBOARD_FAB2_LIB.BASEBOARD_FAB2(SCH_1):SMB_VR_STBY_LVC3_SDA_R1   I163 @BASEBOARD_FAB2_LIB.BASEBOARD_FAB2(SCH_1):PAGE138
     2 SMB_VR_STBY_LVC3_SDA @BASEBOARD_FAB2_LIB.BASEBOARD_FAB2(SCH_1):SMB_VR_STBY_LVC3_SDA   I163 @BASEBOARD_FAB2_LIB.BASEBOARD_FAB2(SCH_1):PAGE138

R8D11 RES_0402-33.2,1%,1/16W,CHIP,G2A
     1 RMII_PCH_SPRNGVLLE_ARB_OUT @BASEBOARD_FAB2_LIB.BASEBOARD_FAB2(SCH_1):RMII_PCH_SPRNGVLLE_ARB_OUT   I101 @BASEBOARD_FAB2_LIB.BASEBOARD_FAB2(SCH_1):PAGE121
     2 RMII_PCH_SPRNGVLLE_ARB_OUT_R @BASEBOARD_FAB2_LIB.BASEBOARD_FAB2(SCH_1):RMII_PCH_SPRNGVLLE_ARB_OUT_R   I101 @BASEBOARD_FAB2_LIB.BASEBOARD_FAB2(SCH_1):PAGE121

R8D13 RES_0402-10.0K,1%,1/16W,EMPTY,A
     1 P3V3_STBY @BASEBOARD_FAB2_LIB.BASEBOARD_FAB2(SCH_1):P3V3_STBY    I87 @BASEBOARD_FAB2_LIB.BASEBOARD_FAB2(SCH_1):PAGE125
     2 PU_ADR_TIMER_HOLD_OFF_N @BASEBOARD_FAB2_LIB.BASEBOARD_FAB2(SCH_1):PU_ADR_TIMER_HOLD_OFF_N    I87 @BASEBOARD_FAB2_LIB.BASEBOARD_FAB2(SCH_1):PAGE125

R8D14 RES_0402-4.75K,1%,1/16W,CHIP,GA
     1 P3V3_STBY @BASEBOARD_FAB2_LIB.BASEBOARD_FAB2(SCH_1):P3V3_STBY   I301 @BASEBOARD_FAB2_LIB.BASEBOARD_FAB2(SCH_1):PAGE133
     2 FP_PWR_ID_LED_N @BASEBOARD_FAB2_LIB.BASEBOARD_FAB2(SCH_1):FP_PWR_ID_LED_N   I301 @BASEBOARD_FAB2_LIB.BASEBOARD_FAB2(SCH_1):PAGE133

R8D15 RES_0402-1.37K,1%,1/16W,CHIP,GA
     1 P3V3_STBY @BASEBOARD_FAB2_LIB.BASEBOARD_FAB2(SCH_1):P3V3_STBY    I88 @BASEBOARD_FAB2_LIB.BASEBOARD_FAB2(SCH_1):PAGE138
     2 SMB_VR_STBY_LVC3_SCL @BASEBOARD_FAB2_LIB.BASEBOARD_FAB2(SCH_1):SMB_VR_STBY_LVC3_SCL    I88 @BASEBOARD_FAB2_LIB.BASEBOARD_FAB2(SCH_1):PAGE138

R8D16 RES_0402-10.0K,1%,1/16W,CHIP,GA
     1 P3V3_STBY @BASEBOARD_FAB2_LIB.BASEBOARD_FAB2(SCH_1):P3V3_STBY    I85 @BASEBOARD_FAB2_LIB.BASEBOARD_FAB2(SCH_1):PAGE125
     2 RMII_PCH_SPRNGVLLE_ARB_OUT @BASEBOARD_FAB2_LIB.BASEBOARD_FAB2(SCH_1):RMII_PCH_SPRNGVLLE_ARB_OUT    I85 @BASEBOARD_FAB2_LIB.BASEBOARD_FAB2(SCH_1):PAGE125

R8D17 RES_0402-1.37K,1%,1/16W,CHIP,GA
     1 P3V3_STBY @BASEBOARD_FAB2_LIB.BASEBOARD_FAB2(SCH_1):P3V3_STBY    I87 @BASEBOARD_FAB2_LIB.BASEBOARD_FAB2(SCH_1):PAGE138
     2 SMB_VR_STBY_LVC3_SDA @BASEBOARD_FAB2_LIB.BASEBOARD_FAB2(SCH_1):SMB_VR_STBY_LVC3_SDA    I87 @BASEBOARD_FAB2_LIB.BASEBOARD_FAB2(SCH_1):PAGE138

R8D19 RES_0402-49.9,1%,1/16W,CHIP,G2A
     1 SGPIO_PCH_SATA_DOUT0 @BASEBOARD_FAB2_LIB.BASEBOARD_FAB2(SCH_1):SGPIO_PCH_SATA_DOUT0     I8 @BASEBOARD_FAB2_LIB.BASEBOARD_FAB2(SCH_1):PAGE178
     2 SGPIO_PCH_SATA_DOUT0_R @BASEBOARD_FAB2_LIB.BASEBOARD_FAB2(SCH_1):SGPIO_PCH_SATA_DOUT0_R     I8 @BASEBOARD_FAB2_LIB.BASEBOARD_FAB2(SCH_1):PAGE178

R8D20 RES_0402-49.9,1%,1/16W,CHIP,G2A
     1 SGPIO_PCH_SATA_LOAD @BASEBOARD_FAB2_LIB.BASEBOARD_FAB2(SCH_1):SGPIO_PCH_SATA_LOAD     I1 @BASEBOARD_FAB2_LIB.BASEBOARD_FAB2(SCH_1):PAGE178
     2 SGPIO_PCH_SATA_LOAD_R @BASEBOARD_FAB2_LIB.BASEBOARD_FAB2(SCH_1):SGPIO_PCH_SATA_LOAD_R     I1 @BASEBOARD_FAB2_LIB.BASEBOARD_FAB2(SCH_1):PAGE178

R8D21 RES_0402-1.00K,1%,1/16W,CHIP,GA
     1 P3V3_STBY @BASEBOARD_FAB2_LIB.BASEBOARD_FAB2(SCH_1):P3V3_STBY   I120 @BASEBOARD_FAB2_LIB.BASEBOARD_FAB2(SCH_1):PAGE135
     2 FM_IE_DISABLE_N @BASEBOARD_FAB2_LIB.BASEBOARD_FAB2(SCH_1):FM_IE_DISABLE_N   I120 @BASEBOARD_FAB2_LIB.BASEBOARD_FAB2(SCH_1):PAGE135

R8D22 RES_0402-33.2,1%,1/16W,CHIP,G2A
     1 RST_BMC_SRST_R2_N @BASEBOARD_FAB2_LIB.BASEBOARD_FAB2(SCH_1):RST_BMC_SRST_R2_N   I386 @BASEBOARD_FAB2_LIB.BASEBOARD_FAB2(SCH_1):PAGE157
     2 FM_TPM_PRES_RST_N @BASEBOARD_FAB2_LIB.BASEBOARD_FAB2(SCH_1):FM_TPM_PRES_RST_N   I386 @BASEBOARD_FAB2_LIB.BASEBOARD_FAB2(SCH_1):PAGE157

R8D23 RES_0402-20.0,1%,1/16W,CHIP,G2A
     1 SMB_SENSOR_STBY_LVC3_SDA_R2 @BASEBOARD_FAB2_LIB.BASEBOARD_FAB2(SCH_1):SMB_SENSOR_STBY_LVC3_SDA_R2    I85 @BASEBOARD_FAB2_LIB.BASEBOARD_FAB2(SCH_1):PAGE167
     2 SMB_SENSOR_STBY_LVC3_SDA @BASEBOARD_FAB2_LIB.BASEBOARD_FAB2(SCH_1):SMB_SENSOR_STBY_LVC3_SDA    I85 @BASEBOARD_FAB2_LIB.BASEBOARD_FAB2(SCH_1):PAGE167

R8D24 RES_0402-20.0,1%,1/16W,CHIP,G2A
     1 SMB_SENSOR_STBY_LVC3_SCL @BASEBOARD_FAB2_LIB.BASEBOARD_FAB2(SCH_1):SMB_SENSOR_STBY_LVC3_SCL    I84 @BASEBOARD_FAB2_LIB.BASEBOARD_FAB2(SCH_1):PAGE167
     2 SMB_SENSOR_STBY_LVC3_SCL_R2 @BASEBOARD_FAB2_LIB.BASEBOARD_FAB2(SCH_1):SMB_SENSOR_STBY_LVC3_SCL_R2    I84 @BASEBOARD_FAB2_LIB.BASEBOARD_FAB2(SCH_1):PAGE167

R8D25 RES_0402-4.75K,1%,1/16W,CHIP,GA
     1 P3V3_STBY @BASEBOARD_FAB2_LIB.BASEBOARD_FAB2(SCH_1):P3V3_STBY   I335 @BASEBOARD_FAB2_LIB.BASEBOARD_FAB2(SCH_1):PAGE157
     2 RST_BMC_SRST_R2_N @BASEBOARD_FAB2_LIB.BASEBOARD_FAB2(SCH_1):RST_BMC_SRST_R2_N   I335 @BASEBOARD_FAB2_LIB.BASEBOARD_FAB2(SCH_1):PAGE157

R8D26 RES_0402-4.75K,1%,1/16W,CHIP,GA
     1 P3V3_STBY @BASEBOARD_FAB2_LIB.BASEBOARD_FAB2(SCH_1):P3V3_STBY    I71 @BASEBOARD_FAB2_LIB.BASEBOARD_FAB2(SCH_1):PAGE170
     2 IRQ_SML1_PMBUS_ALERT_BUF_N @BASEBOARD_FAB2_LIB.BASEBOARD_FAB2(SCH_1):IRQ_SML1_PMBUS_ALERT_BUF_N    I71 @BASEBOARD_FAB2_LIB.BASEBOARD_FAB2(SCH_1):PAGE170

R8D27 RES_0402-1.00K,1%,1/16W,CHIP,GA
     1 PD_FRU_WP @BASEBOARD_FAB2_LIB.BASEBOARD_FAB2(SCH_1):PD_FRU_WP    I50 @BASEBOARD_FAB2_LIB.BASEBOARD_FAB2(SCH_1):PAGE167
     2    GND @BASEBOARD_FAB2_LIB.BASEBOARD_FAB2(SCH_1):GND    I50 @BASEBOARD_FAB2_LIB.BASEBOARD_FAB2(SCH_1):PAGE167

R8D28 RES_0402-1.00K,1%,1/16W,CHIP,GA
     1 P3V3_STBY @BASEBOARD_FAB2_LIB.BASEBOARD_FAB2(SCH_1):P3V3_STBY    I70 @BASEBOARD_FAB2_LIB.BASEBOARD_FAB2(SCH_1):PAGE167
     2 PU_AT24C64_A2 @BASEBOARD_FAB2_LIB.BASEBOARD_FAB2(SCH_1):PU_AT24C64_A2    I70 @BASEBOARD_FAB2_LIB.BASEBOARD_FAB2(SCH_1):PAGE167

R8D29 RES_0402-4.75K,1%,1/16W,CHIP,GA
     1 P3V3_STBY @BASEBOARD_FAB2_LIB.BASEBOARD_FAB2(SCH_1):P3V3_STBY    I26 @BASEBOARD_FAB2_LIB.BASEBOARD_FAB2(SCH_1):PAGE89
     2 IRQ_DIMM_SAVE_LVT3 @BASEBOARD_FAB2_LIB.BASEBOARD_FAB2(SCH_1):IRQ_DIMM_SAVE_LVT3    I26 @BASEBOARD_FAB2_LIB.BASEBOARD_FAB2(SCH_1):PAGE89

R8D30 RES_0402-10.0K,1%,1/16W,CHIP,GA
     1 IRQ_DIMM_SAVE_N @BASEBOARD_FAB2_LIB.BASEBOARD_FAB2(SCH_1):IRQ_DIMM_SAVE_N    I34 @BASEBOARD_FAB2_LIB.BASEBOARD_FAB2(SCH_1):PAGE89
     2 IRQ_DIMM_SAVE_R_N @BASEBOARD_FAB2_LIB.BASEBOARD_FAB2(SCH_1):IRQ_DIMM_SAVE_R_N    I34 @BASEBOARD_FAB2_LIB.BASEBOARD_FAB2(SCH_1):PAGE89

R8D31 RES_0402-4.75K,1%,1/16W,CHIP,GA
     1 P3V3_STBY @BASEBOARD_FAB2_LIB.BASEBOARD_FAB2(SCH_1):P3V3_STBY    I27 @BASEBOARD_FAB2_LIB.BASEBOARD_FAB2(SCH_1):PAGE89
     2 IRQ_DIMM_SAVE_LVT3_N @BASEBOARD_FAB2_LIB.BASEBOARD_FAB2(SCH_1):IRQ_DIMM_SAVE_LVT3_N    I27 @BASEBOARD_FAB2_LIB.BASEBOARD_FAB2(SCH_1):PAGE89

R8D35 RES_0402-0.0,5%,1/16W,CHIP,G21A
     1 SPI_PCH_TPM_CS_N @BASEBOARD_FAB2_LIB.BASEBOARD_FAB2(SCH_1):SPI_PCH_TPM_CS_N    I92 @BASEBOARD_FAB2_LIB.BASEBOARD_FAB2(SCH_1):PAGE184
     2 SPI_PCH_TPM_CS_R_N @BASEBOARD_FAB2_LIB.BASEBOARD_FAB2(SCH_1):SPI_PCH_TPM_CS_R_N    I92 @BASEBOARD_FAB2_LIB.BASEBOARD_FAB2(SCH_1):PAGE184

R8D36 RES_0402-33.2,1%,1/16W,CHIP,G2A
     1 RST_BMC_SRST_R2_N @BASEBOARD_FAB2_LIB.BASEBOARD_FAB2(SCH_1):RST_BMC_SRST_R2_N   I388 @BASEBOARD_FAB2_LIB.BASEBOARD_FAB2(SCH_1):PAGE157
     2 RST_BMC_DDR3_BUF_IN_N @BASEBOARD_FAB2_LIB.BASEBOARD_FAB2(SCH_1):RST_BMC_DDR3_BUF_IN_N   I388 @BASEBOARD_FAB2_LIB.BASEBOARD_FAB2(SCH_1):PAGE157

R8D37 RES_0402-4.75K,1%,1/16W,CHIP,GA
     1 A_PG_P5V @BASEBOARD_FAB2_LIB.BASEBOARD_FAB2(SCH_1):A_PG_P5V   I115 @BASEBOARD_FAB2_LIB.BASEBOARD_FAB2(SCH_1):PAGE196
     2    GND @BASEBOARD_FAB2_LIB.BASEBOARD_FAB2(SCH_1):GND   I115 @BASEBOARD_FAB2_LIB.BASEBOARD_FAB2(SCH_1):PAGE196

R8D38 RES_0402-100.0K,1%,1/16W,CHIP,A
     1   P12V @BASEBOARD_FAB2_LIB.BASEBOARD_FAB2(SCH_1):P12V   I112 @BASEBOARD_FAB2_LIB.BASEBOARD_FAB2(SCH_1):PAGE196
     2 A_PG_P12V_MAIN @BASEBOARD_FAB2_LIB.BASEBOARD_FAB2(SCH_1):A_PG_P12V_MAIN   I112 @BASEBOARD_FAB2_LIB.BASEBOARD_FAB2(SCH_1):PAGE196

R8D39 RES_0402-49.9K,1%,1/16W,CHIP,GA
     1    P5V @BASEBOARD_FAB2_LIB.BASEBOARD_FAB2(SCH_1):P5V   I114 @BASEBOARD_FAB2_LIB.BASEBOARD_FAB2(SCH_1):PAGE196
     2 A_PG_P5V @BASEBOARD_FAB2_LIB.BASEBOARD_FAB2(SCH_1):A_PG_P5V   I114 @BASEBOARD_FAB2_LIB.BASEBOARD_FAB2(SCH_1):PAGE196

R8D40 RES_0402-20.0K,1%,1/16W,CHIP,GA
     1 A_PG_P12V_MAIN @BASEBOARD_FAB2_LIB.BASEBOARD_FAB2(SCH_1):A_PG_P12V_MAIN   I130 @BASEBOARD_FAB2_LIB.BASEBOARD_FAB2(SCH_1):PAGE196
     2    GND @BASEBOARD_FAB2_LIB.BASEBOARD_FAB2(SCH_1):GND   I130 @BASEBOARD_FAB2_LIB.BASEBOARD_FAB2(SCH_1):PAGE196

R8D41 RES_0402-10.0K,1%,1/16W,CHIP,GA
     1 P3V3_STBY @BASEBOARD_FAB2_LIB.BASEBOARD_FAB2(SCH_1):P3V3_STBY   I120 @BASEBOARD_FAB2_LIB.BASEBOARD_FAB2(SCH_1):PAGE196
     2 PWRGD_P12V_MAIN_R @BASEBOARD_FAB2_LIB.BASEBOARD_FAB2(SCH_1):PWRGD_P12V_MAIN_R   I120 @BASEBOARD_FAB2_LIB.BASEBOARD_FAB2(SCH_1):PAGE196

R8D42 RES_0402-100.0,1%,1/16W,CHIP,GA
     1 PWRGD_P12V_MAIN_R @BASEBOARD_FAB2_LIB.BASEBOARD_FAB2(SCH_1):PWRGD_P12V_MAIN_R   I106 @BASEBOARD_FAB2_LIB.BASEBOARD_FAB2(SCH_1):PAGE196
     2 PWRGD_P12V_MAIN @BASEBOARD_FAB2_LIB.BASEBOARD_FAB2(SCH_1):PWRGD_P12V_MAIN   I106 @BASEBOARD_FAB2_LIB.BASEBOARD_FAB2(SCH_1):PAGE196

R8D43 RES_0402-0.0,5%,1/16W,CHIP,G21A
     1 FM_156M_CPU0_BRD_OSC_EN @BASEBOARD_FAB2_LIB.BASEBOARD_FAB2(SCH_1):FM_156M_CPU0_BRD_OSC_EN    I93 @BASEBOARD_FAB2_LIB.BASEBOARD_FAB2(SCH_1):PAGE104
     2 FM_CPU0_STL_BRD_OSC_EN @BASEBOARD_FAB2_LIB.BASEBOARD_FAB2(SCH_1):FM_CPU0_STL_BRD_OSC_EN    I93 @BASEBOARD_FAB2_LIB.BASEBOARD_FAB2(SCH_1):PAGE104

R8D44 RES_0402-10.0K,1%,1/16W,CHIP,GA
     1 P3V3_STBY @BASEBOARD_FAB2_LIB.BASEBOARD_FAB2(SCH_1):P3V3_STBY   I362 @BASEBOARD_FAB2_LIB.BASEBOARD_FAB2(SCH_1):PAGE133
     2 FM_CPU0_RC_EN @BASEBOARD_FAB2_LIB.BASEBOARD_FAB2(SCH_1):FM_CPU0_RC_EN   I362 @BASEBOARD_FAB2_LIB.BASEBOARD_FAB2(SCH_1):PAGE133

R8E1 RES_0402-0.0,5%,1/16W,CHIP,G21A
     1 IRQ_SPI_TPM_N_R @BASEBOARD_FAB2_LIB.BASEBOARD_FAB2(SCH_1):IRQ_SPI_TPM_N_R    I99 @BASEBOARD_FAB2_LIB.BASEBOARD_FAB2(SCH_1):PAGE184
     2 IRQ_PIRQA_SPI_TPM_N @BASEBOARD_FAB2_LIB.BASEBOARD_FAB2(SCH_1):IRQ_PIRQA_SPI_TPM_N    I99 @BASEBOARD_FAB2_LIB.BASEBOARD_FAB2(SCH_1):PAGE184

R8E2 RES_0402-1.00K,1%,1/16W,CHIP,GA
     1 XDP_SPI_PCH_MOSI_BOOT_HALT_N @BASEBOARD_FAB2_LIB.BASEBOARD_FAB2(SCH_1):XDP_SPI_PCH_MOSI_BOOT_HALT_N    I89 @BASEBOARD_FAB2_LIB.BASEBOARD_FAB2(SCH_1):PAGE111
     2 SPI_PCH_MOSI @BASEBOARD_FAB2_LIB.BASEBOARD_FAB2(SCH_1):SPI_PCH_MOSI    I89 @BASEBOARD_FAB2_LIB.BASEBOARD_FAB2(SCH_1):PAGE111

R8E3 RES_0402-4.75K,1%,1/16W,CHIP,GA
     1 P3V3_STBY @BASEBOARD_FAB2_LIB.BASEBOARD_FAB2(SCH_1):P3V3_STBY   I371 @BASEBOARD_FAB2_LIB.BASEBOARD_FAB2(SCH_1):PAGE133
     2 FM_TPM_PRES_N @BASEBOARD_FAB2_LIB.BASEBOARD_FAB2(SCH_1):FM_TPM_PRES_N   I371 @BASEBOARD_FAB2_LIB.BASEBOARD_FAB2(SCH_1):PAGE133

R8E4 RES_0402-1.00K,1%,1/16W,EMPTY,A
     1 SPI_PCH_MOSI @BASEBOARD_FAB2_LIB.BASEBOARD_FAB2(SCH_1):SPI_PCH_MOSI    I24 @BASEBOARD_FAB2_LIB.BASEBOARD_FAB2(SCH_1):PAGE125
     2    GND @BASEBOARD_FAB2_LIB.BASEBOARD_FAB2(SCH_1):GND    I24 @BASEBOARD_FAB2_LIB.BASEBOARD_FAB2(SCH_1):PAGE125

R8E5 RES_0402-33.2,1%,1/16W,CHIP,G2A
     1 FM_CTNR_PS_ON_R @BASEBOARD_FAB2_LIB.BASEBOARD_FAB2(SCH_1):FM_CTNR_PS_ON_R    I63 @BASEBOARD_FAB2_LIB.BASEBOARD_FAB2(SCH_1):PAGE181
     2 FM_CTNR_PS_ON @BASEBOARD_FAB2_LIB.BASEBOARD_FAB2(SCH_1):FM_CTNR_PS_ON    I63 @BASEBOARD_FAB2_LIB.BASEBOARD_FAB2(SCH_1):PAGE181

R8E6 RES_0402-1.00K,1%,1/16W,EMPTY,A
     1 P3V3_STBY @BASEBOARD_FAB2_LIB.BASEBOARD_FAB2(SCH_1):P3V3_STBY    I21 @BASEBOARD_FAB2_LIB.BASEBOARD_FAB2(SCH_1):PAGE125
     2 SPI_PCH_MOSI @BASEBOARD_FAB2_LIB.BASEBOARD_FAB2(SCH_1):SPI_PCH_MOSI    I21 @BASEBOARD_FAB2_LIB.BASEBOARD_FAB2(SCH_1):PAGE125

R8E7 RES_0402-22.1,1.0%,1/16W,CHIP,A
     1 PWRGD_P12V_HSC_DLY_R @BASEBOARD_FAB2_LIB.BASEBOARD_FAB2(SCH_1):PWRGD_P12V_HSC_DLY_R    I90 @BASEBOARD_FAB2_LIB.BASEBOARD_FAB2(SCH_1):PAGE196
     2 PWRGD_P12V_HSC_DLY @BASEBOARD_FAB2_LIB.BASEBOARD_FAB2(SCH_1):PWRGD_P12V_HSC_DLY    I90 @BASEBOARD_FAB2_LIB.BASEBOARD_FAB2(SCH_1):PAGE196

R8E9 RES_0402-33.2,1%,1/16W,CHIP,G2A
     1 SPI_PCH_CLK @BASEBOARD_FAB2_LIB.BASEBOARD_FAB2(SCH_1):SPI_PCH_CLK    I88 @BASEBOARD_FAB2_LIB.BASEBOARD_FAB2(SCH_1):PAGE184
     2 SPI_PCH_TPM_CLK_R @BASEBOARD_FAB2_LIB.BASEBOARD_FAB2(SCH_1):SPI_PCH_TPM_CLK_R    I88 @BASEBOARD_FAB2_LIB.BASEBOARD_FAB2(SCH_1):PAGE184

R8E10 RES_0402-33.2,1%,1/16W,CHIP,G2A
     1 SPI_PCH_MOSI @BASEBOARD_FAB2_LIB.BASEBOARD_FAB2(SCH_1):SPI_PCH_MOSI    I95 @BASEBOARD_FAB2_LIB.BASEBOARD_FAB2(SCH_1):PAGE184
     2 SPI_PCH_TPM_MOSI_R @BASEBOARD_FAB2_LIB.BASEBOARD_FAB2(SCH_1):SPI_PCH_TPM_MOSI_R    I95 @BASEBOARD_FAB2_LIB.BASEBOARD_FAB2(SCH_1):PAGE184

R8E11 RES_0402-0.0,5%,1/16W,EMPTY,G2A
     1 FM_MEM_THERM_EVENT_LVT3_N @BASEBOARD_FAB2_LIB.BASEBOARD_FAB2(SCH_1):FM_MEM_THERM_EVENT_LVT3_N   I279 @BASEBOARD_FAB2_LIB.BASEBOARD_FAB2(SCH_1):PAGE156
     2 FM_ADR_SMI_GPIO_N @BASEBOARD_FAB2_LIB.BASEBOARD_FAB2(SCH_1):FM_ADR_SMI_GPIO_N   I279 @BASEBOARD_FAB2_LIB.BASEBOARD_FAB2(SCH_1):PAGE156

R8E12 RES_0402-4.75K,1%,1/16W,EMPTY,A
     1 P3V3_STBY @BASEBOARD_FAB2_LIB.BASEBOARD_FAB2(SCH_1):P3V3_STBY    I78 @BASEBOARD_FAB2_LIB.BASEBOARD_FAB2(SCH_1):PAGE198
     2 FM_CTNR_PS_ON @BASEBOARD_FAB2_LIB.BASEBOARD_FAB2(SCH_1):FM_CTNR_PS_ON    I78 @BASEBOARD_FAB2_LIB.BASEBOARD_FAB2(SCH_1):PAGE198

R8E13 RES_0402-33.2,1%,1/16W,CHIP,G2A
     1 SPI_PCH_MISO @BASEBOARD_FAB2_LIB.BASEBOARD_FAB2(SCH_1):SPI_PCH_MISO    I93 @BASEBOARD_FAB2_LIB.BASEBOARD_FAB2(SCH_1):PAGE184
     2 SPI_PCH_TPM_MISO_R @BASEBOARD_FAB2_LIB.BASEBOARD_FAB2(SCH_1):SPI_PCH_TPM_MISO_R    I93 @BASEBOARD_FAB2_LIB.BASEBOARD_FAB2(SCH_1):PAGE184

R8E14 RES_0402-4.75K,1%,1/16W,CHIP,GA
     1 P3V3_STBY @BASEBOARD_FAB2_LIB.BASEBOARD_FAB2(SCH_1):P3V3_STBY   I133 @BASEBOARD_FAB2_LIB.BASEBOARD_FAB2(SCH_1):PAGE136
     2 RST_PLTRST_TOP_SWAP @BASEBOARD_FAB2_LIB.BASEBOARD_FAB2(SCH_1):RST_PLTRST_TOP_SWAP   I133 @BASEBOARD_FAB2_LIB.BASEBOARD_FAB2(SCH_1):PAGE136

R8E16 RES_0402-20.0K,1%,1/16W,CHIP,GA
     1 FM_BIOS_TOP_SWAP @BASEBOARD_FAB2_LIB.BASEBOARD_FAB2(SCH_1):FM_BIOS_TOP_SWAP   I140 @BASEBOARD_FAB2_LIB.BASEBOARD_FAB2(SCH_1):PAGE136
     2    GND @BASEBOARD_FAB2_LIB.BASEBOARD_FAB2(SCH_1):GND   I140 @BASEBOARD_FAB2_LIB.BASEBOARD_FAB2(SCH_1):PAGE136

R8E17 RES_0402-33.2,1%,1/16W,CHIP,G2A
     1 IRQ_LVC3_WAKE_R_N @BASEBOARD_FAB2_LIB.BASEBOARD_FAB2(SCH_1):IRQ_LVC3_WAKE_R_N     I2 @BASEBOARD_FAB2_LIB.BASEBOARD_FAB2(SCH_1):PAGE142
     2 IRQ_LVC3_WAKE_N @BASEBOARD_FAB2_LIB.BASEBOARD_FAB2(SCH_1):IRQ_LVC3_WAKE_N     I2 @BASEBOARD_FAB2_LIB.BASEBOARD_FAB2(SCH_1):PAGE142

R8E18 RES_0402-1.0K,0.1%,1/16W,CHIP,A
     1 P5V_STBY @BASEBOARD_FAB2_LIB.BASEBOARD_FAB2(SCH_1):P5V_STBY     I9 @BASEBOARD_FAB2_LIB.BASEBOARD_FAB2(SCH_1):PAGE241
     2    GND @BASEBOARD_FAB2_LIB.BASEBOARD_FAB2(SCH_1):GND     I9 @BASEBOARD_FAB2_LIB.BASEBOARD_FAB2(SCH_1):PAGE241

R8E19 RES_0402-4.75K,1%,1/16W,EMPTY,A
     1 P3V3_STBY @BASEBOARD_FAB2_LIB.BASEBOARD_FAB2(SCH_1):P3V3_STBY   I361 @BASEBOARD_FAB2_LIB.BASEBOARD_FAB2(SCH_1):PAGE157
     2 FM_BIOS_TOP_SWAP @BASEBOARD_FAB2_LIB.BASEBOARD_FAB2(SCH_1):FM_BIOS_TOP_SWAP   I361 @BASEBOARD_FAB2_LIB.BASEBOARD_FAB2(SCH_1):PAGE157

R8E20 RES_0402-33.2,1%,1/16W,CHIP,G2A
     1 FM_BIOS_TOP_SWAP_SPKR_R @BASEBOARD_FAB2_LIB.BASEBOARD_FAB2(SCH_1):FM_BIOS_TOP_SWAP_SPKR_R   I126 @BASEBOARD_FAB2_LIB.BASEBOARD_FAB2(SCH_1):PAGE136
     2 FM_BIOS_TOP_SWAP_SPKR @BASEBOARD_FAB2_LIB.BASEBOARD_FAB2(SCH_1):FM_BIOS_TOP_SWAP_SPKR   I126 @BASEBOARD_FAB2_LIB.BASEBOARD_FAB2(SCH_1):PAGE136

R8E21 RES_0402-0.0,5%,1/16W,CHIP,G21A
     1 FM_PE_SPRV_WAKE_N @BASEBOARD_FAB2_LIB.BASEBOARD_FAB2(SCH_1):FM_PE_SPRV_WAKE_N    I33 @BASEBOARD_FAB2_LIB.BASEBOARD_FAB2(SCH_1):PAGE142
     2 FM_ALL_WAKE_N @BASEBOARD_FAB2_LIB.BASEBOARD_FAB2(SCH_1):FM_ALL_WAKE_N    I33 @BASEBOARD_FAB2_LIB.BASEBOARD_FAB2(SCH_1):PAGE142

R8E22 RES_0402-4.75K,1%,1/16W,CHIP,GA
     1 P3V3_STBY @BASEBOARD_FAB2_LIB.BASEBOARD_FAB2(SCH_1):P3V3_STBY   I215 @BASEBOARD_FAB2_LIB.BASEBOARD_FAB2(SCH_1):PAGE156
     2 IRQ_BMC_PCH_NMI_STBY_N @BASEBOARD_FAB2_LIB.BASEBOARD_FAB2(SCH_1):IRQ_BMC_PCH_NMI_STBY_N   I215 @BASEBOARD_FAB2_LIB.BASEBOARD_FAB2(SCH_1):PAGE156

R8E23 RES_0402-4.75K,1%,1/16W,CHIP,GA
     1 PU_TRI_STATE_EN @BASEBOARD_FAB2_LIB.BASEBOARD_FAB2(SCH_1):PU_TRI_STATE_EN     I3 @BASEBOARD_FAB2_LIB.BASEBOARD_FAB2(SCH_1):PAGE142
     2 P3V3_STBY @BASEBOARD_FAB2_LIB.BASEBOARD_FAB2(SCH_1):P3V3_STBY     I3 @BASEBOARD_FAB2_LIB.BASEBOARD_FAB2(SCH_1):PAGE142

R8E24 RES_0402-33.2,1%,1/16W,CHIP,G2A
     1 IRQ_BMC_PCH_NMI_STBY_N @BASEBOARD_FAB2_LIB.BASEBOARD_FAB2(SCH_1):IRQ_BMC_PCH_NMI_STBY_N   I214 @BASEBOARD_FAB2_LIB.BASEBOARD_FAB2(SCH_1):PAGE156
     2 IRQ_BMC_PCH_NMI_STBY_R_N @BASEBOARD_FAB2_LIB.BASEBOARD_FAB2(SCH_1):IRQ_BMC_PCH_NMI_STBY_R_N   I214 @BASEBOARD_FAB2_LIB.BASEBOARD_FAB2(SCH_1):PAGE156

R8E25 RES_0402-0.0,5%,1/16W,CHIP,G21A
     1 P3V3_STBY @BASEBOARD_FAB2_LIB.BASEBOARD_FAB2(SCH_1):P3V3_STBY   I144 @BASEBOARD_FAB2_LIB.BASEBOARD_FAB2(SCH_1):PAGE240
     2 VSENSE_P3V3_STBY @BASEBOARD_FAB2_LIB.BASEBOARD_FAB2(SCH_1):VSENSE_P3V3_STBY   I144 @BASEBOARD_FAB2_LIB.BASEBOARD_FAB2(SCH_1):PAGE240

R8E26 RES_0402-0.0,5%,1/16W,CHIP,G21A
     1 FM_PE_OCP_WAKE_N @BASEBOARD_FAB2_LIB.BASEBOARD_FAB2(SCH_1):FM_PE_OCP_WAKE_N    I30 @BASEBOARD_FAB2_LIB.BASEBOARD_FAB2(SCH_1):PAGE142
     2 FM_ALL_WAKE_N @BASEBOARD_FAB2_LIB.BASEBOARD_FAB2(SCH_1):FM_ALL_WAKE_N    I30 @BASEBOARD_FAB2_LIB.BASEBOARD_FAB2(SCH_1):PAGE142

R8E27 RES_0402-0.0,5%,1/16W,CHIP,G21A
     1 FM_PE_M2_WAKE_N @BASEBOARD_FAB2_LIB.BASEBOARD_FAB2(SCH_1):FM_PE_M2_WAKE_N    I32 @BASEBOARD_FAB2_LIB.BASEBOARD_FAB2(SCH_1):PAGE142
     2 FM_ALL_WAKE_N @BASEBOARD_FAB2_LIB.BASEBOARD_FAB2(SCH_1):FM_ALL_WAKE_N    I32 @BASEBOARD_FAB2_LIB.BASEBOARD_FAB2(SCH_1):PAGE142

R8E28 RES_0402-0.0,5%,1/16W,CHIP,G21A
     1 FM_PE_SLOTX24_WAKE_N @BASEBOARD_FAB2_LIB.BASEBOARD_FAB2(SCH_1):FM_PE_SLOTX24_WAKE_N    I31 @BASEBOARD_FAB2_LIB.BASEBOARD_FAB2(SCH_1):PAGE142
     2 FM_ALL_WAKE_N @BASEBOARD_FAB2_LIB.BASEBOARD_FAB2(SCH_1):FM_ALL_WAKE_N    I31 @BASEBOARD_FAB2_LIB.BASEBOARD_FAB2(SCH_1):PAGE142

R8E29 RES_0402-0.0,5%,1/16W,EMPTY,G2A
     1 FM_PE_BMC_WAKE_N @BASEBOARD_FAB2_LIB.BASEBOARD_FAB2(SCH_1):FM_PE_BMC_WAKE_N    I18 @BASEBOARD_FAB2_LIB.BASEBOARD_FAB2(SCH_1):PAGE142
     2 FM_ALL_WAKE_N @BASEBOARD_FAB2_LIB.BASEBOARD_FAB2(SCH_1):FM_ALL_WAKE_N    I18 @BASEBOARD_FAB2_LIB.BASEBOARD_FAB2(SCH_1):PAGE142

R8E30 2K15R2F-1-GP_SMD-RG1-2K15R2F-1A
     1 P3V3_STBY @BASEBOARD_FAB2_LIB.BASEBOARD_FAB2(SCH_1):P3V3_STBY    I35 @BASEBOARD_FAB2_LIB.BASEBOARD_FAB2(SCH_1):PAGE142
     2 FM_ALL_WAKE_N @BASEBOARD_FAB2_LIB.BASEBOARD_FAB2(SCH_1):FM_ALL_WAKE_N    I35 @BASEBOARD_FAB2_LIB.BASEBOARD_FAB2(SCH_1):PAGE142

R8E31 RES_0402-23.2K,1%,1/16W,CHIP,GA
     1 VSENSE_P3V3_STBY @BASEBOARD_FAB2_LIB.BASEBOARD_FAB2(SCH_1):VSENSE_P3V3_STBY   I143 @BASEBOARD_FAB2_LIB.BASEBOARD_FAB2(SCH_1):PAGE240
     2 VSENSE_VOUT_P3V3_STBY @BASEBOARD_FAB2_LIB.BASEBOARD_FAB2(SCH_1):VSENSE_VOUT_P3V3_STBY   I143 @BASEBOARD_FAB2_LIB.BASEBOARD_FAB2(SCH_1):PAGE240

R8E32 RES_0402-4.75K,1%,1/16W,CHIP,GA
     1 P3V3_STBY @BASEBOARD_FAB2_LIB.BASEBOARD_FAB2(SCH_1):P3V3_STBY   I385 @BASEBOARD_FAB2_LIB.BASEBOARD_FAB2(SCH_1):PAGE157
     2 FP_NMI_BTN_OUT_R_N @BASEBOARD_FAB2_LIB.BASEBOARD_FAB2(SCH_1):FP_NMI_BTN_OUT_R_N   I385 @BASEBOARD_FAB2_LIB.BASEBOARD_FAB2(SCH_1):PAGE157

R8E33 RES_0402-0.0,5%,1/16W,CHIP,G21A
     1 PWRGD_P12V_HSC_DLY @BASEBOARD_FAB2_LIB.BASEBOARD_FAB2(SCH_1):PWRGD_P12V_HSC_DLY    I91 @BASEBOARD_FAB2_LIB.BASEBOARD_FAB2(SCH_1):PAGE241
     2 VR_P5V_STBY_EN @BASEBOARD_FAB2_LIB.BASEBOARD_FAB2(SCH_1):VR_P5V_STBY_EN    I91 @BASEBOARD_FAB2_LIB.BASEBOARD_FAB2(SCH_1):PAGE241

R8E34 RES_0402-10.0K,1%,1/16W,CHIP,GA
     1 VSENSE_VOUT_P3V3_STBY @BASEBOARD_FAB2_LIB.BASEBOARD_FAB2(SCH_1):VSENSE_VOUT_P3V3_STBY   I142 @BASEBOARD_FAB2_LIB.BASEBOARD_FAB2(SCH_1):PAGE240
     2 AGND_P3V3_STBY @BASEBOARD_FAB2_LIB.BASEBOARD_FAB2(SCH_1):AGND_P3V3_STBY   I142 @BASEBOARD_FAB2_LIB.BASEBOARD_FAB2(SCH_1):PAGE240

R8E35 RES_0402-0.0,5%,1/16W,CHIP,G21A
     1 VR_P3V3_STBY_BOOT @BASEBOARD_FAB2_LIB.BASEBOARD_FAB2(SCH_1):VR_P3V3_STBY_BOOT   I127 @BASEBOARD_FAB2_LIB.BASEBOARD_FAB2(SCH_1):PAGE240
     2 VR_P3V3_STBY_BOOT_R @BASEBOARD_FAB2_LIB.BASEBOARD_FAB2(SCH_1):VR_P3V3_STBY_BOOT_R   I127 @BASEBOARD_FAB2_LIB.BASEBOARD_FAB2(SCH_1):PAGE240

R8E36 2K15R2F-1-GP_SMD-RG1-2K15R2F-1A
     1 P3V3_STBY @BASEBOARD_FAB2_LIB.BASEBOARD_FAB2(SCH_1):P3V3_STBY    I34 @BASEBOARD_FAB2_LIB.BASEBOARD_FAB2(SCH_1):PAGE142
     2 FM_PE_SLOTX24_WAKE_N @BASEBOARD_FAB2_LIB.BASEBOARD_FAB2(SCH_1):FM_PE_SLOTX24_WAKE_N    I34 @BASEBOARD_FAB2_LIB.BASEBOARD_FAB2(SCH_1):PAGE142

R8E37 RES_0402-0.0,5%,1/16W,CHIP,G21A
     1 VR_P5V_STBY_VSENSE_R @BASEBOARD_FAB2_LIB.BASEBOARD_FAB2(SCH_1):VR_P5V_STBY_VSENSE_R    I78 @BASEBOARD_FAB2_LIB.BASEBOARD_FAB2(SCH_1):PAGE241
     2 P5V_STBY @BASEBOARD_FAB2_LIB.BASEBOARD_FAB2(SCH_1):P5V_STBY    I78 @BASEBOARD_FAB2_LIB.BASEBOARD_FAB2(SCH_1):PAGE241

R8E38 RES_0402-0.0,5%,1/16W,CHIP,G21A
     1 VSENSE_RGND_P3V3_STBY @BASEBOARD_FAB2_LIB.BASEBOARD_FAB2(SCH_1):VSENSE_RGND_P3V3_STBY   I140 @BASEBOARD_FAB2_LIB.BASEBOARD_FAB2(SCH_1):PAGE240
     2 AGND_P3V3_STBY @BASEBOARD_FAB2_LIB.BASEBOARD_FAB2(SCH_1):AGND_P3V3_STBY   I140 @BASEBOARD_FAB2_LIB.BASEBOARD_FAB2(SCH_1):PAGE240

R8E39 RES_0402-24.9K,1%,1/16W,CHIP,GA
     1 VR_P5V_STBY_COMP @BASEBOARD_FAB2_LIB.BASEBOARD_FAB2(SCH_1):VR_P5V_STBY_COMP    I54 @BASEBOARD_FAB2_LIB.BASEBOARD_FAB2(SCH_1):PAGE241
     2 VR_P5V_STBY_RC_COMP @BASEBOARD_FAB2_LIB.BASEBOARD_FAB2(SCH_1):VR_P5V_STBY_RC_COMP    I54 @BASEBOARD_FAB2_LIB.BASEBOARD_FAB2(SCH_1):PAGE241

R8E40 RES_0402-100.0K,1%,1/16W,EMPTYA
     1 P3V3_STBY @BASEBOARD_FAB2_LIB.BASEBOARD_FAB2(SCH_1):P3V3_STBY   I177 @BASEBOARD_FAB2_LIB.BASEBOARD_FAB2(SCH_1):PAGE240
     2 VR_P3V3_STBY_EN @BASEBOARD_FAB2_LIB.BASEBOARD_FAB2(SCH_1):VR_P3V3_STBY_EN   I177 @BASEBOARD_FAB2_LIB.BASEBOARD_FAB2(SCH_1):PAGE240

R8F1 RES_0402-10.0K,1%,1/16W,EMPTY,A
     1 PWRGD_P5V_STBY @BASEBOARD_FAB2_LIB.BASEBOARD_FAB2(SCH_1):PWRGD_P5V_STBY   I111 @BASEBOARD_FAB2_LIB.BASEBOARD_FAB2(SCH_1):PAGE240
     2    GND @BASEBOARD_FAB2_LIB.BASEBOARD_FAB2(SCH_1):GND   I111 @BASEBOARD_FAB2_LIB.BASEBOARD_FAB2(SCH_1):PAGE240

R8F2 RES_0402-0.0,5%,1/16W,CHIP,G21A
     1 PWRGD_P5V_STBY @BASEBOARD_FAB2_LIB.BASEBOARD_FAB2(SCH_1):PWRGD_P5V_STBY   I176 @BASEBOARD_FAB2_LIB.BASEBOARD_FAB2(SCH_1):PAGE240
     2 VR_P3V3_STBY_EN @BASEBOARD_FAB2_LIB.BASEBOARD_FAB2(SCH_1):VR_P3V3_STBY_EN   I176 @BASEBOARD_FAB2_LIB.BASEBOARD_FAB2(SCH_1):PAGE240

R8F3 RES_0402-2.2,5%,1/16W,EMPTY,G2A
     1 VR_P3V3_STBY_SNUB @BASEBOARD_FAB2_LIB.BASEBOARD_FAB2(SCH_1):VR_P3V3_STBY_SNUB   I148 @BASEBOARD_FAB2_LIB.BASEBOARD_FAB2(SCH_1):PAGE240
     2    GND @BASEBOARD_FAB2_LIB.BASEBOARD_FAB2(SCH_1):GND   I148 @BASEBOARD_FAB2_LIB.BASEBOARD_FAB2(SCH_1):PAGE240

R8F5 RES_0402-1.00K,1%,1/16W,CHIP,GA
     1 P3V3_STBY @BASEBOARD_FAB2_LIB.BASEBOARD_FAB2(SCH_1):P3V3_STBY   I117 @BASEBOARD_FAB2_LIB.BASEBOARD_FAB2(SCH_1):PAGE240
     2 PWRGD_P3V3_STBY_R @BASEBOARD_FAB2_LIB.BASEBOARD_FAB2(SCH_1):PWRGD_P3V3_STBY_R   I117 @BASEBOARD_FAB2_LIB.BASEBOARD_FAB2(SCH_1):PAGE240

R8F6 RES_0402-0.0,5%,1/16W,CHIP,G21A
     1 SPI_PCH_MISO @BASEBOARD_FAB2_LIB.BASEBOARD_FAB2(SCH_1):SPI_PCH_MISO   I119 @BASEBOARD_FAB2_LIB.BASEBOARD_FAB2(SCH_1):PAGE154
     2 SPI_PCH_MISO_R @BASEBOARD_FAB2_LIB.BASEBOARD_FAB2(SCH_1):SPI_PCH_MISO_R   I119 @BASEBOARD_FAB2_LIB.BASEBOARD_FAB2(SCH_1):PAGE154

R8F7 RES_0402-33.2,1%,1/16W,CHIP,G2A
     1 SPI_SWITCH_CLK @BASEBOARD_FAB2_LIB.BASEBOARD_FAB2(SCH_1):SPI_SWITCH_CLK   I167 @BASEBOARD_FAB2_LIB.BASEBOARD_FAB2(SCH_1):PAGE153
     2 SPI_CLK_R1 @BASEBOARD_FAB2_LIB.BASEBOARD_FAB2(SCH_1):SPI_CLK_R1   I167 @BASEBOARD_FAB2_LIB.BASEBOARD_FAB2(SCH_1):PAGE153

R8F8 RES_0402-33.2,1%,1/16W,CHIP,G2A
     1 SPI_SWITCH_CLK @BASEBOARD_FAB2_LIB.BASEBOARD_FAB2(SCH_1):SPI_SWITCH_CLK   I166 @BASEBOARD_FAB2_LIB.BASEBOARD_FAB2(SCH_1):PAGE153
     2 SPI_CLK_R0 @BASEBOARD_FAB2_LIB.BASEBOARD_FAB2(SCH_1):SPI_CLK_R0   I166 @BASEBOARD_FAB2_LIB.BASEBOARD_FAB2(SCH_1):PAGE153

R8F9 RES_0402-49.9K,1%,1/16W,CHIP,GA
     1 VR_P3V3_STBY_OCSELECT @BASEBOARD_FAB2_LIB.BASEBOARD_FAB2(SCH_1):VR_P3V3_STBY_OCSELECT   I195 @BASEBOARD_FAB2_LIB.BASEBOARD_FAB2(SCH_1):PAGE240
     2 AGND_P3V3_STBY @BASEBOARD_FAB2_LIB.BASEBOARD_FAB2(SCH_1):AGND_P3V3_STBY   I195 @BASEBOARD_FAB2_LIB.BASEBOARD_FAB2(SCH_1):PAGE240

R8F10 RES_0402-22.1,1.0%,1/16W,CHIP,A
     1 PWRGD_P3V3_STBY_R @BASEBOARD_FAB2_LIB.BASEBOARD_FAB2(SCH_1):PWRGD_P3V3_STBY_R   I171 @BASEBOARD_FAB2_LIB.BASEBOARD_FAB2(SCH_1):PAGE240
     2 PWRGD_P3V3_STBY @BASEBOARD_FAB2_LIB.BASEBOARD_FAB2(SCH_1):PWRGD_P3V3_STBY   I171 @BASEBOARD_FAB2_LIB.BASEBOARD_FAB2(SCH_1):PAGE240

R8F11 RES_0402-0.0,5%,1/16W,CHIP,G21A
     1    GND @BASEBOARD_FAB2_LIB.BASEBOARD_FAB2(SCH_1):GND   I146 @BASEBOARD_FAB2_LIB.BASEBOARD_FAB2(SCH_1):PAGE240
     2 AGND_P3V3_STBY @BASEBOARD_FAB2_LIB.BASEBOARD_FAB2(SCH_1):AGND_P3V3_STBY   I146 @BASEBOARD_FAB2_LIB.BASEBOARD_FAB2(SCH_1):PAGE240

R8F12 RES_0402-33.2,1%,1/16W,CHIP,G2A
     1 SPI_BMC_BT_DI @BASEBOARD_FAB2_LIB.BASEBOARD_FAB2(SCH_1):SPI_BMC_BT_DI    I13 @BASEBOARD_FAB2_LIB.BASEBOARD_FAB2(SCH_1):PAGE162
     2 SPI_BMC_BT_DI_R @BASEBOARD_FAB2_LIB.BASEBOARD_FAB2(SCH_1):SPI_BMC_BT_DI_R    I13 @BASEBOARD_FAB2_LIB.BASEBOARD_FAB2(SCH_1):PAGE162

R8F13 RES_0402-4.75K,1%,1/16W,CHIP,GA
     1 P3V3_STBY @BASEBOARD_FAB2_LIB.BASEBOARD_FAB2(SCH_1):P3V3_STBY    I35 @BASEBOARD_FAB2_LIB.BASEBOARD_FAB2(SCH_1):PAGE162
     2 SPI_BMC_BT_CS_N @BASEBOARD_FAB2_LIB.BASEBOARD_FAB2(SCH_1):SPI_BMC_BT_CS_N    I35 @BASEBOARD_FAB2_LIB.BASEBOARD_FAB2(SCH_1):PAGE162

R8F14 RES_0402-4.75K,1%,1/16W,CHIP,GA
     1 P3V3_STBY @BASEBOARD_FAB2_LIB.BASEBOARD_FAB2(SCH_1):P3V3_STBY     I9 @BASEBOARD_FAB2_LIB.BASEBOARD_FAB2(SCH_1):PAGE162
     2 PU_SPI_BMC_BT_HOLD_N @BASEBOARD_FAB2_LIB.BASEBOARD_FAB2(SCH_1):PU_SPI_BMC_BT_HOLD_N     I9 @BASEBOARD_FAB2_LIB.BASEBOARD_FAB2(SCH_1):PAGE162

R8F16 RES_0402-4.75K,1%,1/16W,EMPTY,A
     1 P3V3_STBY @BASEBOARD_FAB2_LIB.BASEBOARD_FAB2(SCH_1):P3V3_STBY     I8 @BASEBOARD_FAB2_LIB.BASEBOARD_FAB2(SCH_1):PAGE162
     2 PU_SPI_FLASH_RESET_2_N @BASEBOARD_FAB2_LIB.BASEBOARD_FAB2(SCH_1):PU_SPI_FLASH_RESET_2_N     I8 @BASEBOARD_FAB2_LIB.BASEBOARD_FAB2(SCH_1):PAGE162

R8F18 RES_0402-0.0,5%,1/16W,CHIP,G21A
     1 P3E_PCH_RX_0_DP @BASEBOARD_FAB2_LIB.BASEBOARD_FAB2(SCH_1):P3E_PCH_RX_0_DP   I105 @BASEBOARD_FAB2_LIB.BASEBOARD_FAB2(SCH_1):PAGE185
     2 P3E_PCH_M2_SATA6G_RX_R_DP @BASEBOARD_FAB2_LIB.BASEBOARD_FAB2(SCH_1):P3E_PCH_M2_SATA6G_RX_R_DP   I105 @BASEBOARD_FAB2_LIB.BASEBOARD_FAB2(SCH_1):PAGE185

R8F21 RES_0402-0.0,5%,1/16W,CHIP,G21A
     1 P3E_PCH_RX_0_DN @BASEBOARD_FAB2_LIB.BASEBOARD_FAB2(SCH_1):P3E_PCH_RX_0_DN   I106 @BASEBOARD_FAB2_LIB.BASEBOARD_FAB2(SCH_1):PAGE185
     2 P3E_PCH_M2_SATA6G_RX_R_DN @BASEBOARD_FAB2_LIB.BASEBOARD_FAB2(SCH_1):P3E_PCH_M2_SATA6G_RX_R_DN   I106 @BASEBOARD_FAB2_LIB.BASEBOARD_FAB2(SCH_1):PAGE185

R8F23 RES_0402-2.21K,1%,1/16W,CHIP,GA
     1 P3V3_STBY @BASEBOARD_FAB2_LIB.BASEBOARD_FAB2(SCH_1):P3V3_STBY   I296 @BASEBOARD_FAB2_LIB.BASEBOARD_FAB2(SCH_1):PAGE157
     2 IRQ_MEZZ_LAN_ALERT_N @BASEBOARD_FAB2_LIB.BASEBOARD_FAB2(SCH_1):IRQ_MEZZ_LAN_ALERT_N   I296 @BASEBOARD_FAB2_LIB.BASEBOARD_FAB2(SCH_1):PAGE157

R8F24 RES_0402-4.75K,1%,1/16W,CHIP,GA
     1 P3V3_STBY @BASEBOARD_FAB2_LIB.BASEBOARD_FAB2(SCH_1):P3V3_STBY   I316 @BASEBOARD_FAB2_LIB.BASEBOARD_FAB2(SCH_1):PAGE157
     2 FP_NMI_BTN_N @BASEBOARD_FAB2_LIB.BASEBOARD_FAB2(SCH_1):FP_NMI_BTN_N   I316 @BASEBOARD_FAB2_LIB.BASEBOARD_FAB2(SCH_1):PAGE157

R8F25 RES_0402-475.0,1%,1/16W,CHIP,GA
     1 A_COMP_CKMNG @BASEBOARD_FAB2_LIB.BASEBOARD_FAB2(SCH_1):A_COMP_CKMNG    I28 @BASEBOARD_FAB2_LIB.BASEBOARD_FAB2(SCH_1):PAGE101
     2    GND @BASEBOARD_FAB2_LIB.BASEBOARD_FAB2(SCH_1):GND    I28 @BASEBOARD_FAB2_LIB.BASEBOARD_FAB2(SCH_1):PAGE101

R8F26 RES_0402-10.0K,1%,1/16W,CHIP,GA
     1 P3V3_STBY @BASEBOARD_FAB2_LIB.BASEBOARD_FAB2(SCH_1):P3V3_STBY   I211 @BASEBOARD_FAB2_LIB.BASEBOARD_FAB2(SCH_1):PAGE156
     2 FM_PCH_PWRBTN_R_N @BASEBOARD_FAB2_LIB.BASEBOARD_FAB2(SCH_1):FM_PCH_PWRBTN_R_N   I211 @BASEBOARD_FAB2_LIB.BASEBOARD_FAB2(SCH_1):PAGE156

R8F27 RES_0402-33.2,1%,1/16W,CHIP,G2A
     1 CLK_32K_SUSCLK_PLD_R @BASEBOARD_FAB2_LIB.BASEBOARD_FAB2(SCH_1):CLK_32K_SUSCLK_PLD_R   I142 @BASEBOARD_FAB2_LIB.BASEBOARD_FAB2(SCH_1):PAGE101
     2 CLK_32K_SUSCLK_PLD @BASEBOARD_FAB2_LIB.BASEBOARD_FAB2(SCH_1):CLK_32K_SUSCLK_PLD   I142 @BASEBOARD_FAB2_LIB.BASEBOARD_FAB2(SCH_1):PAGE101

R8F29 RES_0402-33.2,1%,1/16W,CHIP,G2A
     1 CLK_25M_BMC_R @BASEBOARD_FAB2_LIB.BASEBOARD_FAB2(SCH_1):CLK_25M_BMC_R    I20 @BASEBOARD_FAB2_LIB.BASEBOARD_FAB2(SCH_1):PAGE101
     2 CLK_25M_BMC @BASEBOARD_FAB2_LIB.BASEBOARD_FAB2(SCH_1):CLK_25M_BMC    I20 @BASEBOARD_FAB2_LIB.BASEBOARD_FAB2(SCH_1):PAGE101

R8F34 RES_0402-4.75K,1%,1/16W,CHIP,GA
     1 P3V3_STBY @BASEBOARD_FAB2_LIB.BASEBOARD_FAB2(SCH_1):P3V3_STBY    I22 @BASEBOARD_FAB2_LIB.BASEBOARD_FAB2(SCH_1):PAGE162
     2 PU_SPI_BMC_BT_WP_N @BASEBOARD_FAB2_LIB.BASEBOARD_FAB2(SCH_1):PU_SPI_BMC_BT_WP_N    I22 @BASEBOARD_FAB2_LIB.BASEBOARD_FAB2(SCH_1):PAGE162

R8F35 RES_0402-1.00K,1%,1/16W,EMPTY,A
     1 PU_SPI_BMC_BT_WP_N @BASEBOARD_FAB2_LIB.BASEBOARD_FAB2(SCH_1):PU_SPI_BMC_BT_WP_N    I24 @BASEBOARD_FAB2_LIB.BASEBOARD_FAB2(SCH_1):PAGE162
     2    GND @BASEBOARD_FAB2_LIB.BASEBOARD_FAB2(SCH_1):GND    I24 @BASEBOARD_FAB2_LIB.BASEBOARD_FAB2(SCH_1):PAGE162

R8F36 RES_0402-10.0K,1%,1/16W,CHIP,GA
     1   P3V3 @BASEBOARD_FAB2_LIB.BASEBOARD_FAB2(SCH_1):P3V3   I136 @BASEBOARD_FAB2_LIB.BASEBOARD_FAB2(SCH_1):PAGE185
     2 PU_M2_CLK_REQ_N @BASEBOARD_FAB2_LIB.BASEBOARD_FAB2(SCH_1):PU_M2_CLK_REQ_N   I136 @BASEBOARD_FAB2_LIB.BASEBOARD_FAB2(SCH_1):PAGE185

R8F37 RES_0402-0.0,5%,1/16W,EMPTY,G2A
     1 FM_CPU_ERR0_LVT3_N @BASEBOARD_FAB2_LIB.BASEBOARD_FAB2(SCH_1):FM_CPU_ERR0_LVT3_N   I131 @BASEBOARD_FAB2_LIB.BASEBOARD_FAB2(SCH_1):PAGE93
     2 FM_CPU_ERR0_PCH_N @BASEBOARD_FAB2_LIB.BASEBOARD_FAB2(SCH_1):FM_CPU_ERR0_PCH_N   I131 @BASEBOARD_FAB2_LIB.BASEBOARD_FAB2(SCH_1):PAGE93

R8F38 RES_0402-0.0,5%,1/16W,CHIP,G21A
     1 FM_CPU_ERR0_LVT3_N @BASEBOARD_FAB2_LIB.BASEBOARD_FAB2(SCH_1):FM_CPU_ERR0_LVT3_N   I119 @BASEBOARD_FAB2_LIB.BASEBOARD_FAB2(SCH_1):PAGE93
     2 FM_CPU_ERR0_LVT3_BMC_N @BASEBOARD_FAB2_LIB.BASEBOARD_FAB2(SCH_1):FM_CPU_ERR0_LVT3_BMC_N   I119 @BASEBOARD_FAB2_LIB.BASEBOARD_FAB2(SCH_1):PAGE93

R8G1 RES_0402-22.1,1.0%,1/16W,CHIP,A
     1 CLK_50M_CKMNG_BMC_2_R @BASEBOARD_FAB2_LIB.BASEBOARD_FAB2(SCH_1):CLK_50M_CKMNG_BMC_2_R   I145 @BASEBOARD_FAB2_LIB.BASEBOARD_FAB2(SCH_1):PAGE101
     2 CLK_50M_CKMNG_BMC_2 @BASEBOARD_FAB2_LIB.BASEBOARD_FAB2(SCH_1):CLK_50M_CKMNG_BMC_2   I145 @BASEBOARD_FAB2_LIB.BASEBOARD_FAB2(SCH_1):PAGE101

R8G2 RES_0402-4.75K,1%,1/16W,CHIP,GA
     1 P3V3_STBY @BASEBOARD_FAB2_LIB.BASEBOARD_FAB2(SCH_1):P3V3_STBY   I267 @BASEBOARD_FAB2_LIB.BASEBOARD_FAB2(SCH_1):PAGE156
     2 FM_PCH_PWRBTN_OUT_N @BASEBOARD_FAB2_LIB.BASEBOARD_FAB2(SCH_1):FM_PCH_PWRBTN_OUT_N   I267 @BASEBOARD_FAB2_LIB.BASEBOARD_FAB2(SCH_1):PAGE156

R8G3 RES_0402-2.26K,1.0%,1/16W,EMPTA
     1 P3V3_STBY @BASEBOARD_FAB2_LIB.BASEBOARD_FAB2(SCH_1):P3V3_STBY   I210 @BASEBOARD_FAB2_LIB.BASEBOARD_FAB2(SCH_1):PAGE159
     2 SMB_OCP_LAN_STBY_LVC3_SCL_R @BASEBOARD_FAB2_LIB.BASEBOARD_FAB2(SCH_1):SMB_OCP_LAN_STBY_LVC3_SCL_R   I210 @BASEBOARD_FAB2_LIB.BASEBOARD_FAB2(SCH_1):PAGE159

R8G4 RES_0402-20.0,1%,1/16W,CHIP,G2A
     1 SMB_OCP_LAN_STBY_LVC3_SCL_R @BASEBOARD_FAB2_LIB.BASEBOARD_FAB2(SCH_1):SMB_OCP_LAN_STBY_LVC3_SCL_R   I229 @BASEBOARD_FAB2_LIB.BASEBOARD_FAB2(SCH_1):PAGE159
     2 SMB_OCP_LAN_STBY_LVC3_SCL @BASEBOARD_FAB2_LIB.BASEBOARD_FAB2(SCH_1):SMB_OCP_LAN_STBY_LVC3_SCL   I229 @BASEBOARD_FAB2_LIB.BASEBOARD_FAB2(SCH_1):PAGE159

R8G5 RES_0402-20.0,1%,1/16W,CHIP,G2A
     1 SMB_OCP_LAN_STBY_LVC3_SDA_R @BASEBOARD_FAB2_LIB.BASEBOARD_FAB2(SCH_1):SMB_OCP_LAN_STBY_LVC3_SDA_R   I228 @BASEBOARD_FAB2_LIB.BASEBOARD_FAB2(SCH_1):PAGE159
     2 SMB_OCP_LAN_STBY_LVC3_SDA @BASEBOARD_FAB2_LIB.BASEBOARD_FAB2(SCH_1):SMB_OCP_LAN_STBY_LVC3_SDA   I228 @BASEBOARD_FAB2_LIB.BASEBOARD_FAB2(SCH_1):PAGE159

R8G6 RES_0402-2.26K,1.0%,1/16W,EMPTA
     1 P3V3_STBY @BASEBOARD_FAB2_LIB.BASEBOARD_FAB2(SCH_1):P3V3_STBY   I212 @BASEBOARD_FAB2_LIB.BASEBOARD_FAB2(SCH_1):PAGE159
     2 SMB_OCP_LAN_STBY_LVC3_SDA_R @BASEBOARD_FAB2_LIB.BASEBOARD_FAB2(SCH_1):SMB_OCP_LAN_STBY_LVC3_SDA_R   I212 @BASEBOARD_FAB2_LIB.BASEBOARD_FAB2(SCH_1):PAGE159

R8G7 RES_0402-0.0,5%,1/16W,CHIP,G21A
     1 JTAG_PLD_TDI @BASEBOARD_FAB2_LIB.BASEBOARD_FAB2(SCH_1):JTAG_PLD_TDI    I18 @BASEBOARD_FAB2_LIB.BASEBOARD_FAB2(SCH_1):PAGE189
     2 JTAG_PLD_TDI_MUX @BASEBOARD_FAB2_LIB.BASEBOARD_FAB2(SCH_1):JTAG_PLD_TDI_MUX    I18 @BASEBOARD_FAB2_LIB.BASEBOARD_FAB2(SCH_1):PAGE189

R8G8 RES_0402-0.0,5%,1/16W,CHIP,G21A
     1 JTAG_BMC_TDI @BASEBOARD_FAB2_LIB.BASEBOARD_FAB2(SCH_1):JTAG_BMC_TDI    I17 @BASEBOARD_FAB2_LIB.BASEBOARD_FAB2(SCH_1):PAGE189
     2 JTAG_TDI @BASEBOARD_FAB2_LIB.BASEBOARD_FAB2(SCH_1):JTAG_TDI    I17 @BASEBOARD_FAB2_LIB.BASEBOARD_FAB2(SCH_1):PAGE189

R8G9 RES_0402-0.0,5%,1/16W,EMPTY,G2A
     1 JTAG_PCH_GBE_TRST_N @BASEBOARD_FAB2_LIB.BASEBOARD_FAB2(SCH_1):JTAG_PCH_GBE_TRST_N     I9 @BASEBOARD_FAB2_LIB.BASEBOARD_FAB2(SCH_1):PAGE189
     2 JTAG_TRST_N @BASEBOARD_FAB2_LIB.BASEBOARD_FAB2(SCH_1):JTAG_TRST_N     I9 @BASEBOARD_FAB2_LIB.BASEBOARD_FAB2(SCH_1):PAGE189

R8G10 RES_0402-0.0,5%,1/16W,CHIP,G21A
     1 JTAG_BMC_TRST_N @BASEBOARD_FAB2_LIB.BASEBOARD_FAB2(SCH_1):JTAG_BMC_TRST_N     I7 @BASEBOARD_FAB2_LIB.BASEBOARD_FAB2(SCH_1):PAGE189
     2 JTAG_TRST_N @BASEBOARD_FAB2_LIB.BASEBOARD_FAB2(SCH_1):JTAG_TRST_N     I7 @BASEBOARD_FAB2_LIB.BASEBOARD_FAB2(SCH_1):PAGE189

R8G11 RES_0402-0.0,5%,1/16W,EMPTY,G2A
     1 JTAG_PCH_PLD_TMS @BASEBOARD_FAB2_LIB.BASEBOARD_FAB2(SCH_1):JTAG_PCH_PLD_TMS    I19 @BASEBOARD_FAB2_LIB.BASEBOARD_FAB2(SCH_1):PAGE189
     2 JTAG_TMS @BASEBOARD_FAB2_LIB.BASEBOARD_FAB2(SCH_1):JTAG_TMS    I19 @BASEBOARD_FAB2_LIB.BASEBOARD_FAB2(SCH_1):PAGE189

R8G12 RES_0402-0.0,5%,1/16W,EMPTY,G2A
     1 JTAG_PCH_GBE_TMS @BASEBOARD_FAB2_LIB.BASEBOARD_FAB2(SCH_1):JTAG_PCH_GBE_TMS    I21 @BASEBOARD_FAB2_LIB.BASEBOARD_FAB2(SCH_1):PAGE189
     2 JTAG_TMS @BASEBOARD_FAB2_LIB.BASEBOARD_FAB2(SCH_1):JTAG_TMS    I21 @BASEBOARD_FAB2_LIB.BASEBOARD_FAB2(SCH_1):PAGE189

R8G13 RES_0402-0.0,5%,1/16W,CHIP,G21A
     1 JTAG_PLD_TMS @BASEBOARD_FAB2_LIB.BASEBOARD_FAB2(SCH_1):JTAG_PLD_TMS    I23 @BASEBOARD_FAB2_LIB.BASEBOARD_FAB2(SCH_1):PAGE189
     2 JTAG_PLD_TMS_MUX @BASEBOARD_FAB2_LIB.BASEBOARD_FAB2(SCH_1):JTAG_PLD_TMS_MUX    I23 @BASEBOARD_FAB2_LIB.BASEBOARD_FAB2(SCH_1):PAGE189

R8G14 RES_0402-0.0,5%,1/16W,CHIP,G21A
     1 JTAG_BMC_TMS @BASEBOARD_FAB2_LIB.BASEBOARD_FAB2(SCH_1):JTAG_BMC_TMS    I20 @BASEBOARD_FAB2_LIB.BASEBOARD_FAB2(SCH_1):PAGE189
     2 JTAG_TMS @BASEBOARD_FAB2_LIB.BASEBOARD_FAB2(SCH_1):JTAG_TMS    I20 @BASEBOARD_FAB2_LIB.BASEBOARD_FAB2(SCH_1):PAGE189

R8G15 RES_0402-0.0,5%,1/16W,EMPTY,G2A
     1 JTAG_PCH_GBE_CLK @BASEBOARD_FAB2_LIB.BASEBOARD_FAB2(SCH_1):JTAG_PCH_GBE_CLK    I24 @BASEBOARD_FAB2_LIB.BASEBOARD_FAB2(SCH_1):PAGE189
     2 JTAG_TCK @BASEBOARD_FAB2_LIB.BASEBOARD_FAB2(SCH_1):JTAG_TCK    I24 @BASEBOARD_FAB2_LIB.BASEBOARD_FAB2(SCH_1):PAGE189

R8G16 RES_0402-0.0,5%,1/16W,EMPTY,G2A
     1 JTAG_PCH_PLD_TCK @BASEBOARD_FAB2_LIB.BASEBOARD_FAB2(SCH_1):JTAG_PCH_PLD_TCK    I22 @BASEBOARD_FAB2_LIB.BASEBOARD_FAB2(SCH_1):PAGE189
     2 JTAG_TCK @BASEBOARD_FAB2_LIB.BASEBOARD_FAB2(SCH_1):JTAG_TCK    I22 @BASEBOARD_FAB2_LIB.BASEBOARD_FAB2(SCH_1):PAGE189

R8G17 RES_0402-0.0,5%,1/16W,CHIP,G21A
     1 JTAG_BMC_TCK @BASEBOARD_FAB2_LIB.BASEBOARD_FAB2(SCH_1):JTAG_BMC_TCK    I25 @BASEBOARD_FAB2_LIB.BASEBOARD_FAB2(SCH_1):PAGE189
     2 JTAG_TCK @BASEBOARD_FAB2_LIB.BASEBOARD_FAB2(SCH_1):JTAG_TCK    I25 @BASEBOARD_FAB2_LIB.BASEBOARD_FAB2(SCH_1):PAGE189

R8G18 RES_0402-0.0,5%,1/16W,CHIP,G21A
     1 JTAG_PLD_TCK @BASEBOARD_FAB2_LIB.BASEBOARD_FAB2(SCH_1):JTAG_PLD_TCK    I26 @BASEBOARD_FAB2_LIB.BASEBOARD_FAB2(SCH_1):PAGE189
     2 JTAG_PLD_TCK_MUX @BASEBOARD_FAB2_LIB.BASEBOARD_FAB2(SCH_1):JTAG_PLD_TCK_MUX    I26 @BASEBOARD_FAB2_LIB.BASEBOARD_FAB2(SCH_1):PAGE189

R8G19 RES_0402-0.0,5%,1/16W,CHIP,G21A
     1 JTAG_TDI @BASEBOARD_FAB2_LIB.BASEBOARD_FAB2(SCH_1):JTAG_TDI    I64 @BASEBOARD_FAB2_LIB.BASEBOARD_FAB2(SCH_1):PAGE189
     2 JTAG_TDI_R @BASEBOARD_FAB2_LIB.BASEBOARD_FAB2(SCH_1):JTAG_TDI_R    I64 @BASEBOARD_FAB2_LIB.BASEBOARD_FAB2(SCH_1):PAGE189

R8G20 RES_0402-10.0K,1%,1/16W,CHIP,GA
     1 P3V3_STBY @BASEBOARD_FAB2_LIB.BASEBOARD_FAB2(SCH_1):P3V3_STBY    I50 @BASEBOARD_FAB2_LIB.BASEBOARD_FAB2(SCH_1):PAGE189
     2 JTAG_TMS_R @BASEBOARD_FAB2_LIB.BASEBOARD_FAB2(SCH_1):JTAG_TMS_R    I50 @BASEBOARD_FAB2_LIB.BASEBOARD_FAB2(SCH_1):PAGE189

R8G21 RES_0402-0.0,5%,1/16W,CHIP,G21A
     1 JTAG_TMS @BASEBOARD_FAB2_LIB.BASEBOARD_FAB2(SCH_1):JTAG_TMS    I65 @BASEBOARD_FAB2_LIB.BASEBOARD_FAB2(SCH_1):PAGE189
     2 JTAG_TMS_R @BASEBOARD_FAB2_LIB.BASEBOARD_FAB2(SCH_1):JTAG_TMS_R    I65 @BASEBOARD_FAB2_LIB.BASEBOARD_FAB2(SCH_1):PAGE189

R8G22 RES_0402-0.0,5%,1/16W,CHIP,G21A
     1 JTAG_TCK @BASEBOARD_FAB2_LIB.BASEBOARD_FAB2(SCH_1):JTAG_TCK    I66 @BASEBOARD_FAB2_LIB.BASEBOARD_FAB2(SCH_1):PAGE189
     2 JTAG_TCK_R @BASEBOARD_FAB2_LIB.BASEBOARD_FAB2(SCH_1):JTAG_TCK_R    I66 @BASEBOARD_FAB2_LIB.BASEBOARD_FAB2(SCH_1):PAGE189

R8G23 RES_0402-4.75K,1%,1/16W,CHIP,GA
     1 JTAG_TCK_R @BASEBOARD_FAB2_LIB.BASEBOARD_FAB2(SCH_1):JTAG_TCK_R    I56 @BASEBOARD_FAB2_LIB.BASEBOARD_FAB2(SCH_1):PAGE189
     2    GND @BASEBOARD_FAB2_LIB.BASEBOARD_FAB2(SCH_1):GND    I56 @BASEBOARD_FAB2_LIB.BASEBOARD_FAB2(SCH_1):PAGE189

R8G24 RES_0402-22.1,1.0%,1/16W,CHIP,A
     1 CLK_50M_CKMNG_PCH_10GBE_R @BASEBOARD_FAB2_LIB.BASEBOARD_FAB2(SCH_1):CLK_50M_CKMNG_PCH_10GBE_R   I143 @BASEBOARD_FAB2_LIB.BASEBOARD_FAB2(SCH_1):PAGE101
     2 CLK_50M_CKMNG_PCH_10GBE @BASEBOARD_FAB2_LIB.BASEBOARD_FAB2(SCH_1):CLK_50M_CKMNG_PCH_10GBE   I143 @BASEBOARD_FAB2_LIB.BASEBOARD_FAB2(SCH_1):PAGE101

R8G25 RES_0402-22.1,1.0%,1/16W,CHIP,A
     1 CLK_50M_CKMNG_SPRVLLE_R @BASEBOARD_FAB2_LIB.BASEBOARD_FAB2(SCH_1):CLK_50M_CKMNG_SPRVLLE_R   I144 @BASEBOARD_FAB2_LIB.BASEBOARD_FAB2(SCH_1):PAGE101
     2 CLK_50M_CKMNG_SPRVLLE @BASEBOARD_FAB2_LIB.BASEBOARD_FAB2(SCH_1):CLK_50M_CKMNG_SPRVLLE   I144 @BASEBOARD_FAB2_LIB.BASEBOARD_FAB2(SCH_1):PAGE101

R8N1 RES_0402-1.8K,1%,1/16W,CHIP,G2A
     1 P3V3_STBY @BASEBOARD_FAB2_LIB.BASEBOARD_FAB2(SCH_1):P3V3_STBY   I157 @BASEBOARD_FAB2_LIB.BASEBOARD_FAB2(SCH_1):PAGE55
     2 FM_CPU1_PROC_ID1 @BASEBOARD_FAB2_LIB.BASEBOARD_FAB2(SCH_1):FM_CPU1_PROC_ID1   I157 @BASEBOARD_FAB2_LIB.BASEBOARD_FAB2(SCH_1):PAGE55

R8N2 RES_0402-10.0K,1%,1/16W,CHIP,GA
     1 P3V3_STBY @BASEBOARD_FAB2_LIB.BASEBOARD_FAB2(SCH_1):P3V3_STBY   I161 @BASEBOARD_FAB2_LIB.BASEBOARD_FAB2(SCH_1):PAGE55
     2 FM_CPU1_PKGID0 @BASEBOARD_FAB2_LIB.BASEBOARD_FAB2(SCH_1):FM_CPU1_PKGID0   I161 @BASEBOARD_FAB2_LIB.BASEBOARD_FAB2(SCH_1):PAGE55

R8N3 RES_0402-10.0K,1%,1/16W,CHIP,GA
     1 P3V3_STBY @BASEBOARD_FAB2_LIB.BASEBOARD_FAB2(SCH_1):P3V3_STBY   I159 @BASEBOARD_FAB2_LIB.BASEBOARD_FAB2(SCH_1):PAGE55
     2 FM_CPU1_PKGID2 @BASEBOARD_FAB2_LIB.BASEBOARD_FAB2(SCH_1):FM_CPU1_PKGID2   I159 @BASEBOARD_FAB2_LIB.BASEBOARD_FAB2(SCH_1):PAGE55

R8N4 RES_0402-1.8K,1%,1/16W,CHIP,G2A
     1 P3V3_STBY @BASEBOARD_FAB2_LIB.BASEBOARD_FAB2(SCH_1):P3V3_STBY   I158 @BASEBOARD_FAB2_LIB.BASEBOARD_FAB2(SCH_1):PAGE55
     2 FM_CPU1_PROC_ID0 @BASEBOARD_FAB2_LIB.BASEBOARD_FAB2(SCH_1):FM_CPU1_PROC_ID0   I158 @BASEBOARD_FAB2_LIB.BASEBOARD_FAB2(SCH_1):PAGE55

R8N5 RES_0402-10.0K,1%,1/16W,CHIP,GA
     1 P3V3_STBY @BASEBOARD_FAB2_LIB.BASEBOARD_FAB2(SCH_1):P3V3_STBY   I160 @BASEBOARD_FAB2_LIB.BASEBOARD_FAB2(SCH_1):PAGE55
     2 FM_CPU1_PKGID1 @BASEBOARD_FAB2_LIB.BASEBOARD_FAB2(SCH_1):FM_CPU1_PKGID1   I160 @BASEBOARD_FAB2_LIB.BASEBOARD_FAB2(SCH_1):PAGE55

R8P1 RES_0402-49.9,1%,1/16W,CHIP,G2A
     1 PD_CPU1_TEST14 @BASEBOARD_FAB2_LIB.BASEBOARD_FAB2(SCH_1):PD_CPU1_TEST14    I85 @BASEBOARD_FAB2_LIB.BASEBOARD_FAB2(SCH_1):PAGE90
     2    GND @BASEBOARD_FAB2_LIB.BASEBOARD_FAB2(SCH_1):GND    I85 @BASEBOARD_FAB2_LIB.BASEBOARD_FAB2(SCH_1):PAGE90

R8P2 RES_0402-49.9,1%,1/16W,CHIP,G2A
     1 PD_CPU1_TEST13 @BASEBOARD_FAB2_LIB.BASEBOARD_FAB2(SCH_1):PD_CPU1_TEST13    I86 @BASEBOARD_FAB2_LIB.BASEBOARD_FAB2(SCH_1):PAGE90
     2    GND @BASEBOARD_FAB2_LIB.BASEBOARD_FAB2(SCH_1):GND    I86 @BASEBOARD_FAB2_LIB.BASEBOARD_FAB2(SCH_1):PAGE90

R8P3 RES_0402-49.9,1%,1/16W,CHIP,G2A
     1 PD_CPU1_RSVD_TEST_2 @BASEBOARD_FAB2_LIB.BASEBOARD_FAB2(SCH_1):PD_CPU1_RSVD_TEST_2   I173 @BASEBOARD_FAB2_LIB.BASEBOARD_FAB2(SCH_1):PAGE56
     2    GND @BASEBOARD_FAB2_LIB.BASEBOARD_FAB2(SCH_1):GND   I173 @BASEBOARD_FAB2_LIB.BASEBOARD_FAB2(SCH_1):PAGE56

R8R1 RES_0402-49.9,1%,1/16W,CHIP,G2A
     1 PD_CPU1_RSVD_TEST_1 @BASEBOARD_FAB2_LIB.BASEBOARD_FAB2(SCH_1):PD_CPU1_RSVD_TEST_1   I174 @BASEBOARD_FAB2_LIB.BASEBOARD_FAB2(SCH_1):PAGE56
     2    GND @BASEBOARD_FAB2_LIB.BASEBOARD_FAB2(SCH_1):GND   I174 @BASEBOARD_FAB2_LIB.BASEBOARD_FAB2(SCH_1):PAGE56

R8W1 RES_0402-0.0,5%,1/16W,CHIP,G21A
     1 BMC_SELF_HW_D_RST @BASEBOARD_FAB2_LIB.BASEBOARD_FAB2(SCH_1):BMC_SELF_HW_D_RST    I34 @BASEBOARD_FAB2_LIB.BASEBOARD_FAB2(SCH_1):PAGE249
     2 FM_TPM_PRES_RST_N @BASEBOARD_FAB2_LIB.BASEBOARD_FAB2(SCH_1):FM_TPM_PRES_RST_N    I34 @BASEBOARD_FAB2_LIB.BASEBOARD_FAB2(SCH_1):PAGE249

R8W2 RES_0402-1.00K,1%,1/16W,CHIP,GA
     1 PU_PVNN_PCH_VCLK @BASEBOARD_FAB2_LIB.BASEBOARD_FAB2(SCH_1):PU_PVNN_PCH_VCLK   I247 @BASEBOARD_FAB2_LIB.BASEBOARD_FAB2(SCH_1):PAGE235
     2 VR_PVNN_P1V05_PCH_VD12 @BASEBOARD_FAB2_LIB.BASEBOARD_FAB2(SCH_1):VR_PVNN_P1V05_PCH_VD12   I247 @BASEBOARD_FAB2_LIB.BASEBOARD_FAB2(SCH_1):PAGE235

R8W3 RES_0402-1.00K,1%,1/16W,CHIP,GA
     1 VR_PVNN_P1V05_PCH_VD12 @BASEBOARD_FAB2_LIB.BASEBOARD_FAB2(SCH_1):VR_PVNN_P1V05_PCH_VD12   I248 @BASEBOARD_FAB2_LIB.BASEBOARD_FAB2(SCH_1):PAGE235
     2 PU_PVNN_PCH_VDIO @BASEBOARD_FAB2_LIB.BASEBOARD_FAB2(SCH_1):PU_PVNN_PCH_VDIO   I248 @BASEBOARD_FAB2_LIB.BASEBOARD_FAB2(SCH_1):PAGE235

R8W4 RES_0402-20.0,1%,1/16W,CHIP,G2A
     1 SMB_HOST_STBY_LVC3_SDA @BASEBOARD_FAB2_LIB.BASEBOARD_FAB2(SCH_1):SMB_HOST_STBY_LVC3_SDA   I195 @BASEBOARD_FAB2_LIB.BASEBOARD_FAB2(SCH_1):PAGE138
     2 SMB_HOST_STBY_LVC3_SDA_R5 @BASEBOARD_FAB2_LIB.BASEBOARD_FAB2(SCH_1):SMB_HOST_STBY_LVC3_SDA_R5   I195 @BASEBOARD_FAB2_LIB.BASEBOARD_FAB2(SCH_1):PAGE138

R8W5 RES_0402-20.0,1%,1/16W,CHIP,G2A
     1 SMB_HOST_STBY_LVC3_SCL @BASEBOARD_FAB2_LIB.BASEBOARD_FAB2(SCH_1):SMB_HOST_STBY_LVC3_SCL   I194 @BASEBOARD_FAB2_LIB.BASEBOARD_FAB2(SCH_1):PAGE138
     2 SMB_HOST_STBY_LVC3_SCL_R5 @BASEBOARD_FAB2_LIB.BASEBOARD_FAB2(SCH_1):SMB_HOST_STBY_LVC3_SCL_R5   I194 @BASEBOARD_FAB2_LIB.BASEBOARD_FAB2(SCH_1):PAGE138

R8W6 RES_0402-1.37K,1%,1/16W,CHIP,GA
     1 P3V3_STBY @BASEBOARD_FAB2_LIB.BASEBOARD_FAB2(SCH_1):P3V3_STBY   I205 @BASEBOARD_FAB2_LIB.BASEBOARD_FAB2(SCH_1):PAGE138
     2 SMB_VR_STBY_LVC3_SDA_R1 @BASEBOARD_FAB2_LIB.BASEBOARD_FAB2(SCH_1):SMB_VR_STBY_LVC3_SDA_R1   I205 @BASEBOARD_FAB2_LIB.BASEBOARD_FAB2(SCH_1):PAGE138

R8W7 RES_0402-1.37K,1%,1/16W,CHIP,GA
     1 P3V3_STBY @BASEBOARD_FAB2_LIB.BASEBOARD_FAB2(SCH_1):P3V3_STBY   I202 @BASEBOARD_FAB2_LIB.BASEBOARD_FAB2(SCH_1):PAGE138
     2 SMB_VR_STBY_LVC3_SCL_R1 @BASEBOARD_FAB2_LIB.BASEBOARD_FAB2(SCH_1):SMB_VR_STBY_LVC3_SCL_R1   I202 @BASEBOARD_FAB2_LIB.BASEBOARD_FAB2(SCH_1):PAGE138

R8W8 RES_0402-1.00K,1%,1/16W,CHIP,GA
     1 P3V3_STBY @BASEBOARD_FAB2_LIB.BASEBOARD_FAB2(SCH_1):P3V3_STBY   I249 @BASEBOARD_FAB2_LIB.BASEBOARD_FAB2(SCH_1):PAGE235
     2 PU_PVNN_PCH_PINALRT_N @BASEBOARD_FAB2_LIB.BASEBOARD_FAB2(SCH_1):PU_PVNN_PCH_PINALRT_N   I249 @BASEBOARD_FAB2_LIB.BASEBOARD_FAB2(SCH_1):PAGE235

R8W9 RES_0402-4.75K,1%,1/16W,CHIP,GA
     1 P3V3_STBY @BASEBOARD_FAB2_LIB.BASEBOARD_FAB2(SCH_1):P3V3_STBY    I49 @BASEBOARD_FAB2_LIB.BASEBOARD_FAB2(SCH_1):PAGE89
     2 IRQ_DIMM_SAVE_LVT3_CPU1 @BASEBOARD_FAB2_LIB.BASEBOARD_FAB2(SCH_1):IRQ_DIMM_SAVE_LVT3_CPU1    I49 @BASEBOARD_FAB2_LIB.BASEBOARD_FAB2(SCH_1):PAGE89

R8W10 RES_0402-0.0,5%,1/16W,CHIP,G21A
     1 JTAG_RISER_TMS @BASEBOARD_FAB2_LIB.BASEBOARD_FAB2(SCH_1):JTAG_RISER_TMS    I56 @BASEBOARD_FAB2_LIB.BASEBOARD_FAB2(SCH_1):PAGE245
     2 JTAG_PLD_TMS_MUX @BASEBOARD_FAB2_LIB.BASEBOARD_FAB2(SCH_1):JTAG_PLD_TMS_MUX    I56 @BASEBOARD_FAB2_LIB.BASEBOARD_FAB2(SCH_1):PAGE245

R8W11 RES_0402-0.0,5%,1/16W,CHIP,G21A
     1 JTAG_RISER_TCK @BASEBOARD_FAB2_LIB.BASEBOARD_FAB2(SCH_1):JTAG_RISER_TCK    I57 @BASEBOARD_FAB2_LIB.BASEBOARD_FAB2(SCH_1):PAGE245
     2 JTAG_PLD_TCK_MUX @BASEBOARD_FAB2_LIB.BASEBOARD_FAB2(SCH_1):JTAG_PLD_TCK_MUX    I57 @BASEBOARD_FAB2_LIB.BASEBOARD_FAB2(SCH_1):PAGE245

R8W12 RES_0402-0.0,5%,1/16W,CHIP,G21A
     1 JTAG_RISER_TRST @BASEBOARD_FAB2_LIB.BASEBOARD_FAB2(SCH_1):JTAG_RISER_TRST    I58 @BASEBOARD_FAB2_LIB.BASEBOARD_FAB2(SCH_1):PAGE245
     2 JTAG_BMC_TRST_N @BASEBOARD_FAB2_LIB.BASEBOARD_FAB2(SCH_1):JTAG_BMC_TRST_N    I58 @BASEBOARD_FAB2_LIB.BASEBOARD_FAB2(SCH_1):PAGE245

R8W13 RES_0402-0.0,5%,1/16W,CHIP,G21A
     1 JTAG_RISER_TDI_R @BASEBOARD_FAB2_LIB.BASEBOARD_FAB2(SCH_1):JTAG_RISER_TDI_R    I59 @BASEBOARD_FAB2_LIB.BASEBOARD_FAB2(SCH_1):PAGE245
     2 JTAG_RISER_TDI @BASEBOARD_FAB2_LIB.BASEBOARD_FAB2(SCH_1):JTAG_RISER_TDI    I59 @BASEBOARD_FAB2_LIB.BASEBOARD_FAB2(SCH_1):PAGE245

R8W14 RES_0402-0.0,5%,1/16W,CHIP,G21A
     1 JTAG_RISER_TDO_R @BASEBOARD_FAB2_LIB.BASEBOARD_FAB2(SCH_1):JTAG_RISER_TDO_R    I60 @BASEBOARD_FAB2_LIB.BASEBOARD_FAB2(SCH_1):PAGE245
     2 JTAG_RISER_TDO @BASEBOARD_FAB2_LIB.BASEBOARD_FAB2(SCH_1):JTAG_RISER_TDO    I60 @BASEBOARD_FAB2_LIB.BASEBOARD_FAB2(SCH_1):PAGE245

R8W15 RES_0402-4.75K,1%,1/16W,CHIP,GA
     1 P3V3_STBY @BASEBOARD_FAB2_LIB.BASEBOARD_FAB2(SCH_1):P3V3_STBY    I78 @BASEBOARD_FAB2_LIB.BASEBOARD_FAB2(SCH_1):PAGE245
     2 JTAG_RISER_N @BASEBOARD_FAB2_LIB.BASEBOARD_FAB2(SCH_1):JTAG_RISER_N    I78 @BASEBOARD_FAB2_LIB.BASEBOARD_FAB2(SCH_1):PAGE245

R9A1 RES_0402-1.00K,1%,1/16W,EMPTY,A
     1   P3V3 @BASEBOARD_FAB2_LIB.BASEBOARD_FAB2(SCH_1):P3V3    I95 @BASEBOARD_FAB2_LIB.BASEBOARD_FAB2(SCH_1):PAGE111
     2 XDP_CPU_TCK_BUF @BASEBOARD_FAB2_LIB.BASEBOARD_FAB2(SCH_1):XDP_CPU_TCK_BUF    I95 @BASEBOARD_FAB2_LIB.BASEBOARD_FAB2(SCH_1):PAGE111

R9A2 RES_0402-33.2,1%,1/16W,EMPTY,GA
     1 XDP_PCH_CPU_TCK0 @BASEBOARD_FAB2_LIB.BASEBOARD_FAB2(SCH_1):XDP_PCH_CPU_TCK0    I83 @BASEBOARD_FAB2_LIB.BASEBOARD_FAB2(SCH_1):PAGE111
     2 XDP_CPU_GTL_TCK_R2 @BASEBOARD_FAB2_LIB.BASEBOARD_FAB2(SCH_1):XDP_CPU_GTL_TCK_R2    I83 @BASEBOARD_FAB2_LIB.BASEBOARD_FAB2(SCH_1):PAGE111

R9A3 RES_0402-0.0,5%,1/16W,CHIP,G21A
     1 XDP_PCH_CPU_TCK0 @BASEBOARD_FAB2_LIB.BASEBOARD_FAB2(SCH_1):XDP_PCH_CPU_TCK0    I74 @BASEBOARD_FAB2_LIB.BASEBOARD_FAB2(SCH_1):PAGE111
     2 XDP_CPU_TCK0 @BASEBOARD_FAB2_LIB.BASEBOARD_FAB2(SCH_1):XDP_CPU_TCK0    I74 @BASEBOARD_FAB2_LIB.BASEBOARD_FAB2(SCH_1):PAGE111

R9A4 RES_0402-475.0,1%,1/16W,CHIP,GA
     1 CPU_XDP_PRESENT_N @BASEBOARD_FAB2_LIB.BASEBOARD_FAB2(SCH_1):CPU_XDP_PRESENT_N    I55 @BASEBOARD_FAB2_LIB.BASEBOARD_FAB2(SCH_1):PAGE111
     2 PVCCIO_CPU0 @BASEBOARD_FAB2_LIB.BASEBOARD_FAB2(SCH_1):PVCCIO_CPU0    I55 @BASEBOARD_FAB2_LIB.BASEBOARD_FAB2(SCH_1):PAGE111

R9A5 RES_0402-20.0K,1%,1/16W,CHIP,GA
     1 P5V_STBY @BASEBOARD_FAB2_LIB.BASEBOARD_FAB2(SCH_1):P5V_STBY   I198 @BASEBOARD_FAB2_LIB.BASEBOARD_FAB2(SCH_1):PAGE155
     2 FM_UART_SWITCH_N @BASEBOARD_FAB2_LIB.BASEBOARD_FAB2(SCH_1):FM_UART_SWITCH_N   I198 @BASEBOARD_FAB2_LIB.BASEBOARD_FAB2(SCH_1):PAGE155

R9A7 RES_0402-2.21K,1%,1/16W,CHIP,GA
     1 P3V3_STBY @BASEBOARD_FAB2_LIB.BASEBOARD_FAB2(SCH_1):P3V3_STBY    I80 @BASEBOARD_FAB2_LIB.BASEBOARD_FAB2(SCH_1):PAGE155
     2 SPA_SIN_SW_R @BASEBOARD_FAB2_LIB.BASEBOARD_FAB2(SCH_1):SPA_SIN_SW_R    I80 @BASEBOARD_FAB2_LIB.BASEBOARD_FAB2(SCH_1):PAGE155

R9A8 RES_0402-0.0,5%,1/16W,CHIP,G21A
     1 SPA_SIN_SW_R @BASEBOARD_FAB2_LIB.BASEBOARD_FAB2(SCH_1):SPA_SIN_SW_R    I53 @BASEBOARD_FAB2_LIB.BASEBOARD_FAB2(SCH_1):PAGE155
     2 SPA_MID_DBG1_RX @BASEBOARD_FAB2_LIB.BASEBOARD_FAB2(SCH_1):SPA_MID_DBG1_RX    I53 @BASEBOARD_FAB2_LIB.BASEBOARD_FAB2(SCH_1):PAGE155

R9A9 RES_0402-100.0,1%,1/16W,CHIP,GA
     1 RST_SYSTEM_BTN_BUF_N @BASEBOARD_FAB2_LIB.BASEBOARD_FAB2(SCH_1):RST_SYSTEM_BTN_BUF_N    I95 @BASEBOARD_FAB2_LIB.BASEBOARD_FAB2(SCH_1):PAGE175
     2 RST_SYSTEM_BTN_N @BASEBOARD_FAB2_LIB.BASEBOARD_FAB2(SCH_1):RST_SYSTEM_BTN_N    I95 @BASEBOARD_FAB2_LIB.BASEBOARD_FAB2(SCH_1):PAGE175

R9A11 RES_0402-150.0,1%,1/16W,CHIP,GA
     1 P1V05_PCH_STBY @BASEBOARD_FAB2_LIB.BASEBOARD_FAB2(SCH_1):P1V05_PCH_STBY    I78 @BASEBOARD_FAB2_LIB.BASEBOARD_FAB2(SCH_1):PAGE112
     2 XDP_TDO @BASEBOARD_FAB2_LIB.BASEBOARD_FAB2(SCH_1):XDP_TDO    I78 @BASEBOARD_FAB2_LIB.BASEBOARD_FAB2(SCH_1):PAGE112

R9A12 RES_0402-2.21K,1%,1/16W,CHIP,GA
     1 FM_PCH_SATA_RAID_KEY_R @BASEBOARD_FAB2_LIB.BASEBOARD_FAB2(SCH_1):FM_PCH_SATA_RAID_KEY_R   I117 @BASEBOARD_FAB2_LIB.BASEBOARD_FAB2(SCH_1):PAGE135
     2 P3V3_STBY @BASEBOARD_FAB2_LIB.BASEBOARD_FAB2(SCH_1):P3V3_STBY   I117 @BASEBOARD_FAB2_LIB.BASEBOARD_FAB2(SCH_1):PAGE135

R9A13 RES_0402-33.2,1%,1/16W,CHIP,G2A
     1 FM_PCH_SATA_RAID_KEY_R @BASEBOARD_FAB2_LIB.BASEBOARD_FAB2(SCH_1):FM_PCH_SATA_RAID_KEY_R   I118 @BASEBOARD_FAB2_LIB.BASEBOARD_FAB2(SCH_1):PAGE135
     2 FM_PCH_SATA_RAID_KEY @BASEBOARD_FAB2_LIB.BASEBOARD_FAB2(SCH_1):FM_PCH_SATA_RAID_KEY   I118 @BASEBOARD_FAB2_LIB.BASEBOARD_FAB2(SCH_1):PAGE135

R9A14 RES_0402-1.00K,1%,1/16W,CHIP,GA
     1 XDP_RST_CO_N @BASEBOARD_FAB2_LIB.BASEBOARD_FAB2(SCH_1):XDP_RST_CO_N    I11 @BASEBOARD_FAB2_LIB.BASEBOARD_FAB2(SCH_1):PAGE111
     2 P3V3_STBY @BASEBOARD_FAB2_LIB.BASEBOARD_FAB2(SCH_1):P3V3_STBY    I11 @BASEBOARD_FAB2_LIB.BASEBOARD_FAB2(SCH_1):PAGE111

R9A15 RES_0402-1.00K,1%,1/16W,CHIP,GA
     1 RST_RSMRST_N @BASEBOARD_FAB2_LIB.BASEBOARD_FAB2(SCH_1):RST_RSMRST_N    I60 @BASEBOARD_FAB2_LIB.BASEBOARD_FAB2(SCH_1):PAGE111
     2 XDP_RSMRST_N @BASEBOARD_FAB2_LIB.BASEBOARD_FAB2(SCH_1):XDP_RSMRST_N    I60 @BASEBOARD_FAB2_LIB.BASEBOARD_FAB2(SCH_1):PAGE111

R9A16 RES_0402-2.21K,1%,1/16W,CHIP,GA
     1 PU_KEY_CONN_PIN2_R @BASEBOARD_FAB2_LIB.BASEBOARD_FAB2(SCH_1):PU_KEY_CONN_PIN2_R   I129 @BASEBOARD_FAB2_LIB.BASEBOARD_FAB2(SCH_1):PAGE135
     2 P3V3_STBY @BASEBOARD_FAB2_LIB.BASEBOARD_FAB2(SCH_1):P3V3_STBY   I129 @BASEBOARD_FAB2_LIB.BASEBOARD_FAB2(SCH_1):PAGE135

R9A17 RES_0402-1.00K,1%,1/16W,CHIP,GA
     1 XDP_ITP_PMODE @BASEBOARD_FAB2_LIB.BASEBOARD_FAB2(SCH_1):XDP_ITP_PMODE    I57 @BASEBOARD_FAB2_LIB.BASEBOARD_FAB2(SCH_1):PAGE111
     2 P1V05_PCH_STBY @BASEBOARD_FAB2_LIB.BASEBOARD_FAB2(SCH_1):P1V05_PCH_STBY    I57 @BASEBOARD_FAB2_LIB.BASEBOARD_FAB2(SCH_1):PAGE111

R9A18 RES_0402-4.75K,1%,1/16W,CHIP,GA
     1 P3V3_STBY @BASEBOARD_FAB2_LIB.BASEBOARD_FAB2(SCH_1):P3V3_STBY   I183 @BASEBOARD_FAB2_LIB.BASEBOARD_FAB2(SCH_1):PAGE119
     2 FM_PWR_LED @BASEBOARD_FAB2_LIB.BASEBOARD_FAB2(SCH_1):FM_PWR_LED   I183 @BASEBOARD_FAB2_LIB.BASEBOARD_FAB2(SCH_1):PAGE119

R9A20 RES_0402-221,1.0%,1/16W,CHIP,GA
     1 FM_PWR_LED_A @BASEBOARD_FAB2_LIB.BASEBOARD_FAB2(SCH_1):FM_PWR_LED_A   I178 @BASEBOARD_FAB2_LIB.BASEBOARD_FAB2(SCH_1):PAGE119
     2 P3V3_STBY @BASEBOARD_FAB2_LIB.BASEBOARD_FAB2(SCH_1):P3V3_STBY   I178 @BASEBOARD_FAB2_LIB.BASEBOARD_FAB2(SCH_1):PAGE119

R9A21 RES_0402-4.75K,1%,1/16W,CHIP,GA
     1 P3V3_STBY @BASEBOARD_FAB2_LIB.BASEBOARD_FAB2(SCH_1):P3V3_STBY   I186 @BASEBOARD_FAB2_LIB.BASEBOARD_FAB2(SCH_1):PAGE119
     2 FM_PWR_LED_N @BASEBOARD_FAB2_LIB.BASEBOARD_FAB2(SCH_1):FM_PWR_LED_N   I186 @BASEBOARD_FAB2_LIB.BASEBOARD_FAB2(SCH_1):PAGE119

R9B4 RES_0402-49.9,1%,1/16W,CHIP,G2A
     1 ISENSE_TMP421_1_E @BASEBOARD_FAB2_LIB.BASEBOARD_FAB2(SCH_1):ISENSE_TMP421_1_E     I6 @BASEBOARD_FAB2_LIB.BASEBOARD_FAB2(SCH_1):PAGE167
     2 ISENSE_TMP421_1_DXP @BASEBOARD_FAB2_LIB.BASEBOARD_FAB2(SCH_1):ISENSE_TMP421_1_DXP     I6 @BASEBOARD_FAB2_LIB.BASEBOARD_FAB2(SCH_1):PAGE167

R9B5 RES_0402-49.9,1%,1/16W,CHIP,G2A
     1 ISENSE_TMP421_1_BC @BASEBOARD_FAB2_LIB.BASEBOARD_FAB2(SCH_1):ISENSE_TMP421_1_BC     I5 @BASEBOARD_FAB2_LIB.BASEBOARD_FAB2(SCH_1):PAGE167
     2 ISENSE_TMP421_1_DXN @BASEBOARD_FAB2_LIB.BASEBOARD_FAB2(SCH_1):ISENSE_TMP421_1_DXN     I5 @BASEBOARD_FAB2_LIB.BASEBOARD_FAB2(SCH_1):PAGE167

R9B6 RES_0402-1.00K,1%,1/16W,CHIP,GA
     1 P3V3_STBY @BASEBOARD_FAB2_LIB.BASEBOARD_FAB2(SCH_1):P3V3_STBY    I35 @BASEBOARD_FAB2_LIB.BASEBOARD_FAB2(SCH_1):PAGE167
     2 PU_TMP421_1_A1 @BASEBOARD_FAB2_LIB.BASEBOARD_FAB2(SCH_1):PU_TMP421_1_A1    I35 @BASEBOARD_FAB2_LIB.BASEBOARD_FAB2(SCH_1):PAGE167

R9B7 887R2F-L-GP_SMD-RG-887R2F-L-GPA
     1 FM_MEZZA_PRSNT1_N @BASEBOARD_FAB2_LIB.BASEBOARD_FAB2(SCH_1):FM_MEZZA_PRSNT1_N   I358 @BASEBOARD_FAB2_LIB.BASEBOARD_FAB2(SCH_1):PAGE186
     2    GND @BASEBOARD_FAB2_LIB.BASEBOARD_FAB2(SCH_1):GND   I358 @BASEBOARD_FAB2_LIB.BASEBOARD_FAB2(SCH_1):PAGE186

R9B8 RES_0402-1.00K,1%,1/16W,CHIP,GA
     1 PD_TMP421_1_A0 @BASEBOARD_FAB2_LIB.BASEBOARD_FAB2(SCH_1):PD_TMP421_1_A0    I10 @BASEBOARD_FAB2_LIB.BASEBOARD_FAB2(SCH_1):PAGE167
     2    GND @BASEBOARD_FAB2_LIB.BASEBOARD_FAB2(SCH_1):GND    I10 @BASEBOARD_FAB2_LIB.BASEBOARD_FAB2(SCH_1):PAGE167

R9B9 RES_0402-1.00K,1%,1/16W,CHIP,GA
     1 JTAG_MCP_TCK @BASEBOARD_FAB2_LIB.BASEBOARD_FAB2(SCH_1):JTAG_MCP_TCK   I179 @BASEBOARD_FAB2_LIB.BASEBOARD_FAB2(SCH_1):PAGE113
     2    GND @BASEBOARD_FAB2_LIB.BASEBOARD_FAB2(SCH_1):GND   I179 @BASEBOARD_FAB2_LIB.BASEBOARD_FAB2(SCH_1):PAGE113

R9B10 RES_0402-49.9,1%,1/16W,CHIP,G2A
     1 JTAG_MCP_TCK @BASEBOARD_FAB2_LIB.BASEBOARD_FAB2(SCH_1):JTAG_MCP_TCK   I180 @BASEBOARD_FAB2_LIB.BASEBOARD_FAB2(SCH_1):PAGE113
     2 JTAG_MCP_TCK_R1 @BASEBOARD_FAB2_LIB.BASEBOARD_FAB2(SCH_1):JTAG_MCP_TCK_R1   I180 @BASEBOARD_FAB2_LIB.BASEBOARD_FAB2(SCH_1):PAGE113

R9B11 RES_0402-0.0,5%,1/16W,CHIP,G21A
     1 JTAG_MCP_TCK @BASEBOARD_FAB2_LIB.BASEBOARD_FAB2(SCH_1):JTAG_MCP_TCK   I239 @BASEBOARD_FAB2_LIB.BASEBOARD_FAB2(SCH_1):PAGE113
     2 JTAG_MCP_TCK_R @BASEBOARD_FAB2_LIB.BASEBOARD_FAB2(SCH_1):JTAG_MCP_TCK_R   I239 @BASEBOARD_FAB2_LIB.BASEBOARD_FAB2(SCH_1):PAGE113

R9B12 RES_0402-1.00K,1%,1/16W,CHIP,GA
     1 P1V8_MCP_CPU0 @BASEBOARD_FAB2_LIB.BASEBOARD_FAB2(SCH_1):P1V8_MCP_CPU0   I203 @BASEBOARD_FAB2_LIB.BASEBOARD_FAB2(SCH_1):PAGE113
     2 JTAG_MCP_MUX_TDO @BASEBOARD_FAB2_LIB.BASEBOARD_FAB2(SCH_1):JTAG_MCP_MUX_TDO   I203 @BASEBOARD_FAB2_LIB.BASEBOARD_FAB2(SCH_1):PAGE113

R9B13 RES_0402-0.0,5%,1/16W,CHIP,G21A
     1 JTAG_MCP_TMS @BASEBOARD_FAB2_LIB.BASEBOARD_FAB2(SCH_1):JTAG_MCP_TMS   I240 @BASEBOARD_FAB2_LIB.BASEBOARD_FAB2(SCH_1):PAGE113
     2 JTAG_MCP_TMS_R @BASEBOARD_FAB2_LIB.BASEBOARD_FAB2(SCH_1):JTAG_MCP_TMS_R   I240 @BASEBOARD_FAB2_LIB.BASEBOARD_FAB2(SCH_1):PAGE113

R9B14 RES_0402-1.00K,1%,1/16W,CHIP,GA
     1 PWRGD_CPU0_G @BASEBOARD_FAB2_LIB.BASEBOARD_FAB2(SCH_1):PWRGD_CPU0_G   I168 @BASEBOARD_FAB2_LIB.BASEBOARD_FAB2(SCH_1):PAGE113
     2 PWRGD_CPU0_G_R @BASEBOARD_FAB2_LIB.BASEBOARD_FAB2(SCH_1):PWRGD_CPU0_G_R   I168 @BASEBOARD_FAB2_LIB.BASEBOARD_FAB2(SCH_1):PAGE113

R9E1 RES_0402-10.0K,1%,1/16W,CHIP,GA
     1 P3V3_STBY @BASEBOARD_FAB2_LIB.BASEBOARD_FAB2(SCH_1):P3V3_STBY   I179 @BASEBOARD_FAB2_LIB.BASEBOARD_FAB2(SCH_1):PAGE139
     2 PU_JTAG_SPRV_TDI @BASEBOARD_FAB2_LIB.BASEBOARD_FAB2(SCH_1):PU_JTAG_SPRV_TDI   I179 @BASEBOARD_FAB2_LIB.BASEBOARD_FAB2(SCH_1):PAGE139

R9E2 RES_0402-10.0K,1%,1/16W,CHIP,GA
     1 P3V3_STBY @BASEBOARD_FAB2_LIB.BASEBOARD_FAB2(SCH_1):P3V3_STBY   I177 @BASEBOARD_FAB2_LIB.BASEBOARD_FAB2(SCH_1):PAGE139
     2 PU_JTAG_SPRV_TCK @BASEBOARD_FAB2_LIB.BASEBOARD_FAB2(SCH_1):PU_JTAG_SPRV_TCK   I177 @BASEBOARD_FAB2_LIB.BASEBOARD_FAB2(SCH_1):PAGE139

R9E3 RES_0402-10.0K,1%,1/16W,CHIP,GA
     1 P3V3_STBY @BASEBOARD_FAB2_LIB.BASEBOARD_FAB2(SCH_1):P3V3_STBY   I178 @BASEBOARD_FAB2_LIB.BASEBOARD_FAB2(SCH_1):PAGE139
     2 PU_JTAG_SPRV_TMS @BASEBOARD_FAB2_LIB.BASEBOARD_FAB2(SCH_1):PU_JTAG_SPRV_TMS   I178 @BASEBOARD_FAB2_LIB.BASEBOARD_FAB2(SCH_1):PAGE139

R9E4 RES_0402-10.0K,1%,1/16W,CHIP,GA
     1 P3V3_STBY @BASEBOARD_FAB2_LIB.BASEBOARD_FAB2(SCH_1):P3V3_STBY   I200 @BASEBOARD_FAB2_LIB.BASEBOARD_FAB2(SCH_1):PAGE139
     2 RST_PLTRST_SPRV_R_N @BASEBOARD_FAB2_LIB.BASEBOARD_FAB2(SCH_1):RST_PLTRST_SPRV_R_N   I200 @BASEBOARD_FAB2_LIB.BASEBOARD_FAB2(SCH_1):PAGE139

R9E5 RES_0402-33.2,1%,1/16W,CHIP,G2A
     1 SPI_NIC_CS_R_N @BASEBOARD_FAB2_LIB.BASEBOARD_FAB2(SCH_1):SPI_NIC_CS_R_N   I129 @BASEBOARD_FAB2_LIB.BASEBOARD_FAB2(SCH_1):PAGE139
     2 SPI_NIC_CS_N @BASEBOARD_FAB2_LIB.BASEBOARD_FAB2(SCH_1):SPI_NIC_CS_N   I129 @BASEBOARD_FAB2_LIB.BASEBOARD_FAB2(SCH_1):PAGE139

R9E6 RES_0402-33.2,1%,1/16W,CHIP,G2A
     1 SPI_NIC_MISO_R @BASEBOARD_FAB2_LIB.BASEBOARD_FAB2(SCH_1):SPI_NIC_MISO_R    I17 @BASEBOARD_FAB2_LIB.BASEBOARD_FAB2(SCH_1):PAGE140
     2 SPI_NIC_MISO @BASEBOARD_FAB2_LIB.BASEBOARD_FAB2(SCH_1):SPI_NIC_MISO    I17 @BASEBOARD_FAB2_LIB.BASEBOARD_FAB2(SCH_1):PAGE140

R9E7 RES_0402-3.32K,1%,1/16W,CHIP,GA
     1 P3V3_STBY @BASEBOARD_FAB2_LIB.BASEBOARD_FAB2(SCH_1):P3V3_STBY   I193 @BASEBOARD_FAB2_LIB.BASEBOARD_FAB2(SCH_1):PAGE139
     2 IRQ_LOM_ALERT_N @BASEBOARD_FAB2_LIB.BASEBOARD_FAB2(SCH_1):IRQ_LOM_ALERT_N   I193 @BASEBOARD_FAB2_LIB.BASEBOARD_FAB2(SCH_1):PAGE139

R9E8 RES_0402-33.2,1%,1/16W,CHIP,G2A
     1 SPI_NIC_SCLK_R @BASEBOARD_FAB2_LIB.BASEBOARD_FAB2(SCH_1):SPI_NIC_SCLK_R   I130 @BASEBOARD_FAB2_LIB.BASEBOARD_FAB2(SCH_1):PAGE139
     2 SPI_NIC_SCLK @BASEBOARD_FAB2_LIB.BASEBOARD_FAB2(SCH_1):SPI_NIC_SCLK   I130 @BASEBOARD_FAB2_LIB.BASEBOARD_FAB2(SCH_1):PAGE139

R9E9 RES_0402-33.2,1%,1/16W,CHIP,G2A
     1 SPI_NIC_MOSI_R @BASEBOARD_FAB2_LIB.BASEBOARD_FAB2(SCH_1):SPI_NIC_MOSI_R   I128 @BASEBOARD_FAB2_LIB.BASEBOARD_FAB2(SCH_1):PAGE139
     2 SPI_NIC_MOSI @BASEBOARD_FAB2_LIB.BASEBOARD_FAB2(SCH_1):SPI_NIC_MOSI   I128 @BASEBOARD_FAB2_LIB.BASEBOARD_FAB2(SCH_1):PAGE139

R9E10 RES_0402-200.0,1%,1/16W,CHIP,GA
     1 RST_PCIE_CPU_DEV1_R_N @BASEBOARD_FAB2_LIB.BASEBOARD_FAB2(SCH_1):RST_PCIE_CPU_DEV1_R_N   I145 @BASEBOARD_FAB2_LIB.BASEBOARD_FAB2(SCH_1):PAGE187
     2 RST_PCIE_CPU_DEV1_N @BASEBOARD_FAB2_LIB.BASEBOARD_FAB2(SCH_1):RST_PCIE_CPU_DEV1_N   I145 @BASEBOARD_FAB2_LIB.BASEBOARD_FAB2(SCH_1):PAGE187

R9E11 RES_0402-200.0,1%,1/16W,CHIP,GA
     1 RST_PCIE_CPU_DEV2_R_N @BASEBOARD_FAB2_LIB.BASEBOARD_FAB2(SCH_1):RST_PCIE_CPU_DEV2_R_N   I150 @BASEBOARD_FAB2_LIB.BASEBOARD_FAB2(SCH_1):PAGE187
     2 RST_PCIE_CPU_DEV2_N @BASEBOARD_FAB2_LIB.BASEBOARD_FAB2(SCH_1):RST_PCIE_CPU_DEV2_N   I150 @BASEBOARD_FAB2_LIB.BASEBOARD_FAB2(SCH_1):PAGE187

R9E12 RES_0402-200.0,1%,1/16W,CHIP,GA
     1 RST_PCIE_CPU_DEV3_R_N @BASEBOARD_FAB2_LIB.BASEBOARD_FAB2(SCH_1):RST_PCIE_CPU_DEV3_R_N   I153 @BASEBOARD_FAB2_LIB.BASEBOARD_FAB2(SCH_1):PAGE187
     2 RST_PCIE_CPU_DEV3_N @BASEBOARD_FAB2_LIB.BASEBOARD_FAB2(SCH_1):RST_PCIE_CPU_DEV3_N   I153 @BASEBOARD_FAB2_LIB.BASEBOARD_FAB2(SCH_1):PAGE187

R9E13 RES_0402-10.0K,1%,1/16W,CHIP,GA
     1 RMII_BMC_PCH_SPRNGVLLE_TXEN @BASEBOARD_FAB2_LIB.BASEBOARD_FAB2(SCH_1):RMII_BMC_PCH_SPRNGVLLE_TXEN   I212 @BASEBOARD_FAB2_LIB.BASEBOARD_FAB2(SCH_1):PAGE139
     2    GND @BASEBOARD_FAB2_LIB.BASEBOARD_FAB2(SCH_1):GND   I212 @BASEBOARD_FAB2_LIB.BASEBOARD_FAB2(SCH_1):PAGE139

R9E14 RES_0402-0.0,5%,1/16W,EMPTY,G2A
     1 FM_TPM_PRES_RST_N @BASEBOARD_FAB2_LIB.BASEBOARD_FAB2(SCH_1):FM_TPM_PRES_RST_N   I393 @BASEBOARD_FAB2_LIB.BASEBOARD_FAB2(SCH_1):PAGE157
     2 FM_BMC_ENABLE_N @BASEBOARD_FAB2_LIB.BASEBOARD_FAB2(SCH_1):FM_BMC_ENABLE_N   I393 @BASEBOARD_FAB2_LIB.BASEBOARD_FAB2(SCH_1):PAGE157

R9E16 RES_0402-33.2,1%,1/16W,CHIP,G2A
     1 RMII_PCH_SPRNGVLLE_ARB_IN_R @BASEBOARD_FAB2_LIB.BASEBOARD_FAB2(SCH_1):RMII_PCH_SPRNGVLLE_ARB_IN_R   I235 @BASEBOARD_FAB2_LIB.BASEBOARD_FAB2(SCH_1):PAGE139
     2 RMII_PCH_SPRNGVLLE_ARB_IN @BASEBOARD_FAB2_LIB.BASEBOARD_FAB2(SCH_1):RMII_PCH_SPRNGVLLE_ARB_IN   I235 @BASEBOARD_FAB2_LIB.BASEBOARD_FAB2(SCH_1):PAGE139

R9E17 RES_0402-22.1,1.0%,1/16W,CHIP,A
     1 RMII_SPRNGVLLE_BMC_PCH_RXD0_R @BASEBOARD_FAB2_LIB.BASEBOARD_FAB2(SCH_1):RMII_SPRNGVLLE_BMC_PCH_RXD0_R   I229 @BASEBOARD_FAB2_LIB.BASEBOARD_FAB2(SCH_1):PAGE139
     2 RMII_SPRNGVLLE_BMC_PCH_RXD0 @BASEBOARD_FAB2_LIB.BASEBOARD_FAB2(SCH_1):RMII_SPRNGVLLE_BMC_PCH_RXD0   I229 @BASEBOARD_FAB2_LIB.BASEBOARD_FAB2(SCH_1):PAGE139

R9E18 RES_0402-0.0,5%,1/16W,CHIP,G21A
     1 XTAL_25MHZ_OUT_R @BASEBOARD_FAB2_LIB.BASEBOARD_FAB2(SCH_1):XTAL_25MHZ_OUT_R   I201 @BASEBOARD_FAB2_LIB.BASEBOARD_FAB2(SCH_1):PAGE139
     2 XTAL_25MHZ_OUT @BASEBOARD_FAB2_LIB.BASEBOARD_FAB2(SCH_1):XTAL_25MHZ_OUT   I201 @BASEBOARD_FAB2_LIB.BASEBOARD_FAB2(SCH_1):PAGE139

R9E19 RES_0402-22.1,1.0%,1/16W,CHIP,A
     1 RMII_SPRNGVLLE_BMC_PCH_RXD1_R @BASEBOARD_FAB2_LIB.BASEBOARD_FAB2(SCH_1):RMII_SPRNGVLLE_BMC_PCH_RXD1_R   I228 @BASEBOARD_FAB2_LIB.BASEBOARD_FAB2(SCH_1):PAGE139
     2 RMII_SPRNGVLLE_BMC_PCH_RXD1 @BASEBOARD_FAB2_LIB.BASEBOARD_FAB2(SCH_1):RMII_SPRNGVLLE_BMC_PCH_RXD1   I228 @BASEBOARD_FAB2_LIB.BASEBOARD_FAB2(SCH_1):PAGE139

R9E20 RES_0402-0.0,5%,1/16W,CHIP,G21A
     1 XTAL_25MHZ_IN @BASEBOARD_FAB2_LIB.BASEBOARD_FAB2(SCH_1):XTAL_25MHZ_IN   I110 @BASEBOARD_FAB2_LIB.BASEBOARD_FAB2(SCH_1):PAGE139
     2 XTAL_25MHZ_IN_R @BASEBOARD_FAB2_LIB.BASEBOARD_FAB2(SCH_1):XTAL_25MHZ_IN_R   I110 @BASEBOARD_FAB2_LIB.BASEBOARD_FAB2(SCH_1):PAGE139

R9E21 RES_0402-4.75K,1%,1/16W,CHIP,GA
     1 P3V3_STBY @BASEBOARD_FAB2_LIB.BASEBOARD_FAB2(SCH_1):P3V3_STBY   I173 @BASEBOARD_FAB2_LIB.BASEBOARD_FAB2(SCH_1):PAGE151
     2 FM_HEARTBEAT_LED @BASEBOARD_FAB2_LIB.BASEBOARD_FAB2(SCH_1):FM_HEARTBEAT_LED   I173 @BASEBOARD_FAB2_LIB.BASEBOARD_FAB2(SCH_1):PAGE151

R9E22 RES_0402-10.0K,1%,1/16W,CHIP,GA
     1 PU_JTAG_SPRV_TDO @BASEBOARD_FAB2_LIB.BASEBOARD_FAB2(SCH_1):PU_JTAG_SPRV_TDO   I181 @BASEBOARD_FAB2_LIB.BASEBOARD_FAB2(SCH_1):PAGE139
     2 P3V3_STBY @BASEBOARD_FAB2_LIB.BASEBOARD_FAB2(SCH_1):P3V3_STBY   I181 @BASEBOARD_FAB2_LIB.BASEBOARD_FAB2(SCH_1):PAGE139

R9E23 RES_0402-4.99K,1%,1/16W,CHIP,GA
     1 PD_SPRV_RSET @BASEBOARD_FAB2_LIB.BASEBOARD_FAB2(SCH_1):PD_SPRV_RSET   I174 @BASEBOARD_FAB2_LIB.BASEBOARD_FAB2(SCH_1):PAGE139
     2    GND @BASEBOARD_FAB2_LIB.BASEBOARD_FAB2(SCH_1):GND   I174 @BASEBOARD_FAB2_LIB.BASEBOARD_FAB2(SCH_1):PAGE139

R9E24 RES_0402-221,1.0%,1/16W,CHIP,GA
     1 FM_HEARTBEAT_LED_A @BASEBOARD_FAB2_LIB.BASEBOARD_FAB2(SCH_1):FM_HEARTBEAT_LED_A   I138 @BASEBOARD_FAB2_LIB.BASEBOARD_FAB2(SCH_1):PAGE151
     2 P3V3_STBY @BASEBOARD_FAB2_LIB.BASEBOARD_FAB2(SCH_1):P3V3_STBY   I138 @BASEBOARD_FAB2_LIB.BASEBOARD_FAB2(SCH_1):PAGE151

R9F1 RES_0402-22.1,1.0%,1/16W,CHIP,A
     1 RMII_BMC_PCH_SPRNGVLLE_CRSDV_R @BASEBOARD_FAB2_LIB.BASEBOARD_FAB2(SCH_1):RMII_BMC_PCH_SPRNGVLLE_CRSDV_R   I225 @BASEBOARD_FAB2_LIB.BASEBOARD_FAB2(SCH_1):PAGE139
     2 RMII_BMC_PCH_SPRNGVLLE_CRSDV @BASEBOARD_FAB2_LIB.BASEBOARD_FAB2(SCH_1):RMII_BMC_PCH_SPRNGVLLE_CRSDV   I225 @BASEBOARD_FAB2_LIB.BASEBOARD_FAB2(SCH_1):PAGE139

R9F3 RES_0402-4.75K,1%,1/16W,CHIP,GA
     1 P3V3_STBY @BASEBOARD_FAB2_LIB.BASEBOARD_FAB2(SCH_1):P3V3_STBY    I65 @BASEBOARD_FAB2_LIB.BASEBOARD_FAB2(SCH_1):PAGE170
     2 FM_FAST_PROCHOT_EN @BASEBOARD_FAB2_LIB.BASEBOARD_FAB2(SCH_1):FM_FAST_PROCHOT_EN    I65 @BASEBOARD_FAB2_LIB.BASEBOARD_FAB2(SCH_1):PAGE170

R9F5 RES_0402-3.32K,1%,1/16W,CHIP,GA
     1 P3V3_STBY @BASEBOARD_FAB2_LIB.BASEBOARD_FAB2(SCH_1):P3V3_STBY   I173 @BASEBOARD_FAB2_LIB.BASEBOARD_FAB2(SCH_1):PAGE139
     2 PU_SPRV_LAN_PWR_GOOD @BASEBOARD_FAB2_LIB.BASEBOARD_FAB2(SCH_1):PU_SPRV_LAN_PWR_GOOD   I173 @BASEBOARD_FAB2_LIB.BASEBOARD_FAB2(SCH_1):PAGE139

R9F6 4K42R2F-GP_SMD-RG-4K42R2F-GP,6A
     1 P1V15_AUX_BMC @BASEBOARD_FAB2_LIB.BASEBOARD_FAB2(SCH_1):P1V15_AUX_BMC    I45 @BASEBOARD_FAB2_LIB.BASEBOARD_FAB2(SCH_1):PAGE238
     2 VR_P1V15_BMC_STBY_FB @BASEBOARD_FAB2_LIB.BASEBOARD_FAB2(SCH_1):VR_P1V15_BMC_STBY_FB    I45 @BASEBOARD_FAB2_LIB.BASEBOARD_FAB2(SCH_1):PAGE238

R9F8 RES_0402-10.0K,1%,1/16W,CHIP,GA
     1    GND @BASEBOARD_FAB2_LIB.BASEBOARD_FAB2(SCH_1):GND    I14 @BASEBOARD_FAB2_LIB.BASEBOARD_FAB2(SCH_1):PAGE238
     2 VR_P1V15_BMC_STBY_FB @BASEBOARD_FAB2_LIB.BASEBOARD_FAB2(SCH_1):VR_P1V15_BMC_STBY_FB    I14 @BASEBOARD_FAB2_LIB.BASEBOARD_FAB2(SCH_1):PAGE238

R9F11 RES_0402-22.1,1.0%,1/16W,CHIP,A
     1 PWRGD_P1V15_BMC_STBY_R @BASEBOARD_FAB2_LIB.BASEBOARD_FAB2(SCH_1):PWRGD_P1V15_BMC_STBY_R    I41 @BASEBOARD_FAB2_LIB.BASEBOARD_FAB2(SCH_1):PAGE238
     2 PWRGD_P1V15_BMC_STBY @BASEBOARD_FAB2_LIB.BASEBOARD_FAB2(SCH_1):PWRGD_P1V15_BMC_STBY    I41 @BASEBOARD_FAB2_LIB.BASEBOARD_FAB2(SCH_1):PAGE238

R9F12 RES_0402-10.0K,1%,1/16W,CHIP,GA
     1 P3V3_STBY @BASEBOARD_FAB2_LIB.BASEBOARD_FAB2(SCH_1):P3V3_STBY     I6 @BASEBOARD_FAB2_LIB.BASEBOARD_FAB2(SCH_1):PAGE239
     2 PWRGD_P1V2_BMC_STBY_R @BASEBOARD_FAB2_LIB.BASEBOARD_FAB2(SCH_1):PWRGD_P1V2_BMC_STBY_R     I6 @BASEBOARD_FAB2_LIB.BASEBOARD_FAB2(SCH_1):PAGE239

R9F13 RES_0402-10.0K,1%,1/16W,CHIP,GA
     1 P3V3_STBY @BASEBOARD_FAB2_LIB.BASEBOARD_FAB2(SCH_1):P3V3_STBY    I21 @BASEBOARD_FAB2_LIB.BASEBOARD_FAB2(SCH_1):PAGE238
     2 PWRGD_P1V15_BMC_STBY_R @BASEBOARD_FAB2_LIB.BASEBOARD_FAB2(SCH_1):PWRGD_P1V15_BMC_STBY_R    I21 @BASEBOARD_FAB2_LIB.BASEBOARD_FAB2(SCH_1):PAGE238

R9F20 RES_0402-348,1%,1/16W,EMPTY,G2A
     1 PECI_BMC @BASEBOARD_FAB2_LIB.BASEBOARD_FAB2(SCH_1):PECI_BMC    I22 @BASEBOARD_FAB2_LIB.BASEBOARD_FAB2(SCH_1):PAGE145
     2    GND @BASEBOARD_FAB2_LIB.BASEBOARD_FAB2(SCH_1):GND    I22 @BASEBOARD_FAB2_LIB.BASEBOARD_FAB2(SCH_1):PAGE145

R9F22 RES_0402-20.0,1%,1/16W,CHIP,G2A
     1 SMB_LAN_STBY_LVC3_SCL_R @BASEBOARD_FAB2_LIB.BASEBOARD_FAB2(SCH_1):SMB_LAN_STBY_LVC3_SCL_R    I52 @BASEBOARD_FAB2_LIB.BASEBOARD_FAB2(SCH_1):PAGE160
     2 SMB_LAN_STBY_LVC3_SCL @BASEBOARD_FAB2_LIB.BASEBOARD_FAB2(SCH_1):SMB_LAN_STBY_LVC3_SCL    I52 @BASEBOARD_FAB2_LIB.BASEBOARD_FAB2(SCH_1):PAGE160

R9F23 RES_0402-20.0,1%,1/16W,CHIP,G2A
     1 SMB_LAN_STBY_LVC3_SDA_R @BASEBOARD_FAB2_LIB.BASEBOARD_FAB2(SCH_1):SMB_LAN_STBY_LVC3_SDA_R    I51 @BASEBOARD_FAB2_LIB.BASEBOARD_FAB2(SCH_1):PAGE160
     2 SMB_LAN_STBY_LVC3_SDA @BASEBOARD_FAB2_LIB.BASEBOARD_FAB2(SCH_1):SMB_LAN_STBY_LVC3_SDA    I51 @BASEBOARD_FAB2_LIB.BASEBOARD_FAB2(SCH_1):PAGE160

R9F24 RES_0402-0.0,5%,1/16W,EMPTY,G2A
     1 SPA_MID_DBG_RX @BASEBOARD_FAB2_LIB.BASEBOARD_FAB2(SCH_1):SPA_MID_DBG_RX   I100 @BASEBOARD_FAB2_LIB.BASEBOARD_FAB2(SCH_1):PAGE158
     2 SP2_BMC_CM_UART_RX @BASEBOARD_FAB2_LIB.BASEBOARD_FAB2(SCH_1):SP2_BMC_CM_UART_RX   I100 @BASEBOARD_FAB2_LIB.BASEBOARD_FAB2(SCH_1):PAGE158

R9F25 RES_0402-100.0,1%,1/16W,CHIP,GA
     1 SPA_MID_DBG_RX @BASEBOARD_FAB2_LIB.BASEBOARD_FAB2(SCH_1):SPA_MID_DBG_RX    I86 @BASEBOARD_FAB2_LIB.BASEBOARD_FAB2(SCH_1):PAGE158
     2 UART_MUX_IN_R @BASEBOARD_FAB2_LIB.BASEBOARD_FAB2(SCH_1):UART_MUX_IN_R    I86 @BASEBOARD_FAB2_LIB.BASEBOARD_FAB2(SCH_1):PAGE158

R9F26 RES_0402-0.0,5%,1/16W,EMPTY,G2A
     1 SP2_BMC_CM_UART_TX @BASEBOARD_FAB2_LIB.BASEBOARD_FAB2(SCH_1):SP2_BMC_CM_UART_TX    I99 @BASEBOARD_FAB2_LIB.BASEBOARD_FAB2(SCH_1):PAGE158
     2 SPA_MID_DBG_TX @BASEBOARD_FAB2_LIB.BASEBOARD_FAB2(SCH_1):SPA_MID_DBG_TX    I99 @BASEBOARD_FAB2_LIB.BASEBOARD_FAB2(SCH_1):PAGE158

R9F27 RES_0402-0.0,5%,1/16W,CHIP,G21A
     1 UART_MUX_OUT_R @BASEBOARD_FAB2_LIB.BASEBOARD_FAB2(SCH_1):UART_MUX_OUT_R    I91 @BASEBOARD_FAB2_LIB.BASEBOARD_FAB2(SCH_1):PAGE158
     2 SPA_MID_DBG_TX @BASEBOARD_FAB2_LIB.BASEBOARD_FAB2(SCH_1):SPA_MID_DBG_TX    I91 @BASEBOARD_FAB2_LIB.BASEBOARD_FAB2(SCH_1):PAGE158

R9F28 RES_0402-221,1.0%,1/16W,CHIP,GA
     1 P3V3_STBY @BASEBOARD_FAB2_LIB.BASEBOARD_FAB2(SCH_1):P3V3_STBY    I72 @BASEBOARD_FAB2_LIB.BASEBOARD_FAB2(SCH_1):PAGE177
     2 FM_RED_LED_ANODE @BASEBOARD_FAB2_LIB.BASEBOARD_FAB2(SCH_1):FM_RED_LED_ANODE    I72 @BASEBOARD_FAB2_LIB.BASEBOARD_FAB2(SCH_1):PAGE177

R9F29 RES_0402-4.75K,1%,1/16W,CHIP,GA
     1 P1V2_AUX_BMC @BASEBOARD_FAB2_LIB.BASEBOARD_FAB2(SCH_1):P1V2_AUX_BMC    I55 @BASEBOARD_FAB2_LIB.BASEBOARD_FAB2(SCH_1):PAGE151
     2 RST_BMC_DDR3_R_N @BASEBOARD_FAB2_LIB.BASEBOARD_FAB2(SCH_1):RST_BMC_DDR3_R_N    I55 @BASEBOARD_FAB2_LIB.BASEBOARD_FAB2(SCH_1):PAGE151

R9F30 RES_0402-4.75K,1%,1/16W,CHIP,GA
     1 P3V3_STBY @BASEBOARD_FAB2_LIB.BASEBOARD_FAB2(SCH_1):P3V3_STBY    I76 @BASEBOARD_FAB2_LIB.BASEBOARD_FAB2(SCH_1):PAGE177
     2 FM_BMC_FAULT_LED_N @BASEBOARD_FAB2_LIB.BASEBOARD_FAB2(SCH_1):FM_BMC_FAULT_LED_N    I76 @BASEBOARD_FAB2_LIB.BASEBOARD_FAB2(SCH_1):PAGE177

R9F31 5K1R2F-2-GP_SMD-RG-5K1R2F-2-GPA
     1 P1V2_AUX_BMC @BASEBOARD_FAB2_LIB.BASEBOARD_FAB2(SCH_1):P1V2_AUX_BMC    I98 @BASEBOARD_FAB2_LIB.BASEBOARD_FAB2(SCH_1):PAGE239
     2 VR_P1V2_BMC_STBY_FB @BASEBOARD_FAB2_LIB.BASEBOARD_FAB2(SCH_1):VR_P1V2_BMC_STBY_FB    I98 @BASEBOARD_FAB2_LIB.BASEBOARD_FAB2(SCH_1):PAGE239

R9F32 RES_0402-10.0K,1%,1/16W,CHIP,GA
     1 VR_P1V2_BMC_STBY_FB @BASEBOARD_FAB2_LIB.BASEBOARD_FAB2(SCH_1):VR_P1V2_BMC_STBY_FB   I100 @BASEBOARD_FAB2_LIB.BASEBOARD_FAB2(SCH_1):PAGE239
     2    GND @BASEBOARD_FAB2_LIB.BASEBOARD_FAB2(SCH_1):GND   I100 @BASEBOARD_FAB2_LIB.BASEBOARD_FAB2(SCH_1):PAGE239

R9F33 RES_0402-0.0,5%,1/16W,CHIP,G21A
     1 PECI_BMC @BASEBOARD_FAB2_LIB.BASEBOARD_FAB2(SCH_1):PECI_BMC    I20 @BASEBOARD_FAB2_LIB.BASEBOARD_FAB2(SCH_1):PAGE145
     2 PECI_BMC_R @BASEBOARD_FAB2_LIB.BASEBOARD_FAB2(SCH_1):PECI_BMC_R    I20 @BASEBOARD_FAB2_LIB.BASEBOARD_FAB2(SCH_1):PAGE145

R9F34 RES_0402-33.2,1%,1/16W,EMPTY,GA
     1 RST_BMC_DDR3_R_N @BASEBOARD_FAB2_LIB.BASEBOARD_FAB2(SCH_1):RST_BMC_DDR3_R_N   I209 @BASEBOARD_FAB2_LIB.BASEBOARD_FAB2(SCH_1):PAGE151
     2 BMC_M_RST_N @BASEBOARD_FAB2_LIB.BASEBOARD_FAB2(SCH_1):BMC_M_RST_N   I209 @BASEBOARD_FAB2_LIB.BASEBOARD_FAB2(SCH_1):PAGE151

R9F52 RES_0402-4.75K,1%,1/16W,CHIP,GA
     1 P3V3_STBY @BASEBOARD_FAB2_LIB.BASEBOARD_FAB2(SCH_1):P3V3_STBY    I82 @BASEBOARD_FAB2_LIB.BASEBOARD_FAB2(SCH_1):PAGE177
     2 FM_BMC_FAULT_LED @BASEBOARD_FAB2_LIB.BASEBOARD_FAB2(SCH_1):FM_BMC_FAULT_LED    I82 @BASEBOARD_FAB2_LIB.BASEBOARD_FAB2(SCH_1):PAGE177

R9F55 RES_0402-4.75K,1%,1/16W,CHIP,GA
     1 P3V3_STBY @BASEBOARD_FAB2_LIB.BASEBOARD_FAB2(SCH_1):P3V3_STBY     I3 @BASEBOARD_FAB2_LIB.BASEBOARD_FAB2(SCH_1):PAGE183
     2 FM_UART_ALERT_N @BASEBOARD_FAB2_LIB.BASEBOARD_FAB2(SCH_1):FM_UART_ALERT_N     I3 @BASEBOARD_FAB2_LIB.BASEBOARD_FAB2(SCH_1):PAGE183

R9F60 RES_0402-0.0,5%,1/16W,EMPTY,G2A
     1 CLK_25M_BMC @BASEBOARD_FAB2_LIB.BASEBOARD_FAB2(SCH_1):CLK_25M_BMC    I10 @BASEBOARD_FAB2_LIB.BASEBOARD_FAB2(SCH_1):PAGE145
     2 CLK_24M_25M_BMC_CLKIN @BASEBOARD_FAB2_LIB.BASEBOARD_FAB2(SCH_1):CLK_24M_25M_BMC_CLKIN    I10 @BASEBOARD_FAB2_LIB.BASEBOARD_FAB2(SCH_1):PAGE145

R9F61 RES_0402-10.0K,1%,1/16W,CHIP,GA
     1 P3V3_STBY @BASEBOARD_FAB2_LIB.BASEBOARD_FAB2(SCH_1):P3V3_STBY    I14 @BASEBOARD_FAB2_LIB.BASEBOARD_FAB2(SCH_1):PAGE145
     2 PU_24M_OSC_OE @BASEBOARD_FAB2_LIB.BASEBOARD_FAB2(SCH_1):PU_24M_OSC_OE    I14 @BASEBOARD_FAB2_LIB.BASEBOARD_FAB2(SCH_1):PAGE145

R9F62 RES_0402-0.0,5%,1/16W,CHIP,G21A
     1 CLK_24M_BMC_CLKIN_R @BASEBOARD_FAB2_LIB.BASEBOARD_FAB2(SCH_1):CLK_24M_BMC_CLKIN_R    I11 @BASEBOARD_FAB2_LIB.BASEBOARD_FAB2(SCH_1):PAGE145
     2 CLK_24M_25M_BMC_CLKIN @BASEBOARD_FAB2_LIB.BASEBOARD_FAB2(SCH_1):CLK_24M_25M_BMC_CLKIN    I11 @BASEBOARD_FAB2_LIB.BASEBOARD_FAB2(SCH_1):PAGE145

R9F63 RES_0402-0.0,5%,1/16W,EMPTY,G2A
     1 SPA_MID_DBG_RX @BASEBOARD_FAB2_LIB.BASEBOARD_FAB2(SCH_1):SPA_MID_DBG_RX    I28 @BASEBOARD_FAB2_LIB.BASEBOARD_FAB2(SCH_1):PAGE181
     2 SPA_MID_DBG_RX_R @BASEBOARD_FAB2_LIB.BASEBOARD_FAB2(SCH_1):SPA_MID_DBG_RX_R    I28 @BASEBOARD_FAB2_LIB.BASEBOARD_FAB2(SCH_1):PAGE181

R9F64 RES_0402-0.0,5%,1/16W,CHIP,G21A
     1 SP2_BMC_CM_UART_TX_R1 @BASEBOARD_FAB2_LIB.BASEBOARD_FAB2(SCH_1):SP2_BMC_CM_UART_TX_R1    I29 @BASEBOARD_FAB2_LIB.BASEBOARD_FAB2(SCH_1):PAGE181
     2 SPA_MID_DBG_RX_R @BASEBOARD_FAB2_LIB.BASEBOARD_FAB2(SCH_1):SPA_MID_DBG_RX_R    I29 @BASEBOARD_FAB2_LIB.BASEBOARD_FAB2(SCH_1):PAGE181

R9F65 RES_0402-0.0,5%,1/16W,CHIP,G21A
     1 SP2_BMC_CM_UART_TX_R1 @BASEBOARD_FAB2_LIB.BASEBOARD_FAB2(SCH_1):SP2_BMC_CM_UART_TX_R1   I148 @BASEBOARD_FAB2_LIB.BASEBOARD_FAB2(SCH_1):PAGE158
     2 SP2_BMC_CM_UART_TX_R @BASEBOARD_FAB2_LIB.BASEBOARD_FAB2(SCH_1):SP2_BMC_CM_UART_TX_R   I148 @BASEBOARD_FAB2_LIB.BASEBOARD_FAB2(SCH_1):PAGE158

R9F66 RES_0402-0.0,5%,1/16W,EMPTY,G2A
     1 SP2_BMC_CM_UART_TX @BASEBOARD_FAB2_LIB.BASEBOARD_FAB2(SCH_1):SP2_BMC_CM_UART_TX   I152 @BASEBOARD_FAB2_LIB.BASEBOARD_FAB2(SCH_1):PAGE158
     2 SP2_BMC_CM_UART_TX_R @BASEBOARD_FAB2_LIB.BASEBOARD_FAB2(SCH_1):SP2_BMC_CM_UART_TX_R   I152 @BASEBOARD_FAB2_LIB.BASEBOARD_FAB2(SCH_1):PAGE158

R9F67 RES_0402-0.0,5%,1/16W,CHIP,G21A
     1 SP2_BMC_CM_UART_RX_R1 @BASEBOARD_FAB2_LIB.BASEBOARD_FAB2(SCH_1):SP2_BMC_CM_UART_RX_R1    I33 @BASEBOARD_FAB2_LIB.BASEBOARD_FAB2(SCH_1):PAGE181
     2 SPA_MID_DBG_TX_R @BASEBOARD_FAB2_LIB.BASEBOARD_FAB2(SCH_1):SPA_MID_DBG_TX_R    I33 @BASEBOARD_FAB2_LIB.BASEBOARD_FAB2(SCH_1):PAGE181

R9F68 RES_0402-0.0,5%,1/16W,EMPTY,G2A
     1 SP2_BMC_CM_UART_RX_R @BASEBOARD_FAB2_LIB.BASEBOARD_FAB2(SCH_1):SP2_BMC_CM_UART_RX_R   I149 @BASEBOARD_FAB2_LIB.BASEBOARD_FAB2(SCH_1):PAGE158
     2 SP2_BMC_CM_UART_RX @BASEBOARD_FAB2_LIB.BASEBOARD_FAB2(SCH_1):SP2_BMC_CM_UART_RX   I149 @BASEBOARD_FAB2_LIB.BASEBOARD_FAB2(SCH_1):PAGE158

R9F69 RES_0402-0.0,5%,1/16W,CHIP,G21A
     1 SP2_BMC_CM_UART_RX_R @BASEBOARD_FAB2_LIB.BASEBOARD_FAB2(SCH_1):SP2_BMC_CM_UART_RX_R   I150 @BASEBOARD_FAB2_LIB.BASEBOARD_FAB2(SCH_1):PAGE158
     2 SP2_BMC_CM_UART_RX_R1 @BASEBOARD_FAB2_LIB.BASEBOARD_FAB2(SCH_1):SP2_BMC_CM_UART_RX_R1   I150 @BASEBOARD_FAB2_LIB.BASEBOARD_FAB2(SCH_1):PAGE158

R9F70 RES_0402-0.0,5%,1/16W,EMPTY,G2A
     1 SPA_MID_DBG_TX @BASEBOARD_FAB2_LIB.BASEBOARD_FAB2(SCH_1):SPA_MID_DBG_TX    I30 @BASEBOARD_FAB2_LIB.BASEBOARD_FAB2(SCH_1):PAGE181
     2 SPA_MID_DBG_TX_R @BASEBOARD_FAB2_LIB.BASEBOARD_FAB2(SCH_1):SPA_MID_DBG_TX_R    I30 @BASEBOARD_FAB2_LIB.BASEBOARD_FAB2(SCH_1):PAGE181

R9G1 RES_0402-150.0,1%,1/16W,CHIP,GA
     1 LED_LAN_1_N @BASEBOARD_FAB2_LIB.BASEBOARD_FAB2(SCH_1):LED_LAN_1_N   I157 @BASEBOARD_FAB2_LIB.BASEBOARD_FAB2(SCH_1):PAGE141
     2 LED_LAN_1_R_N @BASEBOARD_FAB2_LIB.BASEBOARD_FAB2(SCH_1):LED_LAN_1_R_N   I157 @BASEBOARD_FAB2_LIB.BASEBOARD_FAB2(SCH_1):PAGE141

R9G2 RES_0402-75,1.0%,1/16W,CHIP,G2A
     1 LED_LAN_2_R_N @BASEBOARD_FAB2_LIB.BASEBOARD_FAB2(SCH_1):LED_LAN_2_R_N   I134 @BASEBOARD_FAB2_LIB.BASEBOARD_FAB2(SCH_1):PAGE141
     2 LED_LAN_2_N @BASEBOARD_FAB2_LIB.BASEBOARD_FAB2(SCH_1):LED_LAN_2_N   I134 @BASEBOARD_FAB2_LIB.BASEBOARD_FAB2(SCH_1):PAGE141

R9G3 RES_0402-75,1.0%,1/16W,CHIP,G2A
     1 LED_LAN_0_R_N @BASEBOARD_FAB2_LIB.BASEBOARD_FAB2(SCH_1):LED_LAN_0_R_N   I135 @BASEBOARD_FAB2_LIB.BASEBOARD_FAB2(SCH_1):PAGE141
     2 LED_LAN_0_N @BASEBOARD_FAB2_LIB.BASEBOARD_FAB2(SCH_1):LED_LAN_0_N   I135 @BASEBOARD_FAB2_LIB.BASEBOARD_FAB2(SCH_1):PAGE141

R9G4 RES_0402-0.0,5%,1/16W,CHIP,G21A
     1 NIC_LED_ACT_ANODE_R @BASEBOARD_FAB2_LIB.BASEBOARD_FAB2(SCH_1):NIC_LED_ACT_ANODE_R   I156 @BASEBOARD_FAB2_LIB.BASEBOARD_FAB2(SCH_1):PAGE141
     2 P3V3_STBY @BASEBOARD_FAB2_LIB.BASEBOARD_FAB2(SCH_1):P3V3_STBY   I156 @BASEBOARD_FAB2_LIB.BASEBOARD_FAB2(SCH_1):PAGE141

R9G9 RES_0402-0.0,5%,1/16W,CHIP,G21A
     1 NIC_SER_P_MDI_3_DP @BASEBOARD_FAB2_LIB.BASEBOARD_FAB2(SCH_1):NIC_SER_P_MDI_3_DP    I75 @BASEBOARD_FAB2_LIB.BASEBOARD_FAB2(SCH_1):PAGE141
     2 NIC_MDI_SPRV_RJ45_3_R_DP @BASEBOARD_FAB2_LIB.BASEBOARD_FAB2(SCH_1):NIC_MDI_SPRV_RJ45_3_R_DP    I75 @BASEBOARD_FAB2_LIB.BASEBOARD_FAB2(SCH_1):PAGE141

R9G11 RES_0402-0.0,5%,1/16W,CHIP,G21A
     1 NIC_SER_N_MDI_3_DN @BASEBOARD_FAB2_LIB.BASEBOARD_FAB2(SCH_1):NIC_SER_N_MDI_3_DN    I76 @BASEBOARD_FAB2_LIB.BASEBOARD_FAB2(SCH_1):PAGE141
     2 NIC_MDI_SPRV_RJ45_3_R_DN @BASEBOARD_FAB2_LIB.BASEBOARD_FAB2(SCH_1):NIC_MDI_SPRV_RJ45_3_R_DN    I76 @BASEBOARD_FAB2_LIB.BASEBOARD_FAB2(SCH_1):PAGE141

R9G12 RES_0402-20.0,1%,1/16W,CHIP,G2A
     1 SMB_OCP_LAN_STBY_LVC3_SDA @BASEBOARD_FAB2_LIB.BASEBOARD_FAB2(SCH_1):SMB_OCP_LAN_STBY_LVC3_SDA   I224 @BASEBOARD_FAB2_LIB.BASEBOARD_FAB2(SCH_1):PAGE159
     2 SMB_SPRINGVILLE_STBY_LVC3_SDA @BASEBOARD_FAB2_LIB.BASEBOARD_FAB2(SCH_1):SMB_SPRINGVILLE_STBY_LVC3_SDA   I224 @BASEBOARD_FAB2_LIB.BASEBOARD_FAB2(SCH_1):PAGE159

R9G13 RES_0402-20.0,1%,1/16W,CHIP,G2A
     1 SMB_OCP_LAN_STBY_LVC3_SCL @BASEBOARD_FAB2_LIB.BASEBOARD_FAB2(SCH_1):SMB_OCP_LAN_STBY_LVC3_SCL   I227 @BASEBOARD_FAB2_LIB.BASEBOARD_FAB2(SCH_1):PAGE159
     2 SMB_SPRINGVILLE_STBY_LVC3_SCL @BASEBOARD_FAB2_LIB.BASEBOARD_FAB2(SCH_1):SMB_SPRINGVILLE_STBY_LVC3_SCL   I227 @BASEBOARD_FAB2_LIB.BASEBOARD_FAB2(SCH_1):PAGE159

R9G14 RES_0402-20.0,1%,1/16W,CHIP,G2A
     1 SMB_SENSOR_BMC_STBY_LVC3_SCL @BASEBOARD_FAB2_LIB.BASEBOARD_FAB2(SCH_1):SMB_SENSOR_BMC_STBY_LVC3_SCL    I77 @BASEBOARD_FAB2_LIB.BASEBOARD_FAB2(SCH_1):PAGE167
     2 SMB_SENSOR_STBY_LVC3_SCL @BASEBOARD_FAB2_LIB.BASEBOARD_FAB2(SCH_1):SMB_SENSOR_STBY_LVC3_SCL    I77 @BASEBOARD_FAB2_LIB.BASEBOARD_FAB2(SCH_1):PAGE167

R9G15 RES_0402-20.0,1%,1/16W,CHIP,G2A
     1 SMB_SENSOR_BMC_STBY_LVC3_SDA @BASEBOARD_FAB2_LIB.BASEBOARD_FAB2(SCH_1):SMB_SENSOR_BMC_STBY_LVC3_SDA    I58 @BASEBOARD_FAB2_LIB.BASEBOARD_FAB2(SCH_1):PAGE167
     2 SMB_SENSOR_STBY_LVC3_SDA @BASEBOARD_FAB2_LIB.BASEBOARD_FAB2(SCH_1):SMB_SENSOR_STBY_LVC3_SDA    I58 @BASEBOARD_FAB2_LIB.BASEBOARD_FAB2(SCH_1):PAGE167

R9G17 RES_0402-0.0,5%,1/16W,CHIP,G21A
     1 NIC_SET_N_MDI_2_DN @BASEBOARD_FAB2_LIB.BASEBOARD_FAB2(SCH_1):NIC_SET_N_MDI_2_DN    I78 @BASEBOARD_FAB2_LIB.BASEBOARD_FAB2(SCH_1):PAGE141
     2 NIC_MDI_SPRV_RJ45_2_R_DN @BASEBOARD_FAB2_LIB.BASEBOARD_FAB2(SCH_1):NIC_MDI_SPRV_RJ45_2_R_DN    I78 @BASEBOARD_FAB2_LIB.BASEBOARD_FAB2(SCH_1):PAGE141

R9G18 RES_0402-0.0,5%,1/16W,CHIP,G21A
     1 NIC_SET_P_MDI_2_DP @BASEBOARD_FAB2_LIB.BASEBOARD_FAB2(SCH_1):NIC_SET_P_MDI_2_DP    I77 @BASEBOARD_FAB2_LIB.BASEBOARD_FAB2(SCH_1):PAGE141
     2 NIC_MDI_SPRV_RJ45_2_R_DP @BASEBOARD_FAB2_LIB.BASEBOARD_FAB2(SCH_1):NIC_MDI_SPRV_RJ45_2_R_DP    I77 @BASEBOARD_FAB2_LIB.BASEBOARD_FAB2(SCH_1):PAGE141

R9G19 RES_0402-0.0,5%,1/16W,CHIP,G21A
     1 NIC_MDI_SPRV_RJ45_1_DP @BASEBOARD_FAB2_LIB.BASEBOARD_FAB2(SCH_1):NIC_MDI_SPRV_RJ45_1_DP    I79 @BASEBOARD_FAB2_LIB.BASEBOARD_FAB2(SCH_1):PAGE141
     2 NIC_MDI_SPRV_RJ45_1_R_DP @BASEBOARD_FAB2_LIB.BASEBOARD_FAB2(SCH_1):NIC_MDI_SPRV_RJ45_1_R_DP    I79 @BASEBOARD_FAB2_LIB.BASEBOARD_FAB2(SCH_1):PAGE141

R9G20 RES_0402-0.0,5%,1/16W,CHIP,G21A
     1 NIC_MDI_SPRV_RJ45_1_DN @BASEBOARD_FAB2_LIB.BASEBOARD_FAB2(SCH_1):NIC_MDI_SPRV_RJ45_1_DN    I80 @BASEBOARD_FAB2_LIB.BASEBOARD_FAB2(SCH_1):PAGE141
     2 NIC_MDI_SPRV_RJ45_1_R_DN @BASEBOARD_FAB2_LIB.BASEBOARD_FAB2(SCH_1):NIC_MDI_SPRV_RJ45_1_R_DN    I80 @BASEBOARD_FAB2_LIB.BASEBOARD_FAB2(SCH_1):PAGE141

R9G22 RES_0402-0.0,5%,1/16W,CHIP,G21A
     1 NIC_MDI_SPRV_RJ45_0_DN @BASEBOARD_FAB2_LIB.BASEBOARD_FAB2(SCH_1):NIC_MDI_SPRV_RJ45_0_DN    I82 @BASEBOARD_FAB2_LIB.BASEBOARD_FAB2(SCH_1):PAGE141
     2 NIC_MDI_SPRV_RJ45_0_R_DN @BASEBOARD_FAB2_LIB.BASEBOARD_FAB2(SCH_1):NIC_MDI_SPRV_RJ45_0_R_DN    I82 @BASEBOARD_FAB2_LIB.BASEBOARD_FAB2(SCH_1):PAGE141

R9G24 RES_0402-0.0,5%,1/16W,CHIP,G21A
     1 NIC_MDI_SPRV_RJ45_0_DP @BASEBOARD_FAB2_LIB.BASEBOARD_FAB2(SCH_1):NIC_MDI_SPRV_RJ45_0_DP    I81 @BASEBOARD_FAB2_LIB.BASEBOARD_FAB2(SCH_1):PAGE141
     2 NIC_MDI_SPRV_RJ45_0_R_DP @BASEBOARD_FAB2_LIB.BASEBOARD_FAB2(SCH_1):NIC_MDI_SPRV_RJ45_0_R_DP    I81 @BASEBOARD_FAB2_LIB.BASEBOARD_FAB2(SCH_1):PAGE141

R9G26 RES_0402-100.0K,1%,1/16W,CHIP,A
     1 A_P3V_BAT_SCALED @BASEBOARD_FAB2_LIB.BASEBOARD_FAB2(SCH_1):A_P3V_BAT_SCALED   I106 @BASEBOARD_FAB2_LIB.BASEBOARD_FAB2(SCH_1):PAGE169
     2    GND @BASEBOARD_FAB2_LIB.BASEBOARD_FAB2(SCH_1):GND   I106 @BASEBOARD_FAB2_LIB.BASEBOARD_FAB2(SCH_1):PAGE169

R9G27 RES_0402-0.0,5%,1/16W,EMPTY,G2A
     1 H_CPU0_MEMDEF_MEMHOT_G_PCH_N @BASEBOARD_FAB2_LIB.BASEBOARD_FAB2(SCH_1):H_CPU0_MEMDEF_MEMHOT_G_PCH_N    I47 @BASEBOARD_FAB2_LIB.BASEBOARD_FAB2(SCH_1):PAGE152
     2 H_CPU0_MEMDEF_MEMHOT_LVT3_K_N @BASEBOARD_FAB2_LIB.BASEBOARD_FAB2(SCH_1):H_CPU0_MEMDEF_MEMHOT_LVT3_K_N    I47 @BASEBOARD_FAB2_LIB.BASEBOARD_FAB2(SCH_1):PAGE152

R9G28 RES_0402-0.0,5%,1/16W,CHIP,G21A
     1 H_CPU1_KLM_MEMHOT_LVT3_R_N @BASEBOARD_FAB2_LIB.BASEBOARD_FAB2(SCH_1):H_CPU1_KLM_MEMHOT_LVT3_R_N    I71 @BASEBOARD_FAB2_LIB.BASEBOARD_FAB2(SCH_1):PAGE152
     2 H_CPU1_MEMKLM_MEMHOT_LVT3_K_N @BASEBOARD_FAB2_LIB.BASEBOARD_FAB2(SCH_1):H_CPU1_MEMKLM_MEMHOT_LVT3_K_N    I71 @BASEBOARD_FAB2_LIB.BASEBOARD_FAB2(SCH_1):PAGE152

R9G29 RES_0402-0.0,5%,1/16W,CHIP,G21A
     1 H_CPU0_MEMDEF_MEMHOT_LVT3_N @BASEBOARD_FAB2_LIB.BASEBOARD_FAB2(SCH_1):H_CPU0_MEMDEF_MEMHOT_LVT3_N    I92 @BASEBOARD_FAB2_LIB.BASEBOARD_FAB2(SCH_1):PAGE152
     2 H_CPU0_MEMDEF_MEMHOT_LVT3_BMC_N @BASEBOARD_FAB2_LIB.BASEBOARD_FAB2(SCH_1):H_CPU0_MEMDEF_MEMHOT_LVT3_BMC_N    I92 @BASEBOARD_FAB2_LIB.BASEBOARD_FAB2(SCH_1):PAGE152

R9G30 RES_0402-0.0,5%,1/16W,EMPTY,G2A
     1 H_CPU0_MEMDEF_MEMHOT_LVT3_N @BASEBOARD_FAB2_LIB.BASEBOARD_FAB2(SCH_1):H_CPU0_MEMDEF_MEMHOT_LVT3_N    I98 @BASEBOARD_FAB2_LIB.BASEBOARD_FAB2(SCH_1):PAGE152
     2 H_CPU0_MEMDEF_MEMHOT_PCH_N @BASEBOARD_FAB2_LIB.BASEBOARD_FAB2(SCH_1):H_CPU0_MEMDEF_MEMHOT_PCH_N    I98 @BASEBOARD_FAB2_LIB.BASEBOARD_FAB2(SCH_1):PAGE152

R9G31 RES_0402-33.2,1%,1/16W,CHIP,G2A
     1 H_CPU0_MEMDEF_MEMHOT_LVT3_K_N @BASEBOARD_FAB2_LIB.BASEBOARD_FAB2(SCH_1):H_CPU0_MEMDEF_MEMHOT_LVT3_K_N    I14 @BASEBOARD_FAB2_LIB.BASEBOARD_FAB2(SCH_1):PAGE152
     2 H_CPU0_MEMDEF_MEMHOT_LVT3_N @BASEBOARD_FAB2_LIB.BASEBOARD_FAB2(SCH_1):H_CPU0_MEMDEF_MEMHOT_LVT3_N    I14 @BASEBOARD_FAB2_LIB.BASEBOARD_FAB2(SCH_1):PAGE152

R9G32 RES_0402-0.0,5%,1/16W,CHIP,G21A
     1 H_CPU1_GHJ_MEMHOT_LVT3_R_N @BASEBOARD_FAB2_LIB.BASEBOARD_FAB2(SCH_1):H_CPU1_GHJ_MEMHOT_LVT3_R_N    I72 @BASEBOARD_FAB2_LIB.BASEBOARD_FAB2(SCH_1):PAGE152
     2 H_CPU1_MEMGHJ_MEMHOT_LVT3_K_N @BASEBOARD_FAB2_LIB.BASEBOARD_FAB2(SCH_1):H_CPU1_MEMGHJ_MEMHOT_LVT3_K_N    I72 @BASEBOARD_FAB2_LIB.BASEBOARD_FAB2(SCH_1):PAGE152

R9G33 RES_0402-0.0,5%,1/16W,CHIP,G21A
     1 H_CPU0_DEF_MEMHOT_LVT3_R_N @BASEBOARD_FAB2_LIB.BASEBOARD_FAB2(SCH_1):H_CPU0_DEF_MEMHOT_LVT3_R_N    I73 @BASEBOARD_FAB2_LIB.BASEBOARD_FAB2(SCH_1):PAGE152
     2 H_CPU0_MEMDEF_MEMHOT_LVT3_K_N @BASEBOARD_FAB2_LIB.BASEBOARD_FAB2(SCH_1):H_CPU0_MEMDEF_MEMHOT_LVT3_K_N    I73 @BASEBOARD_FAB2_LIB.BASEBOARD_FAB2(SCH_1):PAGE152

R9G34 RES_0402-0.0,5%,1/16W,CHIP,G21A
     1 H_CPU0_MEMABC_MEMHOT_G_N @BASEBOARD_FAB2_LIB.BASEBOARD_FAB2(SCH_1):H_CPU0_MEMABC_MEMHOT_G_N    I45 @BASEBOARD_FAB2_LIB.BASEBOARD_FAB2(SCH_1):PAGE152
     2 H_CPU0_MEMABC_MEMHOT_G_R_N @BASEBOARD_FAB2_LIB.BASEBOARD_FAB2(SCH_1):H_CPU0_MEMABC_MEMHOT_G_R_N    I45 @BASEBOARD_FAB2_LIB.BASEBOARD_FAB2(SCH_1):PAGE152

R9G35 RES_0402-2.7K,1%,1/16W,CHIP,G2A
     1 P3V3_STBY @BASEBOARD_FAB2_LIB.BASEBOARD_FAB2(SCH_1):P3V3_STBY   I164 @BASEBOARD_FAB2_LIB.BASEBOARD_FAB2(SCH_1):PAGE169
     2 FM_BATTERY_SENSE_EN_N @BASEBOARD_FAB2_LIB.BASEBOARD_FAB2(SCH_1):FM_BATTERY_SENSE_EN_N   I164 @BASEBOARD_FAB2_LIB.BASEBOARD_FAB2(SCH_1):PAGE169

R9L1 RES_0402-1.00K,1%,1/16W,CHIP,GA
     1 M_M_VREF @BASEBOARD_FAB2_LIB.BASEBOARD_FAB2(SCH_1):M_M_VREF    I40 @BASEBOARD_FAB2_LIB.BASEBOARD_FAB2(SCH_1):PAGE100
     2    GND @BASEBOARD_FAB2_LIB.BASEBOARD_FAB2(SCH_1):GND    I40 @BASEBOARD_FAB2_LIB.BASEBOARD_FAB2(SCH_1):PAGE100

R9L2 RES_0402-1.00K,1%,1/16W,CHIP,GA
     1 PVDDQ_KLM @BASEBOARD_FAB2_LIB.BASEBOARD_FAB2(SCH_1):PVDDQ_KLM    I38 @BASEBOARD_FAB2_LIB.BASEBOARD_FAB2(SCH_1):PAGE100
     2 M_M_VREF @BASEBOARD_FAB2_LIB.BASEBOARD_FAB2(SCH_1):M_M_VREF    I38 @BASEBOARD_FAB2_LIB.BASEBOARD_FAB2(SCH_1):PAGE100

R9L3 RES_0402-2,1.0%,1/16W,CHIP,G21A
     1 M_M_CPU_VREF @BASEBOARD_FAB2_LIB.BASEBOARD_FAB2(SCH_1):M_M_CPU_VREF    I45 @BASEBOARD_FAB2_LIB.BASEBOARD_FAB2(SCH_1):PAGE100
     2 M_M_VREF @BASEBOARD_FAB2_LIB.BASEBOARD_FAB2(SCH_1):M_M_VREF    I45 @BASEBOARD_FAB2_LIB.BASEBOARD_FAB2(SCH_1):PAGE100

R9L4 RES_0402-0.0,5%,1/16W,CHIP,G21A
     1 VR_PVDDQ_KLM_PH2_VCIN @BASEBOARD_FAB2_LIB.BASEBOARD_FAB2(SCH_1):VR_PVDDQ_KLM_PH2_VCIN   I155 @BASEBOARD_FAB2_LIB.BASEBOARD_FAB2(SCH_1):PAGE227
     2 P5V_STBY @BASEBOARD_FAB2_LIB.BASEBOARD_FAB2(SCH_1):P5V_STBY   I155 @BASEBOARD_FAB2_LIB.BASEBOARD_FAB2(SCH_1):PAGE227

R9L6 RES_0402-1.00K,1%,1/16W,CHIP,GA
     1 M_L_VREF @BASEBOARD_FAB2_LIB.BASEBOARD_FAB2(SCH_1):M_L_VREF    I24 @BASEBOARD_FAB2_LIB.BASEBOARD_FAB2(SCH_1):PAGE100
     2    GND @BASEBOARD_FAB2_LIB.BASEBOARD_FAB2(SCH_1):GND    I24 @BASEBOARD_FAB2_LIB.BASEBOARD_FAB2(SCH_1):PAGE100

R9L7 RES_0402-1.00K,1%,1/16W,CHIP,GA
     1 PVDDQ_KLM @BASEBOARD_FAB2_LIB.BASEBOARD_FAB2(SCH_1):PVDDQ_KLM    I22 @BASEBOARD_FAB2_LIB.BASEBOARD_FAB2(SCH_1):PAGE100
     2 M_L_VREF @BASEBOARD_FAB2_LIB.BASEBOARD_FAB2(SCH_1):M_L_VREF    I22 @BASEBOARD_FAB2_LIB.BASEBOARD_FAB2(SCH_1):PAGE100

R9L8 RES_0402-2,1.0%,1/16W,CHIP,G21A
     1 M_L_CPU_VREF @BASEBOARD_FAB2_LIB.BASEBOARD_FAB2(SCH_1):M_L_CPU_VREF    I29 @BASEBOARD_FAB2_LIB.BASEBOARD_FAB2(SCH_1):PAGE100
     2 M_L_VREF @BASEBOARD_FAB2_LIB.BASEBOARD_FAB2(SCH_1):M_L_VREF    I29 @BASEBOARD_FAB2_LIB.BASEBOARD_FAB2(SCH_1):PAGE100

R9L9 RES_0402-0.0,5%,1/16W,CHIP,G21A
     1 VR_PVDDQ_KLM_PH1_VCIN @BASEBOARD_FAB2_LIB.BASEBOARD_FAB2(SCH_1):VR_PVDDQ_KLM_PH1_VCIN   I154 @BASEBOARD_FAB2_LIB.BASEBOARD_FAB2(SCH_1):PAGE227
     2 P5V_STBY @BASEBOARD_FAB2_LIB.BASEBOARD_FAB2(SCH_1):P5V_STBY   I154 @BASEBOARD_FAB2_LIB.BASEBOARD_FAB2(SCH_1):PAGE227

R9L11 RES_0402-1.00K,1%,1/16W,CHIP,GA
     1 M_K_VREF @BASEBOARD_FAB2_LIB.BASEBOARD_FAB2(SCH_1):M_K_VREF     I4 @BASEBOARD_FAB2_LIB.BASEBOARD_FAB2(SCH_1):PAGE100
     2    GND @BASEBOARD_FAB2_LIB.BASEBOARD_FAB2(SCH_1):GND     I4 @BASEBOARD_FAB2_LIB.BASEBOARD_FAB2(SCH_1):PAGE100

R9M1 RES_0402-1.00K,1%,1/16W,CHIP,GA
     1 PVDDQ_KLM @BASEBOARD_FAB2_LIB.BASEBOARD_FAB2(SCH_1):PVDDQ_KLM    I11 @BASEBOARD_FAB2_LIB.BASEBOARD_FAB2(SCH_1):PAGE100
     2 M_K_VREF @BASEBOARD_FAB2_LIB.BASEBOARD_FAB2(SCH_1):M_K_VREF    I11 @BASEBOARD_FAB2_LIB.BASEBOARD_FAB2(SCH_1):PAGE100

R9M2 RES_0402-2,1.0%,1/16W,CHIP,G21A
     1 M_K_CPU_VREF @BASEBOARD_FAB2_LIB.BASEBOARD_FAB2(SCH_1):M_K_CPU_VREF    I13 @BASEBOARD_FAB2_LIB.BASEBOARD_FAB2(SCH_1):PAGE100
     2 M_K_VREF @BASEBOARD_FAB2_LIB.BASEBOARD_FAB2(SCH_1):M_K_VREF    I13 @BASEBOARD_FAB2_LIB.BASEBOARD_FAB2(SCH_1):PAGE100

R9M3 RES_0402-0.0,5%,1/16W,CHIP,G21A
     1 P3V3_STBY @BASEBOARD_FAB2_LIB.BASEBOARD_FAB2(SCH_1):P3V3_STBY    I36 @BASEBOARD_FAB2_LIB.BASEBOARD_FAB2(SCH_1):PAGE226
     2 VR_PVDDQ_KLM_VDD @BASEBOARD_FAB2_LIB.BASEBOARD_FAB2(SCH_1):VR_PVDDQ_KLM_VDD    I36 @BASEBOARD_FAB2_LIB.BASEBOARD_FAB2(SCH_1):PAGE226

R9M4 RES_1206-0.002,1%,1W,CHIP,G521A
     1 P12V_STBY @BASEBOARD_FAB2_LIB.BASEBOARD_FAB2(SCH_1):P12V_STBY    I29 @BASEBOARD_FAB2_LIB.BASEBOARD_FAB2(SCH_1):PAGE197
     2 P12V_NVDIMM_KLM @BASEBOARD_FAB2_LIB.BASEBOARD_FAB2(SCH_1):P12V_NVDIMM_KLM    I29 @BASEBOARD_FAB2_LIB.BASEBOARD_FAB2(SCH_1):PAGE197

R9M5 RES_0402-100.0K,1%,1/16W,EMPTYA
     1 P3V3_STBY @BASEBOARD_FAB2_LIB.BASEBOARD_FAB2(SCH_1):P3V3_STBY    I34 @BASEBOARD_FAB2_LIB.BASEBOARD_FAB2(SCH_1):PAGE226
     2 VR_PVDDQ_KLM_VREN @BASEBOARD_FAB2_LIB.BASEBOARD_FAB2(SCH_1):VR_PVDDQ_KLM_VREN    I34 @BASEBOARD_FAB2_LIB.BASEBOARD_FAB2(SCH_1):PAGE226

R9M6 RES_0402-49.9,1%,1/16W,EMPTY,GA
     1 PVCCIO_CPU1 @BASEBOARD_FAB2_LIB.BASEBOARD_FAB2(SCH_1):PVCCIO_CPU1    I70 @BASEBOARD_FAB2_LIB.BASEBOARD_FAB2(SCH_1):PAGE226
     2 SVID_CLK1_CPU1_R @BASEBOARD_FAB2_LIB.BASEBOARD_FAB2(SCH_1):SVID_CLK1_CPU1_R    I70 @BASEBOARD_FAB2_LIB.BASEBOARD_FAB2(SCH_1):PAGE226

R9M7 RES_0402-100.0,1%,1/16W,EMPTY,A
     1 PVCCIO_CPU1 @BASEBOARD_FAB2_LIB.BASEBOARD_FAB2(SCH_1):PVCCIO_CPU1    I57 @BASEBOARD_FAB2_LIB.BASEBOARD_FAB2(SCH_1):PAGE226
     2 SVID_DIO1_CPU1_R @BASEBOARD_FAB2_LIB.BASEBOARD_FAB2(SCH_1):SVID_DIO1_CPU1_R    I57 @BASEBOARD_FAB2_LIB.BASEBOARD_FAB2(SCH_1):PAGE226

R9M9 RES_0402-0.0,5%,1/16W,CHIP,G21A
     1 FM_PVDDQ_KLM_EN @BASEBOARD_FAB2_LIB.BASEBOARD_FAB2(SCH_1):FM_PVDDQ_KLM_EN    I14 @BASEBOARD_FAB2_LIB.BASEBOARD_FAB2(SCH_1):PAGE226
     2 VR_PVDDQ_KLM_VREN @BASEBOARD_FAB2_LIB.BASEBOARD_FAB2(SCH_1):VR_PVDDQ_KLM_VREN    I14 @BASEBOARD_FAB2_LIB.BASEBOARD_FAB2(SCH_1):PAGE226

R9M13 RES_0402-20.0,1%,1/16W,CHIP,G2A
     1 SMB_PEHPCPU1_STBY_LVC3_R_SDA @BASEBOARD_FAB2_LIB.BASEBOARD_FAB2(SCH_1):SMB_PEHPCPU1_STBY_LVC3_R_SDA    I21 @BASEBOARD_FAB2_LIB.BASEBOARD_FAB2(SCH_1):PAGE163
     2 SMB_PEHPCPU1_STBY_LVC3_SDA @BASEBOARD_FAB2_LIB.BASEBOARD_FAB2(SCH_1):SMB_PEHPCPU1_STBY_LVC3_SDA    I21 @BASEBOARD_FAB2_LIB.BASEBOARD_FAB2(SCH_1):PAGE163

R9M14 RES_0402-20.0,1%,1/16W,CHIP,G2A
     1 SMB_PEHPCPU1_STBY_LVC3_R_SCL @BASEBOARD_FAB2_LIB.BASEBOARD_FAB2(SCH_1):SMB_PEHPCPU1_STBY_LVC3_R_SCL    I20 @BASEBOARD_FAB2_LIB.BASEBOARD_FAB2(SCH_1):PAGE163
     2 SMB_PEHPCPU1_STBY_LVC3_SCL @BASEBOARD_FAB2_LIB.BASEBOARD_FAB2(SCH_1):SMB_PEHPCPU1_STBY_LVC3_SCL    I20 @BASEBOARD_FAB2_LIB.BASEBOARD_FAB2(SCH_1):PAGE163

R9M16 RES_0402-2.0K,1%,1/16W,CHIP,G2A
     1 P3V3_STBY @BASEBOARD_FAB2_LIB.BASEBOARD_FAB2(SCH_1):P3V3_STBY    I16 @BASEBOARD_FAB2_LIB.BASEBOARD_FAB2(SCH_1):PAGE163
     2 SMB_PEHPCPU1_STBY_LVC3_R_SDA @BASEBOARD_FAB2_LIB.BASEBOARD_FAB2(SCH_1):SMB_PEHPCPU1_STBY_LVC3_R_SDA    I16 @BASEBOARD_FAB2_LIB.BASEBOARD_FAB2(SCH_1):PAGE163

R9M17 RES_0402-2.0K,1%,1/16W,CHIP,G2A
     1 P3V3_STBY @BASEBOARD_FAB2_LIB.BASEBOARD_FAB2(SCH_1):P3V3_STBY    I15 @BASEBOARD_FAB2_LIB.BASEBOARD_FAB2(SCH_1):PAGE163
     2 SMB_PEHPCPU1_STBY_LVC3_R_SCL @BASEBOARD_FAB2_LIB.BASEBOARD_FAB2(SCH_1):SMB_PEHPCPU1_STBY_LVC3_R_SCL    I15 @BASEBOARD_FAB2_LIB.BASEBOARD_FAB2(SCH_1):PAGE163

R9M18 RES_0402-240,1.0%,1/16W,CHIP,GA
     1 PVCCIO_CPU1 @BASEBOARD_FAB2_LIB.BASEBOARD_FAB2(SCH_1):PVCCIO_CPU1     I6 @BASEBOARD_FAB2_LIB.BASEBOARD_FAB2(SCH_1):PAGE163
     2 SMB_CPU1_PE_HP_GTL_R_SDA @BASEBOARD_FAB2_LIB.BASEBOARD_FAB2(SCH_1):SMB_CPU1_PE_HP_GTL_R_SDA     I6 @BASEBOARD_FAB2_LIB.BASEBOARD_FAB2(SCH_1):PAGE163

R9M19 RES_0402-240,1.0%,1/16W,CHIP,GA
     1 PVCCIO_CPU1 @BASEBOARD_FAB2_LIB.BASEBOARD_FAB2(SCH_1):PVCCIO_CPU1     I7 @BASEBOARD_FAB2_LIB.BASEBOARD_FAB2(SCH_1):PAGE163
     2 SMB_CPU1_PE_HP_GTL_R_SCL @BASEBOARD_FAB2_LIB.BASEBOARD_FAB2(SCH_1):SMB_CPU1_PE_HP_GTL_R_SCL     I7 @BASEBOARD_FAB2_LIB.BASEBOARD_FAB2(SCH_1):PAGE163

R9M20 RES_0402-0.0,5%,1/16W,CHIP,G21A
     1 SMB_LAN_STBY_LVC3_SCL @BASEBOARD_FAB2_LIB.BASEBOARD_FAB2(SCH_1):SMB_LAN_STBY_LVC3_SCL   I323 @BASEBOARD_FAB2_LIB.BASEBOARD_FAB2(SCH_1):PAGE156
     2 SMB_PIROM_CPU1_SCL @BASEBOARD_FAB2_LIB.BASEBOARD_FAB2(SCH_1):SMB_PIROM_CPU1_SCL   I323 @BASEBOARD_FAB2_LIB.BASEBOARD_FAB2(SCH_1):PAGE156

R9M21 RES_0402-0.0,5%,1/16W,CHIP,G21A
     1 SMB_LAN_STBY_LVC3_SDA @BASEBOARD_FAB2_LIB.BASEBOARD_FAB2(SCH_1):SMB_LAN_STBY_LVC3_SDA   I321 @BASEBOARD_FAB2_LIB.BASEBOARD_FAB2(SCH_1):PAGE156
     2 SMB_PIROM_CPU1_SDA @BASEBOARD_FAB2_LIB.BASEBOARD_FAB2(SCH_1):SMB_PIROM_CPU1_SDA   I321 @BASEBOARD_FAB2_LIB.BASEBOARD_FAB2(SCH_1):PAGE156

R9N1 RES_0402-49.9,1%,1/16W,CHIP,G2A
     1 PVCCIO_CPU1 @BASEBOARD_FAB2_LIB.BASEBOARD_FAB2(SCH_1):PVCCIO_CPU1     I4 @BASEBOARD_FAB2_LIB.BASEBOARD_FAB2(SCH_1):PAGE55
     2 SVID_ALERT1_CPU1_R_N @BASEBOARD_FAB2_LIB.BASEBOARD_FAB2(SCH_1):SVID_ALERT1_CPU1_R_N     I4 @BASEBOARD_FAB2_LIB.BASEBOARD_FAB2(SCH_1):PAGE55

R9N2 RES_0402-100.0,1%,1/16W,CHIP,GA
     1 PVCCIO_CPU1 @BASEBOARD_FAB2_LIB.BASEBOARD_FAB2(SCH_1):PVCCIO_CPU1     I7 @BASEBOARD_FAB2_LIB.BASEBOARD_FAB2(SCH_1):PAGE55
     2 SVID_DIO1_CPU1_R @BASEBOARD_FAB2_LIB.BASEBOARD_FAB2(SCH_1):SVID_DIO1_CPU1_R     I7 @BASEBOARD_FAB2_LIB.BASEBOARD_FAB2(SCH_1):PAGE55

R9N3 RES_0402-0.0,5%,1/16W,CHIP,G21A
     1 VR_PVSA_CPU1_VCIN @BASEBOARD_FAB2_LIB.BASEBOARD_FAB2(SCH_1):VR_PVSA_CPU1_VCIN    I71 @BASEBOARD_FAB2_LIB.BASEBOARD_FAB2(SCH_1):PAGE210
     2 P5V_STBY @BASEBOARD_FAB2_LIB.BASEBOARD_FAB2(SCH_1):P5V_STBY    I71 @BASEBOARD_FAB2_LIB.BASEBOARD_FAB2(SCH_1):PAGE210

R9N4 RES_0402-51.1,1.0%,1/16W,CHIP,A
     1 PVSA_CPU1 @BASEBOARD_FAB2_LIB.BASEBOARD_FAB2(SCH_1):PVSA_CPU1    I45 @BASEBOARD_FAB2_LIB.BASEBOARD_FAB2(SCH_1):PAGE210
     2    GND @BASEBOARD_FAB2_LIB.BASEBOARD_FAB2(SCH_1):GND    I45 @BASEBOARD_FAB2_LIB.BASEBOARD_FAB2(SCH_1):PAGE210

R9N7 RES_0402-3.16K,1%,1/16W,CHIP,GA
     1 VR_PVCCIN_CPU1_XADDR2 @BASEBOARD_FAB2_LIB.BASEBOARD_FAB2(SCH_1):VR_PVCCIN_CPU1_XADDR2   I111 @BASEBOARD_FAB2_LIB.BASEBOARD_FAB2(SCH_1):PAGE206
     2    GND @BASEBOARD_FAB2_LIB.BASEBOARD_FAB2(SCH_1):GND   I111 @BASEBOARD_FAB2_LIB.BASEBOARD_FAB2(SCH_1):PAGE206

R9N8 RES_0402-4.02K,1%,1/16W,CHIP,GA
     1 VR_PVCCIN_CPU1_XADDR1 @BASEBOARD_FAB2_LIB.BASEBOARD_FAB2(SCH_1):VR_PVCCIN_CPU1_XADDR1   I112 @BASEBOARD_FAB2_LIB.BASEBOARD_FAB2(SCH_1):PAGE206
     2    GND @BASEBOARD_FAB2_LIB.BASEBOARD_FAB2(SCH_1):GND   I112 @BASEBOARD_FAB2_LIB.BASEBOARD_FAB2(SCH_1):PAGE206

R9N14 RES_0402-1.00K,1%,1/16W,CHIP,GA
     1 PVCCIO_CPU1 @BASEBOARD_FAB2_LIB.BASEBOARD_FAB2(SCH_1):PVCCIO_CPU1   I120 @BASEBOARD_FAB2_LIB.BASEBOARD_FAB2(SCH_1):PAGE206
     2 VR_PVCCIN_CPU1_VREN @BASEBOARD_FAB2_LIB.BASEBOARD_FAB2(SCH_1):VR_PVCCIN_CPU1_VREN   I120 @BASEBOARD_FAB2_LIB.BASEBOARD_FAB2(SCH_1):PAGE206

R9N16 RES_0402-0.0,5%,1/16W,CHIP,G21A
     1 FM_PVCCIN_PVCCSA_CPU1_EN_LVC1 @BASEBOARD_FAB2_LIB.BASEBOARD_FAB2(SCH_1):FM_PVCCIN_PVCCSA_CPU1_EN_LVC1   I119 @BASEBOARD_FAB2_LIB.BASEBOARD_FAB2(SCH_1):PAGE206
     2 VR_PVCCIN_CPU1_VREN @BASEBOARD_FAB2_LIB.BASEBOARD_FAB2(SCH_1):VR_PVCCIN_CPU1_VREN   I119 @BASEBOARD_FAB2_LIB.BASEBOARD_FAB2(SCH_1):PAGE206

R9P1 RES_0402-100.0,1%,1/16W,CHIP,GA
     1 PVCCIO_CPU1 @BASEBOARD_FAB2_LIB.BASEBOARD_FAB2(SCH_1):PVCCIO_CPU1     I4 @BASEBOARD_FAB2_LIB.BASEBOARD_FAB2(SCH_1):PAGE206
     2 SVID_DIO0_CPU1_R @BASEBOARD_FAB2_LIB.BASEBOARD_FAB2(SCH_1):SVID_DIO0_CPU1_R     I4 @BASEBOARD_FAB2_LIB.BASEBOARD_FAB2(SCH_1):PAGE206

R9P2 RES_0402-49.9,1%,1/16W,CHIP,G2A
     1 PVCCIO_CPU1 @BASEBOARD_FAB2_LIB.BASEBOARD_FAB2(SCH_1):PVCCIO_CPU1    I53 @BASEBOARD_FAB2_LIB.BASEBOARD_FAB2(SCH_1):PAGE206
     2 SVID_CLK0_CPU1_R @BASEBOARD_FAB2_LIB.BASEBOARD_FAB2(SCH_1):SVID_CLK0_CPU1_R    I53 @BASEBOARD_FAB2_LIB.BASEBOARD_FAB2(SCH_1):PAGE206

R9P3 RES_0402-33.2,1%,1/16W,CHIP,G2A
     1 IRQ_PVCCIN_CPU1_VRHOT_LVC3_R_N @BASEBOARD_FAB2_LIB.BASEBOARD_FAB2(SCH_1):IRQ_PVCCIN_CPU1_VRHOT_LVC3_R_N   I117 @BASEBOARD_FAB2_LIB.BASEBOARD_FAB2(SCH_1):PAGE206
     2 IRQ_PVCCIN_CPU1_VRHOT_LVC3_N @BASEBOARD_FAB2_LIB.BASEBOARD_FAB2(SCH_1):IRQ_PVCCIN_CPU1_VRHOT_LVC3_N   I117 @BASEBOARD_FAB2_LIB.BASEBOARD_FAB2(SCH_1):PAGE206

R9P4 RES_0402-2.7K,1%,1/16W,CHIP,G2A
     1 P3V3_STBY @BASEBOARD_FAB2_LIB.BASEBOARD_FAB2(SCH_1):P3V3_STBY   I210 @BASEBOARD_FAB2_LIB.BASEBOARD_FAB2(SCH_1):PAGE200
     2 IRQ_UV_DETECT_N @BASEBOARD_FAB2_LIB.BASEBOARD_FAB2(SCH_1):IRQ_UV_DETECT_N   I210 @BASEBOARD_FAB2_LIB.BASEBOARD_FAB2(SCH_1):PAGE200

R9P5 RES_0402-10.0K,1%,1/16W,CHIP,GA
     1 P3V3_STBY @BASEBOARD_FAB2_LIB.BASEBOARD_FAB2(SCH_1):P3V3_STBY   I215 @BASEBOARD_FAB2_LIB.BASEBOARD_FAB2(SCH_1):PAGE200
     2 FM_DISABLE_FAN_N @BASEBOARD_FAB2_LIB.BASEBOARD_FAB2(SCH_1):FM_DISABLE_FAN_N   I215 @BASEBOARD_FAB2_LIB.BASEBOARD_FAB2(SCH_1):PAGE200

R9P6 RES_0402-10.0K,1%,1/16W,CHIP,GA
     1 P3V3_STBY @BASEBOARD_FAB2_LIB.BASEBOARD_FAB2(SCH_1):P3V3_STBY   I149 @BASEBOARD_FAB2_LIB.BASEBOARD_FAB2(SCH_1):PAGE200
     2 FM_UV_ADR_TRIGGER_N @BASEBOARD_FAB2_LIB.BASEBOARD_FAB2(SCH_1):FM_UV_ADR_TRIGGER_N   I149 @BASEBOARD_FAB2_LIB.BASEBOARD_FAB2(SCH_1):PAGE200

R9P7 RES_0402-100.0K,1%,1/16W,CHIP,A
     1 P12V_STBY @BASEBOARD_FAB2_LIB.BASEBOARD_FAB2(SCH_1):P12V_STBY   I252 @BASEBOARD_FAB2_LIB.BASEBOARD_FAB2(SCH_1):PAGE200
     2 A_P12V_STBY_ADR_TRIGGER @BASEBOARD_FAB2_LIB.BASEBOARD_FAB2(SCH_1):A_P12V_STBY_ADR_TRIGGER   I252 @BASEBOARD_FAB2_LIB.BASEBOARD_FAB2(SCH_1):PAGE200

R9P8 RES_0402-0.0,5%,1/16W,CHIP,G21A
     1 VR_PVCCIN_CPU1_PH4_VCIN @BASEBOARD_FAB2_LIB.BASEBOARD_FAB2(SCH_1):VR_PVCCIN_CPU1_PH4_VCIN   I115 @BASEBOARD_FAB2_LIB.BASEBOARD_FAB2(SCH_1):PAGE208
     2 P5V_STBY @BASEBOARD_FAB2_LIB.BASEBOARD_FAB2(SCH_1):P5V_STBY   I115 @BASEBOARD_FAB2_LIB.BASEBOARD_FAB2(SCH_1):PAGE208

R9P9 RES_0402-3.74K,1%,1/16W,CHIP,GA
     1 A_P12V_STBY_ADR_TRIGGER @BASEBOARD_FAB2_LIB.BASEBOARD_FAB2(SCH_1):A_P12V_STBY_ADR_TRIGGER   I251 @BASEBOARD_FAB2_LIB.BASEBOARD_FAB2(SCH_1):PAGE200
     2 AGND_HSC @BASEBOARD_FAB2_LIB.BASEBOARD_FAB2(SCH_1):AGND_HSC   I251 @BASEBOARD_FAB2_LIB.BASEBOARD_FAB2(SCH_1):PAGE200

R9P10 RES_0402-10.0K,1%,1/16W,CHIP,GA
     1 P3V3_STBY @BASEBOARD_FAB2_LIB.BASEBOARD_FAB2(SCH_1):P3V3_STBY   I192 @BASEBOARD_FAB2_LIB.BASEBOARD_FAB2(SCH_1):PAGE200
     2 A_P12V_STBY_FPH_GATE @BASEBOARD_FAB2_LIB.BASEBOARD_FAB2(SCH_1):A_P12V_STBY_FPH_GATE   I192 @BASEBOARD_FAB2_LIB.BASEBOARD_FAB2(SCH_1):PAGE200

R9P11 RES_0402-10.0K,1%,1/16W,CHIP,GA
     1 A_P12V_STBY_FP_TRIGGER @BASEBOARD_FAB2_LIB.BASEBOARD_FAB2(SCH_1):A_P12V_STBY_FP_TRIGGER   I108 @BASEBOARD_FAB2_LIB.BASEBOARD_FAB2(SCH_1):PAGE200
     2 AGND_HSC @BASEBOARD_FAB2_LIB.BASEBOARD_FAB2(SCH_1):AGND_HSC   I108 @BASEBOARD_FAB2_LIB.BASEBOARD_FAB2(SCH_1):PAGE200

R9P12 RES_0402-4.99K,1%,1/16W,CHIP,GA
     1 A_HSC_INAP @BASEBOARD_FAB2_LIB.BASEBOARD_FAB2(SCH_1):A_HSC_INAP   I218 @BASEBOARD_FAB2_LIB.BASEBOARD_FAB2(SCH_1):PAGE200
     2 AGND_HSC @BASEBOARD_FAB2_LIB.BASEBOARD_FAB2(SCH_1):AGND_HSC   I218 @BASEBOARD_FAB2_LIB.BASEBOARD_FAB2(SCH_1):PAGE200

R9P13 270KR2F-GP_RCL_GP-270KR2F-GP,6A
     1 P12V_STBY @BASEBOARD_FAB2_LIB.BASEBOARD_FAB2(SCH_1):P12V_STBY   I249 @BASEBOARD_FAB2_LIB.BASEBOARD_FAB2(SCH_1):PAGE200
     2 A_P12V_STBY_FP_TRIGGER @BASEBOARD_FAB2_LIB.BASEBOARD_FAB2(SCH_1):A_P12V_STBY_FP_TRIGGER   I249 @BASEBOARD_FAB2_LIB.BASEBOARD_FAB2(SCH_1):PAGE200

R9P15 RES_0402-0.0,5%,1/16W,CHIP,G21A
     1 A_HSC_LOW_DRAIN @BASEBOARD_FAB2_LIB.BASEBOARD_FAB2(SCH_1):A_HSC_LOW_DRAIN   I243 @BASEBOARD_FAB2_LIB.BASEBOARD_FAB2(SCH_1):PAGE200
     2 IRQ_OC_DETECT_N @BASEBOARD_FAB2_LIB.BASEBOARD_FAB2(SCH_1):IRQ_OC_DETECT_N   I243 @BASEBOARD_FAB2_LIB.BASEBOARD_FAB2(SCH_1):PAGE200

R9P16 RES_0402-0.0,5%,1/16W,CHIP,G21A
     1 FM_P12V_HSC_ADR2 @BASEBOARD_FAB2_LIB.BASEBOARD_FAB2(SCH_1):FM_P12V_HSC_ADR2    I36 @BASEBOARD_FAB2_LIB.BASEBOARD_FAB2(SCH_1):PAGE199
     2 AGND_HSC @BASEBOARD_FAB2_LIB.BASEBOARD_FAB2(SCH_1):AGND_HSC    I36 @BASEBOARD_FAB2_LIB.BASEBOARD_FAB2(SCH_1):PAGE199

R9P17 RES_0402-150.0K,1%,1/16W,CHIP,A
     1 FM_P12V_HSC_ADR1 @BASEBOARD_FAB2_LIB.BASEBOARD_FAB2(SCH_1):FM_P12V_HSC_ADR1    I33 @BASEBOARD_FAB2_LIB.BASEBOARD_FAB2(SCH_1):PAGE199
     2 AGND_HSC @BASEBOARD_FAB2_LIB.BASEBOARD_FAB2(SCH_1):AGND_HSC    I33 @BASEBOARD_FAB2_LIB.BASEBOARD_FAB2(SCH_1):PAGE199

R9P18 RES_0402-15.0K,1%,1/16W,CHIP,GA
     1 P12V_STBY @BASEBOARD_FAB2_LIB.BASEBOARD_FAB2(SCH_1):P12V_STBY    I41 @BASEBOARD_FAB2_LIB.BASEBOARD_FAB2(SCH_1):PAGE199
     2 PWRGD_P12V_R @BASEBOARD_FAB2_LIB.BASEBOARD_FAB2(SCH_1):PWRGD_P12V_R    I41 @BASEBOARD_FAB2_LIB.BASEBOARD_FAB2(SCH_1):PAGE199

R9P19 RES_0402-10.0K,1%,1/16W,EMPTY,A
     1 A_HSC_TIMER_R @BASEBOARD_FAB2_LIB.BASEBOARD_FAB2(SCH_1):A_HSC_TIMER_R    I70 @BASEBOARD_FAB2_LIB.BASEBOARD_FAB2(SCH_1):PAGE200
     2 AGND_HSC @BASEBOARD_FAB2_LIB.BASEBOARD_FAB2(SCH_1):AGND_HSC    I70 @BASEBOARD_FAB2_LIB.BASEBOARD_FAB2(SCH_1):PAGE200

R9P20 RES_0402-2.7K,1%,1/16W,CHIP,G2A
     1 P3V3_STBY @BASEBOARD_FAB2_LIB.BASEBOARD_FAB2(SCH_1):P3V3_STBY    I86 @BASEBOARD_FAB2_LIB.BASEBOARD_FAB2(SCH_1):PAGE200
     2 FM_HSC_TIMER_EXP_N @BASEBOARD_FAB2_LIB.BASEBOARD_FAB2(SCH_1):FM_HSC_TIMER_EXP_N    I86 @BASEBOARD_FAB2_LIB.BASEBOARD_FAB2(SCH_1):PAGE200

R9P21 RES_0402-0.0,5%,1/16W,CHIP,G21A
     1 A_HSC_TIMER @BASEBOARD_FAB2_LIB.BASEBOARD_FAB2(SCH_1):A_HSC_TIMER    I71 @BASEBOARD_FAB2_LIB.BASEBOARD_FAB2(SCH_1):PAGE200
     2 A_HSC_TIMER_R @BASEBOARD_FAB2_LIB.BASEBOARD_FAB2(SCH_1):A_HSC_TIMER_R    I71 @BASEBOARD_FAB2_LIB.BASEBOARD_FAB2(SCH_1):PAGE200

R9P22 RES_0402-0.0,5%,1/16W,CHIP,G21A
     1 VR_PVCCIN_CPU1_PH3_VCIN @BASEBOARD_FAB2_LIB.BASEBOARD_FAB2(SCH_1):VR_PVCCIN_CPU1_PH3_VCIN   I114 @BASEBOARD_FAB2_LIB.BASEBOARD_FAB2(SCH_1):PAGE208
     2 P5V_STBY @BASEBOARD_FAB2_LIB.BASEBOARD_FAB2(SCH_1):P5V_STBY   I114 @BASEBOARD_FAB2_LIB.BASEBOARD_FAB2(SCH_1):PAGE208

R9P23 RES_0402-100.0K,1%,1/16W,CHIP,A
     1 P12V_STBY @BASEBOARD_FAB2_LIB.BASEBOARD_FAB2(SCH_1):P12V_STBY    I54 @BASEBOARD_FAB2_LIB.BASEBOARD_FAB2(SCH_1):PAGE199
     2 A_HSC_PWGIN @BASEBOARD_FAB2_LIB.BASEBOARD_FAB2(SCH_1):A_HSC_PWGIN    I54 @BASEBOARD_FAB2_LIB.BASEBOARD_FAB2(SCH_1):PAGE199

R9P24 RES_0402-12.1K,1%,1/16W,CHIP,GA
     1 A_HSC_PWGIN @BASEBOARD_FAB2_LIB.BASEBOARD_FAB2(SCH_1):A_HSC_PWGIN    I55 @BASEBOARD_FAB2_LIB.BASEBOARD_FAB2(SCH_1):PAGE199
     2 AGND_HSC @BASEBOARD_FAB2_LIB.BASEBOARD_FAB2(SCH_1):AGND_HSC    I55 @BASEBOARD_FAB2_LIB.BASEBOARD_FAB2(SCH_1):PAGE199

R9P26 RES_0402-10.0,1%,1/16W,CHIP,G2A
     1 P12V_HSC_SENN1 @BASEBOARD_FAB2_LIB.BASEBOARD_FAB2(SCH_1):P12V_HSC_SENN1    I51 @BASEBOARD_FAB2_LIB.BASEBOARD_FAB2(SCH_1):PAGE200
     2 A_HSC_HSN @BASEBOARD_FAB2_LIB.BASEBOARD_FAB2(SCH_1):A_HSC_HSN    I51 @BASEBOARD_FAB2_LIB.BASEBOARD_FAB2(SCH_1):PAGE200

R9P27 RES_0402-10.0,1%,1/16W,CHIP,G2A
     1 P12V_HSC_SENP1 @BASEBOARD_FAB2_LIB.BASEBOARD_FAB2(SCH_1):P12V_HSC_SENP1    I47 @BASEBOARD_FAB2_LIB.BASEBOARD_FAB2(SCH_1):PAGE200
     2 A_HSC_HSP @BASEBOARD_FAB2_LIB.BASEBOARD_FAB2(SCH_1):A_HSC_HSP    I47 @BASEBOARD_FAB2_LIB.BASEBOARD_FAB2(SCH_1):PAGE200

R9P28 RES_0402-100.0K,1%,1/16W,CHIP,A
     1 P12V_PSU @BASEBOARD_FAB2_LIB.BASEBOARD_FAB2(SCH_1):P12V_PSU   I138 @BASEBOARD_FAB2_LIB.BASEBOARD_FAB2(SCH_1):PAGE199
     2 A_HSC_OV @BASEBOARD_FAB2_LIB.BASEBOARD_FAB2(SCH_1):A_HSC_OV   I138 @BASEBOARD_FAB2_LIB.BASEBOARD_FAB2(SCH_1):PAGE199

R9P29 RES_0402-100.0K,1%,1/16W,CHIP,A
     1 P12V_PSU @BASEBOARD_FAB2_LIB.BASEBOARD_FAB2(SCH_1):P12V_PSU    I12 @BASEBOARD_FAB2_LIB.BASEBOARD_FAB2(SCH_1):PAGE199
     2 A_HSC_UV @BASEBOARD_FAB2_LIB.BASEBOARD_FAB2(SCH_1):A_HSC_UV    I12 @BASEBOARD_FAB2_LIB.BASEBOARD_FAB2(SCH_1):PAGE199

R9P30 RES_0603-10.0,1%,1/10W,CHIP,G2A
     1 P12V_PSU @BASEBOARD_FAB2_LIB.BASEBOARD_FAB2(SCH_1):P12V_PSU     I2 @BASEBOARD_FAB2_LIB.BASEBOARD_FAB2(SCH_1):PAGE199
     2 P12V_HSC_VCC @BASEBOARD_FAB2_LIB.BASEBOARD_FAB2(SCH_1):P12V_HSC_VCC     I2 @BASEBOARD_FAB2_LIB.BASEBOARD_FAB2(SCH_1):PAGE199

R9P32 RES_0402-0.0,5%,1/16W,CHIP,G21A
     1 VR_PVCCIN_CPU1_PH5_VCIN @BASEBOARD_FAB2_LIB.BASEBOARD_FAB2(SCH_1):VR_PVCCIN_CPU1_PH5_VCIN    I79 @BASEBOARD_FAB2_LIB.BASEBOARD_FAB2(SCH_1):PAGE209
     2 P5V_STBY @BASEBOARD_FAB2_LIB.BASEBOARD_FAB2(SCH_1):P5V_STBY    I79 @BASEBOARD_FAB2_LIB.BASEBOARD_FAB2(SCH_1):PAGE209

R9P33 RES_0402-100.0K,1%,1/16W,CHIP,A
     1 P12V_STBY @BASEBOARD_FAB2_LIB.BASEBOARD_FAB2(SCH_1):P12V_STBY   I222 @BASEBOARD_FAB2_LIB.BASEBOARD_FAB2(SCH_1):PAGE200
     2 A_HSC_INAP @BASEBOARD_FAB2_LIB.BASEBOARD_FAB2(SCH_1):A_HSC_INAP   I222 @BASEBOARD_FAB2_LIB.BASEBOARD_FAB2(SCH_1):PAGE200

R9R1 RES_PWR_6PAD-0.001,1%,3W,CHIP,A
     1 P12V_PSU @BASEBOARD_FAB2_LIB.BASEBOARD_FAB2(SCH_1):P12V_PSU    I49 @BASEBOARD_FAB2_LIB.BASEBOARD_FAB2(SCH_1):PAGE200
     2 P12V_MB0_SW @BASEBOARD_FAB2_LIB.BASEBOARD_FAB2(SCH_1):P12V_MB0_SW    I49 @BASEBOARD_FAB2_LIB.BASEBOARD_FAB2(SCH_1):PAGE200
     3 P12V_HSC_SENP1 @BASEBOARD_FAB2_LIB.BASEBOARD_FAB2(SCH_1):P12V_HSC_SENP1    I49 @BASEBOARD_FAB2_LIB.BASEBOARD_FAB2(SCH_1):PAGE200
     4 P12V_HSC_SENN1 @BASEBOARD_FAB2_LIB.BASEBOARD_FAB2(SCH_1):P12V_HSC_SENN1    I49 @BASEBOARD_FAB2_LIB.BASEBOARD_FAB2(SCH_1):PAGE200
     5 P12V_PSU @BASEBOARD_FAB2_LIB.BASEBOARD_FAB2(SCH_1):P12V_PSU    I49 @BASEBOARD_FAB2_LIB.BASEBOARD_FAB2(SCH_1):PAGE200
     6 P12V_MB0_SW @BASEBOARD_FAB2_LIB.BASEBOARD_FAB2(SCH_1):P12V_MB0_SW    I49 @BASEBOARD_FAB2_LIB.BASEBOARD_FAB2(SCH_1):PAGE200

R9R2 RES_0402-0.0,5%,1/16W,CHIP,G21A
     1 VR_PVCCIN_CPU1_PH1_VCIN @BASEBOARD_FAB2_LIB.BASEBOARD_FAB2(SCH_1):VR_PVCCIN_CPU1_PH1_VCIN   I106 @BASEBOARD_FAB2_LIB.BASEBOARD_FAB2(SCH_1):PAGE207
     2 P5V_STBY @BASEBOARD_FAB2_LIB.BASEBOARD_FAB2(SCH_1):P5V_STBY   I106 @BASEBOARD_FAB2_LIB.BASEBOARD_FAB2(SCH_1):PAGE207

R9R4 RES_0402-10.0,1%,1/16W,CHIP,G2A
     1 A_HSC_GATE @BASEBOARD_FAB2_LIB.BASEBOARD_FAB2(SCH_1):A_HSC_GATE    I58 @BASEBOARD_FAB2_LIB.BASEBOARD_FAB2(SCH_1):PAGE200
     2 A_HSC_GATE2_R @BASEBOARD_FAB2_LIB.BASEBOARD_FAB2(SCH_1):A_HSC_GATE2_R    I58 @BASEBOARD_FAB2_LIB.BASEBOARD_FAB2(SCH_1):PAGE200

R9R5 RES_0402-49.9,1%,1/16W,CHIP,G2A
     1 ISENSE_TMP421_2_E @BASEBOARD_FAB2_LIB.BASEBOARD_FAB2(SCH_1):ISENSE_TMP421_2_E    I25 @BASEBOARD_FAB2_LIB.BASEBOARD_FAB2(SCH_1):PAGE167
     2 ISENSE_TMP421_2_DXP @BASEBOARD_FAB2_LIB.BASEBOARD_FAB2(SCH_1):ISENSE_TMP421_2_DXP    I25 @BASEBOARD_FAB2_LIB.BASEBOARD_FAB2(SCH_1):PAGE167

R9R6 RES_0402-49.9,1%,1/16W,CHIP,G2A
     1 ISENSE_TMP421_2_BC @BASEBOARD_FAB2_LIB.BASEBOARD_FAB2(SCH_1):ISENSE_TMP421_2_BC    I26 @BASEBOARD_FAB2_LIB.BASEBOARD_FAB2(SCH_1):PAGE167
     2 ISENSE_TMP421_2_DXN @BASEBOARD_FAB2_LIB.BASEBOARD_FAB2(SCH_1):ISENSE_TMP421_2_DXN    I26 @BASEBOARD_FAB2_LIB.BASEBOARD_FAB2(SCH_1):PAGE167

R9R7 RES_0402-20.0,1%,1/16W,CHIP,G2A
     1 SMB_SENSOR_TMP421_2_SCL @BASEBOARD_FAB2_LIB.BASEBOARD_FAB2(SCH_1):SMB_SENSOR_TMP421_2_SCL    I75 @BASEBOARD_FAB2_LIB.BASEBOARD_FAB2(SCH_1):PAGE167
     2 SMB_SENSOR_STBY_LVC3_SCL @BASEBOARD_FAB2_LIB.BASEBOARD_FAB2(SCH_1):SMB_SENSOR_STBY_LVC3_SCL    I75 @BASEBOARD_FAB2_LIB.BASEBOARD_FAB2(SCH_1):PAGE167

R9R8 RES_0402-20.0,1%,1/16W,CHIP,G2A
     1 SMB_SENSOR_TMP421_2_SDA @BASEBOARD_FAB2_LIB.BASEBOARD_FAB2(SCH_1):SMB_SENSOR_TMP421_2_SDA    I76 @BASEBOARD_FAB2_LIB.BASEBOARD_FAB2(SCH_1):PAGE167
     2 SMB_SENSOR_STBY_LVC3_SDA @BASEBOARD_FAB2_LIB.BASEBOARD_FAB2(SCH_1):SMB_SENSOR_STBY_LVC3_SDA    I76 @BASEBOARD_FAB2_LIB.BASEBOARD_FAB2(SCH_1):PAGE167

R9R9 RES_0402-0.0,5%,1/16W,CHIP,G21A
     1 FAN_TACH3 @BASEBOARD_FAB2_LIB.BASEBOARD_FAB2(SCH_1):FAN_TACH3    I32 @BASEBOARD_FAB2_LIB.BASEBOARD_FAB2(SCH_1):PAGE181
     2 FAN_TACH3_R @BASEBOARD_FAB2_LIB.BASEBOARD_FAB2(SCH_1):FAN_TACH3_R    I32 @BASEBOARD_FAB2_LIB.BASEBOARD_FAB2(SCH_1):PAGE181

R9R10 RES_0402-0.0,5%,1/16W,CHIP,G21A
     1 FAN_TACH1 @BASEBOARD_FAB2_LIB.BASEBOARD_FAB2(SCH_1):FAN_TACH1    I31 @BASEBOARD_FAB2_LIB.BASEBOARD_FAB2(SCH_1):PAGE181
     2 FAN_TACH1_R @BASEBOARD_FAB2_LIB.BASEBOARD_FAB2(SCH_1):FAN_TACH1_R    I31 @BASEBOARD_FAB2_LIB.BASEBOARD_FAB2(SCH_1):PAGE181

R9R11 RES_0402-0.0,5%,1/16W,CHIP,G21A
     1 VR_PVCCIN_CPU1_PH2_VCIN @BASEBOARD_FAB2_LIB.BASEBOARD_FAB2(SCH_1):VR_PVCCIN_CPU1_PH2_VCIN   I105 @BASEBOARD_FAB2_LIB.BASEBOARD_FAB2(SCH_1):PAGE207
     2 P5V_STBY @BASEBOARD_FAB2_LIB.BASEBOARD_FAB2(SCH_1):P5V_STBY   I105 @BASEBOARD_FAB2_LIB.BASEBOARD_FAB2(SCH_1):PAGE207

R9R12 RES_0402-0.0,5%,1/16W,CHIP,G21A
     1 FAN_TACH2 @BASEBOARD_FAB2_LIB.BASEBOARD_FAB2(SCH_1):FAN_TACH2    I27 @BASEBOARD_FAB2_LIB.BASEBOARD_FAB2(SCH_1):PAGE181
     2 FAN_TACH2_R @BASEBOARD_FAB2_LIB.BASEBOARD_FAB2(SCH_1):FAN_TACH2_R    I27 @BASEBOARD_FAB2_LIB.BASEBOARD_FAB2(SCH_1):PAGE181

R9T1 RES_0402-0.0,5%,1/16W,CHIP,G21A
     1 FAN_PWM_OUT_SYS0_R @BASEBOARD_FAB2_LIB.BASEBOARD_FAB2(SCH_1):FAN_PWM_OUT_SYS0_R    I26 @BASEBOARD_FAB2_LIB.BASEBOARD_FAB2(SCH_1):PAGE181
     2 FAN_PWM_OUT_SYS0_R1 @BASEBOARD_FAB2_LIB.BASEBOARD_FAB2(SCH_1):FAN_PWM_OUT_SYS0_R1    I26 @BASEBOARD_FAB2_LIB.BASEBOARD_FAB2(SCH_1):PAGE181

R9T3 RES_0402-6.19K,1%,1/16W,CHIP,GA
     1 FM_P12V_HOTSWAP0_EN @BASEBOARD_FAB2_LIB.BASEBOARD_FAB2(SCH_1):FM_P12V_HOTSWAP0_EN    I64 @BASEBOARD_FAB2_LIB.BASEBOARD_FAB2(SCH_1):PAGE181
     2    GND @BASEBOARD_FAB2_LIB.BASEBOARD_FAB2(SCH_1):GND    I64 @BASEBOARD_FAB2_LIB.BASEBOARD_FAB2(SCH_1):PAGE181

R9T6 RES_0402-15.0K,1%,1/16W,CHIP,GA
     1 P12V_PSU @BASEBOARD_FAB2_LIB.BASEBOARD_FAB2(SCH_1):P12V_PSU    I68 @BASEBOARD_FAB2_LIB.BASEBOARD_FAB2(SCH_1):PAGE181
     2 FM_P12V_HOTSWAP0_EN @BASEBOARD_FAB2_LIB.BASEBOARD_FAB2(SCH_1):FM_P12V_HOTSWAP0_EN    I68 @BASEBOARD_FAB2_LIB.BASEBOARD_FAB2(SCH_1):PAGE181

R9T8 RES_0402-0.0,5%,1/16W,CHIP,G21A
     1 FM_MATED_IN_N @BASEBOARD_FAB2_LIB.BASEBOARD_FAB2(SCH_1):FM_MATED_IN_N   I137 @BASEBOARD_FAB2_LIB.BASEBOARD_FAB2(SCH_1):PAGE181
     2    GND @BASEBOARD_FAB2_LIB.BASEBOARD_FAB2(SCH_1):GND   I137 @BASEBOARD_FAB2_LIB.BASEBOARD_FAB2(SCH_1):PAGE181

R9T9 RES_0402-4.75K,1%,1/16W,CHIP,GA
     1 P12V_PSU @BASEBOARD_FAB2_LIB.BASEBOARD_FAB2(SCH_1):P12V_PSU     I4 @BASEBOARD_FAB2_LIB.BASEBOARD_FAB2(SCH_1):PAGE181
     2 FM_MATED_IN_N @BASEBOARD_FAB2_LIB.BASEBOARD_FAB2(SCH_1):FM_MATED_IN_N     I4 @BASEBOARD_FAB2_LIB.BASEBOARD_FAB2(SCH_1):PAGE181

R9U1 RES_0402-0.0,5%,1/16W,CHIP,G21A
     1 VR_PVDDQ_GHJ_PH1_VCIN @BASEBOARD_FAB2_LIB.BASEBOARD_FAB2(SCH_1):VR_PVDDQ_GHJ_PH1_VCIN   I150 @BASEBOARD_FAB2_LIB.BASEBOARD_FAB2(SCH_1):PAGE224
     2 P5V_STBY @BASEBOARD_FAB2_LIB.BASEBOARD_FAB2(SCH_1):P5V_STBY   I150 @BASEBOARD_FAB2_LIB.BASEBOARD_FAB2(SCH_1):PAGE224

R9U3 RES_0402-100.0,1%,1/16W,CHIP,GA
     1 PVCCIO_CPU1 @BASEBOARD_FAB2_LIB.BASEBOARD_FAB2(SCH_1):PVCCIO_CPU1    I57 @BASEBOARD_FAB2_LIB.BASEBOARD_FAB2(SCH_1):PAGE223
     2 SVID_DIO1_CPU1_R @BASEBOARD_FAB2_LIB.BASEBOARD_FAB2(SCH_1):SVID_DIO1_CPU1_R    I57 @BASEBOARD_FAB2_LIB.BASEBOARD_FAB2(SCH_1):PAGE223

R9U4 RES_0402-49.9,1%,1/16W,CHIP,G2A
     1 PVCCIO_CPU1 @BASEBOARD_FAB2_LIB.BASEBOARD_FAB2(SCH_1):PVCCIO_CPU1    I70 @BASEBOARD_FAB2_LIB.BASEBOARD_FAB2(SCH_1):PAGE223
     2 SVID_CLK1_CPU1_R @BASEBOARD_FAB2_LIB.BASEBOARD_FAB2(SCH_1):SVID_CLK1_CPU1_R    I70 @BASEBOARD_FAB2_LIB.BASEBOARD_FAB2(SCH_1):PAGE223

R9U7 RES_0402-0.0,5%,1/16W,CHIP,G21A
     1 FM_PVDDQ_GHJ_EN @BASEBOARD_FAB2_LIB.BASEBOARD_FAB2(SCH_1):FM_PVDDQ_GHJ_EN    I14 @BASEBOARD_FAB2_LIB.BASEBOARD_FAB2(SCH_1):PAGE223
     2 VR_PVDDQ_GHJ_VREN @BASEBOARD_FAB2_LIB.BASEBOARD_FAB2(SCH_1):VR_PVDDQ_GHJ_VREN    I14 @BASEBOARD_FAB2_LIB.BASEBOARD_FAB2(SCH_1):PAGE223

R9U8 RES_0402-100.0K,1%,1/16W,EMPTYA
     1 P3V3_STBY @BASEBOARD_FAB2_LIB.BASEBOARD_FAB2(SCH_1):P3V3_STBY    I31 @BASEBOARD_FAB2_LIB.BASEBOARD_FAB2(SCH_1):PAGE223
     2 VR_PVDDQ_GHJ_VREN @BASEBOARD_FAB2_LIB.BASEBOARD_FAB2(SCH_1):VR_PVDDQ_GHJ_VREN    I31 @BASEBOARD_FAB2_LIB.BASEBOARD_FAB2(SCH_1):PAGE223

R9U10 RES_0402-0.0,5%,1/16W,CHIP,G21A
     1 P3V3_STBY @BASEBOARD_FAB2_LIB.BASEBOARD_FAB2(SCH_1):P3V3_STBY    I32 @BASEBOARD_FAB2_LIB.BASEBOARD_FAB2(SCH_1):PAGE223
     2 VR_PVDDQ_GHJ_VDD @BASEBOARD_FAB2_LIB.BASEBOARD_FAB2(SCH_1):VR_PVDDQ_GHJ_VDD    I32 @BASEBOARD_FAB2_LIB.BASEBOARD_FAB2(SCH_1):PAGE223

R9U12 RES_0402-0.0,5%,1/16W,CHIP,G21A
     1 VR_PVDDQ_GHJ_PH2_VCIN @BASEBOARD_FAB2_LIB.BASEBOARD_FAB2(SCH_1):VR_PVDDQ_GHJ_PH2_VCIN   I151 @BASEBOARD_FAB2_LIB.BASEBOARD_FAB2(SCH_1):PAGE224
     2 P5V_STBY @BASEBOARD_FAB2_LIB.BASEBOARD_FAB2(SCH_1):P5V_STBY   I151 @BASEBOARD_FAB2_LIB.BASEBOARD_FAB2(SCH_1):PAGE224

R9W1 RES_0402-10.0K,1%,1/16W,CHIP,GA
     1 P3V3_STBY @BASEBOARD_FAB2_LIB.BASEBOARD_FAB2(SCH_1):P3V3_STBY   I356 @BASEBOARD_FAB2_LIB.BASEBOARD_FAB2(SCH_1):PAGE186
     2 FM_MEZZA_PRSNT1_N @BASEBOARD_FAB2_LIB.BASEBOARD_FAB2(SCH_1):FM_MEZZA_PRSNT1_N   I356 @BASEBOARD_FAB2_LIB.BASEBOARD_FAB2(SCH_1):PAGE186

R9W12 RES_0402-10.0K,1%,1/16W,CHIP,GA
     1 P3V3_STBY @BASEBOARD_FAB2_LIB.BASEBOARD_FAB2(SCH_1):P3V3_STBY    I79 @BASEBOARD_FAB2_LIB.BASEBOARD_FAB2(SCH_1):PAGE239
     2 PWRGD_P2V5_BMC_STBY_R @BASEBOARD_FAB2_LIB.BASEBOARD_FAB2(SCH_1):PWRGD_P2V5_BMC_STBY_R    I79 @BASEBOARD_FAB2_LIB.BASEBOARD_FAB2(SCH_1):PAGE239

R9W13 RES_0402-20.0,1%,1/16W,CHIP,G2A
     1 SMB_PEHPCPU0_STBY_LVC3_R_SDA @BASEBOARD_FAB2_LIB.BASEBOARD_FAB2(SCH_1):SMB_PEHPCPU0_STBY_LVC3_R_SDA    I38 @BASEBOARD_FAB2_LIB.BASEBOARD_FAB2(SCH_1):PAGE248
     2 SMB_PEHPCPU0_STBY_LVC3_SDA @BASEBOARD_FAB2_LIB.BASEBOARD_FAB2(SCH_1):SMB_PEHPCPU0_STBY_LVC3_SDA    I38 @BASEBOARD_FAB2_LIB.BASEBOARD_FAB2(SCH_1):PAGE248

R9W14 RES_0402-20.0,1%,1/16W,CHIP,G2A
     1 SMB_PEHPCPU0_STBY_LVC3_R_SCL @BASEBOARD_FAB2_LIB.BASEBOARD_FAB2(SCH_1):SMB_PEHPCPU0_STBY_LVC3_R_SCL    I37 @BASEBOARD_FAB2_LIB.BASEBOARD_FAB2(SCH_1):PAGE248
     2 SMB_PEHPCPU0_STBY_LVC3_SCL @BASEBOARD_FAB2_LIB.BASEBOARD_FAB2(SCH_1):SMB_PEHPCPU0_STBY_LVC3_SCL    I37 @BASEBOARD_FAB2_LIB.BASEBOARD_FAB2(SCH_1):PAGE248

R9W16 RES_0402-2.0K,1%,1/16W,CHIP,G2A
     1 P3V3_STBY @BASEBOARD_FAB2_LIB.BASEBOARD_FAB2(SCH_1):P3V3_STBY    I34 @BASEBOARD_FAB2_LIB.BASEBOARD_FAB2(SCH_1):PAGE248
     2 SMB_PEHPCPU0_STBY_LVC3_R_SDA @BASEBOARD_FAB2_LIB.BASEBOARD_FAB2(SCH_1):SMB_PEHPCPU0_STBY_LVC3_R_SDA    I34 @BASEBOARD_FAB2_LIB.BASEBOARD_FAB2(SCH_1):PAGE248

R9W17 RES_0402-2.0K,1%,1/16W,CHIP,G2A
     1 P3V3_STBY @BASEBOARD_FAB2_LIB.BASEBOARD_FAB2(SCH_1):P3V3_STBY    I35 @BASEBOARD_FAB2_LIB.BASEBOARD_FAB2(SCH_1):PAGE248
     2 SMB_PEHPCPU0_STBY_LVC3_R_SCL @BASEBOARD_FAB2_LIB.BASEBOARD_FAB2(SCH_1):SMB_PEHPCPU0_STBY_LVC3_R_SCL    I35 @BASEBOARD_FAB2_LIB.BASEBOARD_FAB2(SCH_1):PAGE248

R9W18 RES_0402-240,1.0%,1/16W,CHIP,GA
     1 PVCCIO_CPU0 @BASEBOARD_FAB2_LIB.BASEBOARD_FAB2(SCH_1):PVCCIO_CPU0    I27 @BASEBOARD_FAB2_LIB.BASEBOARD_FAB2(SCH_1):PAGE248
     2 SMB_CPU0_PE_HP_GTL_R_SDA @BASEBOARD_FAB2_LIB.BASEBOARD_FAB2(SCH_1):SMB_CPU0_PE_HP_GTL_R_SDA    I27 @BASEBOARD_FAB2_LIB.BASEBOARD_FAB2(SCH_1):PAGE248

R9W19 RES_0402-240,1.0%,1/16W,CHIP,GA
     1 PVCCIO_CPU0 @BASEBOARD_FAB2_LIB.BASEBOARD_FAB2(SCH_1):PVCCIO_CPU0    I26 @BASEBOARD_FAB2_LIB.BASEBOARD_FAB2(SCH_1):PAGE248
     2 SMB_CPU0_PE_HP_GTL_R_SCL @BASEBOARD_FAB2_LIB.BASEBOARD_FAB2(SCH_1):SMB_CPU0_PE_HP_GTL_R_SCL    I26 @BASEBOARD_FAB2_LIB.BASEBOARD_FAB2(SCH_1):PAGE248

R9W31 21K5R2F-GP_RCL_GP-21K5R2F-GP,6A
     1 P2V5_AUX_BMC @BASEBOARD_FAB2_LIB.BASEBOARD_FAB2(SCH_1):P2V5_AUX_BMC   I102 @BASEBOARD_FAB2_LIB.BASEBOARD_FAB2(SCH_1):PAGE239
     2 VR_P2V5_BMC_STBY_FB @BASEBOARD_FAB2_LIB.BASEBOARD_FAB2(SCH_1):VR_P2V5_BMC_STBY_FB   I102 @BASEBOARD_FAB2_LIB.BASEBOARD_FAB2(SCH_1):PAGE239

R9W32 RES_0402-10.0K,1%,1/16W,CHIP,GA
     1 VR_P2V5_BMC_STBY_FB @BASEBOARD_FAB2_LIB.BASEBOARD_FAB2(SCH_1):VR_P2V5_BMC_STBY_FB   I101 @BASEBOARD_FAB2_LIB.BASEBOARD_FAB2(SCH_1):PAGE239
     2    GND @BASEBOARD_FAB2_LIB.BASEBOARD_FAB2(SCH_1):GND   I101 @BASEBOARD_FAB2_LIB.BASEBOARD_FAB2(SCH_1):PAGE239

R9W33 RES_0402-4.75K,1%,1/16W,CHIP,GA
     1 P3V3_STBY @BASEBOARD_FAB2_LIB.BASEBOARD_FAB2(SCH_1):P3V3_STBY   I153 @BASEBOARD_FAB2_LIB.BASEBOARD_FAB2(SCH_1):PAGE158
     2 SP1_BMC_HOST_UART_RX @BASEBOARD_FAB2_LIB.BASEBOARD_FAB2(SCH_1):SP1_BMC_HOST_UART_RX   I153 @BASEBOARD_FAB2_LIB.BASEBOARD_FAB2(SCH_1):PAGE158

R9W34 RES_0402-4.75K,1%,1/16W,CHIP,GA
     1 P3V3_STBY @BASEBOARD_FAB2_LIB.BASEBOARD_FAB2(SCH_1):P3V3_STBY   I154 @BASEBOARD_FAB2_LIB.BASEBOARD_FAB2(SCH_1):PAGE158
     2 UART_BMC_RXD5 @BASEBOARD_FAB2_LIB.BASEBOARD_FAB2(SCH_1):UART_BMC_RXD5   I154 @BASEBOARD_FAB2_LIB.BASEBOARD_FAB2(SCH_1):PAGE158

R9W35 RES_0402-4.75K,1%,1/16W,CHIP,GA
     1 P3V3_STBY @BASEBOARD_FAB2_LIB.BASEBOARD_FAB2(SCH_1):P3V3_STBY   I155 @BASEBOARD_FAB2_LIB.BASEBOARD_FAB2(SCH_1):PAGE158
     2 SP2_BMC_CM_UART_RX_R @BASEBOARD_FAB2_LIB.BASEBOARD_FAB2(SCH_1):SP2_BMC_CM_UART_RX_R   I155 @BASEBOARD_FAB2_LIB.BASEBOARD_FAB2(SCH_1):PAGE158

R9W36 RES_0402-10.0K,1%,1/16W,CHIP,GA
     1 P3V3_STBY @BASEBOARD_FAB2_LIB.BASEBOARD_FAB2(SCH_1):P3V3_STBY   I252 @BASEBOARD_FAB2_LIB.BASEBOARD_FAB2(SCH_1):PAGE139
     2 PU_DEV_OFF_N @BASEBOARD_FAB2_LIB.BASEBOARD_FAB2(SCH_1):PU_DEV_OFF_N   I252 @BASEBOARD_FAB2_LIB.BASEBOARD_FAB2(SCH_1):PAGE139

R10W1 RES_0402-100.0,1%,1/16W,CHIP,GA
     1 PUMP_TACH0 @BASEBOARD_FAB2_LIB.BASEBOARD_FAB2(SCH_1):PUMP_TACH0    I13 @BASEBOARD_FAB2_LIB.BASEBOARD_FAB2(SCH_1):PAGE251
     2 PUMP_TACH_R @BASEBOARD_FAB2_LIB.BASEBOARD_FAB2(SCH_1):PUMP_TACH_R    I13 @BASEBOARD_FAB2_LIB.BASEBOARD_FAB2(SCH_1):PAGE251

R10W2 RES_0402-4.75K,1%,1/16W,CHIP,GA
     1 P3V3_STBY @BASEBOARD_FAB2_LIB.BASEBOARD_FAB2(SCH_1):P3V3_STBY    I15 @BASEBOARD_FAB2_LIB.BASEBOARD_FAB2(SCH_1):PAGE251
     2 PUMP_TACH0 @BASEBOARD_FAB2_LIB.BASEBOARD_FAB2(SCH_1):PUMP_TACH0    I15 @BASEBOARD_FAB2_LIB.BASEBOARD_FAB2(SCH_1):PAGE251

R10W3 RES_0402-4.75K,1%,1/16W,CHIP,GA
     1 P5V_STBY @BASEBOARD_FAB2_LIB.BASEBOARD_FAB2(SCH_1):P5V_STBY    I11 @BASEBOARD_FAB2_LIB.BASEBOARD_FAB2(SCH_1):PAGE251
     2 PUMP_PWM_OUT_R @BASEBOARD_FAB2_LIB.BASEBOARD_FAB2(SCH_1):PUMP_PWM_OUT_R    I11 @BASEBOARD_FAB2_LIB.BASEBOARD_FAB2(SCH_1):PAGE251

R10W4 RES_0402-221,1.0%,1/16W,CHIP,GA
     1 PUMP_PWM_OUT_BUF @BASEBOARD_FAB2_LIB.BASEBOARD_FAB2(SCH_1):PUMP_PWM_OUT_BUF    I14 @BASEBOARD_FAB2_LIB.BASEBOARD_FAB2(SCH_1):PAGE251
     2 PUMP_PWM_OUT_R @BASEBOARD_FAB2_LIB.BASEBOARD_FAB2(SCH_1):PUMP_PWM_OUT_R    I14 @BASEBOARD_FAB2_LIB.BASEBOARD_FAB2(SCH_1):PAGE251

R10W5 RES_0805-0.0,5%,1/8W,CHIP,G221A
     1 P12V_FAN @BASEBOARD_FAB2_LIB.BASEBOARD_FAB2(SCH_1):P12V_FAN     I5 @BASEBOARD_FAB2_LIB.BASEBOARD_FAB2(SCH_1):PAGE251
     2 P12V_PUMP @BASEBOARD_FAB2_LIB.BASEBOARD_FAB2(SCH_1):P12V_PUMP     I5 @BASEBOARD_FAB2_LIB.BASEBOARD_FAB2(SCH_1):PAGE251

R10W6 RES_0402-100.0,1%,1/16W,CHIP,GA
     1 PUMP_TACH1 @BASEBOARD_FAB2_LIB.BASEBOARD_FAB2(SCH_1):PUMP_TACH1    I27 @BASEBOARD_FAB2_LIB.BASEBOARD_FAB2(SCH_1):PAGE251
     2 PUMP_TACH1_R @BASEBOARD_FAB2_LIB.BASEBOARD_FAB2(SCH_1):PUMP_TACH1_R    I27 @BASEBOARD_FAB2_LIB.BASEBOARD_FAB2(SCH_1):PAGE251

R10W7 RES_0402-4.75K,1%,1/16W,CHIP,GA
     1 P3V3_STBY @BASEBOARD_FAB2_LIB.BASEBOARD_FAB2(SCH_1):P3V3_STBY    I31 @BASEBOARD_FAB2_LIB.BASEBOARD_FAB2(SCH_1):PAGE251
     2 PUMP_TACH1 @BASEBOARD_FAB2_LIB.BASEBOARD_FAB2(SCH_1):PUMP_TACH1    I31 @BASEBOARD_FAB2_LIB.BASEBOARD_FAB2(SCH_1):PAGE251

R12W1 665KR5B-1-GP_SMD-RG3-665KR5B-1A
     1 P12V_STBY @BASEBOARD_FAB2_LIB.BASEBOARD_FAB2(SCH_1):P12V_STBY   I101 @BASEBOARD_FAB2_LIB.BASEBOARD_FAB2(SCH_1):PAGE197
     2 VR_PVDDQ_ABC_AIINSEN @BASEBOARD_FAB2_LIB.BASEBOARD_FAB2(SCH_1):VR_PVDDQ_ABC_AIINSEN   I101 @BASEBOARD_FAB2_LIB.BASEBOARD_FAB2(SCH_1):PAGE197

R12W2 665KR5B-1-GP_SMD-RG3-665KR5B-1A
     1 P12V_NVDIMM_ABC_D @BASEBOARD_FAB2_LIB.BASEBOARD_FAB2(SCH_1):P12V_NVDIMM_ABC_D   I117 @BASEBOARD_FAB2_LIB.BASEBOARD_FAB2(SCH_1):PAGE197
     2 VR_PVDDQ_ABC_VINSEN @BASEBOARD_FAB2_LIB.BASEBOARD_FAB2(SCH_1):VR_PVDDQ_ABC_VINSEN   I117 @BASEBOARD_FAB2_LIB.BASEBOARD_FAB2(SCH_1):PAGE197

R12W3 4D02R2F-GP_SMD-RG2-4D02R2F-GP,A
     1 P12V_STBY @BASEBOARD_FAB2_LIB.BASEBOARD_FAB2(SCH_1):P12V_STBY   I115 @BASEBOARD_FAB2_LIB.BASEBOARD_FAB2(SCH_1):PAGE197
     2 P12V_NVDIMM_ABC_D @BASEBOARD_FAB2_LIB.BASEBOARD_FAB2(SCH_1):P12V_NVDIMM_ABC_D   I115 @BASEBOARD_FAB2_LIB.BASEBOARD_FAB2(SCH_1):PAGE197

R12W4 RES_0603-100.0K,1%,1/10W,CHIP,A
     1 P12V_NVDIMM_ABC @BASEBOARD_FAB2_LIB.BASEBOARD_FAB2(SCH_1):P12V_NVDIMM_ABC    I45 @BASEBOARD_FAB2_LIB.BASEBOARD_FAB2(SCH_1):PAGE197
     2 PWRGD_PVDDQ_ABC_N @BASEBOARD_FAB2_LIB.BASEBOARD_FAB2(SCH_1):PWRGD_PVDDQ_ABC_N    I45 @BASEBOARD_FAB2_LIB.BASEBOARD_FAB2(SCH_1):PAGE197

R12W5 665KR2B-GP_SMD-RG2-665KR2B-GP,A
     1 VR_PVDDQ_ABC_AIINSEN @BASEBOARD_FAB2_LIB.BASEBOARD_FAB2(SCH_1):VR_PVDDQ_ABC_AIINSEN   I111 @BASEBOARD_FAB2_LIB.BASEBOARD_FAB2(SCH_1):PAGE197
     2 VR_PVDDQ_ABC_VINSEN @BASEBOARD_FAB2_LIB.BASEBOARD_FAB2(SCH_1):VR_PVDDQ_ABC_VINSEN   I111 @BASEBOARD_FAB2_LIB.BASEBOARD_FAB2(SCH_1):PAGE197

R12W6 665KR5B-1-GP_SMD-RG3-665KR5B-1A
     1 P12V_STBY @BASEBOARD_FAB2_LIB.BASEBOARD_FAB2(SCH_1):P12V_STBY   I120 @BASEBOARD_FAB2_LIB.BASEBOARD_FAB2(SCH_1):PAGE197
     2 VR_PVDDQ_DEF_AIINSEN @BASEBOARD_FAB2_LIB.BASEBOARD_FAB2(SCH_1):VR_PVDDQ_DEF_AIINSEN   I120 @BASEBOARD_FAB2_LIB.BASEBOARD_FAB2(SCH_1):PAGE197

R12W7 665KR5B-1-GP_SMD-RG3-665KR5B-1A
     1 P12V_NVDIMM_DEF_D @BASEBOARD_FAB2_LIB.BASEBOARD_FAB2(SCH_1):P12V_NVDIMM_DEF_D   I121 @BASEBOARD_FAB2_LIB.BASEBOARD_FAB2(SCH_1):PAGE197
     2 VR_PVDDQ_DEF_VINSEN @BASEBOARD_FAB2_LIB.BASEBOARD_FAB2(SCH_1):VR_PVDDQ_DEF_VINSEN   I121 @BASEBOARD_FAB2_LIB.BASEBOARD_FAB2(SCH_1):PAGE197

R12W8 4D02R2F-GP_SMD-RG2-4D02R2F-GP,A
     1 P12V_STBY @BASEBOARD_FAB2_LIB.BASEBOARD_FAB2(SCH_1):P12V_STBY   I113 @BASEBOARD_FAB2_LIB.BASEBOARD_FAB2(SCH_1):PAGE197
     2 P12V_NVDIMM_DEF_D @BASEBOARD_FAB2_LIB.BASEBOARD_FAB2(SCH_1):P12V_NVDIMM_DEF_D   I113 @BASEBOARD_FAB2_LIB.BASEBOARD_FAB2(SCH_1):PAGE197

R12W9 RES_0603-100.0K,1%,1/10W,CHIP,A
     1 P12V_NVDIMM_DEF @BASEBOARD_FAB2_LIB.BASEBOARD_FAB2(SCH_1):P12V_NVDIMM_DEF    I21 @BASEBOARD_FAB2_LIB.BASEBOARD_FAB2(SCH_1):PAGE197
     2 PWRGD_PVDDQ_DEF_N @BASEBOARD_FAB2_LIB.BASEBOARD_FAB2(SCH_1):PWRGD_PVDDQ_DEF_N    I21 @BASEBOARD_FAB2_LIB.BASEBOARD_FAB2(SCH_1):PAGE197

R12W10 665KR2B-GP_SMD-RG2-665KR2B-GP,A
     1 VR_PVDDQ_DEF_AIINSEN @BASEBOARD_FAB2_LIB.BASEBOARD_FAB2(SCH_1):VR_PVDDQ_DEF_AIINSEN   I109 @BASEBOARD_FAB2_LIB.BASEBOARD_FAB2(SCH_1):PAGE197
     2 VR_PVDDQ_DEF_VINSEN @BASEBOARD_FAB2_LIB.BASEBOARD_FAB2(SCH_1):VR_PVDDQ_DEF_VINSEN   I109 @BASEBOARD_FAB2_LIB.BASEBOARD_FAB2(SCH_1):PAGE197

R12W11 665KR5B-1-GP_SMD-RG3-665KR5B-1A
     1 P12V_STBY @BASEBOARD_FAB2_LIB.BASEBOARD_FAB2(SCH_1):P12V_STBY   I118 @BASEBOARD_FAB2_LIB.BASEBOARD_FAB2(SCH_1):PAGE197
     2 VR_PVDDQ_GHJ_AIINSEN @BASEBOARD_FAB2_LIB.BASEBOARD_FAB2(SCH_1):VR_PVDDQ_GHJ_AIINSEN   I118 @BASEBOARD_FAB2_LIB.BASEBOARD_FAB2(SCH_1):PAGE197

R12W12 665KR5B-1-GP_SMD-RG3-665KR5B-1A
     1 P12V_NVDIMM_GHJ_D @BASEBOARD_FAB2_LIB.BASEBOARD_FAB2(SCH_1):P12V_NVDIMM_GHJ_D   I119 @BASEBOARD_FAB2_LIB.BASEBOARD_FAB2(SCH_1):PAGE197
     2 VR_PVDDQ_GHJ_VINSEN @BASEBOARD_FAB2_LIB.BASEBOARD_FAB2(SCH_1):VR_PVDDQ_GHJ_VINSEN   I119 @BASEBOARD_FAB2_LIB.BASEBOARD_FAB2(SCH_1):PAGE197

R12W13 4D02R2F-GP_SMD-RG2-4D02R2F-GP,A
     1 P12V_STBY @BASEBOARD_FAB2_LIB.BASEBOARD_FAB2(SCH_1):P12V_STBY   I116 @BASEBOARD_FAB2_LIB.BASEBOARD_FAB2(SCH_1):PAGE197
     2 P12V_NVDIMM_GHJ_D @BASEBOARD_FAB2_LIB.BASEBOARD_FAB2(SCH_1):P12V_NVDIMM_GHJ_D   I116 @BASEBOARD_FAB2_LIB.BASEBOARD_FAB2(SCH_1):PAGE197

R12W14 RES_0603-100.0K,1%,1/10W,CHIP,A
     1 P12V_NVDIMM_GHJ @BASEBOARD_FAB2_LIB.BASEBOARD_FAB2(SCH_1):P12V_NVDIMM_GHJ    I53 @BASEBOARD_FAB2_LIB.BASEBOARD_FAB2(SCH_1):PAGE197
     2 PWRGD_PVDDQ_GHJ_N @BASEBOARD_FAB2_LIB.BASEBOARD_FAB2(SCH_1):PWRGD_PVDDQ_GHJ_N    I53 @BASEBOARD_FAB2_LIB.BASEBOARD_FAB2(SCH_1):PAGE197

R12W15 665KR2B-GP_SMD-RG2-665KR2B-GP,A
     1 VR_PVDDQ_GHJ_AIINSEN @BASEBOARD_FAB2_LIB.BASEBOARD_FAB2(SCH_1):VR_PVDDQ_GHJ_AIINSEN   I112 @BASEBOARD_FAB2_LIB.BASEBOARD_FAB2(SCH_1):PAGE197
     2 VR_PVDDQ_GHJ_VINSEN @BASEBOARD_FAB2_LIB.BASEBOARD_FAB2(SCH_1):VR_PVDDQ_GHJ_VINSEN   I112 @BASEBOARD_FAB2_LIB.BASEBOARD_FAB2(SCH_1):PAGE197

R12W16 665KR5B-1-GP_SMD-RG3-665KR5B-1A
     1 P12V_STBY @BASEBOARD_FAB2_LIB.BASEBOARD_FAB2(SCH_1):P12V_STBY   I122 @BASEBOARD_FAB2_LIB.BASEBOARD_FAB2(SCH_1):PAGE197
     2 VR_PVDDQ_KLM_AIINSEN @BASEBOARD_FAB2_LIB.BASEBOARD_FAB2(SCH_1):VR_PVDDQ_KLM_AIINSEN   I122 @BASEBOARD_FAB2_LIB.BASEBOARD_FAB2(SCH_1):PAGE197

R12W17 665KR5B-1-GP_SMD-RG3-665KR5B-1A
     1 P12V_NVDIMM_KLM_D @BASEBOARD_FAB2_LIB.BASEBOARD_FAB2(SCH_1):P12V_NVDIMM_KLM_D   I123 @BASEBOARD_FAB2_LIB.BASEBOARD_FAB2(SCH_1):PAGE197
     2 VR_PVDDQ_KLM_VINSEN @BASEBOARD_FAB2_LIB.BASEBOARD_FAB2(SCH_1):VR_PVDDQ_KLM_VINSEN   I123 @BASEBOARD_FAB2_LIB.BASEBOARD_FAB2(SCH_1):PAGE197

R12W18 4D02R2F-GP_SMD-RG2-4D02R2F-GP,A
     1 P12V_STBY @BASEBOARD_FAB2_LIB.BASEBOARD_FAB2(SCH_1):P12V_STBY   I114 @BASEBOARD_FAB2_LIB.BASEBOARD_FAB2(SCH_1):PAGE197
     2 P12V_NVDIMM_KLM_D @BASEBOARD_FAB2_LIB.BASEBOARD_FAB2(SCH_1):P12V_NVDIMM_KLM_D   I114 @BASEBOARD_FAB2_LIB.BASEBOARD_FAB2(SCH_1):PAGE197

R12W19 RES_0603-100.0K,1%,1/10W,CHIP,A
     1 P12V_NVDIMM_KLM @BASEBOARD_FAB2_LIB.BASEBOARD_FAB2(SCH_1):P12V_NVDIMM_KLM    I37 @BASEBOARD_FAB2_LIB.BASEBOARD_FAB2(SCH_1):PAGE197
     2 PWRGD_PVDDQ_KLM_N @BASEBOARD_FAB2_LIB.BASEBOARD_FAB2(SCH_1):PWRGD_PVDDQ_KLM_N    I37 @BASEBOARD_FAB2_LIB.BASEBOARD_FAB2(SCH_1):PAGE197

R12W20 665KR2B-GP_SMD-RG2-665KR2B-GP,A
     1 VR_PVDDQ_KLM_AIINSEN @BASEBOARD_FAB2_LIB.BASEBOARD_FAB2(SCH_1):VR_PVDDQ_KLM_AIINSEN   I110 @BASEBOARD_FAB2_LIB.BASEBOARD_FAB2(SCH_1):PAGE197
     2 VR_PVDDQ_KLM_VINSEN @BASEBOARD_FAB2_LIB.BASEBOARD_FAB2(SCH_1):VR_PVDDQ_KLM_VINSEN   I110 @BASEBOARD_FAB2_LIB.BASEBOARD_FAB2(SCH_1):PAGE197

R12W25 RES_0402-0.0,5%,1/16W,CHIP,G21A
     1 PU_VR_PVDDQ_ABC_FAULT1 @BASEBOARD_FAB2_LIB.BASEBOARD_FAB2(SCH_1):PU_VR_PVDDQ_ABC_FAULT1    I74 @BASEBOARD_FAB2_LIB.BASEBOARD_FAB2(SCH_1):PAGE215
     2 PWRGD_PVDDQ_ABC @BASEBOARD_FAB2_LIB.BASEBOARD_FAB2(SCH_1):PWRGD_PVDDQ_ABC    I74 @BASEBOARD_FAB2_LIB.BASEBOARD_FAB2(SCH_1):PAGE215

R12W26 RES_0402-0.0,5%,1/16W,EMPTY,G2A
     1 TP_PVDDQ_ABC_MP1 @BASEBOARD_FAB2_LIB.BASEBOARD_FAB2(SCH_1):TP_PVDDQ_ABC_MP1    I45 @BASEBOARD_FAB2_LIB.BASEBOARD_FAB2(SCH_1):PAGE215
     2 PWRGD_PVDDQ_ABC @BASEBOARD_FAB2_LIB.BASEBOARD_FAB2(SCH_1):PWRGD_PVDDQ_ABC    I45 @BASEBOARD_FAB2_LIB.BASEBOARD_FAB2(SCH_1):PAGE215

R12W27 RES_0402-0.0,5%,1/16W,EMPTY,G2A
     1 TP_PVDDQ_ABC_MP2 @BASEBOARD_FAB2_LIB.BASEBOARD_FAB2(SCH_1):TP_PVDDQ_ABC_MP2    I54 @BASEBOARD_FAB2_LIB.BASEBOARD_FAB2(SCH_1):PAGE215
     2 PWRGD_PVDDQ_ABC @BASEBOARD_FAB2_LIB.BASEBOARD_FAB2(SCH_1):PWRGD_PVDDQ_ABC    I54 @BASEBOARD_FAB2_LIB.BASEBOARD_FAB2(SCH_1):PAGE215

R12W28 RES_0402-0.0,5%,1/16W,CHIP,G21A
     1 PU_VR_PVDDQ_DEF_FAULT1 @BASEBOARD_FAB2_LIB.BASEBOARD_FAB2(SCH_1):PU_VR_PVDDQ_DEF_FAULT1    I75 @BASEBOARD_FAB2_LIB.BASEBOARD_FAB2(SCH_1):PAGE218
     2 PWRGD_PVDDQ_DEF @BASEBOARD_FAB2_LIB.BASEBOARD_FAB2(SCH_1):PWRGD_PVDDQ_DEF    I75 @BASEBOARD_FAB2_LIB.BASEBOARD_FAB2(SCH_1):PAGE218

R12W29 RES_0402-0.0,5%,1/16W,EMPTY,G2A
     1 TP_PVDDQ_DEF_MP1 @BASEBOARD_FAB2_LIB.BASEBOARD_FAB2(SCH_1):TP_PVDDQ_DEF_MP1    I46 @BASEBOARD_FAB2_LIB.BASEBOARD_FAB2(SCH_1):PAGE218
     2 PWRGD_PVDDQ_DEF @BASEBOARD_FAB2_LIB.BASEBOARD_FAB2(SCH_1):PWRGD_PVDDQ_DEF    I46 @BASEBOARD_FAB2_LIB.BASEBOARD_FAB2(SCH_1):PAGE218

R12W30 RES_0402-0.0,5%,1/16W,EMPTY,G2A
     1 TP_PVDDQ_DEF_MP2 @BASEBOARD_FAB2_LIB.BASEBOARD_FAB2(SCH_1):TP_PVDDQ_DEF_MP2    I55 @BASEBOARD_FAB2_LIB.BASEBOARD_FAB2(SCH_1):PAGE218
     2 PWRGD_PVDDQ_DEF @BASEBOARD_FAB2_LIB.BASEBOARD_FAB2(SCH_1):PWRGD_PVDDQ_DEF    I55 @BASEBOARD_FAB2_LIB.BASEBOARD_FAB2(SCH_1):PAGE218

R12W31 RES_0402-0.0,5%,1/16W,CHIP,G21A
     1 PU_VR_PVDDQ_GHJ_FAULT1 @BASEBOARD_FAB2_LIB.BASEBOARD_FAB2(SCH_1):PU_VR_PVDDQ_GHJ_FAULT1    I75 @BASEBOARD_FAB2_LIB.BASEBOARD_FAB2(SCH_1):PAGE223
     2 PWRGD_PVDDQ_GHJ @BASEBOARD_FAB2_LIB.BASEBOARD_FAB2(SCH_1):PWRGD_PVDDQ_GHJ    I75 @BASEBOARD_FAB2_LIB.BASEBOARD_FAB2(SCH_1):PAGE223

R12W32 RES_0402-0.0,5%,1/16W,EMPTY,G2A
     1 TP_PVDDQ_GHJ_MP1 @BASEBOARD_FAB2_LIB.BASEBOARD_FAB2(SCH_1):TP_PVDDQ_GHJ_MP1    I45 @BASEBOARD_FAB2_LIB.BASEBOARD_FAB2(SCH_1):PAGE223
     2 PWRGD_PVDDQ_GHJ @BASEBOARD_FAB2_LIB.BASEBOARD_FAB2(SCH_1):PWRGD_PVDDQ_GHJ    I45 @BASEBOARD_FAB2_LIB.BASEBOARD_FAB2(SCH_1):PAGE223

R12W33 RES_0402-0.0,5%,1/16W,EMPTY,G2A
     1 TP_PVDDQ_GHJ_MP2 @BASEBOARD_FAB2_LIB.BASEBOARD_FAB2(SCH_1):TP_PVDDQ_GHJ_MP2    I53 @BASEBOARD_FAB2_LIB.BASEBOARD_FAB2(SCH_1):PAGE223
     2 PWRGD_PVDDQ_GHJ @BASEBOARD_FAB2_LIB.BASEBOARD_FAB2(SCH_1):PWRGD_PVDDQ_GHJ    I53 @BASEBOARD_FAB2_LIB.BASEBOARD_FAB2(SCH_1):PAGE223

R12W34 RES_0402-0.0,5%,1/16W,CHIP,G21A
     1 PU_VR_PVDDQ_KLM_FAULT1 @BASEBOARD_FAB2_LIB.BASEBOARD_FAB2(SCH_1):PU_VR_PVDDQ_KLM_FAULT1    I74 @BASEBOARD_FAB2_LIB.BASEBOARD_FAB2(SCH_1):PAGE226
     2 PWRGD_PVDDQ_KLM @BASEBOARD_FAB2_LIB.BASEBOARD_FAB2(SCH_1):PWRGD_PVDDQ_KLM    I74 @BASEBOARD_FAB2_LIB.BASEBOARD_FAB2(SCH_1):PAGE226

R12W35 RES_0402-0.0,5%,1/16W,EMPTY,G2A
     1 NC_PVDDQ_KLM_GP1 @BASEBOARD_FAB2_LIB.BASEBOARD_FAB2(SCH_1):NC_PVDDQ_KLM_GP1    I46 @BASEBOARD_FAB2_LIB.BASEBOARD_FAB2(SCH_1):PAGE226
     2 PWRGD_PVDDQ_KLM @BASEBOARD_FAB2_LIB.BASEBOARD_FAB2(SCH_1):PWRGD_PVDDQ_KLM    I46 @BASEBOARD_FAB2_LIB.BASEBOARD_FAB2(SCH_1):PAGE226

R12W36 RES_0402-0.0,5%,1/16W,EMPTY,G2A
     1 NC_PVDDQ_KLM_GP0 @BASEBOARD_FAB2_LIB.BASEBOARD_FAB2(SCH_1):NC_PVDDQ_KLM_GP0    I53 @BASEBOARD_FAB2_LIB.BASEBOARD_FAB2(SCH_1):PAGE226
     2 PWRGD_PVDDQ_KLM @BASEBOARD_FAB2_LIB.BASEBOARD_FAB2(SCH_1):PWRGD_PVDDQ_KLM    I53 @BASEBOARD_FAB2_LIB.BASEBOARD_FAB2(SCH_1):PAGE226

R24W1 RES_0402-3.3K,5%,1/16W,CHIP,G2A
     1 P3V3_STBY @BASEBOARD_FAB2_LIB.BASEBOARD_FAB2(SCH_1):P3V3_STBY   I198 @BASEBOARD_FAB2_LIB.BASEBOARD_FAB2(SCH_1):PAGE138
     2 SMB_SLOTX24_PCH_STBY_LVC3_SDA @BASEBOARD_FAB2_LIB.BASEBOARD_FAB2(SCH_1):SMB_SLOTX24_PCH_STBY_LVC3_SDA   I198 @BASEBOARD_FAB2_LIB.BASEBOARD_FAB2(SCH_1):PAGE138

R24W2 RES_0402-3.3K,5%,1/16W,CHIP,G2A
     1 P3V3_STBY @BASEBOARD_FAB2_LIB.BASEBOARD_FAB2(SCH_1):P3V3_STBY   I199 @BASEBOARD_FAB2_LIB.BASEBOARD_FAB2(SCH_1):PAGE138
     2 SMB_SLOTX24_PCH_STBY_LVC3_SCL @BASEBOARD_FAB2_LIB.BASEBOARD_FAB2(SCH_1):SMB_SLOTX24_PCH_STBY_LVC3_SCL   I199 @BASEBOARD_FAB2_LIB.BASEBOARD_FAB2(SCH_1):PAGE138

R25W1 120R2F-GP_RCL_GP-120R2F-GP,64.A
     1    GND @BASEBOARD_FAB2_LIB.BASEBOARD_FAB2(SCH_1):GND   I248 @BASEBOARD_FAB2_LIB.BASEBOARD_FAB2(SCH_1):PAGE151
     2 BMC_M_CKE @BASEBOARD_FAB2_LIB.BASEBOARD_FAB2(SCH_1):BMC_M_CKE   I248 @BASEBOARD_FAB2_LIB.BASEBOARD_FAB2(SCH_1):PAGE151

R25W2 120R2F-GP_RCL_GP-120R2F-GP,64.A
     1    GND @BASEBOARD_FAB2_LIB.BASEBOARD_FAB2(SCH_1):GND   I249 @BASEBOARD_FAB2_LIB.BASEBOARD_FAB2(SCH_1):PAGE151
     2 BMC_M_ODT @BASEBOARD_FAB2_LIB.BASEBOARD_FAB2(SCH_1):BMC_M_ODT   I249 @BASEBOARD_FAB2_LIB.BASEBOARD_FAB2(SCH_1):PAGE151

R25W3 120R2F-GP_RCL_GP-120R2F-GP,64.A
     1    GND @BASEBOARD_FAB2_LIB.BASEBOARD_FAB2(SCH_1):GND   I250 @BASEBOARD_FAB2_LIB.BASEBOARD_FAB2(SCH_1):PAGE151
     2 BMC_M_RST_N @BASEBOARD_FAB2_LIB.BASEBOARD_FAB2(SCH_1):BMC_M_RST_N   I250 @BASEBOARD_FAB2_LIB.BASEBOARD_FAB2(SCH_1):PAGE151

R25W4 120R2F-GP_RCL_GP-120R2F-GP,64.A
     1    GND @BASEBOARD_FAB2_LIB.BASEBOARD_FAB2(SCH_1):GND   I251 @BASEBOARD_FAB2_LIB.BASEBOARD_FAB2(SCH_1):PAGE151
     2 BMC_M_MALERT_N @BASEBOARD_FAB2_LIB.BASEBOARD_FAB2(SCH_1):BMC_M_MALERT_N   I251 @BASEBOARD_FAB2_LIB.BASEBOARD_FAB2(SCH_1):PAGE151

R25W5 120R2F-GP_RCL_GP-120R2F-GP,64.A
     1    GND @BASEBOARD_FAB2_LIB.BASEBOARD_FAB2(SCH_1):GND   I252 @BASEBOARD_FAB2_LIB.BASEBOARD_FAB2(SCH_1):PAGE151
     2 BMC_M_CS_N @BASEBOARD_FAB2_LIB.BASEBOARD_FAB2(SCH_1):BMC_M_CS_N   I252 @BASEBOARD_FAB2_LIB.BASEBOARD_FAB2(SCH_1):PAGE151

R25W6 120R2F-GP_RCL_GP-120R2F-GP,64.A
     1    GND @BASEBOARD_FAB2_LIB.BASEBOARD_FAB2(SCH_1):GND   I253 @BASEBOARD_FAB2_LIB.BASEBOARD_FAB2(SCH_1):PAGE151
     2 BMC_M_RAS_N @BASEBOARD_FAB2_LIB.BASEBOARD_FAB2(SCH_1):BMC_M_RAS_N   I253 @BASEBOARD_FAB2_LIB.BASEBOARD_FAB2(SCH_1):PAGE151

R25W7 120R2F-GP_RCL_GP-120R2F-GP,64.A
     1    GND @BASEBOARD_FAB2_LIB.BASEBOARD_FAB2(SCH_1):GND   I254 @BASEBOARD_FAB2_LIB.BASEBOARD_FAB2(SCH_1):PAGE151
     2 BMC_M_CAS_N @BASEBOARD_FAB2_LIB.BASEBOARD_FAB2(SCH_1):BMC_M_CAS_N   I254 @BASEBOARD_FAB2_LIB.BASEBOARD_FAB2(SCH_1):PAGE151

R25W8 120R2F-GP_RCL_GP-120R2F-GP,64.A
     1    GND @BASEBOARD_FAB2_LIB.BASEBOARD_FAB2(SCH_1):GND   I255 @BASEBOARD_FAB2_LIB.BASEBOARD_FAB2(SCH_1):PAGE151
     2 BMC_M_WE_N @BASEBOARD_FAB2_LIB.BASEBOARD_FAB2(SCH_1):BMC_M_WE_N   I255 @BASEBOARD_FAB2_LIB.BASEBOARD_FAB2(SCH_1):PAGE151

R25W9 120R2F-GP_RCL_GP-120R2F-GP,64.A
     1    GND @BASEBOARD_FAB2_LIB.BASEBOARD_FAB2(SCH_1):GND   I258 @BASEBOARD_FAB2_LIB.BASEBOARD_FAB2(SCH_1):PAGE151
     2 BMC_M_BA0 @BASEBOARD_FAB2_LIB.BASEBOARD_FAB2(SCH_1):BMC_M_BA0   I258 @BASEBOARD_FAB2_LIB.BASEBOARD_FAB2(SCH_1):PAGE151

R25W10 120R2F-GP_RCL_GP-120R2F-GP,64.A
     1    GND @BASEBOARD_FAB2_LIB.BASEBOARD_FAB2(SCH_1):GND   I259 @BASEBOARD_FAB2_LIB.BASEBOARD_FAB2(SCH_1):PAGE151
     2 BMC_M_BA1 @BASEBOARD_FAB2_LIB.BASEBOARD_FAB2(SCH_1):BMC_M_BA1   I259 @BASEBOARD_FAB2_LIB.BASEBOARD_FAB2(SCH_1):PAGE151

R25W11 120R2F-GP_RCL_GP-120R2F-GP,64.A
     1    GND @BASEBOARD_FAB2_LIB.BASEBOARD_FAB2(SCH_1):GND   I257 @BASEBOARD_FAB2_LIB.BASEBOARD_FAB2(SCH_1):PAGE151
     2 BMC_M_BG0 @BASEBOARD_FAB2_LIB.BASEBOARD_FAB2(SCH_1):BMC_M_BG0   I257 @BASEBOARD_FAB2_LIB.BASEBOARD_FAB2(SCH_1):PAGE151

R25W12 120R2F-GP_RCL_GP-120R2F-GP,64.A
     1    GND @BASEBOARD_FAB2_LIB.BASEBOARD_FAB2(SCH_1):GND   I256 @BASEBOARD_FAB2_LIB.BASEBOARD_FAB2(SCH_1):PAGE151
     2 BMC_M_A0 @BASEBOARD_FAB2_LIB.BASEBOARD_FAB2(SCH_1):BMC_M_A0   I256 @BASEBOARD_FAB2_LIB.BASEBOARD_FAB2(SCH_1):PAGE151

R25W13 120R2F-GP_RCL_GP-120R2F-GP,64.A
     1    GND @BASEBOARD_FAB2_LIB.BASEBOARD_FAB2(SCH_1):GND   I260 @BASEBOARD_FAB2_LIB.BASEBOARD_FAB2(SCH_1):PAGE151
     2 BMC_M_A1 @BASEBOARD_FAB2_LIB.BASEBOARD_FAB2(SCH_1):BMC_M_A1   I260 @BASEBOARD_FAB2_LIB.BASEBOARD_FAB2(SCH_1):PAGE151

R25W14 120R2F-GP_RCL_GP-120R2F-GP,64.A
     1    GND @BASEBOARD_FAB2_LIB.BASEBOARD_FAB2(SCH_1):GND   I263 @BASEBOARD_FAB2_LIB.BASEBOARD_FAB2(SCH_1):PAGE151
     2 BMC_M_A2 @BASEBOARD_FAB2_LIB.BASEBOARD_FAB2(SCH_1):BMC_M_A2   I263 @BASEBOARD_FAB2_LIB.BASEBOARD_FAB2(SCH_1):PAGE151

R25W15 120R2F-GP_RCL_GP-120R2F-GP,64.A
     1    GND @BASEBOARD_FAB2_LIB.BASEBOARD_FAB2(SCH_1):GND   I262 @BASEBOARD_FAB2_LIB.BASEBOARD_FAB2(SCH_1):PAGE151
     2 BMC_M_A3 @BASEBOARD_FAB2_LIB.BASEBOARD_FAB2(SCH_1):BMC_M_A3   I262 @BASEBOARD_FAB2_LIB.BASEBOARD_FAB2(SCH_1):PAGE151

R25W16 120R2F-GP_RCL_GP-120R2F-GP,64.A
     1    GND @BASEBOARD_FAB2_LIB.BASEBOARD_FAB2(SCH_1):GND   I261 @BASEBOARD_FAB2_LIB.BASEBOARD_FAB2(SCH_1):PAGE151
     2 BMC_M_A4 @BASEBOARD_FAB2_LIB.BASEBOARD_FAB2(SCH_1):BMC_M_A4   I261 @BASEBOARD_FAB2_LIB.BASEBOARD_FAB2(SCH_1):PAGE151

R25W17 120R2F-GP_RCL_GP-120R2F-GP,64.A
     1    GND @BASEBOARD_FAB2_LIB.BASEBOARD_FAB2(SCH_1):GND   I264 @BASEBOARD_FAB2_LIB.BASEBOARD_FAB2(SCH_1):PAGE151
     2 BMC_M_A5 @BASEBOARD_FAB2_LIB.BASEBOARD_FAB2(SCH_1):BMC_M_A5   I264 @BASEBOARD_FAB2_LIB.BASEBOARD_FAB2(SCH_1):PAGE151

R25W18 120R2F-GP_RCL_GP-120R2F-GP,64.A
     1    GND @BASEBOARD_FAB2_LIB.BASEBOARD_FAB2(SCH_1):GND   I265 @BASEBOARD_FAB2_LIB.BASEBOARD_FAB2(SCH_1):PAGE151
     2 BMC_M_A6 @BASEBOARD_FAB2_LIB.BASEBOARD_FAB2(SCH_1):BMC_M_A6   I265 @BASEBOARD_FAB2_LIB.BASEBOARD_FAB2(SCH_1):PAGE151

R25W19 120R2F-GP_RCL_GP-120R2F-GP,64.A
     1    GND @BASEBOARD_FAB2_LIB.BASEBOARD_FAB2(SCH_1):GND   I267 @BASEBOARD_FAB2_LIB.BASEBOARD_FAB2(SCH_1):PAGE151
     2 BMC_M_A7 @BASEBOARD_FAB2_LIB.BASEBOARD_FAB2(SCH_1):BMC_M_A7   I267 @BASEBOARD_FAB2_LIB.BASEBOARD_FAB2(SCH_1):PAGE151

R25W20 120R2F-GP_RCL_GP-120R2F-GP,64.A
     1    GND @BASEBOARD_FAB2_LIB.BASEBOARD_FAB2(SCH_1):GND   I266 @BASEBOARD_FAB2_LIB.BASEBOARD_FAB2(SCH_1):PAGE151
     2 BMC_M_A8 @BASEBOARD_FAB2_LIB.BASEBOARD_FAB2(SCH_1):BMC_M_A8   I266 @BASEBOARD_FAB2_LIB.BASEBOARD_FAB2(SCH_1):PAGE151

R25W21 120R2F-GP_RCL_GP-120R2F-GP,64.A
     1    GND @BASEBOARD_FAB2_LIB.BASEBOARD_FAB2(SCH_1):GND   I271 @BASEBOARD_FAB2_LIB.BASEBOARD_FAB2(SCH_1):PAGE151
     2 BMC_M_A9 @BASEBOARD_FAB2_LIB.BASEBOARD_FAB2(SCH_1):BMC_M_A9   I271 @BASEBOARD_FAB2_LIB.BASEBOARD_FAB2(SCH_1):PAGE151

R25W22 120R2F-GP_RCL_GP-120R2F-GP,64.A
     1    GND @BASEBOARD_FAB2_LIB.BASEBOARD_FAB2(SCH_1):GND   I270 @BASEBOARD_FAB2_LIB.BASEBOARD_FAB2(SCH_1):PAGE151
     2 BMC_M_A10 @BASEBOARD_FAB2_LIB.BASEBOARD_FAB2(SCH_1):BMC_M_A10   I270 @BASEBOARD_FAB2_LIB.BASEBOARD_FAB2(SCH_1):PAGE151

R25W23 120R2F-GP_RCL_GP-120R2F-GP,64.A
     1    GND @BASEBOARD_FAB2_LIB.BASEBOARD_FAB2(SCH_1):GND   I269 @BASEBOARD_FAB2_LIB.BASEBOARD_FAB2(SCH_1):PAGE151
     2 BMC_M_A11 @BASEBOARD_FAB2_LIB.BASEBOARD_FAB2(SCH_1):BMC_M_A11   I269 @BASEBOARD_FAB2_LIB.BASEBOARD_FAB2(SCH_1):PAGE151

R25W24 120R2F-GP_RCL_GP-120R2F-GP,64.A
     1    GND @BASEBOARD_FAB2_LIB.BASEBOARD_FAB2(SCH_1):GND   I268 @BASEBOARD_FAB2_LIB.BASEBOARD_FAB2(SCH_1):PAGE151
     2 BMC_M_A12 @BASEBOARD_FAB2_LIB.BASEBOARD_FAB2(SCH_1):BMC_M_A12   I268 @BASEBOARD_FAB2_LIB.BASEBOARD_FAB2(SCH_1):PAGE151

R25W25 120R2F-GP_RCL_GP-120R2F-GP,64.A
     1    GND @BASEBOARD_FAB2_LIB.BASEBOARD_FAB2(SCH_1):GND   I275 @BASEBOARD_FAB2_LIB.BASEBOARD_FAB2(SCH_1):PAGE151
     2 BMC_M_A13 @BASEBOARD_FAB2_LIB.BASEBOARD_FAB2(SCH_1):BMC_M_A13   I275 @BASEBOARD_FAB2_LIB.BASEBOARD_FAB2(SCH_1):PAGE151

R25W26 120R2F-GP_RCL_GP-120R2F-GP,64.A
     1    GND @BASEBOARD_FAB2_LIB.BASEBOARD_FAB2(SCH_1):GND   I274 @BASEBOARD_FAB2_LIB.BASEBOARD_FAB2(SCH_1):PAGE151
     2 BMC_M_MACT_N @BASEBOARD_FAB2_LIB.BASEBOARD_FAB2(SCH_1):BMC_M_MACT_N   I274 @BASEBOARD_FAB2_LIB.BASEBOARD_FAB2(SCH_1):PAGE151

R25W27 120R2F-GP_RCL_GP-120R2F-GP,64.A
     1 BMC_M_CKE @BASEBOARD_FAB2_LIB.BASEBOARD_FAB2(SCH_1):BMC_M_CKE   I223 @BASEBOARD_FAB2_LIB.BASEBOARD_FAB2(SCH_1):PAGE151
     2 P1V2_AUX_BMC @BASEBOARD_FAB2_LIB.BASEBOARD_FAB2(SCH_1):P1V2_AUX_BMC   I223 @BASEBOARD_FAB2_LIB.BASEBOARD_FAB2(SCH_1):PAGE151

R25W28 120R2F-GP_RCL_GP-120R2F-GP,64.A
     1 BMC_M_ODT @BASEBOARD_FAB2_LIB.BASEBOARD_FAB2(SCH_1):BMC_M_ODT   I224 @BASEBOARD_FAB2_LIB.BASEBOARD_FAB2(SCH_1):PAGE151
     2 P1V2_AUX_BMC @BASEBOARD_FAB2_LIB.BASEBOARD_FAB2(SCH_1):P1V2_AUX_BMC   I224 @BASEBOARD_FAB2_LIB.BASEBOARD_FAB2(SCH_1):PAGE151

R25W29 120R2F-GP_RCL_GP-120R2F-GP,64.A
     1 BMC_M_RST_N @BASEBOARD_FAB2_LIB.BASEBOARD_FAB2(SCH_1):BMC_M_RST_N   I225 @BASEBOARD_FAB2_LIB.BASEBOARD_FAB2(SCH_1):PAGE151
     2 P1V2_AUX_BMC @BASEBOARD_FAB2_LIB.BASEBOARD_FAB2(SCH_1):P1V2_AUX_BMC   I225 @BASEBOARD_FAB2_LIB.BASEBOARD_FAB2(SCH_1):PAGE151

R25W30 RES_0402-2.7K,1%,1/16W,CHIP,G2A
     1 BMC_M_MALERT_N @BASEBOARD_FAB2_LIB.BASEBOARD_FAB2(SCH_1):BMC_M_MALERT_N   I222 @BASEBOARD_FAB2_LIB.BASEBOARD_FAB2(SCH_1):PAGE151
     2 P1V2_AUX_BMC @BASEBOARD_FAB2_LIB.BASEBOARD_FAB2(SCH_1):P1V2_AUX_BMC   I222 @BASEBOARD_FAB2_LIB.BASEBOARD_FAB2(SCH_1):PAGE151

R25W31 120R2F-GP_RCL_GP-120R2F-GP,64.A
     1 BMC_M_CS_N @BASEBOARD_FAB2_LIB.BASEBOARD_FAB2(SCH_1):BMC_M_CS_N   I226 @BASEBOARD_FAB2_LIB.BASEBOARD_FAB2(SCH_1):PAGE151
     2 P1V2_AUX_BMC @BASEBOARD_FAB2_LIB.BASEBOARD_FAB2(SCH_1):P1V2_AUX_BMC   I226 @BASEBOARD_FAB2_LIB.BASEBOARD_FAB2(SCH_1):PAGE151

R25W32 120R2F-GP_RCL_GP-120R2F-GP,64.A
     1 BMC_M_RAS_N @BASEBOARD_FAB2_LIB.BASEBOARD_FAB2(SCH_1):BMC_M_RAS_N   I227 @BASEBOARD_FAB2_LIB.BASEBOARD_FAB2(SCH_1):PAGE151
     2 P1V2_AUX_BMC @BASEBOARD_FAB2_LIB.BASEBOARD_FAB2(SCH_1):P1V2_AUX_BMC   I227 @BASEBOARD_FAB2_LIB.BASEBOARD_FAB2(SCH_1):PAGE151

R25W33 120R2F-GP_RCL_GP-120R2F-GP,64.A
     1 BMC_M_CAS_N @BASEBOARD_FAB2_LIB.BASEBOARD_FAB2(SCH_1):BMC_M_CAS_N   I228 @BASEBOARD_FAB2_LIB.BASEBOARD_FAB2(SCH_1):PAGE151
     2 P1V2_AUX_BMC @BASEBOARD_FAB2_LIB.BASEBOARD_FAB2(SCH_1):P1V2_AUX_BMC   I228 @BASEBOARD_FAB2_LIB.BASEBOARD_FAB2(SCH_1):PAGE151

R25W34 120R2F-GP_RCL_GP-120R2F-GP,64.A
     1 BMC_M_WE_N @BASEBOARD_FAB2_LIB.BASEBOARD_FAB2(SCH_1):BMC_M_WE_N   I229 @BASEBOARD_FAB2_LIB.BASEBOARD_FAB2(SCH_1):PAGE151
     2 P1V2_AUX_BMC @BASEBOARD_FAB2_LIB.BASEBOARD_FAB2(SCH_1):P1V2_AUX_BMC   I229 @BASEBOARD_FAB2_LIB.BASEBOARD_FAB2(SCH_1):PAGE151

R25W35 120R2F-GP_RCL_GP-120R2F-GP,64.A
     1 BMC_M_BA0 @BASEBOARD_FAB2_LIB.BASEBOARD_FAB2(SCH_1):BMC_M_BA0   I230 @BASEBOARD_FAB2_LIB.BASEBOARD_FAB2(SCH_1):PAGE151
     2 P1V2_AUX_BMC @BASEBOARD_FAB2_LIB.BASEBOARD_FAB2(SCH_1):P1V2_AUX_BMC   I230 @BASEBOARD_FAB2_LIB.BASEBOARD_FAB2(SCH_1):PAGE151

R25W36 120R2F-GP_RCL_GP-120R2F-GP,64.A
     1 BMC_M_BA1 @BASEBOARD_FAB2_LIB.BASEBOARD_FAB2(SCH_1):BMC_M_BA1   I231 @BASEBOARD_FAB2_LIB.BASEBOARD_FAB2(SCH_1):PAGE151
     2 P1V2_AUX_BMC @BASEBOARD_FAB2_LIB.BASEBOARD_FAB2(SCH_1):P1V2_AUX_BMC   I231 @BASEBOARD_FAB2_LIB.BASEBOARD_FAB2(SCH_1):PAGE151

R25W37 120R2F-GP_RCL_GP-120R2F-GP,64.A
     1 BMC_M_BG0 @BASEBOARD_FAB2_LIB.BASEBOARD_FAB2(SCH_1):BMC_M_BG0   I232 @BASEBOARD_FAB2_LIB.BASEBOARD_FAB2(SCH_1):PAGE151
     2 P1V2_AUX_BMC @BASEBOARD_FAB2_LIB.BASEBOARD_FAB2(SCH_1):P1V2_AUX_BMC   I232 @BASEBOARD_FAB2_LIB.BASEBOARD_FAB2(SCH_1):PAGE151

R25W38 120R2F-GP_RCL_GP-120R2F-GP,64.A
     1 BMC_M_A0 @BASEBOARD_FAB2_LIB.BASEBOARD_FAB2(SCH_1):BMC_M_A0   I233 @BASEBOARD_FAB2_LIB.BASEBOARD_FAB2(SCH_1):PAGE151
     2 P1V2_AUX_BMC @BASEBOARD_FAB2_LIB.BASEBOARD_FAB2(SCH_1):P1V2_AUX_BMC   I233 @BASEBOARD_FAB2_LIB.BASEBOARD_FAB2(SCH_1):PAGE151

R25W39 120R2F-GP_RCL_GP-120R2F-GP,64.A
     1 BMC_M_A1 @BASEBOARD_FAB2_LIB.BASEBOARD_FAB2(SCH_1):BMC_M_A1   I234 @BASEBOARD_FAB2_LIB.BASEBOARD_FAB2(SCH_1):PAGE151
     2 P1V2_AUX_BMC @BASEBOARD_FAB2_LIB.BASEBOARD_FAB2(SCH_1):P1V2_AUX_BMC   I234 @BASEBOARD_FAB2_LIB.BASEBOARD_FAB2(SCH_1):PAGE151

R25W40 120R2F-GP_RCL_GP-120R2F-GP,64.A
     1 BMC_M_A2 @BASEBOARD_FAB2_LIB.BASEBOARD_FAB2(SCH_1):BMC_M_A2   I247 @BASEBOARD_FAB2_LIB.BASEBOARD_FAB2(SCH_1):PAGE151
     2 P1V2_AUX_BMC @BASEBOARD_FAB2_LIB.BASEBOARD_FAB2(SCH_1):P1V2_AUX_BMC   I247 @BASEBOARD_FAB2_LIB.BASEBOARD_FAB2(SCH_1):PAGE151

R25W41 120R2F-GP_RCL_GP-120R2F-GP,64.A
     1 BMC_M_A3 @BASEBOARD_FAB2_LIB.BASEBOARD_FAB2(SCH_1):BMC_M_A3   I235 @BASEBOARD_FAB2_LIB.BASEBOARD_FAB2(SCH_1):PAGE151
     2 P1V2_AUX_BMC @BASEBOARD_FAB2_LIB.BASEBOARD_FAB2(SCH_1):P1V2_AUX_BMC   I235 @BASEBOARD_FAB2_LIB.BASEBOARD_FAB2(SCH_1):PAGE151

R25W42 120R2F-GP_RCL_GP-120R2F-GP,64.A
     1 BMC_M_A4 @BASEBOARD_FAB2_LIB.BASEBOARD_FAB2(SCH_1):BMC_M_A4   I236 @BASEBOARD_FAB2_LIB.BASEBOARD_FAB2(SCH_1):PAGE151
     2 P1V2_AUX_BMC @BASEBOARD_FAB2_LIB.BASEBOARD_FAB2(SCH_1):P1V2_AUX_BMC   I236 @BASEBOARD_FAB2_LIB.BASEBOARD_FAB2(SCH_1):PAGE151

R25W43 120R2F-GP_RCL_GP-120R2F-GP,64.A
     1 BMC_M_A5 @BASEBOARD_FAB2_LIB.BASEBOARD_FAB2(SCH_1):BMC_M_A5   I238 @BASEBOARD_FAB2_LIB.BASEBOARD_FAB2(SCH_1):PAGE151
     2 P1V2_AUX_BMC @BASEBOARD_FAB2_LIB.BASEBOARD_FAB2(SCH_1):P1V2_AUX_BMC   I238 @BASEBOARD_FAB2_LIB.BASEBOARD_FAB2(SCH_1):PAGE151

R25W44 120R2F-GP_RCL_GP-120R2F-GP,64.A
     1 BMC_M_A6 @BASEBOARD_FAB2_LIB.BASEBOARD_FAB2(SCH_1):BMC_M_A6   I237 @BASEBOARD_FAB2_LIB.BASEBOARD_FAB2(SCH_1):PAGE151
     2 P1V2_AUX_BMC @BASEBOARD_FAB2_LIB.BASEBOARD_FAB2(SCH_1):P1V2_AUX_BMC   I237 @BASEBOARD_FAB2_LIB.BASEBOARD_FAB2(SCH_1):PAGE151

R25W45 120R2F-GP_RCL_GP-120R2F-GP,64.A
     1 BMC_M_A7 @BASEBOARD_FAB2_LIB.BASEBOARD_FAB2(SCH_1):BMC_M_A7   I242 @BASEBOARD_FAB2_LIB.BASEBOARD_FAB2(SCH_1):PAGE151
     2 P1V2_AUX_BMC @BASEBOARD_FAB2_LIB.BASEBOARD_FAB2(SCH_1):P1V2_AUX_BMC   I242 @BASEBOARD_FAB2_LIB.BASEBOARD_FAB2(SCH_1):PAGE151

R25W46 120R2F-GP_RCL_GP-120R2F-GP,64.A
     1 BMC_M_A8 @BASEBOARD_FAB2_LIB.BASEBOARD_FAB2(SCH_1):BMC_M_A8   I241 @BASEBOARD_FAB2_LIB.BASEBOARD_FAB2(SCH_1):PAGE151
     2 P1V2_AUX_BMC @BASEBOARD_FAB2_LIB.BASEBOARD_FAB2(SCH_1):P1V2_AUX_BMC   I241 @BASEBOARD_FAB2_LIB.BASEBOARD_FAB2(SCH_1):PAGE151

R25W47 120R2F-GP_RCL_GP-120R2F-GP,64.A
     1 BMC_M_A9 @BASEBOARD_FAB2_LIB.BASEBOARD_FAB2(SCH_1):BMC_M_A9   I239 @BASEBOARD_FAB2_LIB.BASEBOARD_FAB2(SCH_1):PAGE151
     2 P1V2_AUX_BMC @BASEBOARD_FAB2_LIB.BASEBOARD_FAB2(SCH_1):P1V2_AUX_BMC   I239 @BASEBOARD_FAB2_LIB.BASEBOARD_FAB2(SCH_1):PAGE151

R25W48 120R2F-GP_RCL_GP-120R2F-GP,64.A
     1 BMC_M_A10 @BASEBOARD_FAB2_LIB.BASEBOARD_FAB2(SCH_1):BMC_M_A10   I240 @BASEBOARD_FAB2_LIB.BASEBOARD_FAB2(SCH_1):PAGE151
     2 P1V2_AUX_BMC @BASEBOARD_FAB2_LIB.BASEBOARD_FAB2(SCH_1):P1V2_AUX_BMC   I240 @BASEBOARD_FAB2_LIB.BASEBOARD_FAB2(SCH_1):PAGE151

R25W49 120R2F-GP_RCL_GP-120R2F-GP,64.A
     1 BMC_M_A11 @BASEBOARD_FAB2_LIB.BASEBOARD_FAB2(SCH_1):BMC_M_A11   I243 @BASEBOARD_FAB2_LIB.BASEBOARD_FAB2(SCH_1):PAGE151
     2 P1V2_AUX_BMC @BASEBOARD_FAB2_LIB.BASEBOARD_FAB2(SCH_1):P1V2_AUX_BMC   I243 @BASEBOARD_FAB2_LIB.BASEBOARD_FAB2(SCH_1):PAGE151

R25W50 120R2F-GP_RCL_GP-120R2F-GP,64.A
     1 BMC_M_A12 @BASEBOARD_FAB2_LIB.BASEBOARD_FAB2(SCH_1):BMC_M_A12   I244 @BASEBOARD_FAB2_LIB.BASEBOARD_FAB2(SCH_1):PAGE151
     2 P1V2_AUX_BMC @BASEBOARD_FAB2_LIB.BASEBOARD_FAB2(SCH_1):P1V2_AUX_BMC   I244 @BASEBOARD_FAB2_LIB.BASEBOARD_FAB2(SCH_1):PAGE151

R25W51 120R2F-GP_RCL_GP-120R2F-GP,64.A
     1 BMC_M_A13 @BASEBOARD_FAB2_LIB.BASEBOARD_FAB2(SCH_1):BMC_M_A13   I245 @BASEBOARD_FAB2_LIB.BASEBOARD_FAB2(SCH_1):PAGE151
     2 P1V2_AUX_BMC @BASEBOARD_FAB2_LIB.BASEBOARD_FAB2(SCH_1):P1V2_AUX_BMC   I245 @BASEBOARD_FAB2_LIB.BASEBOARD_FAB2(SCH_1):PAGE151

R25W52 120R2F-GP_RCL_GP-120R2F-GP,64.A
     1 BMC_M_MACT_N @BASEBOARD_FAB2_LIB.BASEBOARD_FAB2(SCH_1):BMC_M_MACT_N   I246 @BASEBOARD_FAB2_LIB.BASEBOARD_FAB2(SCH_1):PAGE151
     2 P1V2_AUX_BMC @BASEBOARD_FAB2_LIB.BASEBOARD_FAB2(SCH_1):P1V2_AUX_BMC   I246 @BASEBOARD_FAB2_LIB.BASEBOARD_FAB2(SCH_1):PAGE151

R25W57 RES_0402-49.9K,1%,1/16W,CHIP,GA
     1 PD_ADCREXT @BASEBOARD_FAB2_LIB.BASEBOARD_FAB2(SCH_1):PD_ADCREXT   I151 @BASEBOARD_FAB2_LIB.BASEBOARD_FAB2(SCH_1):PAGE147
     2    GND @BASEBOARD_FAB2_LIB.BASEBOARD_FAB2(SCH_1):GND   I151 @BASEBOARD_FAB2_LIB.BASEBOARD_FAB2(SCH_1):PAGE147

R25W58 18KR2F-GP_RCL_GP-18KR2F-GP,64.A
     1 A_DACRSET @BASEBOARD_FAB2_LIB.BASEBOARD_FAB2(SCH_1):A_DACRSET   I150 @BASEBOARD_FAB2_LIB.BASEBOARD_FAB2(SCH_1):PAGE144
     2    GND @BASEBOARD_FAB2_LIB.BASEBOARD_FAB2(SCH_1):GND   I150 @BASEBOARD_FAB2_LIB.BASEBOARD_FAB2(SCH_1):PAGE144

R25W59 RES_0402-0.0,5%,1/16W,CHIP,G21A
     1 P3V3_STBY @BASEBOARD_FAB2_LIB.BASEBOARD_FAB2(SCH_1):P3V3_STBY    I16 @BASEBOARD_FAB2_LIB.BASEBOARD_FAB2(SCH_1):PAGE148
     2 VCCBAT_TW12 @BASEBOARD_FAB2_LIB.BASEBOARD_FAB2(SCH_1):VCCBAT_TW12    I16 @BASEBOARD_FAB2_LIB.BASEBOARD_FAB2(SCH_1):PAGE148

R25W60 RES_0402-100.0K,1%,1/16W,CHIP,A
     1 CLK_100M_BMC_PE_R_DN @BASEBOARD_FAB2_LIB.BASEBOARD_FAB2(SCH_1):CLK_100M_BMC_PE_R_DN    I34 @BASEBOARD_FAB2_LIB.BASEBOARD_FAB2(SCH_1):PAGE145
     2    GND @BASEBOARD_FAB2_LIB.BASEBOARD_FAB2(SCH_1):GND    I34 @BASEBOARD_FAB2_LIB.BASEBOARD_FAB2(SCH_1):PAGE145

R25W61 RES_0402-100.0K,1%,1/16W,CHIP,A
     1 CLK_100M_BMC_PE_R_DP @BASEBOARD_FAB2_LIB.BASEBOARD_FAB2(SCH_1):CLK_100M_BMC_PE_R_DP    I30 @BASEBOARD_FAB2_LIB.BASEBOARD_FAB2(SCH_1):PAGE145
     2    GND @BASEBOARD_FAB2_LIB.BASEBOARD_FAB2(SCH_1):GND    I30 @BASEBOARD_FAB2_LIB.BASEBOARD_FAB2(SCH_1):PAGE145

R25W62 RES_0402-100.0K,1%,1/16W,CHIP,A
     1 RST_PLTRST_BUF_N_R @BASEBOARD_FAB2_LIB.BASEBOARD_FAB2(SCH_1):RST_PLTRST_BUF_N_R    I31 @BASEBOARD_FAB2_LIB.BASEBOARD_FAB2(SCH_1):PAGE145
     2    GND @BASEBOARD_FAB2_LIB.BASEBOARD_FAB2(SCH_1):GND    I31 @BASEBOARD_FAB2_LIB.BASEBOARD_FAB2(SCH_1):PAGE145

R25W63 RES_0402-100.0K,1%,1/16W,CHIP,A
     1 FM_PE_BMC_WAKE_N @BASEBOARD_FAB2_LIB.BASEBOARD_FAB2(SCH_1):FM_PE_BMC_WAKE_N    I65 @BASEBOARD_FAB2_LIB.BASEBOARD_FAB2(SCH_1):PAGE146
     2    GND @BASEBOARD_FAB2_LIB.BASEBOARD_FAB2(SCH_1):GND    I65 @BASEBOARD_FAB2_LIB.BASEBOARD_FAB2(SCH_1):PAGE146

R25W64 RES_0402-100.0K,1%,1/16W,CHIP,A
     1 P2E_SSB_BMC_TX_C_DP @BASEBOARD_FAB2_LIB.BASEBOARD_FAB2(SCH_1):P2E_SSB_BMC_TX_C_DP    I36 @BASEBOARD_FAB2_LIB.BASEBOARD_FAB2(SCH_1):PAGE145
     2    GND @BASEBOARD_FAB2_LIB.BASEBOARD_FAB2(SCH_1):GND    I36 @BASEBOARD_FAB2_LIB.BASEBOARD_FAB2(SCH_1):PAGE145

R25W65 RES_0402-100.0K,1%,1/16W,CHIP,A
     1 P2E_SSB_BMC_TX_C_DN @BASEBOARD_FAB2_LIB.BASEBOARD_FAB2(SCH_1):P2E_SSB_BMC_TX_C_DN    I38 @BASEBOARD_FAB2_LIB.BASEBOARD_FAB2(SCH_1):PAGE145
     2    GND @BASEBOARD_FAB2_LIB.BASEBOARD_FAB2(SCH_1):GND    I38 @BASEBOARD_FAB2_LIB.BASEBOARD_FAB2(SCH_1):PAGE145

R25W66 RES_0402-100.0K,1%,1/16W,CHIP,A
     1 CLK_24M_BMC_LPC @BASEBOARD_FAB2_LIB.BASEBOARD_FAB2(SCH_1):CLK_24M_BMC_LPC    I76 @BASEBOARD_FAB2_LIB.BASEBOARD_FAB2(SCH_1):PAGE146
     2    GND @BASEBOARD_FAB2_LIB.BASEBOARD_FAB2(SCH_1):GND    I76 @BASEBOARD_FAB2_LIB.BASEBOARD_FAB2(SCH_1):PAGE146

R25W67 200R2F-L1-GP_SMD-RG4-200R2F-L1A
     1 PD_PEREXT @BASEBOARD_FAB2_LIB.BASEBOARD_FAB2(SCH_1):PD_PEREXT   I118 @BASEBOARD_FAB2_LIB.BASEBOARD_FAB2(SCH_1):PAGE145
     2    GND @BASEBOARD_FAB2_LIB.BASEBOARD_FAB2(SCH_1):GND   I118 @BASEBOARD_FAB2_LIB.BASEBOARD_FAB2(SCH_1):PAGE145

R25W68 RES_0402-33.2,1%,1/16W,CHIP,G2A
     1 LPC_LAD3_IO3 @BASEBOARD_FAB2_LIB.BASEBOARD_FAB2(SCH_1):LPC_LAD3_IO3    I84 @BASEBOARD_FAB2_LIB.BASEBOARD_FAB2(SCH_1):PAGE146
     2 LPC_LAD3_IO3_R @BASEBOARD_FAB2_LIB.BASEBOARD_FAB2(SCH_1):LPC_LAD3_IO3_R    I84 @BASEBOARD_FAB2_LIB.BASEBOARD_FAB2(SCH_1):PAGE146

R25W69 RES_0402-33.2,1%,1/16W,CHIP,G2A
     1 LPC_LAD1_IO1 @BASEBOARD_FAB2_LIB.BASEBOARD_FAB2(SCH_1):LPC_LAD1_IO1    I85 @BASEBOARD_FAB2_LIB.BASEBOARD_FAB2(SCH_1):PAGE146
     2 LPC_LAD1_IO1_R @BASEBOARD_FAB2_LIB.BASEBOARD_FAB2(SCH_1):LPC_LAD1_IO1_R    I85 @BASEBOARD_FAB2_LIB.BASEBOARD_FAB2(SCH_1):PAGE146

R25W70 RES_0402-33.2,1%,1/16W,CHIP,G2A
     1 FM_CPU0_FIVR_FAULT_LVT3_R_N @BASEBOARD_FAB2_LIB.BASEBOARD_FAB2(SCH_1):FM_CPU0_FIVR_FAULT_LVT3_R_N   I114 @BASEBOARD_FAB2_LIB.BASEBOARD_FAB2(SCH_1):PAGE144
     2 FM_CPU0_FIVR_FAULT_LVT3_N @BASEBOARD_FAB2_LIB.BASEBOARD_FAB2(SCH_1):FM_CPU0_FIVR_FAULT_LVT3_N   I114 @BASEBOARD_FAB2_LIB.BASEBOARD_FAB2(SCH_1):PAGE144

R25W72 RES_0402-33.2,1%,1/16W,CHIP,G2A
     1 LPC_LFRAME_N_CS0_N @BASEBOARD_FAB2_LIB.BASEBOARD_FAB2(SCH_1):LPC_LFRAME_N_CS0_N    I71 @BASEBOARD_FAB2_LIB.BASEBOARD_FAB2(SCH_1):PAGE146
     2 LPC_LFRAME_N_CS0_R_N @BASEBOARD_FAB2_LIB.BASEBOARD_FAB2(SCH_1):LPC_LFRAME_N_CS0_R_N    I71 @BASEBOARD_FAB2_LIB.BASEBOARD_FAB2(SCH_1):PAGE146

R25W73 RES_0402-33.2,1%,1/16W,CHIP,G2A
     1 IRQ_LPC_SERIRQ_N @BASEBOARD_FAB2_LIB.BASEBOARD_FAB2(SCH_1):IRQ_LPC_SERIRQ_N    I73 @BASEBOARD_FAB2_LIB.BASEBOARD_FAB2(SCH_1):PAGE146
     2 IRQ_LPC_SERIRQ_R @BASEBOARD_FAB2_LIB.BASEBOARD_FAB2(SCH_1):IRQ_LPC_SERIRQ_R    I73 @BASEBOARD_FAB2_LIB.BASEBOARD_FAB2(SCH_1):PAGE146

R25W74 RES_0402-0.0,5%,1/16W,CHIP,G21A
     1 RST_PLTRST_BUF_N @BASEBOARD_FAB2_LIB.BASEBOARD_FAB2(SCH_1):RST_PLTRST_BUF_N    I70 @BASEBOARD_FAB2_LIB.BASEBOARD_FAB2(SCH_1):PAGE146
     2 RST_BMC_LVC3_N @BASEBOARD_FAB2_LIB.BASEBOARD_FAB2(SCH_1):RST_BMC_LVC3_N    I70 @BASEBOARD_FAB2_LIB.BASEBOARD_FAB2(SCH_1):PAGE146

R25W75 RES_0402-33.2,1%,1/16W,CHIP,G2A
     1 FM_CPU1_FIVR_FAULT_LVT3_R_N @BASEBOARD_FAB2_LIB.BASEBOARD_FAB2(SCH_1):FM_CPU1_FIVR_FAULT_LVT3_R_N   I118 @BASEBOARD_FAB2_LIB.BASEBOARD_FAB2(SCH_1):PAGE144
     2 FM_CPU1_FIVR_FAULT_LVT3_N @BASEBOARD_FAB2_LIB.BASEBOARD_FAB2(SCH_1):FM_CPU1_FIVR_FAULT_LVT3_N   I118 @BASEBOARD_FAB2_LIB.BASEBOARD_FAB2(SCH_1):PAGE144

R25W78 RES_0402-22.1,1.0%,1/16W,CHIP,A
     1 SPI_BMC_BT_CS_R_N @BASEBOARD_FAB2_LIB.BASEBOARD_FAB2(SCH_1):SPI_BMC_BT_CS_R_N   I123 @BASEBOARD_FAB2_LIB.BASEBOARD_FAB2(SCH_1):PAGE146
     2 SPI_BMC_BT_CS_N @BASEBOARD_FAB2_LIB.BASEBOARD_FAB2(SCH_1):SPI_BMC_BT_CS_N   I123 @BASEBOARD_FAB2_LIB.BASEBOARD_FAB2(SCH_1):PAGE146

R25W79 RES_0402-10.0K,1%,1/16W,CHIP,GA
     1 P3V3_STBY @BASEBOARD_FAB2_LIB.BASEBOARD_FAB2(SCH_1):P3V3_STBY    I42 @BASEBOARD_FAB2_LIB.BASEBOARD_FAB2(SCH_1):PAGE147
     2 RMII_SPRNGVLLE_BMC_PCH_RXD0 @BASEBOARD_FAB2_LIB.BASEBOARD_FAB2(SCH_1):RMII_SPRNGVLLE_BMC_PCH_RXD0    I42 @BASEBOARD_FAB2_LIB.BASEBOARD_FAB2(SCH_1):PAGE147

R25W80 RES_0402-10.0K,1%,1/16W,CHIP,GA
     1 P3V3_STBY @BASEBOARD_FAB2_LIB.BASEBOARD_FAB2(SCH_1):P3V3_STBY    I43 @BASEBOARD_FAB2_LIB.BASEBOARD_FAB2(SCH_1):PAGE147
     2 RMII_SPRNGVLLE_BMC_PCH_RXD1 @BASEBOARD_FAB2_LIB.BASEBOARD_FAB2(SCH_1):RMII_SPRNGVLLE_BMC_PCH_RXD1    I43 @BASEBOARD_FAB2_LIB.BASEBOARD_FAB2(SCH_1):PAGE147

R25W81 RES_0402-33.2,1%,1/16W,CHIP,G2A
     1 SPI_BMC_BT_CLK @BASEBOARD_FAB2_LIB.BASEBOARD_FAB2(SCH_1):SPI_BMC_BT_CLK    I67 @BASEBOARD_FAB2_LIB.BASEBOARD_FAB2(SCH_1):PAGE146
     2 SPI_BMC_BT_CLK_R @BASEBOARD_FAB2_LIB.BASEBOARD_FAB2(SCH_1):SPI_BMC_BT_CLK_R    I67 @BASEBOARD_FAB2_LIB.BASEBOARD_FAB2(SCH_1):PAGE146

R25W82 RES_0402-33.2,1%,1/16W,CHIP,G2A
     1 SPI_BMC_BT_DO @BASEBOARD_FAB2_LIB.BASEBOARD_FAB2(SCH_1):SPI_BMC_BT_DO    I68 @BASEBOARD_FAB2_LIB.BASEBOARD_FAB2(SCH_1):PAGE146
     2 SPI_BMC_BT_DO_R @BASEBOARD_FAB2_LIB.BASEBOARD_FAB2(SCH_1):SPI_BMC_BT_DO_R    I68 @BASEBOARD_FAB2_LIB.BASEBOARD_FAB2(SCH_1):PAGE146

R25W83 RES_0402-0.0,5%,1/16W,CHIP,G21A
     1 FM_BMC_NMI_N @BASEBOARD_FAB2_LIB.BASEBOARD_FAB2(SCH_1):FM_BMC_NMI_N    I26 @BASEBOARD_FAB2_LIB.BASEBOARD_FAB2(SCH_1):PAGE146
     2 FM_BMC_NMI_N_R @BASEBOARD_FAB2_LIB.BASEBOARD_FAB2(SCH_1):FM_BMC_NMI_N_R    I26 @BASEBOARD_FAB2_LIB.BASEBOARD_FAB2(SCH_1):PAGE146

R25W85 RES_0402-22.1,1.0%,1/16W,CHIP,A
     1 RMII_BMC_OCP_TXEN_R @BASEBOARD_FAB2_LIB.BASEBOARD_FAB2(SCH_1):RMII_BMC_OCP_TXEN_R    I23 @BASEBOARD_FAB2_LIB.BASEBOARD_FAB2(SCH_1):PAGE147
     2 RMII_BMC_OCP_TXEN @BASEBOARD_FAB2_LIB.BASEBOARD_FAB2(SCH_1):RMII_BMC_OCP_TXEN    I23 @BASEBOARD_FAB2_LIB.BASEBOARD_FAB2(SCH_1):PAGE147

R25W86 RES_0402-22.1,1.0%,1/16W,CHIP,A
     1 RMII_BMC_OCP_TXD0_R @BASEBOARD_FAB2_LIB.BASEBOARD_FAB2(SCH_1):RMII_BMC_OCP_TXD0_R    I24 @BASEBOARD_FAB2_LIB.BASEBOARD_FAB2(SCH_1):PAGE147
     2 RMII_BMC_OCP_TXD0 @BASEBOARD_FAB2_LIB.BASEBOARD_FAB2(SCH_1):RMII_BMC_OCP_TXD0    I24 @BASEBOARD_FAB2_LIB.BASEBOARD_FAB2(SCH_1):PAGE147

R25W87 RES_0402-22.1,1.0%,1/16W,CHIP,A
     1 RMII_BMC_OCP_TXD1_R @BASEBOARD_FAB2_LIB.BASEBOARD_FAB2(SCH_1):RMII_BMC_OCP_TXD1_R    I25 @BASEBOARD_FAB2_LIB.BASEBOARD_FAB2(SCH_1):PAGE147
     2 RMII_BMC_OCP_TXD1 @BASEBOARD_FAB2_LIB.BASEBOARD_FAB2(SCH_1):RMII_BMC_OCP_TXD1    I25 @BASEBOARD_FAB2_LIB.BASEBOARD_FAB2(SCH_1):PAGE147

R25W88 RES_0402-22.1,1.0%,1/16W,CHIP,A
     1 RMII_BMC_SPRNGVLLE_TXEN_R @BASEBOARD_FAB2_LIB.BASEBOARD_FAB2(SCH_1):RMII_BMC_SPRNGVLLE_TXEN_R     I8 @BASEBOARD_FAB2_LIB.BASEBOARD_FAB2(SCH_1):PAGE147
     2 RMII_BMC_PCH_SPRNGVLLE_TXEN @BASEBOARD_FAB2_LIB.BASEBOARD_FAB2(SCH_1):RMII_BMC_PCH_SPRNGVLLE_TXEN     I8 @BASEBOARD_FAB2_LIB.BASEBOARD_FAB2(SCH_1):PAGE147

R25W89 RES_0402-22.1,1.0%,1/16W,CHIP,A
     1 RMII_BMC_PCH_SPRNGVLLE_TXD0_R @BASEBOARD_FAB2_LIB.BASEBOARD_FAB2(SCH_1):RMII_BMC_PCH_SPRNGVLLE_TXD0_R    I22 @BASEBOARD_FAB2_LIB.BASEBOARD_FAB2(SCH_1):PAGE147
     2 RMII_BMC_PCH_SPRNGVLLE_TXD0 @BASEBOARD_FAB2_LIB.BASEBOARD_FAB2(SCH_1):RMII_BMC_PCH_SPRNGVLLE_TXD0    I22 @BASEBOARD_FAB2_LIB.BASEBOARD_FAB2(SCH_1):PAGE147

R25W90 RES_0402-22.1,1.0%,1/16W,CHIP,A
     1 RMII_BMC_PCH_SPRNGVLLE_TXD1_R @BASEBOARD_FAB2_LIB.BASEBOARD_FAB2(SCH_1):RMII_BMC_PCH_SPRNGVLLE_TXD1_R    I21 @BASEBOARD_FAB2_LIB.BASEBOARD_FAB2(SCH_1):PAGE147
     2 RMII_BMC_PCH_SPRNGVLLE_TXD1 @BASEBOARD_FAB2_LIB.BASEBOARD_FAB2(SCH_1):RMII_BMC_PCH_SPRNGVLLE_TXD1    I21 @BASEBOARD_FAB2_LIB.BASEBOARD_FAB2(SCH_1):PAGE147

R25W93 RES_0603-0,5.0%,1/10W,CHIP,G22A
     1 P3V3_STBY @BASEBOARD_FAB2_LIB.BASEBOARD_FAB2(SCH_1):P3V3_STBY    I90 @BASEBOARD_FAB2_LIB.BASEBOARD_FAB2(SCH_1):PAGE149
     2 VCC_DACAV3V3 @BASEBOARD_FAB2_LIB.BASEBOARD_FAB2(SCH_1):VCC_DACAV3V3    I90 @BASEBOARD_FAB2_LIB.BASEBOARD_FAB2(SCH_1):PAGE149

R25W94 RES_0402-4.75K,1%,1/16W,CHIP,GA
     1    GND @BASEBOARD_FAB2_LIB.BASEBOARD_FAB2(SCH_1):GND   I140 @BASEBOARD_FAB2_LIB.BASEBOARD_FAB2(SCH_1):PAGE137
     2 PD_SPI_BMC_BT_CS0_N @BASEBOARD_FAB2_LIB.BASEBOARD_FAB2(SCH_1):PD_SPI_BMC_BT_CS0_N   I140 @BASEBOARD_FAB2_LIB.BASEBOARD_FAB2(SCH_1):PAGE137

R25W95 RES_0402-4.75K,1%,1/16W,CHIP,GA
     1 P3V3_STBY @BASEBOARD_FAB2_LIB.BASEBOARD_FAB2(SCH_1):P3V3_STBY   I144 @BASEBOARD_FAB2_LIB.BASEBOARD_FAB2(SCH_1):PAGE150
     2 SPI_BMC_BT_CLK @BASEBOARD_FAB2_LIB.BASEBOARD_FAB2(SCH_1):SPI_BMC_BT_CLK   I144 @BASEBOARD_FAB2_LIB.BASEBOARD_FAB2(SCH_1):PAGE150

R25W96 RES_0402-4.75K,1%,1/16W,CHIP,GA
     1 P3V3_STBY @BASEBOARD_FAB2_LIB.BASEBOARD_FAB2(SCH_1):P3V3_STBY   I145 @BASEBOARD_FAB2_LIB.BASEBOARD_FAB2(SCH_1):PAGE150
     2 SPI_BMC_BT_DO @BASEBOARD_FAB2_LIB.BASEBOARD_FAB2(SCH_1):SPI_BMC_BT_DO   I145 @BASEBOARD_FAB2_LIB.BASEBOARD_FAB2(SCH_1):PAGE150

R25W97 RES_0402-4.75K,1%,1/16W,EMPTY,A
     1 P3V3_STBY @BASEBOARD_FAB2_LIB.BASEBOARD_FAB2(SCH_1):P3V3_STBY   I146 @BASEBOARD_FAB2_LIB.BASEBOARD_FAB2(SCH_1):PAGE150
     2 SPI_BMC_BT_DI @BASEBOARD_FAB2_LIB.BASEBOARD_FAB2(SCH_1):SPI_BMC_BT_DI   I146 @BASEBOARD_FAB2_LIB.BASEBOARD_FAB2(SCH_1):PAGE150

R25W98 RES_0402-4.75K,1%,1/16W,EMPTY,A
     1 P3V3_STBY @BASEBOARD_FAB2_LIB.BASEBOARD_FAB2(SCH_1):P3V3_STBY   I209 @BASEBOARD_FAB2_LIB.BASEBOARD_FAB2(SCH_1):PAGE150
     2 BMC_STRAP_BIT3 @BASEBOARD_FAB2_LIB.BASEBOARD_FAB2(SCH_1):BMC_STRAP_BIT3   I209 @BASEBOARD_FAB2_LIB.BASEBOARD_FAB2(SCH_1):PAGE150

R25W99 RES_0402-4.75K,1%,1/16W,EMPTY,A
     1 P3V3_STBY @BASEBOARD_FAB2_LIB.BASEBOARD_FAB2(SCH_1):P3V3_STBY   I210 @BASEBOARD_FAB2_LIB.BASEBOARD_FAB2(SCH_1):PAGE150
     2 BMC_STRAP_BIT5 @BASEBOARD_FAB2_LIB.BASEBOARD_FAB2(SCH_1):BMC_STRAP_BIT5   I210 @BASEBOARD_FAB2_LIB.BASEBOARD_FAB2(SCH_1):PAGE150

R25W100 RES_0402-4.75K,1%,1/16W,CHIP,GA
     1 P3V3_STBY @BASEBOARD_FAB2_LIB.BASEBOARD_FAB2(SCH_1):P3V3_STBY   I211 @BASEBOARD_FAB2_LIB.BASEBOARD_FAB2(SCH_1):PAGE150
     2 GPIOS7 @BASEBOARD_FAB2_LIB.BASEBOARD_FAB2(SCH_1):GPIOS7   I211 @BASEBOARD_FAB2_LIB.BASEBOARD_FAB2(SCH_1):PAGE150

R25W101 RES_0402-4.75K,1%,1/16W,EMPTY,A
     1 P3V3_STBY @BASEBOARD_FAB2_LIB.BASEBOARD_FAB2(SCH_1):P3V3_STBY   I241 @BASEBOARD_FAB2_LIB.BASEBOARD_FAB2(SCH_1):PAGE150
     2 BMC_STRAP_BIT17 @BASEBOARD_FAB2_LIB.BASEBOARD_FAB2(SCH_1):BMC_STRAP_BIT17   I241 @BASEBOARD_FAB2_LIB.BASEBOARD_FAB2(SCH_1):PAGE150

R25W102 RES_0402-4.75K,1%,1/16W,EMPTY,A
     1 P3V3_STBY @BASEBOARD_FAB2_LIB.BASEBOARD_FAB2(SCH_1):P3V3_STBY   I239 @BASEBOARD_FAB2_LIB.BASEBOARD_FAB2(SCH_1):PAGE150
     2 BMC_STRAP_BIT18 @BASEBOARD_FAB2_LIB.BASEBOARD_FAB2(SCH_1):BMC_STRAP_BIT18   I239 @BASEBOARD_FAB2_LIB.BASEBOARD_FAB2(SCH_1):PAGE150

R25W103 RES_0402-4.75K,1%,1/16W,EMPTY,A
     1 P3V3_STBY @BASEBOARD_FAB2_LIB.BASEBOARD_FAB2(SCH_1):P3V3_STBY   I214 @BASEBOARD_FAB2_LIB.BASEBOARD_FAB2(SCH_1):PAGE150
     2 BMC_STRAP_BIT20 @BASEBOARD_FAB2_LIB.BASEBOARD_FAB2(SCH_1):BMC_STRAP_BIT20   I214 @BASEBOARD_FAB2_LIB.BASEBOARD_FAB2(SCH_1):PAGE150

R25W104 RES_0402-4.75K,1%,1/16W,CHIP,GA
     1 P3V3_STBY @BASEBOARD_FAB2_LIB.BASEBOARD_FAB2(SCH_1):P3V3_STBY   I215 @BASEBOARD_FAB2_LIB.BASEBOARD_FAB2(SCH_1):PAGE150
     2 BMC_STRAP_BIT27 @BASEBOARD_FAB2_LIB.BASEBOARD_FAB2(SCH_1):BMC_STRAP_BIT27   I215 @BASEBOARD_FAB2_LIB.BASEBOARD_FAB2(SCH_1):PAGE150

R25W105 RES_0402-4.75K,1%,1/16W,EMPTY,A
     1 P3V3_STBY @BASEBOARD_FAB2_LIB.BASEBOARD_FAB2(SCH_1):P3V3_STBY   I196 @BASEBOARD_FAB2_LIB.BASEBOARD_FAB2(SCH_1):PAGE150
     2 PU_JTAG_BMC_RTCK @BASEBOARD_FAB2_LIB.BASEBOARD_FAB2(SCH_1):PU_JTAG_BMC_RTCK   I196 @BASEBOARD_FAB2_LIB.BASEBOARD_FAB2(SCH_1):PAGE150

R25W106 RES_0402-4.75K,1%,1/16W,EMPTY,A
     1 P3V3_STBY @BASEBOARD_FAB2_LIB.BASEBOARD_FAB2(SCH_1):P3V3_STBY   I175 @BASEBOARD_FAB2_LIB.BASEBOARD_FAB2(SCH_1):PAGE150
     2 RMII_BMC_OCP_TXEN @BASEBOARD_FAB2_LIB.BASEBOARD_FAB2(SCH_1):RMII_BMC_OCP_TXEN   I175 @BASEBOARD_FAB2_LIB.BASEBOARD_FAB2(SCH_1):PAGE150

R25W107 RES_0402-4.75K,1%,1/16W,CHIP,GA
     1 P3V3_STBY @BASEBOARD_FAB2_LIB.BASEBOARD_FAB2(SCH_1):P3V3_STBY   I190 @BASEBOARD_FAB2_LIB.BASEBOARD_FAB2(SCH_1):PAGE150
     2 RMII_BMC_OCP_TXD0_R @BASEBOARD_FAB2_LIB.BASEBOARD_FAB2(SCH_1):RMII_BMC_OCP_TXD0_R   I190 @BASEBOARD_FAB2_LIB.BASEBOARD_FAB2(SCH_1):PAGE150

R25W108 RES_0402-4.75K,1%,1/16W,EMPTY,A
     1 P3V3_STBY @BASEBOARD_FAB2_LIB.BASEBOARD_FAB2(SCH_1):P3V3_STBY   I191 @BASEBOARD_FAB2_LIB.BASEBOARD_FAB2(SCH_1):PAGE150
     2 RMII_BMC_OCP_TXD1_R @BASEBOARD_FAB2_LIB.BASEBOARD_FAB2(SCH_1):RMII_BMC_OCP_TXD1_R   I191 @BASEBOARD_FAB2_LIB.BASEBOARD_FAB2(SCH_1):PAGE150

R25W109 RES_0402-4.75K,1%,1/16W,CHIP,GA
     1 P3V3_STBY @BASEBOARD_FAB2_LIB.BASEBOARD_FAB2(SCH_1):P3V3_STBY   I236 @BASEBOARD_FAB2_LIB.BASEBOARD_FAB2(SCH_1):PAGE150
     2 TP_RGMII2TXD3_GPIOU3 @BASEBOARD_FAB2_LIB.BASEBOARD_FAB2(SCH_1):TP_RGMII2TXD3_GPIOU3   I236 @BASEBOARD_FAB2_LIB.BASEBOARD_FAB2(SCH_1):PAGE150

R25W110 RES_0402-4.75K,1%,1/16W,EMPTY,A
     1 P3V3_STBY @BASEBOARD_FAB2_LIB.BASEBOARD_FAB2(SCH_1):P3V3_STBY   I233 @BASEBOARD_FAB2_LIB.BASEBOARD_FAB2(SCH_1):PAGE150
     2 TP_RGMII2TXD2_GPIOU2 @BASEBOARD_FAB2_LIB.BASEBOARD_FAB2(SCH_1):TP_RGMII2TXD2_GPIOU2   I233 @BASEBOARD_FAB2_LIB.BASEBOARD_FAB2(SCH_1):PAGE150

R25W111 RES_0402-4.75K,1%,1/16W,EMPTY,A
     1 P3V3_STBY @BASEBOARD_FAB2_LIB.BASEBOARD_FAB2(SCH_1):P3V3_STBY   I180 @BASEBOARD_FAB2_LIB.BASEBOARD_FAB2(SCH_1):PAGE150
     2 RMII_BMC_PCH_SPRNGVLLE_TXEN @BASEBOARD_FAB2_LIB.BASEBOARD_FAB2(SCH_1):RMII_BMC_PCH_SPRNGVLLE_TXEN   I180 @BASEBOARD_FAB2_LIB.BASEBOARD_FAB2(SCH_1):PAGE150

R25W112 RES_0402-4.75K,1%,1/16W,EMPTY,A
     1 P3V3_STBY @BASEBOARD_FAB2_LIB.BASEBOARD_FAB2(SCH_1):P3V3_STBY   I228 @BASEBOARD_FAB2_LIB.BASEBOARD_FAB2(SCH_1):PAGE150
     2 RMII_BMC_PCH_SPRNGVLLE_TXD0_R @BASEBOARD_FAB2_LIB.BASEBOARD_FAB2(SCH_1):RMII_BMC_PCH_SPRNGVLLE_TXD0_R   I228 @BASEBOARD_FAB2_LIB.BASEBOARD_FAB2(SCH_1):PAGE150

R25W113 RES_0402-4.75K,1%,1/16W,EMPTY,A
     1 P3V3_STBY @BASEBOARD_FAB2_LIB.BASEBOARD_FAB2(SCH_1):P3V3_STBY   I230 @BASEBOARD_FAB2_LIB.BASEBOARD_FAB2(SCH_1):PAGE150
     2 RMII_BMC_PCH_SPRNGVLLE_TXD1_R @BASEBOARD_FAB2_LIB.BASEBOARD_FAB2(SCH_1):RMII_BMC_PCH_SPRNGVLLE_TXD1_R   I230 @BASEBOARD_FAB2_LIB.BASEBOARD_FAB2(SCH_1):PAGE150

R25W114 RES_0402-4.75K,1%,1/16W,EMPTY,A
     1 P3V3_STBY @BASEBOARD_FAB2_LIB.BASEBOARD_FAB2(SCH_1):P3V3_STBY   I218 @BASEBOARD_FAB2_LIB.BASEBOARD_FAB2(SCH_1):PAGE150
     2 TP_RGMII1TXD2_GPIOT4 @BASEBOARD_FAB2_LIB.BASEBOARD_FAB2(SCH_1):TP_RGMII1TXD2_GPIOT4   I218 @BASEBOARD_FAB2_LIB.BASEBOARD_FAB2(SCH_1):PAGE150

R25W115 RES_0402-4.75K,1%,1/16W,EMPTY,A
     1 P3V3_STBY @BASEBOARD_FAB2_LIB.BASEBOARD_FAB2(SCH_1):P3V3_STBY   I242 @BASEBOARD_FAB2_LIB.BASEBOARD_FAB2(SCH_1):PAGE150
     2 TP_RGMII1TXD3_GPIOT5 @BASEBOARD_FAB2_LIB.BASEBOARD_FAB2(SCH_1):TP_RGMII1TXD3_GPIOT5   I242 @BASEBOARD_FAB2_LIB.BASEBOARD_FAB2(SCH_1):PAGE150

R25W116 RES_0402-3.32K,1%,1/16W,EMPTY,A
     1    GND @BASEBOARD_FAB2_LIB.BASEBOARD_FAB2(SCH_1):GND   I189 @BASEBOARD_FAB2_LIB.BASEBOARD_FAB2(SCH_1):PAGE150
     2 UART_BMC_TXD5 @BASEBOARD_FAB2_LIB.BASEBOARD_FAB2(SCH_1):UART_BMC_TXD5   I189 @BASEBOARD_FAB2_LIB.BASEBOARD_FAB2(SCH_1):PAGE150

R25W117 RES_0402-240,1.0%,1/16W,CHIP,GA
     1 BMC_ZQ @BASEBOARD_FAB2_LIB.BASEBOARD_FAB2(SCH_1):BMC_ZQ   I101 @BASEBOARD_FAB2_LIB.BASEBOARD_FAB2(SCH_1):PAGE151
     2    GND @BASEBOARD_FAB2_LIB.BASEBOARD_FAB2(SCH_1):GND   I101 @BASEBOARD_FAB2_LIB.BASEBOARD_FAB2(SCH_1):PAGE151

R25W118 RES_0402-0.0,5%,1/16W,CHIP,G21A
     1 BMC_M_PAR @BASEBOARD_FAB2_LIB.BASEBOARD_FAB2(SCH_1):BMC_M_PAR   I211 @BASEBOARD_FAB2_LIB.BASEBOARD_FAB2(SCH_1):PAGE151
     2    GND @BASEBOARD_FAB2_LIB.BASEBOARD_FAB2(SCH_1):GND   I211 @BASEBOARD_FAB2_LIB.BASEBOARD_FAB2(SCH_1):PAGE151

R25W119 RES_0402-4.75K,1%,1/16W,EMPTY,A
     1 P1V2_AUX_BMC @BASEBOARD_FAB2_LIB.BASEBOARD_FAB2(SCH_1):P1V2_AUX_BMC   I210 @BASEBOARD_FAB2_LIB.BASEBOARD_FAB2(SCH_1):PAGE151
     2 BMC_M_PAR @BASEBOARD_FAB2_LIB.BASEBOARD_FAB2(SCH_1):BMC_M_PAR   I210 @BASEBOARD_FAB2_LIB.BASEBOARD_FAB2(SCH_1):PAGE151

R25W120 RES_0603-0,5.0%,1/10W,CHIP,G22A
     1 P3V3_STBY @BASEBOARD_FAB2_LIB.BASEBOARD_FAB2(SCH_1):P3V3_STBY    I91 @BASEBOARD_FAB2_LIB.BASEBOARD_FAB2(SCH_1):PAGE149
     2 P3V3_USB2A_ALG @BASEBOARD_FAB2_LIB.BASEBOARD_FAB2(SCH_1):P3V3_USB2A_ALG    I91 @BASEBOARD_FAB2_LIB.BASEBOARD_FAB2(SCH_1):PAGE149

R25W121 RES_0402-20.0,1%,1/16W,CHIP,G2A
     1 SMB_PEHPCPU0_STBY_LVC3_R_SDA @BASEBOARD_FAB2_LIB.BASEBOARD_FAB2(SCH_1):SMB_PEHPCPU0_STBY_LVC3_R_SDA   I163 @BASEBOARD_FAB2_LIB.BASEBOARD_FAB2(SCH_1):PAGE145
     2 SMB_PEHPCPU0_STBY_LVC3_R2_SDA @BASEBOARD_FAB2_LIB.BASEBOARD_FAB2(SCH_1):SMB_PEHPCPU0_STBY_LVC3_R2_SDA   I163 @BASEBOARD_FAB2_LIB.BASEBOARD_FAB2(SCH_1):PAGE145

R25W122 RES_0402-20.0,1%,1/16W,CHIP,G2A
     1 SMB_PEHPCPU0_STBY_LVC3_R_SCL @BASEBOARD_FAB2_LIB.BASEBOARD_FAB2(SCH_1):SMB_PEHPCPU0_STBY_LVC3_R_SCL   I164 @BASEBOARD_FAB2_LIB.BASEBOARD_FAB2(SCH_1):PAGE145
     2 SMB_PEHPCPU0_STBY_LVC3_R2_SCL @BASEBOARD_FAB2_LIB.BASEBOARD_FAB2(SCH_1):SMB_PEHPCPU0_STBY_LVC3_R2_SCL   I164 @BASEBOARD_FAB2_LIB.BASEBOARD_FAB2(SCH_1):PAGE145

R25W123 RES_0402-150.0,1%,1/16W,CHIP,GA
     1 BMC_VGA_BLUE @BASEBOARD_FAB2_LIB.BASEBOARD_FAB2(SCH_1):BMC_VGA_BLUE   I139 @BASEBOARD_FAB2_LIB.BASEBOARD_FAB2(SCH_1):PAGE144
     2    GND @BASEBOARD_FAB2_LIB.BASEBOARD_FAB2(SCH_1):GND   I139 @BASEBOARD_FAB2_LIB.BASEBOARD_FAB2(SCH_1):PAGE144

R25W124 RES_0402-150.0,1%,1/16W,CHIP,GA
     1 BMC_VGA_GREEN @BASEBOARD_FAB2_LIB.BASEBOARD_FAB2(SCH_1):BMC_VGA_GREEN   I140 @BASEBOARD_FAB2_LIB.BASEBOARD_FAB2(SCH_1):PAGE144
     2    GND @BASEBOARD_FAB2_LIB.BASEBOARD_FAB2(SCH_1):GND   I140 @BASEBOARD_FAB2_LIB.BASEBOARD_FAB2(SCH_1):PAGE144

R25W125 RES_0402-150.0,1%,1/16W,CHIP,GA
     1 BMC_VGA_RED @BASEBOARD_FAB2_LIB.BASEBOARD_FAB2(SCH_1):BMC_VGA_RED   I141 @BASEBOARD_FAB2_LIB.BASEBOARD_FAB2(SCH_1):PAGE144
     2    GND @BASEBOARD_FAB2_LIB.BASEBOARD_FAB2(SCH_1):GND   I141 @BASEBOARD_FAB2_LIB.BASEBOARD_FAB2(SCH_1):PAGE144

R25W126 RES_0402-150.0,1%,1/16W,CHIP,GA
     1 V_IO_B_J @BASEBOARD_FAB2_LIB.BASEBOARD_FAB2(SCH_1):V_IO_B_J    I26 @BASEBOARD_FAB2_LIB.BASEBOARD_FAB2(SCH_1):PAGE255
     2    GND @BASEBOARD_FAB2_LIB.BASEBOARD_FAB2(SCH_1):GND    I26 @BASEBOARD_FAB2_LIB.BASEBOARD_FAB2(SCH_1):PAGE255

R25W127 RES_0402-150.0,1%,1/16W,CHIP,GA
     1 V_IO_G_J @BASEBOARD_FAB2_LIB.BASEBOARD_FAB2(SCH_1):V_IO_G_J    I24 @BASEBOARD_FAB2_LIB.BASEBOARD_FAB2(SCH_1):PAGE255
     2    GND @BASEBOARD_FAB2_LIB.BASEBOARD_FAB2(SCH_1):GND    I24 @BASEBOARD_FAB2_LIB.BASEBOARD_FAB2(SCH_1):PAGE255

R25W128 RES_0402-150.0,1%,1/16W,CHIP,GA
     1 V_IO_R_J @BASEBOARD_FAB2_LIB.BASEBOARD_FAB2(SCH_1):V_IO_R_J    I22 @BASEBOARD_FAB2_LIB.BASEBOARD_FAB2(SCH_1):PAGE255
     2    GND @BASEBOARD_FAB2_LIB.BASEBOARD_FAB2(SCH_1):GND    I22 @BASEBOARD_FAB2_LIB.BASEBOARD_FAB2(SCH_1):PAGE255

R25W129 RES_0402-4.75K,1%,1/16W,CHIP,GA
     1   P3V3 @BASEBOARD_FAB2_LIB.BASEBOARD_FAB2(SCH_1):P3V3   I152 @BASEBOARD_FAB2_LIB.BASEBOARD_FAB2(SCH_1):PAGE146
     2 I2C_BMC_VGA_DDC_SCL @BASEBOARD_FAB2_LIB.BASEBOARD_FAB2(SCH_1):I2C_BMC_VGA_DDC_SCL   I152 @BASEBOARD_FAB2_LIB.BASEBOARD_FAB2(SCH_1):PAGE146

R25W130 RES_0402-4.75K,1%,1/16W,CHIP,GA
     1   P3V3 @BASEBOARD_FAB2_LIB.BASEBOARD_FAB2(SCH_1):P3V3   I153 @BASEBOARD_FAB2_LIB.BASEBOARD_FAB2(SCH_1):PAGE146
     2 I2C_BMC_VGA_DDC_SDA @BASEBOARD_FAB2_LIB.BASEBOARD_FAB2(SCH_1):I2C_BMC_VGA_DDC_SDA   I153 @BASEBOARD_FAB2_LIB.BASEBOARD_FAB2(SCH_1):PAGE146

R25W131 RES_0402-4.75K,1%,1/16W,CHIP,GA
     1   P3V3 @BASEBOARD_FAB2_LIB.BASEBOARD_FAB2(SCH_1):P3V3    I30 @BASEBOARD_FAB2_LIB.BASEBOARD_FAB2(SCH_1):PAGE255
     2 Q25W1_GATE @BASEBOARD_FAB2_LIB.BASEBOARD_FAB2(SCH_1):Q25W1_GATE    I30 @BASEBOARD_FAB2_LIB.BASEBOARD_FAB2(SCH_1):PAGE255

R25W132 RES_0402-4.75K,1%,1/16W,CHIP,GA
     1 P5V_VGA_D @BASEBOARD_FAB2_LIB.BASEBOARD_FAB2(SCH_1):P5V_VGA_D    I31 @BASEBOARD_FAB2_LIB.BASEBOARD_FAB2(SCH_1):PAGE255
     2 I2C_BMC_VGA_DDC_SCL_G @BASEBOARD_FAB2_LIB.BASEBOARD_FAB2(SCH_1):I2C_BMC_VGA_DDC_SCL_G    I31 @BASEBOARD_FAB2_LIB.BASEBOARD_FAB2(SCH_1):PAGE255

R25W133 RES_0402-33.2,1%,1/16W,CHIP,G2A
     1 I2C_BMC_VGA_DDC_SCL_G @BASEBOARD_FAB2_LIB.BASEBOARD_FAB2(SCH_1):I2C_BMC_VGA_DDC_SCL_G    I34 @BASEBOARD_FAB2_LIB.BASEBOARD_FAB2(SCH_1):PAGE255
     2 V_IBMC_5V_DDC_SCL_J @BASEBOARD_FAB2_LIB.BASEBOARD_FAB2(SCH_1):V_IBMC_5V_DDC_SCL_J    I34 @BASEBOARD_FAB2_LIB.BASEBOARD_FAB2(SCH_1):PAGE255

R25W134 RES_0402-4.75K,1%,1/16W,CHIP,GA
     1   P3V3 @BASEBOARD_FAB2_LIB.BASEBOARD_FAB2(SCH_1):P3V3    I43 @BASEBOARD_FAB2_LIB.BASEBOARD_FAB2(SCH_1):PAGE255
     2 Q25W2_GATE @BASEBOARD_FAB2_LIB.BASEBOARD_FAB2(SCH_1):Q25W2_GATE    I43 @BASEBOARD_FAB2_LIB.BASEBOARD_FAB2(SCH_1):PAGE255

R25W135 RES_0402-4.75K,1%,1/16W,CHIP,GA
     1 P5V_VGA_D @BASEBOARD_FAB2_LIB.BASEBOARD_FAB2(SCH_1):P5V_VGA_D    I44 @BASEBOARD_FAB2_LIB.BASEBOARD_FAB2(SCH_1):PAGE255
     2 I2C_BMC_VGA_DDC_SDA_G @BASEBOARD_FAB2_LIB.BASEBOARD_FAB2(SCH_1):I2C_BMC_VGA_DDC_SDA_G    I44 @BASEBOARD_FAB2_LIB.BASEBOARD_FAB2(SCH_1):PAGE255

R25W136 RES_0402-33.2,1%,1/16W,CHIP,G2A
     1 I2C_BMC_VGA_DDC_SDA_G @BASEBOARD_FAB2_LIB.BASEBOARD_FAB2(SCH_1):I2C_BMC_VGA_DDC_SDA_G    I38 @BASEBOARD_FAB2_LIB.BASEBOARD_FAB2(SCH_1):PAGE255
     2 V_IBMC_5V_DDC_SDA_J @BASEBOARD_FAB2_LIB.BASEBOARD_FAB2(SCH_1):V_IBMC_5V_DDC_SDA_J    I38 @BASEBOARD_FAB2_LIB.BASEBOARD_FAB2(SCH_1):PAGE255

R25W138 RES_0402-33.2,1%,1/16W,CHIP,G2A
     1 VGA_REAR_HSYNC_S @BASEBOARD_FAB2_LIB.BASEBOARD_FAB2(SCH_1):VGA_REAR_HSYNC_S    I49 @BASEBOARD_FAB2_LIB.BASEBOARD_FAB2(SCH_1):PAGE255
     2 V_IO_HSYNC_J @BASEBOARD_FAB2_LIB.BASEBOARD_FAB2(SCH_1):V_IO_HSYNC_J    I49 @BASEBOARD_FAB2_LIB.BASEBOARD_FAB2(SCH_1):PAGE255

R25W139 RES_0402-33.2,1%,1/16W,CHIP,G2A
     1 VGA_REAR_VSYNC_S @BASEBOARD_FAB2_LIB.BASEBOARD_FAB2(SCH_1):VGA_REAR_VSYNC_S    I59 @BASEBOARD_FAB2_LIB.BASEBOARD_FAB2(SCH_1):PAGE255
     2 V_IO_VSYNC_J @BASEBOARD_FAB2_LIB.BASEBOARD_FAB2(SCH_1):V_IO_VSYNC_J    I59 @BASEBOARD_FAB2_LIB.BASEBOARD_FAB2(SCH_1):PAGE255

R25W140 RES_0402-0.0,5%,1/16W,EMPTY,G2A
     1 CLK_48M_USB_BMC @BASEBOARD_FAB2_LIB.BASEBOARD_FAB2(SCH_1):CLK_48M_USB_BMC   I148 @BASEBOARD_FAB2_LIB.BASEBOARD_FAB2(SCH_1):PAGE144
     2 CLK_48M_USB_BMC_R @BASEBOARD_FAB2_LIB.BASEBOARD_FAB2(SCH_1):CLK_48M_USB_BMC_R   I148 @BASEBOARD_FAB2_LIB.BASEBOARD_FAB2(SCH_1):PAGE144

R25W141 RES_0402-0.0,5%,1/16W,CHIP,G21A
     1 RST_PLTRST_BUF_N @BASEBOARD_FAB2_LIB.BASEBOARD_FAB2(SCH_1):RST_PLTRST_BUF_N   I160 @BASEBOARD_FAB2_LIB.BASEBOARD_FAB2(SCH_1):PAGE145
     2 RST_PLTRST_BUF_N_R @BASEBOARD_FAB2_LIB.BASEBOARD_FAB2(SCH_1):RST_PLTRST_BUF_N_R   I160 @BASEBOARD_FAB2_LIB.BASEBOARD_FAB2(SCH_1):PAGE145

R25W142 RES_0402-100.0K,1%,1/16W,CHIP,A
     1 PUMP_TACH1 @BASEBOARD_FAB2_LIB.BASEBOARD_FAB2(SCH_1):PUMP_TACH1   I156 @BASEBOARD_FAB2_LIB.BASEBOARD_FAB2(SCH_1):PAGE147
     2    GND @BASEBOARD_FAB2_LIB.BASEBOARD_FAB2(SCH_1):GND   I156 @BASEBOARD_FAB2_LIB.BASEBOARD_FAB2(SCH_1):PAGE147

R25W143 RES_0402-0.0,5%,1/16W,CHIP,G21A
     1 FM_GLOBAL_RST_WARN_N_R @BASEBOARD_FAB2_LIB.BASEBOARD_FAB2(SCH_1):FM_GLOBAL_RST_WARN_N_R   I159 @BASEBOARD_FAB2_LIB.BASEBOARD_FAB2(SCH_1):PAGE147
     2 FM_GLOBAL_RST_WARN_N @BASEBOARD_FAB2_LIB.BASEBOARD_FAB2(SCH_1):FM_GLOBAL_RST_WARN_N   I159 @BASEBOARD_FAB2_LIB.BASEBOARD_FAB2(SCH_1):PAGE147

R25W144 RES_0402-0.0,5%,1/16W,CHIP,G21A
     1 FM_PWR_BTN_R1_N @BASEBOARD_FAB2_LIB.BASEBOARD_FAB2(SCH_1):FM_PWR_BTN_R1_N   I173 @BASEBOARD_FAB2_LIB.BASEBOARD_FAB2(SCH_1):PAGE145
     2 FM_PWR_BTN_N @BASEBOARD_FAB2_LIB.BASEBOARD_FAB2(SCH_1):FM_PWR_BTN_N   I173 @BASEBOARD_FAB2_LIB.BASEBOARD_FAB2(SCH_1):PAGE145

R25W145 RES_0402-0.0,5%,1/16W,CHIP,G21A
     1 RST_SYSTEM_BTN_R_N @BASEBOARD_FAB2_LIB.BASEBOARD_FAB2(SCH_1):RST_SYSTEM_BTN_R_N   I175 @BASEBOARD_FAB2_LIB.BASEBOARD_FAB2(SCH_1):PAGE145
     2 RST_SYSTEM_BTN_N @BASEBOARD_FAB2_LIB.BASEBOARD_FAB2(SCH_1):RST_SYSTEM_BTN_N   I175 @BASEBOARD_FAB2_LIB.BASEBOARD_FAB2(SCH_1):PAGE145

R25W146 RES_0402-4.75K,1%,1/16W,CHIP,GA
     1    GND @BASEBOARD_FAB2_LIB.BASEBOARD_FAB2(SCH_1):GND   I199 @BASEBOARD_FAB2_LIB.BASEBOARD_FAB2(SCH_1):PAGE150
     2 RMII_BMC_OCP_TXEN @BASEBOARD_FAB2_LIB.BASEBOARD_FAB2(SCH_1):RMII_BMC_OCP_TXEN   I199 @BASEBOARD_FAB2_LIB.BASEBOARD_FAB2(SCH_1):PAGE150

R25W148 RES_0402-4.75K,1%,1/16W,CHIP,GA
     1    GND @BASEBOARD_FAB2_LIB.BASEBOARD_FAB2(SCH_1):GND   I216 @BASEBOARD_FAB2_LIB.BASEBOARD_FAB2(SCH_1):PAGE150
     2 RMII_BMC_OCP_TXD1_R @BASEBOARD_FAB2_LIB.BASEBOARD_FAB2(SCH_1):RMII_BMC_OCP_TXD1_R   I216 @BASEBOARD_FAB2_LIB.BASEBOARD_FAB2(SCH_1):PAGE150

R25W149 RES_0402-4.75K,1%,1/16W,CHIP,GA
     1    GND @BASEBOARD_FAB2_LIB.BASEBOARD_FAB2(SCH_1):GND   I219 @BASEBOARD_FAB2_LIB.BASEBOARD_FAB2(SCH_1):PAGE150
     2 TP_RGMII1TXD2_GPIOT4 @BASEBOARD_FAB2_LIB.BASEBOARD_FAB2(SCH_1):TP_RGMII1TXD2_GPIOT4   I219 @BASEBOARD_FAB2_LIB.BASEBOARD_FAB2(SCH_1):PAGE150

R25W150 RES_0402-4.75K,1%,1/16W,CHIP,GA
     1    GND @BASEBOARD_FAB2_LIB.BASEBOARD_FAB2(SCH_1):GND   I229 @BASEBOARD_FAB2_LIB.BASEBOARD_FAB2(SCH_1):PAGE150
     2 RMII_BMC_PCH_SPRNGVLLE_TXD0_R @BASEBOARD_FAB2_LIB.BASEBOARD_FAB2(SCH_1):RMII_BMC_PCH_SPRNGVLLE_TXD0_R   I229 @BASEBOARD_FAB2_LIB.BASEBOARD_FAB2(SCH_1):PAGE150

R25W151 RES_0402-4.75K,1%,1/16W,CHIP,GA
     1    GND @BASEBOARD_FAB2_LIB.BASEBOARD_FAB2(SCH_1):GND   I232 @BASEBOARD_FAB2_LIB.BASEBOARD_FAB2(SCH_1):PAGE150
     2 RMII_BMC_PCH_SPRNGVLLE_TXD1_R @BASEBOARD_FAB2_LIB.BASEBOARD_FAB2(SCH_1):RMII_BMC_PCH_SPRNGVLLE_TXD1_R   I232 @BASEBOARD_FAB2_LIB.BASEBOARD_FAB2(SCH_1):PAGE150

R25W152 RES_0402-4.75K,1%,1/16W,CHIP,GA
     1    GND @BASEBOARD_FAB2_LIB.BASEBOARD_FAB2(SCH_1):GND   I234 @BASEBOARD_FAB2_LIB.BASEBOARD_FAB2(SCH_1):PAGE150
     2 TP_RGMII2TXD2_GPIOU2 @BASEBOARD_FAB2_LIB.BASEBOARD_FAB2(SCH_1):TP_RGMII2TXD2_GPIOU2   I234 @BASEBOARD_FAB2_LIB.BASEBOARD_FAB2(SCH_1):PAGE150

R25W153 RES_0402-4.75K,1%,1/16W,CHIP,GA
     1 P3V3_STBY @BASEBOARD_FAB2_LIB.BASEBOARD_FAB2(SCH_1):P3V3_STBY   I396 @BASEBOARD_FAB2_LIB.BASEBOARD_FAB2(SCH_1):PAGE157
     2 RST_BMC_SRST_N @BASEBOARD_FAB2_LIB.BASEBOARD_FAB2(SCH_1):RST_BMC_SRST_N   I396 @BASEBOARD_FAB2_LIB.BASEBOARD_FAB2(SCH_1):PAGE157

R25W154 RES_0402-0.0,5%,1/16W,CHIP,G21A
     1 SPI_BMC_BT_WP0_N @BASEBOARD_FAB2_LIB.BASEBOARD_FAB2(SCH_1):SPI_BMC_BT_WP0_N   I133 @BASEBOARD_FAB2_LIB.BASEBOARD_FAB2(SCH_1):PAGE137
     2 TPM_SPI_BMC_WP_N @BASEBOARD_FAB2_LIB.BASEBOARD_FAB2(SCH_1):TPM_SPI_BMC_WP_N   I133 @BASEBOARD_FAB2_LIB.BASEBOARD_FAB2(SCH_1):PAGE137

R25W155 RES_0402-0.0,5%,1/16W,CHIP,G21A
     1 PVCCIO_CPU0 @BASEBOARD_FAB2_LIB.BASEBOARD_FAB2(SCH_1):PVCCIO_CPU0    I29 @BASEBOARD_FAB2_LIB.BASEBOARD_FAB2(SCH_1):PAGE148
     2 PVCCIO_CPU0_R @BASEBOARD_FAB2_LIB.BASEBOARD_FAB2(SCH_1):PVCCIO_CPU0_R    I29 @BASEBOARD_FAB2_LIB.BASEBOARD_FAB2(SCH_1):PAGE148

R25W156 RES_0402-3.32K,1%,1/16W,EMPTY,A
     1 P3V3_STBY @BASEBOARD_FAB2_LIB.BASEBOARD_FAB2(SCH_1):P3V3_STBY   I240 @BASEBOARD_FAB2_LIB.BASEBOARD_FAB2(SCH_1):PAGE150
     2 UART_BMC_TXD5 @BASEBOARD_FAB2_LIB.BASEBOARD_FAB2(SCH_1):UART_BMC_TXD5   I240 @BASEBOARD_FAB2_LIB.BASEBOARD_FAB2(SCH_1):PAGE150

R25W157 RES_0402-100.0K,1%,1/16W,CHIP,A
     1 PUMP_TACH0 @BASEBOARD_FAB2_LIB.BASEBOARD_FAB2(SCH_1):PUMP_TACH0   I164 @BASEBOARD_FAB2_LIB.BASEBOARD_FAB2(SCH_1):PAGE147
     2    GND @BASEBOARD_FAB2_LIB.BASEBOARD_FAB2(SCH_1):GND   I164 @BASEBOARD_FAB2_LIB.BASEBOARD_FAB2(SCH_1):PAGE147

R25W158 RES_0402-1.00K,1%,1/16W,CHIP,GA
     1 P3V3_STBY @BASEBOARD_FAB2_LIB.BASEBOARD_FAB2(SCH_1):P3V3_STBY    I22 @BASEBOARD_FAB2_LIB.BASEBOARD_FAB2(SCH_1):PAGE269
     2 PU_GTL2014_3_DIR @BASEBOARD_FAB2_LIB.BASEBOARD_FAB2(SCH_1):PU_GTL2014_3_DIR    I22 @BASEBOARD_FAB2_LIB.BASEBOARD_FAB2(SCH_1):PAGE269

R25W159 RES_0402-1.00K,1%,1/16W,CHIP,GA
     1    GND @BASEBOARD_FAB2_LIB.BASEBOARD_FAB2(SCH_1):GND    I24 @BASEBOARD_FAB2_LIB.BASEBOARD_FAB2(SCH_1):PAGE269
     2 PD_GTL2014_3_VREF @BASEBOARD_FAB2_LIB.BASEBOARD_FAB2(SCH_1):PD_GTL2014_3_VREF    I24 @BASEBOARD_FAB2_LIB.BASEBOARD_FAB2(SCH_1):PAGE269

R25W160 RES_0402-1.00K,1%,1/16W,CHIP,GA
     1 P3V3_STBY @BASEBOARD_FAB2_LIB.BASEBOARD_FAB2(SCH_1):P3V3_STBY    I20 @BASEBOARD_FAB2_LIB.BASEBOARD_FAB2(SCH_1):PAGE269
     2 JTAG_BMC_BUF_TDI @BASEBOARD_FAB2_LIB.BASEBOARD_FAB2(SCH_1):JTAG_BMC_BUF_TDI    I20 @BASEBOARD_FAB2_LIB.BASEBOARD_FAB2(SCH_1):PAGE269

R25W161 RES_0402-1.00K,1%,1/16W,CHIP,GA
     1 P3V3_STBY @BASEBOARD_FAB2_LIB.BASEBOARD_FAB2(SCH_1):P3V3_STBY    I21 @BASEBOARD_FAB2_LIB.BASEBOARD_FAB2(SCH_1):PAGE269
     2 JTAG_BMC_BUF_TMS @BASEBOARD_FAB2_LIB.BASEBOARD_FAB2(SCH_1):JTAG_BMC_BUF_TMS    I21 @BASEBOARD_FAB2_LIB.BASEBOARD_FAB2(SCH_1):PAGE269

R25W164 RES_0402-49.9,1%,1/16W,CHIP,G2A
     1 P1V05_PCH_STBY @BASEBOARD_FAB2_LIB.BASEBOARD_FAB2(SCH_1):P1V05_PCH_STBY    I29 @BASEBOARD_FAB2_LIB.BASEBOARD_FAB2(SCH_1):PAGE268
     2 P0V7_GTL2014_VREF_6 @BASEBOARD_FAB2_LIB.BASEBOARD_FAB2(SCH_1):P0V7_GTL2014_VREF_6    I29 @BASEBOARD_FAB2_LIB.BASEBOARD_FAB2(SCH_1):PAGE268

R25W165 RES_0402-100.0,1%,1/16W,CHIP,GA
     1 P0V7_GTL2014_VREF_6 @BASEBOARD_FAB2_LIB.BASEBOARD_FAB2(SCH_1):P0V7_GTL2014_VREF_6    I28 @BASEBOARD_FAB2_LIB.BASEBOARD_FAB2(SCH_1):PAGE268
     2    GND @BASEBOARD_FAB2_LIB.BASEBOARD_FAB2(SCH_1):GND    I28 @BASEBOARD_FAB2_LIB.BASEBOARD_FAB2(SCH_1):PAGE268

R25W166 RES_0402-1.00K,1%,1/16W,CHIP,GA
     1 PD_GTL2014_DIR_6 @BASEBOARD_FAB2_LIB.BASEBOARD_FAB2(SCH_1):PD_GTL2014_DIR_6    I26 @BASEBOARD_FAB2_LIB.BASEBOARD_FAB2(SCH_1):PAGE268
     2    GND @BASEBOARD_FAB2_LIB.BASEBOARD_FAB2(SCH_1):GND    I26 @BASEBOARD_FAB2_LIB.BASEBOARD_FAB2(SCH_1):PAGE268

R25W167 RES_0402-1.00K,1%,1/16W,CHIP,GA
     1 BMC_TCK_MUX_SEL @BASEBOARD_FAB2_LIB.BASEBOARD_FAB2(SCH_1):BMC_TCK_MUX_SEL    I10 @BASEBOARD_FAB2_LIB.BASEBOARD_FAB2(SCH_1):PAGE269
     2    GND @BASEBOARD_FAB2_LIB.BASEBOARD_FAB2(SCH_1):GND    I10 @BASEBOARD_FAB2_LIB.BASEBOARD_FAB2(SCH_1):PAGE269

R25W168 RES_0402-1.00K,1%,1/16W,CHIP,GA
     1 JTAG_BMC_TCK0 @BASEBOARD_FAB2_LIB.BASEBOARD_FAB2(SCH_1):JTAG_BMC_TCK0    I11 @BASEBOARD_FAB2_LIB.BASEBOARD_FAB2(SCH_1):PAGE269
     2    GND @BASEBOARD_FAB2_LIB.BASEBOARD_FAB2(SCH_1):GND    I11 @BASEBOARD_FAB2_LIB.BASEBOARD_FAB2(SCH_1):PAGE269

R25W169 RES_0402-1.00K,1%,1/16W,CHIP,GA
     1 JTAG_BMC_TCK1 @BASEBOARD_FAB2_LIB.BASEBOARD_FAB2(SCH_1):JTAG_BMC_TCK1    I12 @BASEBOARD_FAB2_LIB.BASEBOARD_FAB2(SCH_1):PAGE269
     2    GND @BASEBOARD_FAB2_LIB.BASEBOARD_FAB2(SCH_1):GND    I12 @BASEBOARD_FAB2_LIB.BASEBOARD_FAB2(SCH_1):PAGE269

R25W170 RES_0402-1.00K,1%,1/16W,CHIP,GA
     1 JTAG_BMC_TRST_BUF_N @BASEBOARD_FAB2_LIB.BASEBOARD_FAB2(SCH_1):JTAG_BMC_TRST_BUF_N    I13 @BASEBOARD_FAB2_LIB.BASEBOARD_FAB2(SCH_1):PAGE269
     2    GND @BASEBOARD_FAB2_LIB.BASEBOARD_FAB2(SCH_1):GND    I13 @BASEBOARD_FAB2_LIB.BASEBOARD_FAB2(SCH_1):PAGE269

R25W174 RES_0402-10.0K,1%,1/16W,CHIP,GA
     1 P3V3_STBY @BASEBOARD_FAB2_LIB.BASEBOARD_FAB2(SCH_1):P3V3_STBY     I4 @BASEBOARD_FAB2_LIB.BASEBOARD_FAB2(SCH_1):PAGE269
     2 BMC_JTAG_SEL_N @BASEBOARD_FAB2_LIB.BASEBOARD_FAB2(SCH_1):BMC_JTAG_SEL_N     I4 @BASEBOARD_FAB2_LIB.BASEBOARD_FAB2(SCH_1):PAGE269

R25W175 RES_0402-1.00K,1%,1/16W,CHIP,GA
     1 PD_GTL2014_6_B0 @BASEBOARD_FAB2_LIB.BASEBOARD_FAB2(SCH_1):PD_GTL2014_6_B0    I17 @BASEBOARD_FAB2_LIB.BASEBOARD_FAB2(SCH_1):PAGE268
     2    GND @BASEBOARD_FAB2_LIB.BASEBOARD_FAB2(SCH_1):GND    I17 @BASEBOARD_FAB2_LIB.BASEBOARD_FAB2(SCH_1):PAGE268

R25W176 RES_0402-1.00K,1%,1/16W,CHIP,GA
     1 PD_GTL2014_6_B2 @BASEBOARD_FAB2_LIB.BASEBOARD_FAB2(SCH_1):PD_GTL2014_6_B2    I14 @BASEBOARD_FAB2_LIB.BASEBOARD_FAB2(SCH_1):PAGE268
     2    GND @BASEBOARD_FAB2_LIB.BASEBOARD_FAB2(SCH_1):GND    I14 @BASEBOARD_FAB2_LIB.BASEBOARD_FAB2(SCH_1):PAGE268

R25W177 RES_0402-1.00K,1%,1/16W,CHIP,GA
     1 P3V3_STBY @BASEBOARD_FAB2_LIB.BASEBOARD_FAB2(SCH_1):P3V3_STBY    I18 @BASEBOARD_FAB2_LIB.BASEBOARD_FAB2(SCH_1):PAGE269
     2 BMC_PREQ_BUF_N @BASEBOARD_FAB2_LIB.BASEBOARD_FAB2(SCH_1):BMC_PREQ_BUF_N    I18 @BASEBOARD_FAB2_LIB.BASEBOARD_FAB2(SCH_1):PAGE269

R25W178 RES_0402-1.00K,1%,1/16W,CHIP,GA
     1 P3V3_STBY @BASEBOARD_FAB2_LIB.BASEBOARD_FAB2(SCH_1):P3V3_STBY    I19 @BASEBOARD_FAB2_LIB.BASEBOARD_FAB2(SCH_1):PAGE269
     2 BMC_PWR_DEBUG_BUF_N @BASEBOARD_FAB2_LIB.BASEBOARD_FAB2(SCH_1):BMC_PWR_DEBUG_BUF_N    I19 @BASEBOARD_FAB2_LIB.BASEBOARD_FAB2(SCH_1):PAGE269

R25W179 RES_0402-1.00K,1%,1/16W,CHIP,GA
     1 P3V3_STBY @BASEBOARD_FAB2_LIB.BASEBOARD_FAB2(SCH_1):P3V3_STBY     I7 @BASEBOARD_FAB2_LIB.BASEBOARD_FAB2(SCH_1):PAGE268
     2 XDP_PRESENT_N @BASEBOARD_FAB2_LIB.BASEBOARD_FAB2(SCH_1):XDP_PRESENT_N     I7 @BASEBOARD_FAB2_LIB.BASEBOARD_FAB2(SCH_1):PAGE268

R25W180 RES_0402-1.00K,1%,1/16W,CHIP,GA
     1 P3V3_STBY @BASEBOARD_FAB2_LIB.BASEBOARD_FAB2(SCH_1):P3V3_STBY     I2 @BASEBOARD_FAB2_LIB.BASEBOARD_FAB2(SCH_1):PAGE268
     2 BMC_DEBUG_EN_N @BASEBOARD_FAB2_LIB.BASEBOARD_FAB2(SCH_1):BMC_DEBUG_EN_N     I2 @BASEBOARD_FAB2_LIB.BASEBOARD_FAB2(SCH_1):PAGE268

R25W181 RES_0402-0.0,5%,1/16W,CHIP,G21A
     1 RST_RSMRST_N @BASEBOARD_FAB2_LIB.BASEBOARD_FAB2(SCH_1):RST_RSMRST_N   I173 @BASEBOARD_FAB2_LIB.BASEBOARD_FAB2(SCH_1):PAGE147
     2 BMC_RSMRST_B_N @BASEBOARD_FAB2_LIB.BASEBOARD_FAB2(SCH_1):BMC_RSMRST_B_N   I173 @BASEBOARD_FAB2_LIB.BASEBOARD_FAB2(SCH_1):PAGE147

R25W182 RES_0402-0.0,5%,1/16W,CHIP,G21A
     1 XDP_SYSPWROK @BASEBOARD_FAB2_LIB.BASEBOARD_FAB2(SCH_1):XDP_SYSPWROK   I151 @BASEBOARD_FAB2_LIB.BASEBOARD_FAB2(SCH_1):PAGE144
     2 PWRGD_SYS_PWROK @BASEBOARD_FAB2_LIB.BASEBOARD_FAB2(SCH_1):PWRGD_SYS_PWROK   I151 @BASEBOARD_FAB2_LIB.BASEBOARD_FAB2(SCH_1):PAGE144

R25W183 374R2F-1-GP_SMD-RG-374R2F-1-GPA
     1 P3V3_STBY @BASEBOARD_FAB2_LIB.BASEBOARD_FAB2(SCH_1):P3V3_STBY    I36 @BASEBOARD_FAB2_LIB.BASEBOARD_FAB2(SCH_1):PAGE268
     2 P0V7_GTL2014_VREF_6 @BASEBOARD_FAB2_LIB.BASEBOARD_FAB2(SCH_1):P0V7_GTL2014_VREF_6    I36 @BASEBOARD_FAB2_LIB.BASEBOARD_FAB2(SCH_1):PAGE268

R25W184 RES_0402-0.0,5%,1/16W,CHIP,G21A
     1 RST_BMC_PLTRST_BUF_N @BASEBOARD_FAB2_LIB.BASEBOARD_FAB2(SCH_1):RST_BMC_PLTRST_BUF_N   I166 @BASEBOARD_FAB2_LIB.BASEBOARD_FAB2(SCH_1):PAGE146
     2 RST_PLTRST_BUF_N @BASEBOARD_FAB2_LIB.BASEBOARD_FAB2(SCH_1):RST_PLTRST_BUF_N   I166 @BASEBOARD_FAB2_LIB.BASEBOARD_FAB2(SCH_1):PAGE146

R25W185 RES_0402-4.75K,1%,1/16W,CHIP,GA
     1 P3V3_STBY @BASEBOARD_FAB2_LIB.BASEBOARD_FAB2(SCH_1):P3V3_STBY    I54 @BASEBOARD_FAB2_LIB.BASEBOARD_FAB2(SCH_1):PAGE268
     2 BMC_JTAG_SEL @BASEBOARD_FAB2_LIB.BASEBOARD_FAB2(SCH_1):BMC_JTAG_SEL    I54 @BASEBOARD_FAB2_LIB.BASEBOARD_FAB2(SCH_1):PAGE268

R25W186 RES_0402-0.0,5%,1/16W,CHIP,G21A
     1 BMC_JTAG_SEL_N @BASEBOARD_FAB2_LIB.BASEBOARD_FAB2(SCH_1):BMC_JTAG_SEL_N    I77 @BASEBOARD_FAB2_LIB.BASEBOARD_FAB2(SCH_1):PAGE189
     2 FM_JTAG_PLD_EN_DEBUG @BASEBOARD_FAB2_LIB.BASEBOARD_FAB2(SCH_1):FM_JTAG_PLD_EN_DEBUG    I77 @BASEBOARD_FAB2_LIB.BASEBOARD_FAB2(SCH_1):PAGE189

R25W187 RES_0402-0.0,5%,1/16W,CHIP,G21A
     1 JTAG_BMC_BUF_TDO_R @BASEBOARD_FAB2_LIB.BASEBOARD_FAB2(SCH_1):JTAG_BMC_BUF_TDO_R    I66 @BASEBOARD_FAB2_LIB.BASEBOARD_FAB2(SCH_1):PAGE268
     2 JTAG_BMC_BUF_TDO @BASEBOARD_FAB2_LIB.BASEBOARD_FAB2(SCH_1):JTAG_BMC_BUF_TDO    I66 @BASEBOARD_FAB2_LIB.BASEBOARD_FAB2(SCH_1):PAGE268

R30W1 RES_0402-0.0,5%,1/16W,CHIP,G21A
     1 USB3_P01_RXN @BASEBOARD_FAB2_LIB.BASEBOARD_FAB2(SCH_1):USB3_P01_RXN    I13 @BASEBOARD_FAB2_LIB.BASEBOARD_FAB2(SCH_1):PAGE253
     2 USB3_P01_FB_RXN @BASEBOARD_FAB2_LIB.BASEBOARD_FAB2(SCH_1):USB3_P01_FB_RXN    I13 @BASEBOARD_FAB2_LIB.BASEBOARD_FAB2(SCH_1):PAGE253

R30W2 RES_0402-0.0,5%,1/16W,CHIP,G21A
     1 USB3_P01_RXP @BASEBOARD_FAB2_LIB.BASEBOARD_FAB2(SCH_1):USB3_P01_RXP    I12 @BASEBOARD_FAB2_LIB.BASEBOARD_FAB2(SCH_1):PAGE253
     2 USB3_P01_FB_RXP @BASEBOARD_FAB2_LIB.BASEBOARD_FAB2(SCH_1):USB3_P01_FB_RXP    I12 @BASEBOARD_FAB2_LIB.BASEBOARD_FAB2(SCH_1):PAGE253

R30W3 RES_0402-0.0,5%,1/16W,CHIP,G21A
     1 USB3_P01_C_TXN @BASEBOARD_FAB2_LIB.BASEBOARD_FAB2(SCH_1):USB3_P01_C_TXN    I15 @BASEBOARD_FAB2_LIB.BASEBOARD_FAB2(SCH_1):PAGE253
     2 USB3_P01_FB_TXN @BASEBOARD_FAB2_LIB.BASEBOARD_FAB2(SCH_1):USB3_P01_FB_TXN    I15 @BASEBOARD_FAB2_LIB.BASEBOARD_FAB2(SCH_1):PAGE253

R30W4 RES_0402-0.0,5%,1/16W,CHIP,G21A
     1 USB3_P01_C_TXP @BASEBOARD_FAB2_LIB.BASEBOARD_FAB2(SCH_1):USB3_P01_C_TXP    I14 @BASEBOARD_FAB2_LIB.BASEBOARD_FAB2(SCH_1):PAGE253
     2 USB3_P01_FB_TXP @BASEBOARD_FAB2_LIB.BASEBOARD_FAB2(SCH_1):USB3_P01_FB_TXP    I14 @BASEBOARD_FAB2_LIB.BASEBOARD_FAB2(SCH_1):PAGE253

R32W1 RES_0402-4.02K,1%,1/16W,CHIP,GA
     1   P3V3 @BASEBOARD_FAB2_LIB.BASEBOARD_FAB2(SCH_1):P3V3   I208 @BASEBOARD_FAB2_LIB.BASEBOARD_FAB2(SCH_1):PAGE185
     2 P1V8_M2 @BASEBOARD_FAB2_LIB.BASEBOARD_FAB2(SCH_1):P1V8_M2   I208 @BASEBOARD_FAB2_LIB.BASEBOARD_FAB2(SCH_1):PAGE185

R32W2 RES_0402-1.5K,1%,1/16W,CHIP,G2A
     1 P1V8_M2 @BASEBOARD_FAB2_LIB.BASEBOARD_FAB2(SCH_1):P1V8_M2   I207 @BASEBOARD_FAB2_LIB.BASEBOARD_FAB2(SCH_1):PAGE185
     2 VREF_LMV431_1V42 @BASEBOARD_FAB2_LIB.BASEBOARD_FAB2(SCH_1):VREF_LMV431_1V42   I207 @BASEBOARD_FAB2_LIB.BASEBOARD_FAB2(SCH_1):PAGE185

R32W3 RES_0402-3.3K,5%,1/16W,CHIP,G2A
     1 VREF_LMV431_1V42 @BASEBOARD_FAB2_LIB.BASEBOARD_FAB2(SCH_1):VREF_LMV431_1V42   I206 @BASEBOARD_FAB2_LIB.BASEBOARD_FAB2(SCH_1):PAGE185
     2    GND @BASEBOARD_FAB2_LIB.BASEBOARD_FAB2(SCH_1):GND   I206 @BASEBOARD_FAB2_LIB.BASEBOARD_FAB2(SCH_1):PAGE185

R32W4 RES_0402-49.9K,1%,1/16W,CHIP,GA
     1 P1V8_M2 @BASEBOARD_FAB2_LIB.BASEBOARD_FAB2(SCH_1):P1V8_M2   I211 @BASEBOARD_FAB2_LIB.BASEBOARD_FAB2(SCH_1):PAGE185
     2    GND @BASEBOARD_FAB2_LIB.BASEBOARD_FAB2(SCH_1):GND   I211 @BASEBOARD_FAB2_LIB.BASEBOARD_FAB2(SCH_1):PAGE185

R32W5 RES_0402-2.0K,1%,1/16W,CHIP,G2A
     1 P1V8_M2 @BASEBOARD_FAB2_LIB.BASEBOARD_FAB2(SCH_1):P1V8_M2   I216 @BASEBOARD_FAB2_LIB.BASEBOARD_FAB2(SCH_1):PAGE185
     2 SMB_M2_SCL @BASEBOARD_FAB2_LIB.BASEBOARD_FAB2(SCH_1):SMB_M2_SCL   I216 @BASEBOARD_FAB2_LIB.BASEBOARD_FAB2(SCH_1):PAGE185

R32W6 RES_0402-2.0K,1%,1/16W,CHIP,G2A
     1 P1V8_M2 @BASEBOARD_FAB2_LIB.BASEBOARD_FAB2(SCH_1):P1V8_M2   I214 @BASEBOARD_FAB2_LIB.BASEBOARD_FAB2(SCH_1):PAGE185
     2 SMB_M2_SDA @BASEBOARD_FAB2_LIB.BASEBOARD_FAB2(SCH_1):SMB_M2_SDA   I214 @BASEBOARD_FAB2_LIB.BASEBOARD_FAB2(SCH_1):PAGE185

R32W7 RES_0402-2.0K,1%,1/16W,CHIP,G2A
     1 P1V8_M2 @BASEBOARD_FAB2_LIB.BASEBOARD_FAB2(SCH_1):P1V8_M2   I215 @BASEBOARD_FAB2_LIB.BASEBOARD_FAB2(SCH_1):PAGE185
     2 SMB_M2_ALT_N @BASEBOARD_FAB2_LIB.BASEBOARD_FAB2(SCH_1):SMB_M2_ALT_N   I215 @BASEBOARD_FAB2_LIB.BASEBOARD_FAB2(SCH_1):PAGE185

R32W9 RES_0402-10.0K,1%,1/16W,CHIP,GA
     1 PD_SMB_M2_EN @BASEBOARD_FAB2_LIB.BASEBOARD_FAB2(SCH_1):PD_SMB_M2_EN   I200 @BASEBOARD_FAB2_LIB.BASEBOARD_FAB2(SCH_1):PAGE185
     2    GND @BASEBOARD_FAB2_LIB.BASEBOARD_FAB2(SCH_1):GND   I200 @BASEBOARD_FAB2_LIB.BASEBOARD_FAB2(SCH_1):PAGE185

R32W10 RES_0402-0.0,5%,1/16W,CHIP,G21A
     1 SMB_M2_SCL @BASEBOARD_FAB2_LIB.BASEBOARD_FAB2(SCH_1):SMB_M2_SCL   I183 @BASEBOARD_FAB2_LIB.BASEBOARD_FAB2(SCH_1):PAGE185
     2 SMB_M2_SCL_R @BASEBOARD_FAB2_LIB.BASEBOARD_FAB2(SCH_1):SMB_M2_SCL_R   I183 @BASEBOARD_FAB2_LIB.BASEBOARD_FAB2(SCH_1):PAGE185

R32W11 RES_0402-0.0,5%,1/16W,CHIP,G21A
     1 SMB_M2_SDA @BASEBOARD_FAB2_LIB.BASEBOARD_FAB2(SCH_1):SMB_M2_SDA   I184 @BASEBOARD_FAB2_LIB.BASEBOARD_FAB2(SCH_1):PAGE185
     2 SMB_M2_SDA_R @BASEBOARD_FAB2_LIB.BASEBOARD_FAB2(SCH_1):SMB_M2_SDA_R   I184 @BASEBOARD_FAB2_LIB.BASEBOARD_FAB2(SCH_1):PAGE185

R32W12 RES_0402-0.0,5%,1/16W,CHIP,G21A
     1 SMB_M2_ALT_N @BASEBOARD_FAB2_LIB.BASEBOARD_FAB2(SCH_1):SMB_M2_ALT_N   I187 @BASEBOARD_FAB2_LIB.BASEBOARD_FAB2(SCH_1):PAGE185
     2 SMB_M2_ALT_R_N @BASEBOARD_FAB2_LIB.BASEBOARD_FAB2(SCH_1):SMB_M2_ALT_R_N   I187 @BASEBOARD_FAB2_LIB.BASEBOARD_FAB2(SCH_1):PAGE185

R760 RES_0402-0.0,5%,1/16W,CHIP,G21A
     1 P3E_CPU0_PE1_PCH_RXN<15> @BASEBOARD_FAB2_LIB.BASEBOARD_FAB2(SCH_1):P3E_CPU0_PE1_PCH_RXN(15)    I64 @BASEBOARD_FAB2_LIB.BASEBOARD_FAB2(SCH_1):PAGE244
     2 P3E_CPU0_PE1_PCH_CON_RXN<15> @BASEBOARD_FAB2_LIB.BASEBOARD_FAB2(SCH_1):P3E_CPU0_PE1_PCH_CON_RXN(15)    I64 @BASEBOARD_FAB2_LIB.BASEBOARD_FAB2(SCH_1):PAGE244

R767 RES_0402-0.0,5%,1/16W,CHIP,G21A
     1 P3E_CPU0_PE1_PCH_RXP<15> @BASEBOARD_FAB2_LIB.BASEBOARD_FAB2(SCH_1):P3E_CPU0_PE1_PCH_RXP(15)    I39 @BASEBOARD_FAB2_LIB.BASEBOARD_FAB2(SCH_1):PAGE244
     2 P3E_CPU0_PE1_PCH_CON_RXP<15> @BASEBOARD_FAB2_LIB.BASEBOARD_FAB2(SCH_1):P3E_CPU0_PE1_PCH_CON_RXP(15)    I39 @BASEBOARD_FAB2_LIB.BASEBOARD_FAB2(SCH_1):PAGE244

R768 RES_0402-0.0,5%,1/16W,CHIP,G21A
     1 P3E_CPU0_PE1_PCH_RXN<14> @BASEBOARD_FAB2_LIB.BASEBOARD_FAB2(SCH_1):P3E_CPU0_PE1_PCH_RXN(14)    I66 @BASEBOARD_FAB2_LIB.BASEBOARD_FAB2(SCH_1):PAGE244
     2 P3E_CPU0_PE1_PCH_CON_RXN<14> @BASEBOARD_FAB2_LIB.BASEBOARD_FAB2(SCH_1):P3E_CPU0_PE1_PCH_CON_RXN(14)    I66 @BASEBOARD_FAB2_LIB.BASEBOARD_FAB2(SCH_1):PAGE244

R769 RES_0402-0.0,5%,1/16W,CHIP,G21A
     1 P3E_CPU0_PE1_PCH_RXP<14> @BASEBOARD_FAB2_LIB.BASEBOARD_FAB2(SCH_1):P3E_CPU0_PE1_PCH_RXP(14)    I58 @BASEBOARD_FAB2_LIB.BASEBOARD_FAB2(SCH_1):PAGE244
     2 P3E_CPU0_PE1_PCH_CON_RXP<14> @BASEBOARD_FAB2_LIB.BASEBOARD_FAB2(SCH_1):P3E_CPU0_PE1_PCH_CON_RXP(14)    I58 @BASEBOARD_FAB2_LIB.BASEBOARD_FAB2(SCH_1):PAGE244

R771 RES_0402-0.0,5%,1/16W,CHIP,G21A
     1 P3E_CPU0_PE1_PCH_RXN<13> @BASEBOARD_FAB2_LIB.BASEBOARD_FAB2(SCH_1):P3E_CPU0_PE1_PCH_RXN(13)    I65 @BASEBOARD_FAB2_LIB.BASEBOARD_FAB2(SCH_1):PAGE244
     2 P3E_CPU0_PE1_PCH_CON_RXN<13> @BASEBOARD_FAB2_LIB.BASEBOARD_FAB2(SCH_1):P3E_CPU0_PE1_PCH_CON_RXN(13)    I65 @BASEBOARD_FAB2_LIB.BASEBOARD_FAB2(SCH_1):PAGE244

R774 RES_0402-0.0,5%,1/16W,CHIP,G21A
     1 P3E_CPU0_PE1_PCH_RXP<13> @BASEBOARD_FAB2_LIB.BASEBOARD_FAB2(SCH_1):P3E_CPU0_PE1_PCH_RXP(13)    I72 @BASEBOARD_FAB2_LIB.BASEBOARD_FAB2(SCH_1):PAGE244
     2 P3E_CPU0_PE1_PCH_CON_RXP<13> @BASEBOARD_FAB2_LIB.BASEBOARD_FAB2(SCH_1):P3E_CPU0_PE1_PCH_CON_RXP(13)    I72 @BASEBOARD_FAB2_LIB.BASEBOARD_FAB2(SCH_1):PAGE244

R775 RES_0402-0.0,5%,1/16W,CHIP,G21A
     1 P3E_CPU0_PE1_PCH_RXN<12> @BASEBOARD_FAB2_LIB.BASEBOARD_FAB2(SCH_1):P3E_CPU0_PE1_PCH_RXN(12)    I93 @BASEBOARD_FAB2_LIB.BASEBOARD_FAB2(SCH_1):PAGE244
     2 P3E_CPU0_PE1_PCH_CON_RXN<12> @BASEBOARD_FAB2_LIB.BASEBOARD_FAB2(SCH_1):P3E_CPU0_PE1_PCH_CON_RXN(12)    I93 @BASEBOARD_FAB2_LIB.BASEBOARD_FAB2(SCH_1):PAGE244

R777 RES_0402-0.0,5%,1/16W,CHIP,G21A
     1 P3E_CPU0_PE1_PCH_RXP<12> @BASEBOARD_FAB2_LIB.BASEBOARD_FAB2(SCH_1):P3E_CPU0_PE1_PCH_RXP(12)    I80 @BASEBOARD_FAB2_LIB.BASEBOARD_FAB2(SCH_1):PAGE244
     2 P3E_CPU0_PE1_PCH_CON_RXP<12> @BASEBOARD_FAB2_LIB.BASEBOARD_FAB2(SCH_1):P3E_CPU0_PE1_PCH_CON_RXP(12)    I80 @BASEBOARD_FAB2_LIB.BASEBOARD_FAB2(SCH_1):PAGE244

R778 RES_0402-0.0,5%,1/16W,CHIP,G21A
     1 P3E_CPU0_PE1_PCH_RXN<11> @BASEBOARD_FAB2_LIB.BASEBOARD_FAB2(SCH_1):P3E_CPU0_PE1_PCH_RXN(11)    I94 @BASEBOARD_FAB2_LIB.BASEBOARD_FAB2(SCH_1):PAGE244
     2 P3E_CPU0_PE1_PCH_CON_RXN<11> @BASEBOARD_FAB2_LIB.BASEBOARD_FAB2(SCH_1):P3E_CPU0_PE1_PCH_CON_RXN(11)    I94 @BASEBOARD_FAB2_LIB.BASEBOARD_FAB2(SCH_1):PAGE244

R779 RES_0402-0.0,5%,1/16W,CHIP,G21A
     1 P3E_CPU0_PE1_PCH_RXP<11> @BASEBOARD_FAB2_LIB.BASEBOARD_FAB2(SCH_1):P3E_CPU0_PE1_PCH_RXP(11)    I74 @BASEBOARD_FAB2_LIB.BASEBOARD_FAB2(SCH_1):PAGE244
     2 P3E_CPU0_PE1_PCH_CON_RXP<11> @BASEBOARD_FAB2_LIB.BASEBOARD_FAB2(SCH_1):P3E_CPU0_PE1_PCH_CON_RXP(11)    I74 @BASEBOARD_FAB2_LIB.BASEBOARD_FAB2(SCH_1):PAGE244

R780 RES_0402-0.0,5%,1/16W,CHIP,G21A
     1 P3E_CPU0_PE1_PCH_RXN<10> @BASEBOARD_FAB2_LIB.BASEBOARD_FAB2(SCH_1):P3E_CPU0_PE1_PCH_RXN(10)    I97 @BASEBOARD_FAB2_LIB.BASEBOARD_FAB2(SCH_1):PAGE244
     2 P3E_CPU0_PE1_PCH_CON_RXN<10> @BASEBOARD_FAB2_LIB.BASEBOARD_FAB2(SCH_1):P3E_CPU0_PE1_PCH_CON_RXN(10)    I97 @BASEBOARD_FAB2_LIB.BASEBOARD_FAB2(SCH_1):PAGE244

R781 RES_0402-0.0,5%,1/16W,CHIP,G21A
     1 P3E_CPU0_PE1_PCH_RXP<10> @BASEBOARD_FAB2_LIB.BASEBOARD_FAB2(SCH_1):P3E_CPU0_PE1_PCH_RXP(10)    I86 @BASEBOARD_FAB2_LIB.BASEBOARD_FAB2(SCH_1):PAGE244
     2 P3E_CPU0_PE1_PCH_CON_RXP<10> @BASEBOARD_FAB2_LIB.BASEBOARD_FAB2(SCH_1):P3E_CPU0_PE1_PCH_CON_RXP(10)    I86 @BASEBOARD_FAB2_LIB.BASEBOARD_FAB2(SCH_1):PAGE244

R782 RES_0402-0.0,5%,1/16W,CHIP,G21A
     1 P3E_CPU0_PE1_PCH_RXN<9> @BASEBOARD_FAB2_LIB.BASEBOARD_FAB2(SCH_1):P3E_CPU0_PE1_PCH_RXN(9)    I98 @BASEBOARD_FAB2_LIB.BASEBOARD_FAB2(SCH_1):PAGE244
     2 P3E_CPU0_PE1_PCH_CON_RXN<9> @BASEBOARD_FAB2_LIB.BASEBOARD_FAB2(SCH_1):P3E_CPU0_PE1_PCH_CON_RXN(9)    I98 @BASEBOARD_FAB2_LIB.BASEBOARD_FAB2(SCH_1):PAGE244

R783 RES_0402-0.0,5%,1/16W,CHIP,G21A
     1 P3E_CPU0_PE1_PCH_RXP<9> @BASEBOARD_FAB2_LIB.BASEBOARD_FAB2(SCH_1):P3E_CPU0_PE1_PCH_RXP(9)    I77 @BASEBOARD_FAB2_LIB.BASEBOARD_FAB2(SCH_1):PAGE244
     2 P3E_CPU0_PE1_PCH_CON_RXP<9> @BASEBOARD_FAB2_LIB.BASEBOARD_FAB2(SCH_1):P3E_CPU0_PE1_PCH_CON_RXP(9)    I77 @BASEBOARD_FAB2_LIB.BASEBOARD_FAB2(SCH_1):PAGE244

R784 RES_0402-0.0,5%,1/16W,CHIP,G21A
     1 P3E_CPU0_PE1_PCH_RXN<8> @BASEBOARD_FAB2_LIB.BASEBOARD_FAB2(SCH_1):P3E_CPU0_PE1_PCH_RXN(8)    I99 @BASEBOARD_FAB2_LIB.BASEBOARD_FAB2(SCH_1):PAGE244
     2 P3E_CPU0_PE1_PCH_CON_RXN<8> @BASEBOARD_FAB2_LIB.BASEBOARD_FAB2(SCH_1):P3E_CPU0_PE1_PCH_CON_RXN(8)    I99 @BASEBOARD_FAB2_LIB.BASEBOARD_FAB2(SCH_1):PAGE244

R785 RES_0402-0.0,5%,1/16W,CHIP,G21A
     1 P3E_CPU0_PE1_PCH_RXP<8> @BASEBOARD_FAB2_LIB.BASEBOARD_FAB2(SCH_1):P3E_CPU0_PE1_PCH_RXP(8)   I103 @BASEBOARD_FAB2_LIB.BASEBOARD_FAB2(SCH_1):PAGE244
     2 P3E_CPU0_PE1_PCH_CON_RXP<8> @BASEBOARD_FAB2_LIB.BASEBOARD_FAB2(SCH_1):P3E_CPU0_PE1_PCH_CON_RXP(8)   I103 @BASEBOARD_FAB2_LIB.BASEBOARD_FAB2(SCH_1):PAGE244

 RF1 RES_0402-1.0K,0.1%,1/16W,CHIP,A
     1 VR_PVCCIN_CPU0_AIREF1 @BASEBOARD_FAB2_LIB.BASEBOARD_FAB2(SCH_1):VR_PVCCIN_CPU0_AIREF1   I182 @BASEBOARD_FAB2_LIB.BASEBOARD_FAB2(SCH_1):PAGE201
     2 ISENSE_PVCCIN_CPU0_PH1_IMON @BASEBOARD_FAB2_LIB.BASEBOARD_FAB2(SCH_1):ISENSE_PVCCIN_CPU0_PH1_IMON   I182 @BASEBOARD_FAB2_LIB.BASEBOARD_FAB2(SCH_1):PAGE201

 RF2 RES_0402-1.0K,0.1%,1/16W,CHIP,A
     1 VR_PVCCIN_CPU0_AIREF2 @BASEBOARD_FAB2_LIB.BASEBOARD_FAB2(SCH_1):VR_PVCCIN_CPU0_AIREF2   I183 @BASEBOARD_FAB2_LIB.BASEBOARD_FAB2(SCH_1):PAGE201
     2 ISENSE_PVCCIN_CPU0_PH2_IMON @BASEBOARD_FAB2_LIB.BASEBOARD_FAB2(SCH_1):ISENSE_PVCCIN_CPU0_PH2_IMON   I183 @BASEBOARD_FAB2_LIB.BASEBOARD_FAB2(SCH_1):PAGE201

 RF3 RES_0402-1.0K,0.1%,1/16W,CHIP,A
     1 VR_PVCCIN_CPU0_AIREF3 @BASEBOARD_FAB2_LIB.BASEBOARD_FAB2(SCH_1):VR_PVCCIN_CPU0_AIREF3   I184 @BASEBOARD_FAB2_LIB.BASEBOARD_FAB2(SCH_1):PAGE201
     2 ISENSE_PVCCIN_CPU0_PH3_IMON @BASEBOARD_FAB2_LIB.BASEBOARD_FAB2(SCH_1):ISENSE_PVCCIN_CPU0_PH3_IMON   I184 @BASEBOARD_FAB2_LIB.BASEBOARD_FAB2(SCH_1):PAGE201

 RF4 RES_0402-1.0K,0.1%,1/16W,CHIP,A
     1 VR_PVCCIN_CPU0_AIREF4 @BASEBOARD_FAB2_LIB.BASEBOARD_FAB2(SCH_1):VR_PVCCIN_CPU0_AIREF4   I185 @BASEBOARD_FAB2_LIB.BASEBOARD_FAB2(SCH_1):PAGE201
     2 ISENSE_PVCCIN_CPU0_PH4_IMON @BASEBOARD_FAB2_LIB.BASEBOARD_FAB2(SCH_1):ISENSE_PVCCIN_CPU0_PH4_IMON   I185 @BASEBOARD_FAB2_LIB.BASEBOARD_FAB2(SCH_1):PAGE201

 RF5 RES_0402-1.0K,0.1%,1/16W,CHIP,A
     1 VR_PVCCIN_CPU0_AIREF5 @BASEBOARD_FAB2_LIB.BASEBOARD_FAB2(SCH_1):VR_PVCCIN_CPU0_AIREF5   I186 @BASEBOARD_FAB2_LIB.BASEBOARD_FAB2(SCH_1):PAGE201
     2 ISENSE_PVCCIN_CPU0_PH5_IMON @BASEBOARD_FAB2_LIB.BASEBOARD_FAB2(SCH_1):ISENSE_PVCCIN_CPU0_PH5_IMON   I186 @BASEBOARD_FAB2_LIB.BASEBOARD_FAB2(SCH_1):PAGE201

 RF6 RES_0402-1.0K,0.1%,1/16W,CHIP,A
     1 VR_PVSA_CPU0_BIREF1 @BASEBOARD_FAB2_LIB.BASEBOARD_FAB2(SCH_1):VR_PVSA_CPU0_BIREF1   I180 @BASEBOARD_FAB2_LIB.BASEBOARD_FAB2(SCH_1):PAGE201
     2 ISENSE_PVSA_CPU0_IMON @BASEBOARD_FAB2_LIB.BASEBOARD_FAB2(SCH_1):ISENSE_PVSA_CPU0_IMON   I180 @BASEBOARD_FAB2_LIB.BASEBOARD_FAB2(SCH_1):PAGE201

 RF7 RES_0402-1.0K,0.1%,1/16W,CHIP,A
     1 VR_PVCCIN_CPU1_AIREF1 @BASEBOARD_FAB2_LIB.BASEBOARD_FAB2(SCH_1):VR_PVCCIN_CPU1_AIREF1   I150 @BASEBOARD_FAB2_LIB.BASEBOARD_FAB2(SCH_1):PAGE206
     2 ISENSE_PVCCIN_CPU1_PH1_IMON @BASEBOARD_FAB2_LIB.BASEBOARD_FAB2(SCH_1):ISENSE_PVCCIN_CPU1_PH1_IMON   I150 @BASEBOARD_FAB2_LIB.BASEBOARD_FAB2(SCH_1):PAGE206

 RF8 RES_0402-1.0K,0.1%,1/16W,CHIP,A
     1 VR_PVCCIN_CPU1_AIREF2 @BASEBOARD_FAB2_LIB.BASEBOARD_FAB2(SCH_1):VR_PVCCIN_CPU1_AIREF2   I151 @BASEBOARD_FAB2_LIB.BASEBOARD_FAB2(SCH_1):PAGE206
     2 ISENSE_PVCCIN_CPU1_PH2_IMON @BASEBOARD_FAB2_LIB.BASEBOARD_FAB2(SCH_1):ISENSE_PVCCIN_CPU1_PH2_IMON   I151 @BASEBOARD_FAB2_LIB.BASEBOARD_FAB2(SCH_1):PAGE206

 RF9 RES_0402-1.0K,0.1%,1/16W,CHIP,A
     1 VR_PVCCIN_CPU1_AIREF3 @BASEBOARD_FAB2_LIB.BASEBOARD_FAB2(SCH_1):VR_PVCCIN_CPU1_AIREF3   I152 @BASEBOARD_FAB2_LIB.BASEBOARD_FAB2(SCH_1):PAGE206
     2 ISENSE_PVCCIN_CPU1_PH3_IMON @BASEBOARD_FAB2_LIB.BASEBOARD_FAB2(SCH_1):ISENSE_PVCCIN_CPU1_PH3_IMON   I152 @BASEBOARD_FAB2_LIB.BASEBOARD_FAB2(SCH_1):PAGE206

RF10 RES_0402-1.0K,0.1%,1/16W,CHIP,A
     1 VR_PVCCIN_CPU1_AIREF4 @BASEBOARD_FAB2_LIB.BASEBOARD_FAB2(SCH_1):VR_PVCCIN_CPU1_AIREF4   I153 @BASEBOARD_FAB2_LIB.BASEBOARD_FAB2(SCH_1):PAGE206
     2 ISENSE_PVCCIN_CPU1_PH4_IMON @BASEBOARD_FAB2_LIB.BASEBOARD_FAB2(SCH_1):ISENSE_PVCCIN_CPU1_PH4_IMON   I153 @BASEBOARD_FAB2_LIB.BASEBOARD_FAB2(SCH_1):PAGE206

RF11 RES_0402-1.0K,0.1%,1/16W,CHIP,A
     1 VR_PVCCIN_CPU1_AIREF5 @BASEBOARD_FAB2_LIB.BASEBOARD_FAB2(SCH_1):VR_PVCCIN_CPU1_AIREF5   I154 @BASEBOARD_FAB2_LIB.BASEBOARD_FAB2(SCH_1):PAGE206
     2 ISENSE_PVCCIN_CPU1_PH5_IMON @BASEBOARD_FAB2_LIB.BASEBOARD_FAB2(SCH_1):ISENSE_PVCCIN_CPU1_PH5_IMON   I154 @BASEBOARD_FAB2_LIB.BASEBOARD_FAB2(SCH_1):PAGE206

RF12 RES_0402-1.0K,0.1%,1/16W,CHIP,A
     1 VR_PVSA_CPU1_BIREF1 @BASEBOARD_FAB2_LIB.BASEBOARD_FAB2(SCH_1):VR_PVSA_CPU1_BIREF1   I149 @BASEBOARD_FAB2_LIB.BASEBOARD_FAB2(SCH_1):PAGE206
     2 ISENSE_PVSA_CPU1_IMON @BASEBOARD_FAB2_LIB.BASEBOARD_FAB2(SCH_1):ISENSE_PVSA_CPU1_IMON   I149 @BASEBOARD_FAB2_LIB.BASEBOARD_FAB2(SCH_1):PAGE206

RF13 RES_0402-1.0K,0.1%,1/16W,CHIP,A
     1 VR_PVCCIO_CPU0_AIREF1 @BASEBOARD_FAB2_LIB.BASEBOARD_FAB2(SCH_1):VR_PVCCIO_CPU0_AIREF1    I96 @BASEBOARD_FAB2_LIB.BASEBOARD_FAB2(SCH_1):PAGE211
     2 ISENSE_PVCCIO_CPU0_PH1_IMON @BASEBOARD_FAB2_LIB.BASEBOARD_FAB2(SCH_1):ISENSE_PVCCIO_CPU0_PH1_IMON    I96 @BASEBOARD_FAB2_LIB.BASEBOARD_FAB2(SCH_1):PAGE211

RF14 RES_0402-1.0K,0.1%,1/16W,CHIP,A
     1 VR_PVCCIO_CPU1_AIREF1 @BASEBOARD_FAB2_LIB.BASEBOARD_FAB2(SCH_1):VR_PVCCIO_CPU1_AIREF1    I99 @BASEBOARD_FAB2_LIB.BASEBOARD_FAB2(SCH_1):PAGE213
     2 ISENSE_PVCCIO_CPU1_PH1_IMON @BASEBOARD_FAB2_LIB.BASEBOARD_FAB2(SCH_1):ISENSE_PVCCIO_CPU1_PH1_IMON    I99 @BASEBOARD_FAB2_LIB.BASEBOARD_FAB2(SCH_1):PAGE213

RF15 RES_0402-1.0K,0.1%,1/16W,CHIP,A
     1 VR_PVDDQ_ABC_AIREF1 @BASEBOARD_FAB2_LIB.BASEBOARD_FAB2(SCH_1):VR_PVDDQ_ABC_AIREF1    I15 @BASEBOARD_FAB2_LIB.BASEBOARD_FAB2(SCH_1):PAGE215
     2 ISENSE_PVDDQ_ABC_PH1_IMON @BASEBOARD_FAB2_LIB.BASEBOARD_FAB2(SCH_1):ISENSE_PVDDQ_ABC_PH1_IMON    I15 @BASEBOARD_FAB2_LIB.BASEBOARD_FAB2(SCH_1):PAGE215

RF16 RES_0402-1.0K,0.1%,1/16W,CHIP,A
     1 VR_PVDDQ_ABC_AIREF2 @BASEBOARD_FAB2_LIB.BASEBOARD_FAB2(SCH_1):VR_PVDDQ_ABC_AIREF2    I27 @BASEBOARD_FAB2_LIB.BASEBOARD_FAB2(SCH_1):PAGE215
     2 ISENSE_PVDDQ_ABC_PH2_IMON @BASEBOARD_FAB2_LIB.BASEBOARD_FAB2(SCH_1):ISENSE_PVDDQ_ABC_PH2_IMON    I27 @BASEBOARD_FAB2_LIB.BASEBOARD_FAB2(SCH_1):PAGE215

RF17 RES_0402-1.0K,0.1%,1/16W,CHIP,A
     1 VR_PVDDQ_DEF_AIREF1 @BASEBOARD_FAB2_LIB.BASEBOARD_FAB2(SCH_1):VR_PVDDQ_DEF_AIREF1    I18 @BASEBOARD_FAB2_LIB.BASEBOARD_FAB2(SCH_1):PAGE218
     2 ISENSE_PVDDQ_DEF_PH1_IMON @BASEBOARD_FAB2_LIB.BASEBOARD_FAB2(SCH_1):ISENSE_PVDDQ_DEF_PH1_IMON    I18 @BASEBOARD_FAB2_LIB.BASEBOARD_FAB2(SCH_1):PAGE218

RF18 RES_0402-1.0K,0.1%,1/16W,CHIP,A
     1 VR_PVDDQ_DEF_AIREF2 @BASEBOARD_FAB2_LIB.BASEBOARD_FAB2(SCH_1):VR_PVDDQ_DEF_AIREF2    I19 @BASEBOARD_FAB2_LIB.BASEBOARD_FAB2(SCH_1):PAGE218
     2 ISENSE_PVDDQ_DEF_PH2_IMON @BASEBOARD_FAB2_LIB.BASEBOARD_FAB2(SCH_1):ISENSE_PVDDQ_DEF_PH2_IMON    I19 @BASEBOARD_FAB2_LIB.BASEBOARD_FAB2(SCH_1):PAGE218

RF19 RES_0402-1.0K,0.1%,1/16W,CHIP,A
     1 VR_PVDDQ_GHJ_AIREF1 @BASEBOARD_FAB2_LIB.BASEBOARD_FAB2(SCH_1):VR_PVDDQ_GHJ_AIREF1    I16 @BASEBOARD_FAB2_LIB.BASEBOARD_FAB2(SCH_1):PAGE223
     2 ISENSE_PVDDQ_GHJ_PH1_IMON @BASEBOARD_FAB2_LIB.BASEBOARD_FAB2(SCH_1):ISENSE_PVDDQ_GHJ_PH1_IMON    I16 @BASEBOARD_FAB2_LIB.BASEBOARD_FAB2(SCH_1):PAGE223

RF20 RES_0402-1.0K,0.1%,1/16W,CHIP,A
     1 VR_PVDDQ_GHJ_AIREF2 @BASEBOARD_FAB2_LIB.BASEBOARD_FAB2(SCH_1):VR_PVDDQ_GHJ_AIREF2    I19 @BASEBOARD_FAB2_LIB.BASEBOARD_FAB2(SCH_1):PAGE223
     2 ISENSE_PVDDQ_GHJ_PH2_IMON @BASEBOARD_FAB2_LIB.BASEBOARD_FAB2(SCH_1):ISENSE_PVDDQ_GHJ_PH2_IMON    I19 @BASEBOARD_FAB2_LIB.BASEBOARD_FAB2(SCH_1):PAGE223

RF21 RES_0402-1.0K,0.1%,1/16W,CHIP,A
     1 VR_PVDDQ_KLM_AIREF1 @BASEBOARD_FAB2_LIB.BASEBOARD_FAB2(SCH_1):VR_PVDDQ_KLM_AIREF1    I16 @BASEBOARD_FAB2_LIB.BASEBOARD_FAB2(SCH_1):PAGE226
     2 ISENSE_PVDDQ_KLM_PH1_IMON @BASEBOARD_FAB2_LIB.BASEBOARD_FAB2(SCH_1):ISENSE_PVDDQ_KLM_PH1_IMON    I16 @BASEBOARD_FAB2_LIB.BASEBOARD_FAB2(SCH_1):PAGE226

RF22 RES_0402-1.0K,0.1%,1/16W,CHIP,A
     1 VR_PVDDQ_KLM_AIREF2 @BASEBOARD_FAB2_LIB.BASEBOARD_FAB2(SCH_1):VR_PVDDQ_KLM_AIREF2    I18 @BASEBOARD_FAB2_LIB.BASEBOARD_FAB2(SCH_1):PAGE226
     2 ISENSE_PVDDQ_KLM_PH2_IMON @BASEBOARD_FAB2_LIB.BASEBOARD_FAB2(SCH_1):ISENSE_PVDDQ_KLM_PH2_IMON    I18 @BASEBOARD_FAB2_LIB.BASEBOARD_FAB2(SCH_1):PAGE226

RF23 RES_0402-1.0K,0.1%,1/16W,CHIP,A
     1 VR_PVNN_PCH_AIREF1 @BASEBOARD_FAB2_LIB.BASEBOARD_FAB2(SCH_1):VR_PVNN_PCH_AIREF1   I241 @BASEBOARD_FAB2_LIB.BASEBOARD_FAB2(SCH_1):PAGE235
     2 ISENSE_PVNN_PCH_PH1_IMON @BASEBOARD_FAB2_LIB.BASEBOARD_FAB2(SCH_1):ISENSE_PVNN_PCH_PH1_IMON   I241 @BASEBOARD_FAB2_LIB.BASEBOARD_FAB2(SCH_1):PAGE235

RF24 RES_0402-1.0K,0.1%,1/16W,CHIP,A
     1 VR_P1V05_PCH_BIREF1 @BASEBOARD_FAB2_LIB.BASEBOARD_FAB2(SCH_1):VR_P1V05_PCH_BIREF1   I242 @BASEBOARD_FAB2_LIB.BASEBOARD_FAB2(SCH_1):PAGE235
     2 ISENSE_P1V05_PCH_STBY_PH1_IMON @BASEBOARD_FAB2_LIB.BASEBOARD_FAB2(SCH_1):ISENSE_P1V05_PCH_STBY_PH1_IMON   I242 @BASEBOARD_FAB2_LIB.BASEBOARD_FAB2(SCH_1):PAGE235

RM1E1 CONN3_G98259001_PIP-CONN,G9825A
     1    GND @BASEBOARD_FAB2_LIB.BASEBOARD_FAB2(SCH_1):GND    I26 @BASEBOARD_FAB2_LIB.BASEBOARD_FAB2(SCH_1):PAGE195
     2    GND @BASEBOARD_FAB2_LIB.BASEBOARD_FAB2(SCH_1):GND    I26 @BASEBOARD_FAB2_LIB.BASEBOARD_FAB2(SCH_1):PAGE195
     3    GND @BASEBOARD_FAB2_LIB.BASEBOARD_FAB2(SCH_1):GND    I26 @BASEBOARD_FAB2_LIB.BASEBOARD_FAB2(SCH_1):PAGE195

RM1G1 STFT363B238R224H453-GP_DISCRETA
     1    GND @BASEBOARD_FAB2_LIB.BASEBOARD_FAB2(SCH_1):GND   I117 @BASEBOARD_FAB2_LIB.BASEBOARD_FAB2(SCH_1):PAGE195

RM8D1 STANDOFF_TH1-SO,H72821-001
     1    GND @BASEBOARD_FAB2_LIB.BASEBOARD_FAB2(SCH_1):GND   I104 @BASEBOARD_FAB2_LIB.BASEBOARD_FAB2(SCH_1):PAGE184

RN8F1 RES_0402-4.75K,1%,1/16W,CHIP,GA
     1 P3V3_STBY @BASEBOARD_FAB2_LIB.BASEBOARD_FAB2(SCH_1):P3V3_STBY   I142 @BASEBOARD_FAB2_LIB.BASEBOARD_FAB2(SCH_1):PAGE137
     2 PU_SPI_BMC_BT_CS0_N @BASEBOARD_FAB2_LIB.BASEBOARD_FAB2(SCH_1):PU_SPI_BMC_BT_CS0_N   I142 @BASEBOARD_FAB2_LIB.BASEBOARD_FAB2(SCH_1):PAGE137

RN8F2 RES_0402-4.75K,1%,1/16W,EMPTY,A
     1 P3V3_STBY @BASEBOARD_FAB2_LIB.BASEBOARD_FAB2(SCH_1):P3V3_STBY    I20 @BASEBOARD_FAB2_LIB.BASEBOARD_FAB2(SCH_1):PAGE246
     2 TPM_SPI_BMC_WP_N @BASEBOARD_FAB2_LIB.BASEBOARD_FAB2(SCH_1):TPM_SPI_BMC_WP_N    I20 @BASEBOARD_FAB2_LIB.BASEBOARD_FAB2(SCH_1):PAGE246

RN8F3 RES_0402-4.75K,1%,1/16W,CHIP,GA
     1 P3V3_STBY @BASEBOARD_FAB2_LIB.BASEBOARD_FAB2(SCH_1):P3V3_STBY    I11 @BASEBOARD_FAB2_LIB.BASEBOARD_FAB2(SCH_1):PAGE246
     2 PU_TPM_SPI_BMC_HOLD_N @BASEBOARD_FAB2_LIB.BASEBOARD_FAB2(SCH_1):PU_TPM_SPI_BMC_HOLD_N    I11 @BASEBOARD_FAB2_LIB.BASEBOARD_FAB2(SCH_1):PAGE246

RN8F4 RES_0402-4.75K,1%,1/16W,EMPTY,A
     1 P3V3_STBY @BASEBOARD_FAB2_LIB.BASEBOARD_FAB2(SCH_1):P3V3_STBY    I12 @BASEBOARD_FAB2_LIB.BASEBOARD_FAB2(SCH_1):PAGE246
     2 PU_TPM_SPI_FLASH_RESET_2_N @BASEBOARD_FAB2_LIB.BASEBOARD_FAB2(SCH_1):PU_TPM_SPI_FLASH_RESET_2_N    I12 @BASEBOARD_FAB2_LIB.BASEBOARD_FAB2(SCH_1):PAGE246

RN8F5 RES_0402-33.2,1%,1/16W,CHIP,G2A
     1 SPI_BMC_BT_DI @BASEBOARD_FAB2_LIB.BASEBOARD_FAB2(SCH_1):SPI_BMC_BT_DI     I9 @BASEBOARD_FAB2_LIB.BASEBOARD_FAB2(SCH_1):PAGE246
     2 SPI_TPM_BMC_DI_R @BASEBOARD_FAB2_LIB.BASEBOARD_FAB2(SCH_1):SPI_TPM_BMC_DI_R     I9 @BASEBOARD_FAB2_LIB.BASEBOARD_FAB2(SCH_1):PAGE246

RN8F6 82KR2F-1-GP_SMD-RG-82KR2F-1-GPA
     1 TPM_SPI_BMC_WP_N @BASEBOARD_FAB2_LIB.BASEBOARD_FAB2(SCH_1):TPM_SPI_BMC_WP_N    I19 @BASEBOARD_FAB2_LIB.BASEBOARD_FAB2(SCH_1):PAGE246
     2    GND @BASEBOARD_FAB2_LIB.BASEBOARD_FAB2(SCH_1):GND    I19 @BASEBOARD_FAB2_LIB.BASEBOARD_FAB2(SCH_1):PAGE246

 RT1 RES_0603-0,5.0%,1/10W,CHIP,G22A
     1 VR_PVCCIN_CPU0_PH1_BOOT @BASEBOARD_FAB2_LIB.BASEBOARD_FAB2(SCH_1):VR_PVCCIN_CPU0_PH1_BOOT   I101 @BASEBOARD_FAB2_LIB.BASEBOARD_FAB2(SCH_1):PAGE202
     2 VR_PVCCIN_CPU0_PH1_BOOT_R @BASEBOARD_FAB2_LIB.BASEBOARD_FAB2(SCH_1):VR_PVCCIN_CPU0_PH1_BOOT_R   I101 @BASEBOARD_FAB2_LIB.BASEBOARD_FAB2(SCH_1):PAGE202

 RT2 1R3F-GP_RCL_GP-1R3F-GP,64.1R00A
     1 VR_PVCCIN_CPU0_PHASE1_RC @BASEBOARD_FAB2_LIB.BASEBOARD_FAB2(SCH_1):VR_PVCCIN_CPU0_PHASE1_RC   I114 @BASEBOARD_FAB2_LIB.BASEBOARD_FAB2(SCH_1):PAGE202
     2    GND @BASEBOARD_FAB2_LIB.BASEBOARD_FAB2(SCH_1):GND   I114 @BASEBOARD_FAB2_LIB.BASEBOARD_FAB2(SCH_1):PAGE202

 RT3 RES_0603-0,5.0%,1/10W,CHIP,G22A
     1 VR_PVCCIN_CPU0_PH2_BOOT @BASEBOARD_FAB2_LIB.BASEBOARD_FAB2(SCH_1):VR_PVCCIN_CPU0_PH2_BOOT   I102 @BASEBOARD_FAB2_LIB.BASEBOARD_FAB2(SCH_1):PAGE202
     2 VR_PVCCIN_CPU0_PH2_BOOT_R @BASEBOARD_FAB2_LIB.BASEBOARD_FAB2(SCH_1):VR_PVCCIN_CPU0_PH2_BOOT_R   I102 @BASEBOARD_FAB2_LIB.BASEBOARD_FAB2(SCH_1):PAGE202

 RT4 1R3F-GP_RCL_GP-1R3F-GP,64.1R00A
     1 VR_PVCCIN_CPU0_PHASE2_RC @BASEBOARD_FAB2_LIB.BASEBOARD_FAB2(SCH_1):VR_PVCCIN_CPU0_PHASE2_RC   I115 @BASEBOARD_FAB2_LIB.BASEBOARD_FAB2(SCH_1):PAGE202
     2    GND @BASEBOARD_FAB2_LIB.BASEBOARD_FAB2(SCH_1):GND   I115 @BASEBOARD_FAB2_LIB.BASEBOARD_FAB2(SCH_1):PAGE202

 RT5 RES_0603-0,5.0%,1/10W,CHIP,G22A
     1 VR_PVDDQ_KLM_PH1_BOOT @BASEBOARD_FAB2_LIB.BASEBOARD_FAB2(SCH_1):VR_PVDDQ_KLM_PH1_BOOT   I138 @BASEBOARD_FAB2_LIB.BASEBOARD_FAB2(SCH_1):PAGE227
     2 VR_PVDDQ_KLM_PH1_BOOT_R @BASEBOARD_FAB2_LIB.BASEBOARD_FAB2(SCH_1):VR_PVDDQ_KLM_PH1_BOOT_R   I138 @BASEBOARD_FAB2_LIB.BASEBOARD_FAB2(SCH_1):PAGE227

 RT6 1R3F-GP_RCL_GP-1R3F-GP,64.1R00A
     1 VR_PVDDQ_KLM_PH1_RC @BASEBOARD_FAB2_LIB.BASEBOARD_FAB2(SCH_1):VR_PVDDQ_KLM_PH1_RC   I149 @BASEBOARD_FAB2_LIB.BASEBOARD_FAB2(SCH_1):PAGE227
     2    GND @BASEBOARD_FAB2_LIB.BASEBOARD_FAB2(SCH_1):GND   I149 @BASEBOARD_FAB2_LIB.BASEBOARD_FAB2(SCH_1):PAGE227

 RT7 1R3F-GP_RCL_GP-1R3F-GP,64.1R00A
     1 VR_PVDDQ_KLM_PH2_RC @BASEBOARD_FAB2_LIB.BASEBOARD_FAB2(SCH_1):VR_PVDDQ_KLM_PH2_RC   I150 @BASEBOARD_FAB2_LIB.BASEBOARD_FAB2(SCH_1):PAGE227
     2    GND @BASEBOARD_FAB2_LIB.BASEBOARD_FAB2(SCH_1):GND   I150 @BASEBOARD_FAB2_LIB.BASEBOARD_FAB2(SCH_1):PAGE227

 RT8 RES_0603-0,5.0%,1/10W,CHIP,G22A
     1 VR_PVDDQ_KLM_PH2_BOOT @BASEBOARD_FAB2_LIB.BASEBOARD_FAB2(SCH_1):VR_PVDDQ_KLM_PH2_BOOT   I139 @BASEBOARD_FAB2_LIB.BASEBOARD_FAB2(SCH_1):PAGE227
     2 VR_PVDDQ_KLM_PH2_BOOT_R @BASEBOARD_FAB2_LIB.BASEBOARD_FAB2(SCH_1):VR_PVDDQ_KLM_PH2_BOOT_R   I139 @BASEBOARD_FAB2_LIB.BASEBOARD_FAB2(SCH_1):PAGE227

RT8P1 RES_0603-100.0K,1%,1/10W,CHIP,A
     1 PVCCIN_CPU1 @BASEBOARD_FAB2_LIB.BASEBOARD_FAB2(SCH_1):PVCCIN_CPU1    I49 @BASEBOARD_FAB2_LIB.BASEBOARD_FAB2(SCH_1):PAGE71
     2 VSENSE_VCCINR2PMAX_CPU1 @BASEBOARD_FAB2_LIB.BASEBOARD_FAB2(SCH_1):VSENSE_VCCINR2PMAX_CPU1    I49 @BASEBOARD_FAB2_LIB.BASEBOARD_FAB2(SCH_1):PAGE71

 RT9 RES_0603-0,5.0%,1/10W,CHIP,G22A
     1 VR_PVCCIN_CPU1_PH5_BOOT @BASEBOARD_FAB2_LIB.BASEBOARD_FAB2(SCH_1):VR_PVCCIN_CPU1_PH5_BOOT    I75 @BASEBOARD_FAB2_LIB.BASEBOARD_FAB2(SCH_1):PAGE209
     2 VR_PVCCIN_CPU1_PH5_BOOT_R @BASEBOARD_FAB2_LIB.BASEBOARD_FAB2(SCH_1):VR_PVCCIN_CPU1_PH5_BOOT_R    I75 @BASEBOARD_FAB2_LIB.BASEBOARD_FAB2(SCH_1):PAGE209

RT10 1R3F-GP_RCL_GP-1R3F-GP,64.1R00A
     1 VR_PVCCIN_CPU1_PHASE5_RC @BASEBOARD_FAB2_LIB.BASEBOARD_FAB2(SCH_1):VR_PVCCIN_CPU1_PHASE5_RC    I90 @BASEBOARD_FAB2_LIB.BASEBOARD_FAB2(SCH_1):PAGE209
     2    GND @BASEBOARD_FAB2_LIB.BASEBOARD_FAB2(SCH_1):GND    I90 @BASEBOARD_FAB2_LIB.BASEBOARD_FAB2(SCH_1):PAGE209

RT11 RES_0603-0,5.0%,1/10W,CHIP,G22A
     1 VR_PVCCIN_CPU1_PH3_BOOT @BASEBOARD_FAB2_LIB.BASEBOARD_FAB2(SCH_1):VR_PVCCIN_CPU1_PH3_BOOT   I108 @BASEBOARD_FAB2_LIB.BASEBOARD_FAB2(SCH_1):PAGE208
     2 VR_PVCCIN_CPU1_PH3_BOOT_R @BASEBOARD_FAB2_LIB.BASEBOARD_FAB2(SCH_1):VR_PVCCIN_CPU1_PH3_BOOT_R   I108 @BASEBOARD_FAB2_LIB.BASEBOARD_FAB2(SCH_1):PAGE208

RT12 1R3F-GP_RCL_GP-1R3F-GP,64.1R00A
     1 VR_PVCCIN_CPU1_PHASE3_RC @BASEBOARD_FAB2_LIB.BASEBOARD_FAB2(SCH_1):VR_PVCCIN_CPU1_PHASE3_RC   I120 @BASEBOARD_FAB2_LIB.BASEBOARD_FAB2(SCH_1):PAGE208
     2    GND @BASEBOARD_FAB2_LIB.BASEBOARD_FAB2(SCH_1):GND   I120 @BASEBOARD_FAB2_LIB.BASEBOARD_FAB2(SCH_1):PAGE208

RT13 1R3F-GP_RCL_GP-1R3F-GP,64.1R00A
     1 VR_PVCCIN_CPU1_PHASE4_RC @BASEBOARD_FAB2_LIB.BASEBOARD_FAB2(SCH_1):VR_PVCCIN_CPU1_PHASE4_RC   I121 @BASEBOARD_FAB2_LIB.BASEBOARD_FAB2(SCH_1):PAGE208
     2    GND @BASEBOARD_FAB2_LIB.BASEBOARD_FAB2(SCH_1):GND   I121 @BASEBOARD_FAB2_LIB.BASEBOARD_FAB2(SCH_1):PAGE208

RT14 RES_0603-0,5.0%,1/10W,CHIP,G22A
     1 VR_PVCCIN_CPU1_PH4_BOOT @BASEBOARD_FAB2_LIB.BASEBOARD_FAB2(SCH_1):VR_PVCCIN_CPU1_PH4_BOOT   I109 @BASEBOARD_FAB2_LIB.BASEBOARD_FAB2(SCH_1):PAGE208
     2 VR_PVCCIN_CPU1_PH4_BOOT_R @BASEBOARD_FAB2_LIB.BASEBOARD_FAB2(SCH_1):VR_PVCCIN_CPU1_PH4_BOOT_R   I109 @BASEBOARD_FAB2_LIB.BASEBOARD_FAB2(SCH_1):PAGE208

RT15 RES_0603-0,5.0%,1/10W,CHIP,G22A
     1 VR_PVCCIN_CPU1_PH1_BOOT @BASEBOARD_FAB2_LIB.BASEBOARD_FAB2(SCH_1):VR_PVCCIN_CPU1_PH1_BOOT    I99 @BASEBOARD_FAB2_LIB.BASEBOARD_FAB2(SCH_1):PAGE207
     2 VR_PVCCIN_CPU1_PH1_BOOT_R @BASEBOARD_FAB2_LIB.BASEBOARD_FAB2(SCH_1):VR_PVCCIN_CPU1_PH1_BOOT_R    I99 @BASEBOARD_FAB2_LIB.BASEBOARD_FAB2(SCH_1):PAGE207

RT16 1R3F-GP_RCL_GP-1R3F-GP,64.1R00A
     1 VR_PVCCIN_CPU1_PHASE1_RC @BASEBOARD_FAB2_LIB.BASEBOARD_FAB2(SCH_1):VR_PVCCIN_CPU1_PHASE1_RC   I111 @BASEBOARD_FAB2_LIB.BASEBOARD_FAB2(SCH_1):PAGE207
     2    GND @BASEBOARD_FAB2_LIB.BASEBOARD_FAB2(SCH_1):GND   I111 @BASEBOARD_FAB2_LIB.BASEBOARD_FAB2(SCH_1):PAGE207

RT17 RES_0603-0,5.0%,1/10W,CHIP,G22A
     1 VR_PVCCIN_CPU1_PH2_BOOT @BASEBOARD_FAB2_LIB.BASEBOARD_FAB2(SCH_1):VR_PVCCIN_CPU1_PH2_BOOT   I100 @BASEBOARD_FAB2_LIB.BASEBOARD_FAB2(SCH_1):PAGE207
     2 VR_PVCCIN_CPU1_PH2_BOOT_R @BASEBOARD_FAB2_LIB.BASEBOARD_FAB2(SCH_1):VR_PVCCIN_CPU1_PH2_BOOT_R   I100 @BASEBOARD_FAB2_LIB.BASEBOARD_FAB2(SCH_1):PAGE207

RT18 1R3F-GP_RCL_GP-1R3F-GP,64.1R00A
     1 VR_PVCCIN_CPU1_PHASE2_RC @BASEBOARD_FAB2_LIB.BASEBOARD_FAB2(SCH_1):VR_PVCCIN_CPU1_PHASE2_RC   I112 @BASEBOARD_FAB2_LIB.BASEBOARD_FAB2(SCH_1):PAGE207
     2    GND @BASEBOARD_FAB2_LIB.BASEBOARD_FAB2(SCH_1):GND   I112 @BASEBOARD_FAB2_LIB.BASEBOARD_FAB2(SCH_1):PAGE207

RT19 RES_0603-0,5.0%,1/10W,CHIP,G22A
     1 VR_PVDDQ_GHJ_PH1_BOOT @BASEBOARD_FAB2_LIB.BASEBOARD_FAB2(SCH_1):VR_PVDDQ_GHJ_PH1_BOOT   I144 @BASEBOARD_FAB2_LIB.BASEBOARD_FAB2(SCH_1):PAGE224
     2 VR_PVDDQ_GHJ_PH1_BOOT_R @BASEBOARD_FAB2_LIB.BASEBOARD_FAB2(SCH_1):VR_PVDDQ_GHJ_PH1_BOOT_R   I144 @BASEBOARD_FAB2_LIB.BASEBOARD_FAB2(SCH_1):PAGE224

RT20 1R3F-GP_RCL_GP-1R3F-GP,64.1R00A
     1 VR_PVDDQ_GHJ_PH1_SW_RC @BASEBOARD_FAB2_LIB.BASEBOARD_FAB2(SCH_1):VR_PVDDQ_GHJ_PH1_SW_RC   I156 @BASEBOARD_FAB2_LIB.BASEBOARD_FAB2(SCH_1):PAGE224
     2    GND @BASEBOARD_FAB2_LIB.BASEBOARD_FAB2(SCH_1):GND   I156 @BASEBOARD_FAB2_LIB.BASEBOARD_FAB2(SCH_1):PAGE224

RT21 RES_0603-0,5.0%,1/10W,CHIP,G22A
     1 VR_PVDDQ_GHJ_PH2_BOOT @BASEBOARD_FAB2_LIB.BASEBOARD_FAB2(SCH_1):VR_PVDDQ_GHJ_PH2_BOOT   I145 @BASEBOARD_FAB2_LIB.BASEBOARD_FAB2(SCH_1):PAGE224
     2 VR_PVDDQ_GHJ_PH2_BOOT_R @BASEBOARD_FAB2_LIB.BASEBOARD_FAB2(SCH_1):VR_PVDDQ_GHJ_PH2_BOOT_R   I145 @BASEBOARD_FAB2_LIB.BASEBOARD_FAB2(SCH_1):PAGE224

RT22 1R3F-GP_RCL_GP-1R3F-GP,64.1R00A
     1 VR_PVDDQ_GHJ_PH2_SW_RC @BASEBOARD_FAB2_LIB.BASEBOARD_FAB2(SCH_1):VR_PVDDQ_GHJ_PH2_SW_RC   I157 @BASEBOARD_FAB2_LIB.BASEBOARD_FAB2(SCH_1):PAGE224
     2    GND @BASEBOARD_FAB2_LIB.BASEBOARD_FAB2(SCH_1):GND   I157 @BASEBOARD_FAB2_LIB.BASEBOARD_FAB2(SCH_1):PAGE224

RT23 RES_0603-0,5.0%,1/10W,CHIP,G22A
     1 VR_PVCCIN_CPU0_PH5_BOOT @BASEBOARD_FAB2_LIB.BASEBOARD_FAB2(SCH_1):VR_PVCCIN_CPU0_PH5_BOOT    I99 @BASEBOARD_FAB2_LIB.BASEBOARD_FAB2(SCH_1):PAGE204
     2 VR_PVCCIN_CPU0_PH5_BOOT_R @BASEBOARD_FAB2_LIB.BASEBOARD_FAB2(SCH_1):VR_PVCCIN_CPU0_PH5_BOOT_R    I99 @BASEBOARD_FAB2_LIB.BASEBOARD_FAB2(SCH_1):PAGE204

RT24 1R3F-GP_RCL_GP-1R3F-GP,64.1R00A
     1 VR_PVCCIN_CPU0_PHASE5_RC @BASEBOARD_FAB2_LIB.BASEBOARD_FAB2(SCH_1):VR_PVCCIN_CPU0_PHASE5_RC   I114 @BASEBOARD_FAB2_LIB.BASEBOARD_FAB2(SCH_1):PAGE204
     2    GND @BASEBOARD_FAB2_LIB.BASEBOARD_FAB2(SCH_1):GND   I114 @BASEBOARD_FAB2_LIB.BASEBOARD_FAB2(SCH_1):PAGE204

RT25 RES_0603-0,5.0%,1/10W,CHIP,G22A
     1 VR_PVCCIN_CPU0_PH3_BOOT @BASEBOARD_FAB2_LIB.BASEBOARD_FAB2(SCH_1):VR_PVCCIN_CPU0_PH3_BOOT   I122 @BASEBOARD_FAB2_LIB.BASEBOARD_FAB2(SCH_1):PAGE203
     2 VR_PVCCIN_CPU0_PH3_BOOT_R @BASEBOARD_FAB2_LIB.BASEBOARD_FAB2(SCH_1):VR_PVCCIN_CPU0_PH3_BOOT_R   I122 @BASEBOARD_FAB2_LIB.BASEBOARD_FAB2(SCH_1):PAGE203

RT26 1R3F-GP_RCL_GP-1R3F-GP,64.1R00A
     1 VR_PVCCIN_CPU0_PHASE3_RC @BASEBOARD_FAB2_LIB.BASEBOARD_FAB2(SCH_1):VR_PVCCIN_CPU0_PHASE3_RC   I134 @BASEBOARD_FAB2_LIB.BASEBOARD_FAB2(SCH_1):PAGE203
     2    GND @BASEBOARD_FAB2_LIB.BASEBOARD_FAB2(SCH_1):GND   I134 @BASEBOARD_FAB2_LIB.BASEBOARD_FAB2(SCH_1):PAGE203

RT27 1R3F-GP_RCL_GP-1R3F-GP,64.1R00A
     1 VR_PVCCIN_CPU0_PHASE4_RC @BASEBOARD_FAB2_LIB.BASEBOARD_FAB2(SCH_1):VR_PVCCIN_CPU0_PHASE4_RC   I135 @BASEBOARD_FAB2_LIB.BASEBOARD_FAB2(SCH_1):PAGE203
     2    GND @BASEBOARD_FAB2_LIB.BASEBOARD_FAB2(SCH_1):GND   I135 @BASEBOARD_FAB2_LIB.BASEBOARD_FAB2(SCH_1):PAGE203

RT28 RES_0603-0,5.0%,1/10W,CHIP,G22A
     1 VR_PVCCIN_CPU0_PH4_BOOT @BASEBOARD_FAB2_LIB.BASEBOARD_FAB2(SCH_1):VR_PVCCIN_CPU0_PH4_BOOT   I123 @BASEBOARD_FAB2_LIB.BASEBOARD_FAB2(SCH_1):PAGE203
     2 VR_PVCCIN_CPU0_PH4_BOOT_R @BASEBOARD_FAB2_LIB.BASEBOARD_FAB2(SCH_1):VR_PVCCIN_CPU0_PH4_BOOT_R   I123 @BASEBOARD_FAB2_LIB.BASEBOARD_FAB2(SCH_1):PAGE203

RT29 1R3F-GP_RCL_GP-1R3F-GP,64.1R00A
     1 VR_PVDDQ_DEF_PH1_SW_RC @BASEBOARD_FAB2_LIB.BASEBOARD_FAB2(SCH_1):VR_PVDDQ_DEF_PH1_SW_RC   I153 @BASEBOARD_FAB2_LIB.BASEBOARD_FAB2(SCH_1):PAGE219
     2    GND @BASEBOARD_FAB2_LIB.BASEBOARD_FAB2(SCH_1):GND   I153 @BASEBOARD_FAB2_LIB.BASEBOARD_FAB2(SCH_1):PAGE219

RT30 RES_0603-0,5.0%,1/10W,CHIP,G22A
     1 VR_PVDDQ_DEF_PH1_BOOT @BASEBOARD_FAB2_LIB.BASEBOARD_FAB2(SCH_1):VR_PVDDQ_DEF_PH1_BOOT   I141 @BASEBOARD_FAB2_LIB.BASEBOARD_FAB2(SCH_1):PAGE219
     2 VR_PVDDQ_DEF_PH1_BOOT_R @BASEBOARD_FAB2_LIB.BASEBOARD_FAB2(SCH_1):VR_PVDDQ_DEF_PH1_BOOT_R   I141 @BASEBOARD_FAB2_LIB.BASEBOARD_FAB2(SCH_1):PAGE219

RT31 RES_0603-0,5.0%,1/10W,CHIP,G22A
     1 VR_PVDDQ_DEF_PH2_BOOT @BASEBOARD_FAB2_LIB.BASEBOARD_FAB2(SCH_1):VR_PVDDQ_DEF_PH2_BOOT   I142 @BASEBOARD_FAB2_LIB.BASEBOARD_FAB2(SCH_1):PAGE219
     2 VR_PVDDQ_DEF_PH2_BOOT_R @BASEBOARD_FAB2_LIB.BASEBOARD_FAB2(SCH_1):VR_PVDDQ_DEF_PH2_BOOT_R   I142 @BASEBOARD_FAB2_LIB.BASEBOARD_FAB2(SCH_1):PAGE219

RT32 1R3F-GP_RCL_GP-1R3F-GP,64.1R00A
     1 VR_PVDDQ_DEF_PH2_SW_RC @BASEBOARD_FAB2_LIB.BASEBOARD_FAB2(SCH_1):VR_PVDDQ_DEF_PH2_SW_RC   I154 @BASEBOARD_FAB2_LIB.BASEBOARD_FAB2(SCH_1):PAGE219
     2    GND @BASEBOARD_FAB2_LIB.BASEBOARD_FAB2(SCH_1):GND   I154 @BASEBOARD_FAB2_LIB.BASEBOARD_FAB2(SCH_1):PAGE219

RT33 RES_0603-0,5.0%,1/10W,CHIP,G22A
     1 VR_PVDDQ_ABC_PH1_BOOT @BASEBOARD_FAB2_LIB.BASEBOARD_FAB2(SCH_1):VR_PVDDQ_ABC_PH1_BOOT   I139 @BASEBOARD_FAB2_LIB.BASEBOARD_FAB2(SCH_1):PAGE216
     2 VR_PVDDQ_ABC_PH1_BOOT_R @BASEBOARD_FAB2_LIB.BASEBOARD_FAB2(SCH_1):VR_PVDDQ_ABC_PH1_BOOT_R   I139 @BASEBOARD_FAB2_LIB.BASEBOARD_FAB2(SCH_1):PAGE216

RT34 1R3F-GP_RCL_GP-1R3F-GP,64.1R00A
     1 VR_PVDDQ_ABC_PH1_SW_RC @BASEBOARD_FAB2_LIB.BASEBOARD_FAB2(SCH_1):VR_PVDDQ_ABC_PH1_SW_RC   I151 @BASEBOARD_FAB2_LIB.BASEBOARD_FAB2(SCH_1):PAGE216
     2    GND @BASEBOARD_FAB2_LIB.BASEBOARD_FAB2(SCH_1):GND   I151 @BASEBOARD_FAB2_LIB.BASEBOARD_FAB2(SCH_1):PAGE216

RT35 1R3F-GP_RCL_GP-1R3F-GP,64.1R00A
     1 VR_PVDDQ_ABC_PH2_SW_RC @BASEBOARD_FAB2_LIB.BASEBOARD_FAB2(SCH_1):VR_PVDDQ_ABC_PH2_SW_RC   I152 @BASEBOARD_FAB2_LIB.BASEBOARD_FAB2(SCH_1):PAGE216
     2    GND @BASEBOARD_FAB2_LIB.BASEBOARD_FAB2(SCH_1):GND   I152 @BASEBOARD_FAB2_LIB.BASEBOARD_FAB2(SCH_1):PAGE216

RT36 RES_0603-0,5.0%,1/10W,CHIP,G22A
     1 VR_PVDDQ_ABC_PH2_BOOT @BASEBOARD_FAB2_LIB.BASEBOARD_FAB2(SCH_1):VR_PVDDQ_ABC_PH2_BOOT   I140 @BASEBOARD_FAB2_LIB.BASEBOARD_FAB2(SCH_1):PAGE216
     2 VR_PVDDQ_ABC_PH2_BOOT_R @BASEBOARD_FAB2_LIB.BASEBOARD_FAB2(SCH_1):VR_PVDDQ_ABC_PH2_BOOT_R   I140 @BASEBOARD_FAB2_LIB.BASEBOARD_FAB2(SCH_1):PAGE216

RT37 RES_0603-0,5.0%,1/10W,CHIP,G22A
     1 VR_PVSA_CPU1_BOOT @BASEBOARD_FAB2_LIB.BASEBOARD_FAB2(SCH_1):VR_PVSA_CPU1_BOOT    I68 @BASEBOARD_FAB2_LIB.BASEBOARD_FAB2(SCH_1):PAGE210
     2 VR_PVSA_CPU1_BOOT_R @BASEBOARD_FAB2_LIB.BASEBOARD_FAB2(SCH_1):VR_PVSA_CPU1_BOOT_R    I68 @BASEBOARD_FAB2_LIB.BASEBOARD_FAB2(SCH_1):PAGE210

RT38 1R3F-GP_RCL_GP-1R3F-GP,64.1R00A
     1 VR_PVSA_CPU1_PHASE_SW_RC @BASEBOARD_FAB2_LIB.BASEBOARD_FAB2(SCH_1):VR_PVSA_CPU1_PHASE_SW_RC    I74 @BASEBOARD_FAB2_LIB.BASEBOARD_FAB2(SCH_1):PAGE210
     2    GND @BASEBOARD_FAB2_LIB.BASEBOARD_FAB2(SCH_1):GND    I74 @BASEBOARD_FAB2_LIB.BASEBOARD_FAB2(SCH_1):PAGE210

RT39 1R3F-GP_RCL_GP-1R3F-GP,64.1R00A
     1 VR_PVSA_CPU0_PHASE_SW_RC @BASEBOARD_FAB2_LIB.BASEBOARD_FAB2(SCH_1):VR_PVSA_CPU0_PHASE_SW_RC    I84 @BASEBOARD_FAB2_LIB.BASEBOARD_FAB2(SCH_1):PAGE205
     2    GND @BASEBOARD_FAB2_LIB.BASEBOARD_FAB2(SCH_1):GND    I84 @BASEBOARD_FAB2_LIB.BASEBOARD_FAB2(SCH_1):PAGE205

RT40 RES_0603-0,5.0%,1/10W,CHIP,G22A
     1 VR_PVSA_CPU0_BOOT @BASEBOARD_FAB2_LIB.BASEBOARD_FAB2(SCH_1):VR_PVSA_CPU0_BOOT    I78 @BASEBOARD_FAB2_LIB.BASEBOARD_FAB2(SCH_1):PAGE205
     2 VR_PVSA_CPU0_BOOT_R @BASEBOARD_FAB2_LIB.BASEBOARD_FAB2(SCH_1):VR_PVSA_CPU0_BOOT_R    I78 @BASEBOARD_FAB2_LIB.BASEBOARD_FAB2(SCH_1):PAGE205

RT41 RES_0603-0,5.0%,1/10W,CHIP,G22A
     1 VR_PVCCIO_CPU1_PH1_BOOT @BASEBOARD_FAB2_LIB.BASEBOARD_FAB2(SCH_1):VR_PVCCIO_CPU1_PH1_BOOT   I145 @BASEBOARD_FAB2_LIB.BASEBOARD_FAB2(SCH_1):PAGE214
     2 VR_PVCCIO_CPU1_PH1_BOOT_R @BASEBOARD_FAB2_LIB.BASEBOARD_FAB2(SCH_1):VR_PVCCIO_CPU1_PH1_BOOT_R   I145 @BASEBOARD_FAB2_LIB.BASEBOARD_FAB2(SCH_1):PAGE214

RT42 1R3F-GP_RCL_GP-1R3F-GP,64.1R00A
     1 VR_PVCCIO_CPU1_PH1_SW_RC @BASEBOARD_FAB2_LIB.BASEBOARD_FAB2(SCH_1):VR_PVCCIO_CPU1_PH1_SW_RC   I176 @BASEBOARD_FAB2_LIB.BASEBOARD_FAB2(SCH_1):PAGE214
     2    GND @BASEBOARD_FAB2_LIB.BASEBOARD_FAB2(SCH_1):GND   I176 @BASEBOARD_FAB2_LIB.BASEBOARD_FAB2(SCH_1):PAGE214

RT43 1R3F-GP_RCL_GP-1R3F-GP,64.1R00A
     1 VR_PVNN_PCH_PH1_PHASE_SW_RC @BASEBOARD_FAB2_LIB.BASEBOARD_FAB2(SCH_1):VR_PVNN_PCH_PH1_PHASE_SW_RC   I182 @BASEBOARD_FAB2_LIB.BASEBOARD_FAB2(SCH_1):PAGE236
     2    GND @BASEBOARD_FAB2_LIB.BASEBOARD_FAB2(SCH_1):GND   I182 @BASEBOARD_FAB2_LIB.BASEBOARD_FAB2(SCH_1):PAGE236

RT44 RES_0603-0,5.0%,1/10W,CHIP,G22A
     1 VR_PVNN_PCH_PH1_BOOT @BASEBOARD_FAB2_LIB.BASEBOARD_FAB2(SCH_1):VR_PVNN_PCH_PH1_BOOT   I153 @BASEBOARD_FAB2_LIB.BASEBOARD_FAB2(SCH_1):PAGE236
     2 VR_PVNN_PCH_PH1_BOOT_R @BASEBOARD_FAB2_LIB.BASEBOARD_FAB2(SCH_1):VR_PVNN_PCH_PH1_BOOT_R   I153 @BASEBOARD_FAB2_LIB.BASEBOARD_FAB2(SCH_1):PAGE236

RT45 1R3F-GP_RCL_GP-1R3F-GP,64.1R00A
     1 VR_P1V05_PCH_STBY_PH1_SW_RC @BASEBOARD_FAB2_LIB.BASEBOARD_FAB2(SCH_1):VR_P1V05_PCH_STBY_PH1_SW_RC   I183 @BASEBOARD_FAB2_LIB.BASEBOARD_FAB2(SCH_1):PAGE236
     2    GND @BASEBOARD_FAB2_LIB.BASEBOARD_FAB2(SCH_1):GND   I183 @BASEBOARD_FAB2_LIB.BASEBOARD_FAB2(SCH_1):PAGE236

RT46 RES_0603-0,5.0%,1/10W,CHIP,G22A
     1 VR_P1V05_PCH_STBY_PH1_BOOT @BASEBOARD_FAB2_LIB.BASEBOARD_FAB2(SCH_1):VR_P1V05_PCH_STBY_PH1_BOOT   I154 @BASEBOARD_FAB2_LIB.BASEBOARD_FAB2(SCH_1):PAGE236
     2 VR_P1V05_PCH_STBY_PH1_BOOT_R @BASEBOARD_FAB2_LIB.BASEBOARD_FAB2(SCH_1):VR_P1V05_PCH_STBY_PH1_BOOT_R   I154 @BASEBOARD_FAB2_LIB.BASEBOARD_FAB2(SCH_1):PAGE236

RT47 RES_0603-0,5.0%,1/10W,CHIP,G22A
     1 VR_PVCCIO_CPU0_PH1_BOOT @BASEBOARD_FAB2_LIB.BASEBOARD_FAB2(SCH_1):VR_PVCCIO_CPU0_PH1_BOOT   I120 @BASEBOARD_FAB2_LIB.BASEBOARD_FAB2(SCH_1):PAGE212
     2 VR_PVCCIO_CPU0_PH1_BOOT_R @BASEBOARD_FAB2_LIB.BASEBOARD_FAB2(SCH_1):VR_PVCCIO_CPU0_PH1_BOOT_R   I120 @BASEBOARD_FAB2_LIB.BASEBOARD_FAB2(SCH_1):PAGE212

RT48 1R3F-GP_RCL_GP-1R3F-GP,64.1R00A
     1 VR_PVCCIO_CPU0_PH1_SW_RC @BASEBOARD_FAB2_LIB.BASEBOARD_FAB2(SCH_1):VR_PVCCIO_CPU0_PH1_SW_RC   I144 @BASEBOARD_FAB2_LIB.BASEBOARD_FAB2(SCH_1):PAGE212
     2    GND @BASEBOARD_FAB2_LIB.BASEBOARD_FAB2(SCH_1):GND   I144 @BASEBOARD_FAB2_LIB.BASEBOARD_FAB2(SCH_1):PAGE212

S8E1 SWITCH_D90553001_SMLF-IC,D9055A
     1    GND @BASEBOARD_FAB2_LIB.BASEBOARD_FAB2(SCH_1):GND   I351 @BASEBOARD_FAB2_LIB.BASEBOARD_FAB2(SCH_1):PAGE157
     2 FP_NMI_BTN_OUT_R_N @BASEBOARD_FAB2_LIB.BASEBOARD_FAB2(SCH_1):FP_NMI_BTN_OUT_R_N   I351 @BASEBOARD_FAB2_LIB.BASEBOARD_FAB2(SCH_1):PAGE157

S9A1 SWITCH_D37771002_SM-IC,D37771-A
     4    GND @BASEBOARD_FAB2_LIB.BASEBOARD_FAB2(SCH_1):GND    I78 @BASEBOARD_FAB2_LIB.BASEBOARD_FAB2(SCH_1):PAGE175
     3    GND @BASEBOARD_FAB2_LIB.BASEBOARD_FAB2(SCH_1):GND    I78 @BASEBOARD_FAB2_LIB.BASEBOARD_FAB2(SCH_1):PAGE175
     1 FM_DEBUG_RST_BTN_N @BASEBOARD_FAB2_LIB.BASEBOARD_FAB2(SCH_1):FM_DEBUG_RST_BTN_N    I78 @BASEBOARD_FAB2_LIB.BASEBOARD_FAB2(SCH_1):PAGE175
     2 FM_DEBUG_RST_BTN_N @BASEBOARD_FAB2_LIB.BASEBOARD_FAB2(SCH_1):FM_DEBUG_RST_BTN_N    I78 @BASEBOARD_FAB2_LIB.BASEBOARD_FAB2(SCH_1):PAGE175

S9A2 SWITCH_D37771002_SM-IC,D37771-A
     4 FP_PWR_BTN_R_N @BASEBOARD_FAB2_LIB.BASEBOARD_FAB2(SCH_1):FP_PWR_BTN_R_N    I92 @BASEBOARD_FAB2_LIB.BASEBOARD_FAB2(SCH_1):PAGE175
     3 FP_PWR_BTN_R_N @BASEBOARD_FAB2_LIB.BASEBOARD_FAB2(SCH_1):FP_PWR_BTN_R_N    I92 @BASEBOARD_FAB2_LIB.BASEBOARD_FAB2(SCH_1):PAGE175
     1    GND @BASEBOARD_FAB2_LIB.BASEBOARD_FAB2(SCH_1):GND    I92 @BASEBOARD_FAB2_LIB.BASEBOARD_FAB2(SCH_1):PAGE175
     2    GND @BASEBOARD_FAB2_LIB.BASEBOARD_FAB2(SCH_1):GND    I92 @BASEBOARD_FAB2_LIB.BASEBOARD_FAB2(SCH_1):PAGE175

S9W1 SW-SLIDE75-GP_DISCRET-G6-SW-SLA
     1     NC     NC    I63 @BASEBOARD_FAB2_LIB.BASEBOARD_FAB2(SCH_1):PAGE268
     2 BMC_JTAG_SEL @BASEBOARD_FAB2_LIB.BASEBOARD_FAB2(SCH_1):BMC_JTAG_SEL    I63 @BASEBOARD_FAB2_LIB.BASEBOARD_FAB2(SCH_1):PAGE268
     3    GND @BASEBOARD_FAB2_LIB.BASEBOARD_FAB2(SCH_1):GND    I63 @BASEBOARD_FAB2_LIB.BASEBOARD_FAB2(SCH_1):PAGE268
     4    GND @BASEBOARD_FAB2_LIB.BASEBOARD_FAB2(SCH_1):GND    I63 @BASEBOARD_FAB2_LIB.BASEBOARD_FAB2(SCH_1):PAGE268
     5    GND @BASEBOARD_FAB2_LIB.BASEBOARD_FAB2(SCH_1):GND    I63 @BASEBOARD_FAB2_LIB.BASEBOARD_FAB2(SCH_1):PAGE268
   NP1     NC     NC    I63 @BASEBOARD_FAB2_LIB.BASEBOARD_FAB2(SCH_1):PAGE268
   NP2     NC     NC    I63 @BASEBOARD_FAB2_LIB.BASEBOARD_FAB2(SCH_1):PAGE268
     6    GND @BASEBOARD_FAB2_LIB.BASEBOARD_FAB2(SCH_1):GND    I63 @BASEBOARD_FAB2_LIB.BASEBOARD_FAB2(SCH_1):PAGE268
     7    GND @BASEBOARD_FAB2_LIB.BASEBOARD_FAB2(SCH_1):GND    I63 @BASEBOARD_FAB2_LIB.BASEBOARD_FAB2(SCH_1):PAGE268

SH3D1 SHUNT_SH0201-EMPTY,N_A
     1 VSENSE_PVCCIO_CPU1_SKT_VRTN @BASEBOARD_FAB2_LIB.BASEBOARD_FAB2(SCH_1):VSENSE_PVCCIO_CPU1_SKT_VRTN   I130 @BASEBOARD_FAB2_LIB.BASEBOARD_FAB2(SCH_1):PAGE214
     2 VSENSE_PVCCIO_CPU1_AVSN @BASEBOARD_FAB2_LIB.BASEBOARD_FAB2(SCH_1):VSENSE_PVCCIO_CPU1_AVSN   I130 @BASEBOARD_FAB2_LIB.BASEBOARD_FAB2(SCH_1):PAGE214

SH3D2 SHUNT_SH0201-EMPTY,N_A
     1 VSENSE_PVCCIO_CPU1_SKT_VSEN @BASEBOARD_FAB2_LIB.BASEBOARD_FAB2(SCH_1):VSENSE_PVCCIO_CPU1_SKT_VSEN   I129 @BASEBOARD_FAB2_LIB.BASEBOARD_FAB2(SCH_1):PAGE214
     2 VSENSE_PVCCIO_CPU1_AVSP @BASEBOARD_FAB2_LIB.BASEBOARD_FAB2(SCH_1):VSENSE_PVCCIO_CPU1_AVSP   I129 @BASEBOARD_FAB2_LIB.BASEBOARD_FAB2(SCH_1):PAGE214

SH3P1 SHUNT_SH0201-EMPTY,N_A
     1 VSENSE_PVCCIO_CPU0_SKT_VSEN @BASEBOARD_FAB2_LIB.BASEBOARD_FAB2(SCH_1):VSENSE_PVCCIO_CPU0_SKT_VSEN   I104 @BASEBOARD_FAB2_LIB.BASEBOARD_FAB2(SCH_1):PAGE212
     2 VSENSE_PVCCIO_CPU0_AVSP @BASEBOARD_FAB2_LIB.BASEBOARD_FAB2(SCH_1):VSENSE_PVCCIO_CPU0_AVSP   I104 @BASEBOARD_FAB2_LIB.BASEBOARD_FAB2(SCH_1):PAGE212

SH3P2 SHUNT_SH0201-EMPTY,N_A
     1 VSENSE_PVCCIO_CPU0_SKT_VRTN @BASEBOARD_FAB2_LIB.BASEBOARD_FAB2(SCH_1):VSENSE_PVCCIO_CPU0_SKT_VRTN   I105 @BASEBOARD_FAB2_LIB.BASEBOARD_FAB2(SCH_1):PAGE212
     2 VSENSE_PVCCIO_CPU0_AVSN @BASEBOARD_FAB2_LIB.BASEBOARD_FAB2(SCH_1):VSENSE_PVCCIO_CPU0_AVSN   I105 @BASEBOARD_FAB2_LIB.BASEBOARD_FAB2(SCH_1):PAGE212

SH4L1 SHUNT_SH0201-EMPTY,N_A
     1 VSENSE_PVDDQ_DEF_N @BASEBOARD_FAB2_LIB.BASEBOARD_FAB2(SCH_1):VSENSE_PVDDQ_DEF_N   I240 @BASEBOARD_FAB2_LIB.BASEBOARD_FAB2(SCH_1):PAGE220
     2    GND @BASEBOARD_FAB2_LIB.BASEBOARD_FAB2(SCH_1):GND   I240 @BASEBOARD_FAB2_LIB.BASEBOARD_FAB2(SCH_1):PAGE220

SH4L2 SHUNT_SH0201-EMPTY,N_A
     1 VSENSE_PVDDQ_DEF_P @BASEBOARD_FAB2_LIB.BASEBOARD_FAB2(SCH_1):VSENSE_PVDDQ_DEF_P   I239 @BASEBOARD_FAB2_LIB.BASEBOARD_FAB2(SCH_1):PAGE220
     2 PVDDQ_DEF @BASEBOARD_FAB2_LIB.BASEBOARD_FAB2(SCH_1):PVDDQ_DEF   I239 @BASEBOARD_FAB2_LIB.BASEBOARD_FAB2(SCH_1):PAGE220

SH4U1 SHUNT_SH0201-EMPTY,N_A
     1 VSENSE_PVDDQ_ABC_N @BASEBOARD_FAB2_LIB.BASEBOARD_FAB2(SCH_1):VSENSE_PVDDQ_ABC_N   I259 @BASEBOARD_FAB2_LIB.BASEBOARD_FAB2(SCH_1):PAGE217
     2    GND @BASEBOARD_FAB2_LIB.BASEBOARD_FAB2(SCH_1):GND   I259 @BASEBOARD_FAB2_LIB.BASEBOARD_FAB2(SCH_1):PAGE217

SH4U2 SHUNT_SH0201-EMPTY,N_A
     1 VSENSE_PVDDQ_ABC_P @BASEBOARD_FAB2_LIB.BASEBOARD_FAB2(SCH_1):VSENSE_PVDDQ_ABC_P   I260 @BASEBOARD_FAB2_LIB.BASEBOARD_FAB2(SCH_1):PAGE217
     2 PVDDQ_ABC @BASEBOARD_FAB2_LIB.BASEBOARD_FAB2(SCH_1):PVDDQ_ABC   I260 @BASEBOARD_FAB2_LIB.BASEBOARD_FAB2(SCH_1):PAGE217

SH5L1 SHUNT_SH0201-EMPTY,N_A
     1 VR_PVTT_DEF_SNS @BASEBOARD_FAB2_LIB.BASEBOARD_FAB2(SCH_1):VR_PVTT_DEF_SNS    I30 @BASEBOARD_FAB2_LIB.BASEBOARD_FAB2(SCH_1):PAGE222
     2 PVTT_DEF @BASEBOARD_FAB2_LIB.BASEBOARD_FAB2(SCH_1):PVTT_DEF    I30 @BASEBOARD_FAB2_LIB.BASEBOARD_FAB2(SCH_1):PAGE222

SH5U1 SHUNT_SH0201-EMPTY,N_A
     1 VR_PVTT_ABC_SNS @BASEBOARD_FAB2_LIB.BASEBOARD_FAB2(SCH_1):VR_PVTT_ABC_SNS     I9 @BASEBOARD_FAB2_LIB.BASEBOARD_FAB2(SCH_1):PAGE221
     2 PVTT_ABC @BASEBOARD_FAB2_LIB.BASEBOARD_FAB2(SCH_1):PVTT_ABC     I9 @BASEBOARD_FAB2_LIB.BASEBOARD_FAB2(SCH_1):PAGE221

SH7L1 SHUNT_SH0201-EMPTY,N_A
     1 VSENSE_PVDDQ_KLM_N @BASEBOARD_FAB2_LIB.BASEBOARD_FAB2(SCH_1):VSENSE_PVDDQ_KLM_N   I246 @BASEBOARD_FAB2_LIB.BASEBOARD_FAB2(SCH_1):PAGE228
     2    GND @BASEBOARD_FAB2_LIB.BASEBOARD_FAB2(SCH_1):GND   I246 @BASEBOARD_FAB2_LIB.BASEBOARD_FAB2(SCH_1):PAGE228

SH7L2 SHUNT_SH0201-EMPTY,N_A
     1 VSENSE_PVDDQ_KLM_P @BASEBOARD_FAB2_LIB.BASEBOARD_FAB2(SCH_1):VSENSE_PVDDQ_KLM_P   I245 @BASEBOARD_FAB2_LIB.BASEBOARD_FAB2(SCH_1):PAGE228
     2 PVDDQ_KLM @BASEBOARD_FAB2_LIB.BASEBOARD_FAB2(SCH_1):PVDDQ_KLM   I245 @BASEBOARD_FAB2_LIB.BASEBOARD_FAB2(SCH_1):PAGE228

SH7U1 SHUNT_SH0201-EMPTY,N_A
     1 VSENSE_PVDDQ_GHJ_P @BASEBOARD_FAB2_LIB.BASEBOARD_FAB2(SCH_1):VSENSE_PVDDQ_GHJ_P   I243 @BASEBOARD_FAB2_LIB.BASEBOARD_FAB2(SCH_1):PAGE225
     2 PVDDQ_GHJ @BASEBOARD_FAB2_LIB.BASEBOARD_FAB2(SCH_1):PVDDQ_GHJ   I243 @BASEBOARD_FAB2_LIB.BASEBOARD_FAB2(SCH_1):PAGE225

SH7U2 SHUNT_SH0201-EMPTY,N_A
     1 VSENSE_PVDDQ_GHJ_N @BASEBOARD_FAB2_LIB.BASEBOARD_FAB2(SCH_1):VSENSE_PVDDQ_GHJ_N   I244 @BASEBOARD_FAB2_LIB.BASEBOARD_FAB2(SCH_1):PAGE225
     2    GND @BASEBOARD_FAB2_LIB.BASEBOARD_FAB2(SCH_1):GND   I244 @BASEBOARD_FAB2_LIB.BASEBOARD_FAB2(SCH_1):PAGE225

SH8L1 SHUNT_SH0201-EMPTY,N_A
     1 VR_PVTT_KLM_SNS @BASEBOARD_FAB2_LIB.BASEBOARD_FAB2(SCH_1):VR_PVTT_KLM_SNS    I30 @BASEBOARD_FAB2_LIB.BASEBOARD_FAB2(SCH_1):PAGE230
     2 PVTT_KLM @BASEBOARD_FAB2_LIB.BASEBOARD_FAB2(SCH_1):PVTT_KLM    I30 @BASEBOARD_FAB2_LIB.BASEBOARD_FAB2(SCH_1):PAGE230

SH8U1 SHUNT_SH0201-EMPTY,N_A
     1 VR_PVTT_GHJ_SNS @BASEBOARD_FAB2_LIB.BASEBOARD_FAB2(SCH_1):VR_PVTT_GHJ_SNS    I12 @BASEBOARD_FAB2_LIB.BASEBOARD_FAB2(SCH_1):PAGE229
     2 PVTT_GHJ @BASEBOARD_FAB2_LIB.BASEBOARD_FAB2(SCH_1):PVTT_GHJ    I12 @BASEBOARD_FAB2_LIB.BASEBOARD_FAB2(SCH_1):PAGE229

T1D1 TEST-PAD-12P-1-GP-U_DISCRET-GBA
     3    GND @BASEBOARD_FAB2_LIB.BASEBOARD_FAB2(SCH_1):GND     I1 @BASEBOARD_FAB2_LIB.BASEBOARD_FAB2(SCH_1):PAGE270
     4    GND @BASEBOARD_FAB2_LIB.BASEBOARD_FAB2(SCH_1):GND     I1 @BASEBOARD_FAB2_LIB.BASEBOARD_FAB2(SCH_1):PAGE270
     5    GND @BASEBOARD_FAB2_LIB.BASEBOARD_FAB2(SCH_1):GND     I1 @BASEBOARD_FAB2_LIB.BASEBOARD_FAB2(SCH_1):PAGE270
     6    GND @BASEBOARD_FAB2_LIB.BASEBOARD_FAB2(SCH_1):GND     I1 @BASEBOARD_FAB2_LIB.BASEBOARD_FAB2(SCH_1):PAGE270
     7    GND @BASEBOARD_FAB2_LIB.BASEBOARD_FAB2(SCH_1):GND     I1 @BASEBOARD_FAB2_LIB.BASEBOARD_FAB2(SCH_1):PAGE270
     8    GND @BASEBOARD_FAB2_LIB.BASEBOARD_FAB2(SCH_1):GND     I1 @BASEBOARD_FAB2_LIB.BASEBOARD_FAB2(SCH_1):PAGE270
     9    GND @BASEBOARD_FAB2_LIB.BASEBOARD_FAB2(SCH_1):GND     I1 @BASEBOARD_FAB2_LIB.BASEBOARD_FAB2(SCH_1):PAGE270
    10    GND @BASEBOARD_FAB2_LIB.BASEBOARD_FAB2(SCH_1):GND     I1 @BASEBOARD_FAB2_LIB.BASEBOARD_FAB2(SCH_1):PAGE270
    11    GND @BASEBOARD_FAB2_LIB.BASEBOARD_FAB2(SCH_1):GND     I1 @BASEBOARD_FAB2_LIB.BASEBOARD_FAB2(SCH_1):PAGE270
    12    GND @BASEBOARD_FAB2_LIB.BASEBOARD_FAB2(SCH_1):GND     I1 @BASEBOARD_FAB2_LIB.BASEBOARD_FAB2(SCH_1):PAGE270
     1 L1_85OHM_5INCH_DP @BASEBOARD_FAB2_LIB.BASEBOARD_FAB2(SCH_1):L1_85OHM_5INCH_DP     I1 @BASEBOARD_FAB2_LIB.BASEBOARD_FAB2(SCH_1):PAGE270
     2 L1_85OHM_5INCH_DN @BASEBOARD_FAB2_LIB.BASEBOARD_FAB2(SCH_1):L1_85OHM_5INCH_DN     I1 @BASEBOARD_FAB2_LIB.BASEBOARD_FAB2(SCH_1):PAGE270

T1D2 TEST-PAD-12P-1-GP-U_DISCRET-GBA
     3    GND @BASEBOARD_FAB2_LIB.BASEBOARD_FAB2(SCH_1):GND     I3 @BASEBOARD_FAB2_LIB.BASEBOARD_FAB2(SCH_1):PAGE270
     4    GND @BASEBOARD_FAB2_LIB.BASEBOARD_FAB2(SCH_1):GND     I3 @BASEBOARD_FAB2_LIB.BASEBOARD_FAB2(SCH_1):PAGE270
     5    GND @BASEBOARD_FAB2_LIB.BASEBOARD_FAB2(SCH_1):GND     I3 @BASEBOARD_FAB2_LIB.BASEBOARD_FAB2(SCH_1):PAGE270
     6    GND @BASEBOARD_FAB2_LIB.BASEBOARD_FAB2(SCH_1):GND     I3 @BASEBOARD_FAB2_LIB.BASEBOARD_FAB2(SCH_1):PAGE270
     7    GND @BASEBOARD_FAB2_LIB.BASEBOARD_FAB2(SCH_1):GND     I3 @BASEBOARD_FAB2_LIB.BASEBOARD_FAB2(SCH_1):PAGE270
     8    GND @BASEBOARD_FAB2_LIB.BASEBOARD_FAB2(SCH_1):GND     I3 @BASEBOARD_FAB2_LIB.BASEBOARD_FAB2(SCH_1):PAGE270
     9    GND @BASEBOARD_FAB2_LIB.BASEBOARD_FAB2(SCH_1):GND     I3 @BASEBOARD_FAB2_LIB.BASEBOARD_FAB2(SCH_1):PAGE270
    10    GND @BASEBOARD_FAB2_LIB.BASEBOARD_FAB2(SCH_1):GND     I3 @BASEBOARD_FAB2_LIB.BASEBOARD_FAB2(SCH_1):PAGE270
    11    GND @BASEBOARD_FAB2_LIB.BASEBOARD_FAB2(SCH_1):GND     I3 @BASEBOARD_FAB2_LIB.BASEBOARD_FAB2(SCH_1):PAGE270
    12    GND @BASEBOARD_FAB2_LIB.BASEBOARD_FAB2(SCH_1):GND     I3 @BASEBOARD_FAB2_LIB.BASEBOARD_FAB2(SCH_1):PAGE270
     1 L1_85OHM_5INCH_DN @BASEBOARD_FAB2_LIB.BASEBOARD_FAB2(SCH_1):L1_85OHM_5INCH_DN     I3 @BASEBOARD_FAB2_LIB.BASEBOARD_FAB2(SCH_1):PAGE270
     2 L1_85OHM_5INCH_DP @BASEBOARD_FAB2_LIB.BASEBOARD_FAB2(SCH_1):L1_85OHM_5INCH_DP     I3 @BASEBOARD_FAB2_LIB.BASEBOARD_FAB2(SCH_1):PAGE270

T1D3 TEST-PAD-12P-1-GP-U_DISCRET-GBA
     3    GND @BASEBOARD_FAB2_LIB.BASEBOARD_FAB2(SCH_1):GND     I5 @BASEBOARD_FAB2_LIB.BASEBOARD_FAB2(SCH_1):PAGE270
     4    GND @BASEBOARD_FAB2_LIB.BASEBOARD_FAB2(SCH_1):GND     I5 @BASEBOARD_FAB2_LIB.BASEBOARD_FAB2(SCH_1):PAGE270
     5    GND @BASEBOARD_FAB2_LIB.BASEBOARD_FAB2(SCH_1):GND     I5 @BASEBOARD_FAB2_LIB.BASEBOARD_FAB2(SCH_1):PAGE270
     6    GND @BASEBOARD_FAB2_LIB.BASEBOARD_FAB2(SCH_1):GND     I5 @BASEBOARD_FAB2_LIB.BASEBOARD_FAB2(SCH_1):PAGE270
     7    GND @BASEBOARD_FAB2_LIB.BASEBOARD_FAB2(SCH_1):GND     I5 @BASEBOARD_FAB2_LIB.BASEBOARD_FAB2(SCH_1):PAGE270
     8    GND @BASEBOARD_FAB2_LIB.BASEBOARD_FAB2(SCH_1):GND     I5 @BASEBOARD_FAB2_LIB.BASEBOARD_FAB2(SCH_1):PAGE270
     9    GND @BASEBOARD_FAB2_LIB.BASEBOARD_FAB2(SCH_1):GND     I5 @BASEBOARD_FAB2_LIB.BASEBOARD_FAB2(SCH_1):PAGE270
    10    GND @BASEBOARD_FAB2_LIB.BASEBOARD_FAB2(SCH_1):GND     I5 @BASEBOARD_FAB2_LIB.BASEBOARD_FAB2(SCH_1):PAGE270
    11    GND @BASEBOARD_FAB2_LIB.BASEBOARD_FAB2(SCH_1):GND     I5 @BASEBOARD_FAB2_LIB.BASEBOARD_FAB2(SCH_1):PAGE270
    12    GND @BASEBOARD_FAB2_LIB.BASEBOARD_FAB2(SCH_1):GND     I5 @BASEBOARD_FAB2_LIB.BASEBOARD_FAB2(SCH_1):PAGE270
     1 L3_85OHM_5INCH_DP @BASEBOARD_FAB2_LIB.BASEBOARD_FAB2(SCH_1):L3_85OHM_5INCH_DP     I5 @BASEBOARD_FAB2_LIB.BASEBOARD_FAB2(SCH_1):PAGE270
     2 L3_85OHM_5INCH_DN @BASEBOARD_FAB2_LIB.BASEBOARD_FAB2(SCH_1):L3_85OHM_5INCH_DN     I5 @BASEBOARD_FAB2_LIB.BASEBOARD_FAB2(SCH_1):PAGE270

T1D4 TEST-PAD-12P-1-GP-U_DISCRET-GBA
     3    GND @BASEBOARD_FAB2_LIB.BASEBOARD_FAB2(SCH_1):GND     I6 @BASEBOARD_FAB2_LIB.BASEBOARD_FAB2(SCH_1):PAGE270
     4    GND @BASEBOARD_FAB2_LIB.BASEBOARD_FAB2(SCH_1):GND     I6 @BASEBOARD_FAB2_LIB.BASEBOARD_FAB2(SCH_1):PAGE270
     5    GND @BASEBOARD_FAB2_LIB.BASEBOARD_FAB2(SCH_1):GND     I6 @BASEBOARD_FAB2_LIB.BASEBOARD_FAB2(SCH_1):PAGE270
     6    GND @BASEBOARD_FAB2_LIB.BASEBOARD_FAB2(SCH_1):GND     I6 @BASEBOARD_FAB2_LIB.BASEBOARD_FAB2(SCH_1):PAGE270
     7    GND @BASEBOARD_FAB2_LIB.BASEBOARD_FAB2(SCH_1):GND     I6 @BASEBOARD_FAB2_LIB.BASEBOARD_FAB2(SCH_1):PAGE270
     8    GND @BASEBOARD_FAB2_LIB.BASEBOARD_FAB2(SCH_1):GND     I6 @BASEBOARD_FAB2_LIB.BASEBOARD_FAB2(SCH_1):PAGE270
     9    GND @BASEBOARD_FAB2_LIB.BASEBOARD_FAB2(SCH_1):GND     I6 @BASEBOARD_FAB2_LIB.BASEBOARD_FAB2(SCH_1):PAGE270
    10    GND @BASEBOARD_FAB2_LIB.BASEBOARD_FAB2(SCH_1):GND     I6 @BASEBOARD_FAB2_LIB.BASEBOARD_FAB2(SCH_1):PAGE270
    11    GND @BASEBOARD_FAB2_LIB.BASEBOARD_FAB2(SCH_1):GND     I6 @BASEBOARD_FAB2_LIB.BASEBOARD_FAB2(SCH_1):PAGE270
    12    GND @BASEBOARD_FAB2_LIB.BASEBOARD_FAB2(SCH_1):GND     I6 @BASEBOARD_FAB2_LIB.BASEBOARD_FAB2(SCH_1):PAGE270
     1 L3_85OHM_5INCH_DN @BASEBOARD_FAB2_LIB.BASEBOARD_FAB2(SCH_1):L3_85OHM_5INCH_DN     I6 @BASEBOARD_FAB2_LIB.BASEBOARD_FAB2(SCH_1):PAGE270
     2 L3_85OHM_5INCH_DP @BASEBOARD_FAB2_LIB.BASEBOARD_FAB2(SCH_1):L3_85OHM_5INCH_DP     I6 @BASEBOARD_FAB2_LIB.BASEBOARD_FAB2(SCH_1):PAGE270

T1D5 TEST-PAD-12P-1-GP-U_DISCRET-GBA
     3    GND @BASEBOARD_FAB2_LIB.BASEBOARD_FAB2(SCH_1):GND    I12 @BASEBOARD_FAB2_LIB.BASEBOARD_FAB2(SCH_1):PAGE270
     4    GND @BASEBOARD_FAB2_LIB.BASEBOARD_FAB2(SCH_1):GND    I12 @BASEBOARD_FAB2_LIB.BASEBOARD_FAB2(SCH_1):PAGE270
     5    GND @BASEBOARD_FAB2_LIB.BASEBOARD_FAB2(SCH_1):GND    I12 @BASEBOARD_FAB2_LIB.BASEBOARD_FAB2(SCH_1):PAGE270
     6    GND @BASEBOARD_FAB2_LIB.BASEBOARD_FAB2(SCH_1):GND    I12 @BASEBOARD_FAB2_LIB.BASEBOARD_FAB2(SCH_1):PAGE270
     7    GND @BASEBOARD_FAB2_LIB.BASEBOARD_FAB2(SCH_1):GND    I12 @BASEBOARD_FAB2_LIB.BASEBOARD_FAB2(SCH_1):PAGE270
     8    GND @BASEBOARD_FAB2_LIB.BASEBOARD_FAB2(SCH_1):GND    I12 @BASEBOARD_FAB2_LIB.BASEBOARD_FAB2(SCH_1):PAGE270
     9    GND @BASEBOARD_FAB2_LIB.BASEBOARD_FAB2(SCH_1):GND    I12 @BASEBOARD_FAB2_LIB.BASEBOARD_FAB2(SCH_1):PAGE270
    10    GND @BASEBOARD_FAB2_LIB.BASEBOARD_FAB2(SCH_1):GND    I12 @BASEBOARD_FAB2_LIB.BASEBOARD_FAB2(SCH_1):PAGE270
    11    GND @BASEBOARD_FAB2_LIB.BASEBOARD_FAB2(SCH_1):GND    I12 @BASEBOARD_FAB2_LIB.BASEBOARD_FAB2(SCH_1):PAGE270
    12    GND @BASEBOARD_FAB2_LIB.BASEBOARD_FAB2(SCH_1):GND    I12 @BASEBOARD_FAB2_LIB.BASEBOARD_FAB2(SCH_1):PAGE270
     1 L5_85OHM_5INCH_DP @BASEBOARD_FAB2_LIB.BASEBOARD_FAB2(SCH_1):L5_85OHM_5INCH_DP    I12 @BASEBOARD_FAB2_LIB.BASEBOARD_FAB2(SCH_1):PAGE270
     2 L5_85OHM_5INCH_DN @BASEBOARD_FAB2_LIB.BASEBOARD_FAB2(SCH_1):L5_85OHM_5INCH_DN    I12 @BASEBOARD_FAB2_LIB.BASEBOARD_FAB2(SCH_1):PAGE270

T1D6 TEST-PAD-12P-1-GP-U_DISCRET-GBA
     3    GND @BASEBOARD_FAB2_LIB.BASEBOARD_FAB2(SCH_1):GND     I9 @BASEBOARD_FAB2_LIB.BASEBOARD_FAB2(SCH_1):PAGE270
     4    GND @BASEBOARD_FAB2_LIB.BASEBOARD_FAB2(SCH_1):GND     I9 @BASEBOARD_FAB2_LIB.BASEBOARD_FAB2(SCH_1):PAGE270
     5    GND @BASEBOARD_FAB2_LIB.BASEBOARD_FAB2(SCH_1):GND     I9 @BASEBOARD_FAB2_LIB.BASEBOARD_FAB2(SCH_1):PAGE270
     6    GND @BASEBOARD_FAB2_LIB.BASEBOARD_FAB2(SCH_1):GND     I9 @BASEBOARD_FAB2_LIB.BASEBOARD_FAB2(SCH_1):PAGE270
     7    GND @BASEBOARD_FAB2_LIB.BASEBOARD_FAB2(SCH_1):GND     I9 @BASEBOARD_FAB2_LIB.BASEBOARD_FAB2(SCH_1):PAGE270
     8    GND @BASEBOARD_FAB2_LIB.BASEBOARD_FAB2(SCH_1):GND     I9 @BASEBOARD_FAB2_LIB.BASEBOARD_FAB2(SCH_1):PAGE270
     9    GND @BASEBOARD_FAB2_LIB.BASEBOARD_FAB2(SCH_1):GND     I9 @BASEBOARD_FAB2_LIB.BASEBOARD_FAB2(SCH_1):PAGE270
    10    GND @BASEBOARD_FAB2_LIB.BASEBOARD_FAB2(SCH_1):GND     I9 @BASEBOARD_FAB2_LIB.BASEBOARD_FAB2(SCH_1):PAGE270
    11    GND @BASEBOARD_FAB2_LIB.BASEBOARD_FAB2(SCH_1):GND     I9 @BASEBOARD_FAB2_LIB.BASEBOARD_FAB2(SCH_1):PAGE270
    12    GND @BASEBOARD_FAB2_LIB.BASEBOARD_FAB2(SCH_1):GND     I9 @BASEBOARD_FAB2_LIB.BASEBOARD_FAB2(SCH_1):PAGE270
     1 L5_85OHM_5INCH_DN @BASEBOARD_FAB2_LIB.BASEBOARD_FAB2(SCH_1):L5_85OHM_5INCH_DN     I9 @BASEBOARD_FAB2_LIB.BASEBOARD_FAB2(SCH_1):PAGE270
     2 L5_85OHM_5INCH_DP @BASEBOARD_FAB2_LIB.BASEBOARD_FAB2(SCH_1):L5_85OHM_5INCH_DP     I9 @BASEBOARD_FAB2_LIB.BASEBOARD_FAB2(SCH_1):PAGE270

T1D7 TEST-PAD-12P-1-GP-U_DISCRET-GBA
     3    GND @BASEBOARD_FAB2_LIB.BASEBOARD_FAB2(SCH_1):GND    I16 @BASEBOARD_FAB2_LIB.BASEBOARD_FAB2(SCH_1):PAGE270
     4    GND @BASEBOARD_FAB2_LIB.BASEBOARD_FAB2(SCH_1):GND    I16 @BASEBOARD_FAB2_LIB.BASEBOARD_FAB2(SCH_1):PAGE270
     5    GND @BASEBOARD_FAB2_LIB.BASEBOARD_FAB2(SCH_1):GND    I16 @BASEBOARD_FAB2_LIB.BASEBOARD_FAB2(SCH_1):PAGE270
     6    GND @BASEBOARD_FAB2_LIB.BASEBOARD_FAB2(SCH_1):GND    I16 @BASEBOARD_FAB2_LIB.BASEBOARD_FAB2(SCH_1):PAGE270
     7    GND @BASEBOARD_FAB2_LIB.BASEBOARD_FAB2(SCH_1):GND    I16 @BASEBOARD_FAB2_LIB.BASEBOARD_FAB2(SCH_1):PAGE270
     8    GND @BASEBOARD_FAB2_LIB.BASEBOARD_FAB2(SCH_1):GND    I16 @BASEBOARD_FAB2_LIB.BASEBOARD_FAB2(SCH_1):PAGE270
     9    GND @BASEBOARD_FAB2_LIB.BASEBOARD_FAB2(SCH_1):GND    I16 @BASEBOARD_FAB2_LIB.BASEBOARD_FAB2(SCH_1):PAGE270
    10    GND @BASEBOARD_FAB2_LIB.BASEBOARD_FAB2(SCH_1):GND    I16 @BASEBOARD_FAB2_LIB.BASEBOARD_FAB2(SCH_1):PAGE270
    11    GND @BASEBOARD_FAB2_LIB.BASEBOARD_FAB2(SCH_1):GND    I16 @BASEBOARD_FAB2_LIB.BASEBOARD_FAB2(SCH_1):PAGE270
    12    GND @BASEBOARD_FAB2_LIB.BASEBOARD_FAB2(SCH_1):GND    I16 @BASEBOARD_FAB2_LIB.BASEBOARD_FAB2(SCH_1):PAGE270
     1 L10_85OHM_5INCH_DP @BASEBOARD_FAB2_LIB.BASEBOARD_FAB2(SCH_1):L10_85OHM_5INCH_DP    I16 @BASEBOARD_FAB2_LIB.BASEBOARD_FAB2(SCH_1):PAGE270
     2 L10_85OHM_5INCH_DN @BASEBOARD_FAB2_LIB.BASEBOARD_FAB2(SCH_1):L10_85OHM_5INCH_DN    I16 @BASEBOARD_FAB2_LIB.BASEBOARD_FAB2(SCH_1):PAGE270

T1D8 TEST-PAD-12P-1-GP-U_DISCRET-GBA
     3    GND @BASEBOARD_FAB2_LIB.BASEBOARD_FAB2(SCH_1):GND    I13 @BASEBOARD_FAB2_LIB.BASEBOARD_FAB2(SCH_1):PAGE270
     4    GND @BASEBOARD_FAB2_LIB.BASEBOARD_FAB2(SCH_1):GND    I13 @BASEBOARD_FAB2_LIB.BASEBOARD_FAB2(SCH_1):PAGE270
     5    GND @BASEBOARD_FAB2_LIB.BASEBOARD_FAB2(SCH_1):GND    I13 @BASEBOARD_FAB2_LIB.BASEBOARD_FAB2(SCH_1):PAGE270
     6    GND @BASEBOARD_FAB2_LIB.BASEBOARD_FAB2(SCH_1):GND    I13 @BASEBOARD_FAB2_LIB.BASEBOARD_FAB2(SCH_1):PAGE270
     7    GND @BASEBOARD_FAB2_LIB.BASEBOARD_FAB2(SCH_1):GND    I13 @BASEBOARD_FAB2_LIB.BASEBOARD_FAB2(SCH_1):PAGE270
     8    GND @BASEBOARD_FAB2_LIB.BASEBOARD_FAB2(SCH_1):GND    I13 @BASEBOARD_FAB2_LIB.BASEBOARD_FAB2(SCH_1):PAGE270
     9    GND @BASEBOARD_FAB2_LIB.BASEBOARD_FAB2(SCH_1):GND    I13 @BASEBOARD_FAB2_LIB.BASEBOARD_FAB2(SCH_1):PAGE270
    10    GND @BASEBOARD_FAB2_LIB.BASEBOARD_FAB2(SCH_1):GND    I13 @BASEBOARD_FAB2_LIB.BASEBOARD_FAB2(SCH_1):PAGE270
    11    GND @BASEBOARD_FAB2_LIB.BASEBOARD_FAB2(SCH_1):GND    I13 @BASEBOARD_FAB2_LIB.BASEBOARD_FAB2(SCH_1):PAGE270
    12    GND @BASEBOARD_FAB2_LIB.BASEBOARD_FAB2(SCH_1):GND    I13 @BASEBOARD_FAB2_LIB.BASEBOARD_FAB2(SCH_1):PAGE270
     1 L10_85OHM_5INCH_DN @BASEBOARD_FAB2_LIB.BASEBOARD_FAB2(SCH_1):L10_85OHM_5INCH_DN    I13 @BASEBOARD_FAB2_LIB.BASEBOARD_FAB2(SCH_1):PAGE270
     2 L10_85OHM_5INCH_DP @BASEBOARD_FAB2_LIB.BASEBOARD_FAB2(SCH_1):L10_85OHM_5INCH_DP    I13 @BASEBOARD_FAB2_LIB.BASEBOARD_FAB2(SCH_1):PAGE270

T1D9 TEST-PAD-12P-1-GP-U_DISCRET-GBA
     3    GND @BASEBOARD_FAB2_LIB.BASEBOARD_FAB2(SCH_1):GND    I18 @BASEBOARD_FAB2_LIB.BASEBOARD_FAB2(SCH_1):PAGE270
     4    GND @BASEBOARD_FAB2_LIB.BASEBOARD_FAB2(SCH_1):GND    I18 @BASEBOARD_FAB2_LIB.BASEBOARD_FAB2(SCH_1):PAGE270
     5    GND @BASEBOARD_FAB2_LIB.BASEBOARD_FAB2(SCH_1):GND    I18 @BASEBOARD_FAB2_LIB.BASEBOARD_FAB2(SCH_1):PAGE270
     6    GND @BASEBOARD_FAB2_LIB.BASEBOARD_FAB2(SCH_1):GND    I18 @BASEBOARD_FAB2_LIB.BASEBOARD_FAB2(SCH_1):PAGE270
     7    GND @BASEBOARD_FAB2_LIB.BASEBOARD_FAB2(SCH_1):GND    I18 @BASEBOARD_FAB2_LIB.BASEBOARD_FAB2(SCH_1):PAGE270
     8    GND @BASEBOARD_FAB2_LIB.BASEBOARD_FAB2(SCH_1):GND    I18 @BASEBOARD_FAB2_LIB.BASEBOARD_FAB2(SCH_1):PAGE270
     9    GND @BASEBOARD_FAB2_LIB.BASEBOARD_FAB2(SCH_1):GND    I18 @BASEBOARD_FAB2_LIB.BASEBOARD_FAB2(SCH_1):PAGE270
    10    GND @BASEBOARD_FAB2_LIB.BASEBOARD_FAB2(SCH_1):GND    I18 @BASEBOARD_FAB2_LIB.BASEBOARD_FAB2(SCH_1):PAGE270
    11    GND @BASEBOARD_FAB2_LIB.BASEBOARD_FAB2(SCH_1):GND    I18 @BASEBOARD_FAB2_LIB.BASEBOARD_FAB2(SCH_1):PAGE270
    12    GND @BASEBOARD_FAB2_LIB.BASEBOARD_FAB2(SCH_1):GND    I18 @BASEBOARD_FAB2_LIB.BASEBOARD_FAB2(SCH_1):PAGE270
     1 L12_85OHM_5INCH_DP @BASEBOARD_FAB2_LIB.BASEBOARD_FAB2(SCH_1):L12_85OHM_5INCH_DP    I18 @BASEBOARD_FAB2_LIB.BASEBOARD_FAB2(SCH_1):PAGE270
     2 L12_85OHM_5INCH_DN @BASEBOARD_FAB2_LIB.BASEBOARD_FAB2(SCH_1):L12_85OHM_5INCH_DN    I18 @BASEBOARD_FAB2_LIB.BASEBOARD_FAB2(SCH_1):PAGE270

T1D10 TEST-PAD-12P-1-GP-U_DISCRET-GBA
     3    GND @BASEBOARD_FAB2_LIB.BASEBOARD_FAB2(SCH_1):GND    I17 @BASEBOARD_FAB2_LIB.BASEBOARD_FAB2(SCH_1):PAGE270
     4    GND @BASEBOARD_FAB2_LIB.BASEBOARD_FAB2(SCH_1):GND    I17 @BASEBOARD_FAB2_LIB.BASEBOARD_FAB2(SCH_1):PAGE270
     5    GND @BASEBOARD_FAB2_LIB.BASEBOARD_FAB2(SCH_1):GND    I17 @BASEBOARD_FAB2_LIB.BASEBOARD_FAB2(SCH_1):PAGE270
     6    GND @BASEBOARD_FAB2_LIB.BASEBOARD_FAB2(SCH_1):GND    I17 @BASEBOARD_FAB2_LIB.BASEBOARD_FAB2(SCH_1):PAGE270
     7    GND @BASEBOARD_FAB2_LIB.BASEBOARD_FAB2(SCH_1):GND    I17 @BASEBOARD_FAB2_LIB.BASEBOARD_FAB2(SCH_1):PAGE270
     8    GND @BASEBOARD_FAB2_LIB.BASEBOARD_FAB2(SCH_1):GND    I17 @BASEBOARD_FAB2_LIB.BASEBOARD_FAB2(SCH_1):PAGE270
     9    GND @BASEBOARD_FAB2_LIB.BASEBOARD_FAB2(SCH_1):GND    I17 @BASEBOARD_FAB2_LIB.BASEBOARD_FAB2(SCH_1):PAGE270
    10    GND @BASEBOARD_FAB2_LIB.BASEBOARD_FAB2(SCH_1):GND    I17 @BASEBOARD_FAB2_LIB.BASEBOARD_FAB2(SCH_1):PAGE270
    11    GND @BASEBOARD_FAB2_LIB.BASEBOARD_FAB2(SCH_1):GND    I17 @BASEBOARD_FAB2_LIB.BASEBOARD_FAB2(SCH_1):PAGE270
    12    GND @BASEBOARD_FAB2_LIB.BASEBOARD_FAB2(SCH_1):GND    I17 @BASEBOARD_FAB2_LIB.BASEBOARD_FAB2(SCH_1):PAGE270
     1 L12_85OHM_5INCH_DN @BASEBOARD_FAB2_LIB.BASEBOARD_FAB2(SCH_1):L12_85OHM_5INCH_DN    I17 @BASEBOARD_FAB2_LIB.BASEBOARD_FAB2(SCH_1):PAGE270
     2 L12_85OHM_5INCH_DP @BASEBOARD_FAB2_LIB.BASEBOARD_FAB2(SCH_1):L12_85OHM_5INCH_DP    I17 @BASEBOARD_FAB2_LIB.BASEBOARD_FAB2(SCH_1):PAGE270

T1D11 TEST-PAD-12P-1-GP-U_DISCRET-GBA
     3    GND @BASEBOARD_FAB2_LIB.BASEBOARD_FAB2(SCH_1):GND    I24 @BASEBOARD_FAB2_LIB.BASEBOARD_FAB2(SCH_1):PAGE270
     4    GND @BASEBOARD_FAB2_LIB.BASEBOARD_FAB2(SCH_1):GND    I24 @BASEBOARD_FAB2_LIB.BASEBOARD_FAB2(SCH_1):PAGE270
     5    GND @BASEBOARD_FAB2_LIB.BASEBOARD_FAB2(SCH_1):GND    I24 @BASEBOARD_FAB2_LIB.BASEBOARD_FAB2(SCH_1):PAGE270
     6    GND @BASEBOARD_FAB2_LIB.BASEBOARD_FAB2(SCH_1):GND    I24 @BASEBOARD_FAB2_LIB.BASEBOARD_FAB2(SCH_1):PAGE270
     7    GND @BASEBOARD_FAB2_LIB.BASEBOARD_FAB2(SCH_1):GND    I24 @BASEBOARD_FAB2_LIB.BASEBOARD_FAB2(SCH_1):PAGE270
     8    GND @BASEBOARD_FAB2_LIB.BASEBOARD_FAB2(SCH_1):GND    I24 @BASEBOARD_FAB2_LIB.BASEBOARD_FAB2(SCH_1):PAGE270
     9    GND @BASEBOARD_FAB2_LIB.BASEBOARD_FAB2(SCH_1):GND    I24 @BASEBOARD_FAB2_LIB.BASEBOARD_FAB2(SCH_1):PAGE270
    10    GND @BASEBOARD_FAB2_LIB.BASEBOARD_FAB2(SCH_1):GND    I24 @BASEBOARD_FAB2_LIB.BASEBOARD_FAB2(SCH_1):PAGE270
    11    GND @BASEBOARD_FAB2_LIB.BASEBOARD_FAB2(SCH_1):GND    I24 @BASEBOARD_FAB2_LIB.BASEBOARD_FAB2(SCH_1):PAGE270
    12    GND @BASEBOARD_FAB2_LIB.BASEBOARD_FAB2(SCH_1):GND    I24 @BASEBOARD_FAB2_LIB.BASEBOARD_FAB2(SCH_1):PAGE270
     1 L14_85OHM_5INCH_DP @BASEBOARD_FAB2_LIB.BASEBOARD_FAB2(SCH_1):L14_85OHM_5INCH_DP    I24 @BASEBOARD_FAB2_LIB.BASEBOARD_FAB2(SCH_1):PAGE270
     2 L14_85OHM_5INCH_DN @BASEBOARD_FAB2_LIB.BASEBOARD_FAB2(SCH_1):L14_85OHM_5INCH_DN    I24 @BASEBOARD_FAB2_LIB.BASEBOARD_FAB2(SCH_1):PAGE270

T1D12 TEST-PAD-12P-1-GP-U_DISCRET-GBA
     3    GND @BASEBOARD_FAB2_LIB.BASEBOARD_FAB2(SCH_1):GND    I21 @BASEBOARD_FAB2_LIB.BASEBOARD_FAB2(SCH_1):PAGE270
     4    GND @BASEBOARD_FAB2_LIB.BASEBOARD_FAB2(SCH_1):GND    I21 @BASEBOARD_FAB2_LIB.BASEBOARD_FAB2(SCH_1):PAGE270
     5    GND @BASEBOARD_FAB2_LIB.BASEBOARD_FAB2(SCH_1):GND    I21 @BASEBOARD_FAB2_LIB.BASEBOARD_FAB2(SCH_1):PAGE270
     6    GND @BASEBOARD_FAB2_LIB.BASEBOARD_FAB2(SCH_1):GND    I21 @BASEBOARD_FAB2_LIB.BASEBOARD_FAB2(SCH_1):PAGE270
     7    GND @BASEBOARD_FAB2_LIB.BASEBOARD_FAB2(SCH_1):GND    I21 @BASEBOARD_FAB2_LIB.BASEBOARD_FAB2(SCH_1):PAGE270
     8    GND @BASEBOARD_FAB2_LIB.BASEBOARD_FAB2(SCH_1):GND    I21 @BASEBOARD_FAB2_LIB.BASEBOARD_FAB2(SCH_1):PAGE270
     9    GND @BASEBOARD_FAB2_LIB.BASEBOARD_FAB2(SCH_1):GND    I21 @BASEBOARD_FAB2_LIB.BASEBOARD_FAB2(SCH_1):PAGE270
    10    GND @BASEBOARD_FAB2_LIB.BASEBOARD_FAB2(SCH_1):GND    I21 @BASEBOARD_FAB2_LIB.BASEBOARD_FAB2(SCH_1):PAGE270
    11    GND @BASEBOARD_FAB2_LIB.BASEBOARD_FAB2(SCH_1):GND    I21 @BASEBOARD_FAB2_LIB.BASEBOARD_FAB2(SCH_1):PAGE270
    12    GND @BASEBOARD_FAB2_LIB.BASEBOARD_FAB2(SCH_1):GND    I21 @BASEBOARD_FAB2_LIB.BASEBOARD_FAB2(SCH_1):PAGE270
     1 L14_85OHM_5INCH_DN @BASEBOARD_FAB2_LIB.BASEBOARD_FAB2(SCH_1):L14_85OHM_5INCH_DN    I21 @BASEBOARD_FAB2_LIB.BASEBOARD_FAB2(SCH_1):PAGE270
     2 L14_85OHM_5INCH_DP @BASEBOARD_FAB2_LIB.BASEBOARD_FAB2(SCH_1):L14_85OHM_5INCH_DP    I21 @BASEBOARD_FAB2_LIB.BASEBOARD_FAB2(SCH_1):PAGE270

T1D13 TEST-PAD-12P-1-GP-U_DISCRET-GBA
     3    GND @BASEBOARD_FAB2_LIB.BASEBOARD_FAB2(SCH_1):GND     I5 @BASEBOARD_FAB2_LIB.BASEBOARD_FAB2(SCH_1):PAGE272
     4    GND @BASEBOARD_FAB2_LIB.BASEBOARD_FAB2(SCH_1):GND     I5 @BASEBOARD_FAB2_LIB.BASEBOARD_FAB2(SCH_1):PAGE272
     5    GND @BASEBOARD_FAB2_LIB.BASEBOARD_FAB2(SCH_1):GND     I5 @BASEBOARD_FAB2_LIB.BASEBOARD_FAB2(SCH_1):PAGE272
     6    GND @BASEBOARD_FAB2_LIB.BASEBOARD_FAB2(SCH_1):GND     I5 @BASEBOARD_FAB2_LIB.BASEBOARD_FAB2(SCH_1):PAGE272
     7    GND @BASEBOARD_FAB2_LIB.BASEBOARD_FAB2(SCH_1):GND     I5 @BASEBOARD_FAB2_LIB.BASEBOARD_FAB2(SCH_1):PAGE272
     8    GND @BASEBOARD_FAB2_LIB.BASEBOARD_FAB2(SCH_1):GND     I5 @BASEBOARD_FAB2_LIB.BASEBOARD_FAB2(SCH_1):PAGE272
     9    GND @BASEBOARD_FAB2_LIB.BASEBOARD_FAB2(SCH_1):GND     I5 @BASEBOARD_FAB2_LIB.BASEBOARD_FAB2(SCH_1):PAGE272
    10    GND @BASEBOARD_FAB2_LIB.BASEBOARD_FAB2(SCH_1):GND     I5 @BASEBOARD_FAB2_LIB.BASEBOARD_FAB2(SCH_1):PAGE272
    11    GND @BASEBOARD_FAB2_LIB.BASEBOARD_FAB2(SCH_1):GND     I5 @BASEBOARD_FAB2_LIB.BASEBOARD_FAB2(SCH_1):PAGE272
    12    GND @BASEBOARD_FAB2_LIB.BASEBOARD_FAB2(SCH_1):GND     I5 @BASEBOARD_FAB2_LIB.BASEBOARD_FAB2(SCH_1):PAGE272
     1 L1_85OHM_10INCH_DP @BASEBOARD_FAB2_LIB.BASEBOARD_FAB2(SCH_1):L1_85OHM_10INCH_DP     I5 @BASEBOARD_FAB2_LIB.BASEBOARD_FAB2(SCH_1):PAGE272
     2 L1_85OHM_10INCH_DN @BASEBOARD_FAB2_LIB.BASEBOARD_FAB2(SCH_1):L1_85OHM_10INCH_DN     I5 @BASEBOARD_FAB2_LIB.BASEBOARD_FAB2(SCH_1):PAGE272

T1D14 TEST-PAD-12P-1-GP-U_DISCRET-GBA
     3    GND @BASEBOARD_FAB2_LIB.BASEBOARD_FAB2(SCH_1):GND    I22 @BASEBOARD_FAB2_LIB.BASEBOARD_FAB2(SCH_1):PAGE272
     4    GND @BASEBOARD_FAB2_LIB.BASEBOARD_FAB2(SCH_1):GND    I22 @BASEBOARD_FAB2_LIB.BASEBOARD_FAB2(SCH_1):PAGE272
     5    GND @BASEBOARD_FAB2_LIB.BASEBOARD_FAB2(SCH_1):GND    I22 @BASEBOARD_FAB2_LIB.BASEBOARD_FAB2(SCH_1):PAGE272
     6    GND @BASEBOARD_FAB2_LIB.BASEBOARD_FAB2(SCH_1):GND    I22 @BASEBOARD_FAB2_LIB.BASEBOARD_FAB2(SCH_1):PAGE272
     7    GND @BASEBOARD_FAB2_LIB.BASEBOARD_FAB2(SCH_1):GND    I22 @BASEBOARD_FAB2_LIB.BASEBOARD_FAB2(SCH_1):PAGE272
     8    GND @BASEBOARD_FAB2_LIB.BASEBOARD_FAB2(SCH_1):GND    I22 @BASEBOARD_FAB2_LIB.BASEBOARD_FAB2(SCH_1):PAGE272
     9    GND @BASEBOARD_FAB2_LIB.BASEBOARD_FAB2(SCH_1):GND    I22 @BASEBOARD_FAB2_LIB.BASEBOARD_FAB2(SCH_1):PAGE272
    10    GND @BASEBOARD_FAB2_LIB.BASEBOARD_FAB2(SCH_1):GND    I22 @BASEBOARD_FAB2_LIB.BASEBOARD_FAB2(SCH_1):PAGE272
    11    GND @BASEBOARD_FAB2_LIB.BASEBOARD_FAB2(SCH_1):GND    I22 @BASEBOARD_FAB2_LIB.BASEBOARD_FAB2(SCH_1):PAGE272
    12    GND @BASEBOARD_FAB2_LIB.BASEBOARD_FAB2(SCH_1):GND    I22 @BASEBOARD_FAB2_LIB.BASEBOARD_FAB2(SCH_1):PAGE272
     1 L1_85OHM_10INCH_DN @BASEBOARD_FAB2_LIB.BASEBOARD_FAB2(SCH_1):L1_85OHM_10INCH_DN    I22 @BASEBOARD_FAB2_LIB.BASEBOARD_FAB2(SCH_1):PAGE272
     2 L1_85OHM_10INCH_DP @BASEBOARD_FAB2_LIB.BASEBOARD_FAB2(SCH_1):L1_85OHM_10INCH_DP    I22 @BASEBOARD_FAB2_LIB.BASEBOARD_FAB2(SCH_1):PAGE272

T1D15 TEST-PAD-12P-1-GP-U_DISCRET-GBA
     3    GND @BASEBOARD_FAB2_LIB.BASEBOARD_FAB2(SCH_1):GND     I3 @BASEBOARD_FAB2_LIB.BASEBOARD_FAB2(SCH_1):PAGE272
     4    GND @BASEBOARD_FAB2_LIB.BASEBOARD_FAB2(SCH_1):GND     I3 @BASEBOARD_FAB2_LIB.BASEBOARD_FAB2(SCH_1):PAGE272
     5    GND @BASEBOARD_FAB2_LIB.BASEBOARD_FAB2(SCH_1):GND     I3 @BASEBOARD_FAB2_LIB.BASEBOARD_FAB2(SCH_1):PAGE272
     6    GND @BASEBOARD_FAB2_LIB.BASEBOARD_FAB2(SCH_1):GND     I3 @BASEBOARD_FAB2_LIB.BASEBOARD_FAB2(SCH_1):PAGE272
     7    GND @BASEBOARD_FAB2_LIB.BASEBOARD_FAB2(SCH_1):GND     I3 @BASEBOARD_FAB2_LIB.BASEBOARD_FAB2(SCH_1):PAGE272
     8    GND @BASEBOARD_FAB2_LIB.BASEBOARD_FAB2(SCH_1):GND     I3 @BASEBOARD_FAB2_LIB.BASEBOARD_FAB2(SCH_1):PAGE272
     9    GND @BASEBOARD_FAB2_LIB.BASEBOARD_FAB2(SCH_1):GND     I3 @BASEBOARD_FAB2_LIB.BASEBOARD_FAB2(SCH_1):PAGE272
    10    GND @BASEBOARD_FAB2_LIB.BASEBOARD_FAB2(SCH_1):GND     I3 @BASEBOARD_FAB2_LIB.BASEBOARD_FAB2(SCH_1):PAGE272
    11    GND @BASEBOARD_FAB2_LIB.BASEBOARD_FAB2(SCH_1):GND     I3 @BASEBOARD_FAB2_LIB.BASEBOARD_FAB2(SCH_1):PAGE272
    12    GND @BASEBOARD_FAB2_LIB.BASEBOARD_FAB2(SCH_1):GND     I3 @BASEBOARD_FAB2_LIB.BASEBOARD_FAB2(SCH_1):PAGE272
     1 L3_85OHM_10INCH_DP @BASEBOARD_FAB2_LIB.BASEBOARD_FAB2(SCH_1):L3_85OHM_10INCH_DP     I3 @BASEBOARD_FAB2_LIB.BASEBOARD_FAB2(SCH_1):PAGE272
     2 L3_85OHM_10INCH_DN @BASEBOARD_FAB2_LIB.BASEBOARD_FAB2(SCH_1):L3_85OHM_10INCH_DN     I3 @BASEBOARD_FAB2_LIB.BASEBOARD_FAB2(SCH_1):PAGE272

T1D16 TEST-PAD-12P-1-GP-U_DISCRET-GBA
     3    GND @BASEBOARD_FAB2_LIB.BASEBOARD_FAB2(SCH_1):GND    I14 @BASEBOARD_FAB2_LIB.BASEBOARD_FAB2(SCH_1):PAGE272
     4    GND @BASEBOARD_FAB2_LIB.BASEBOARD_FAB2(SCH_1):GND    I14 @BASEBOARD_FAB2_LIB.BASEBOARD_FAB2(SCH_1):PAGE272
     5    GND @BASEBOARD_FAB2_LIB.BASEBOARD_FAB2(SCH_1):GND    I14 @BASEBOARD_FAB2_LIB.BASEBOARD_FAB2(SCH_1):PAGE272
     6    GND @BASEBOARD_FAB2_LIB.BASEBOARD_FAB2(SCH_1):GND    I14 @BASEBOARD_FAB2_LIB.BASEBOARD_FAB2(SCH_1):PAGE272
     7    GND @BASEBOARD_FAB2_LIB.BASEBOARD_FAB2(SCH_1):GND    I14 @BASEBOARD_FAB2_LIB.BASEBOARD_FAB2(SCH_1):PAGE272
     8    GND @BASEBOARD_FAB2_LIB.BASEBOARD_FAB2(SCH_1):GND    I14 @BASEBOARD_FAB2_LIB.BASEBOARD_FAB2(SCH_1):PAGE272
     9    GND @BASEBOARD_FAB2_LIB.BASEBOARD_FAB2(SCH_1):GND    I14 @BASEBOARD_FAB2_LIB.BASEBOARD_FAB2(SCH_1):PAGE272
    10    GND @BASEBOARD_FAB2_LIB.BASEBOARD_FAB2(SCH_1):GND    I14 @BASEBOARD_FAB2_LIB.BASEBOARD_FAB2(SCH_1):PAGE272
    11    GND @BASEBOARD_FAB2_LIB.BASEBOARD_FAB2(SCH_1):GND    I14 @BASEBOARD_FAB2_LIB.BASEBOARD_FAB2(SCH_1):PAGE272
    12    GND @BASEBOARD_FAB2_LIB.BASEBOARD_FAB2(SCH_1):GND    I14 @BASEBOARD_FAB2_LIB.BASEBOARD_FAB2(SCH_1):PAGE272
     1 L3_85OHM_10INCH_DN @BASEBOARD_FAB2_LIB.BASEBOARD_FAB2(SCH_1):L3_85OHM_10INCH_DN    I14 @BASEBOARD_FAB2_LIB.BASEBOARD_FAB2(SCH_1):PAGE272
     2 L3_85OHM_10INCH_DP @BASEBOARD_FAB2_LIB.BASEBOARD_FAB2(SCH_1):L3_85OHM_10INCH_DP    I14 @BASEBOARD_FAB2_LIB.BASEBOARD_FAB2(SCH_1):PAGE272

T1D17 TEST-PAD-12P-1-GP-U_DISCRET-GBA
     3    GND @BASEBOARD_FAB2_LIB.BASEBOARD_FAB2(SCH_1):GND     I1 @BASEBOARD_FAB2_LIB.BASEBOARD_FAB2(SCH_1):PAGE272
     4    GND @BASEBOARD_FAB2_LIB.BASEBOARD_FAB2(SCH_1):GND     I1 @BASEBOARD_FAB2_LIB.BASEBOARD_FAB2(SCH_1):PAGE272
     5    GND @BASEBOARD_FAB2_LIB.BASEBOARD_FAB2(SCH_1):GND     I1 @BASEBOARD_FAB2_LIB.BASEBOARD_FAB2(SCH_1):PAGE272
     6    GND @BASEBOARD_FAB2_LIB.BASEBOARD_FAB2(SCH_1):GND     I1 @BASEBOARD_FAB2_LIB.BASEBOARD_FAB2(SCH_1):PAGE272
     7    GND @BASEBOARD_FAB2_LIB.BASEBOARD_FAB2(SCH_1):GND     I1 @BASEBOARD_FAB2_LIB.BASEBOARD_FAB2(SCH_1):PAGE272
     8    GND @BASEBOARD_FAB2_LIB.BASEBOARD_FAB2(SCH_1):GND     I1 @BASEBOARD_FAB2_LIB.BASEBOARD_FAB2(SCH_1):PAGE272
     9    GND @BASEBOARD_FAB2_LIB.BASEBOARD_FAB2(SCH_1):GND     I1 @BASEBOARD_FAB2_LIB.BASEBOARD_FAB2(SCH_1):PAGE272
    10    GND @BASEBOARD_FAB2_LIB.BASEBOARD_FAB2(SCH_1):GND     I1 @BASEBOARD_FAB2_LIB.BASEBOARD_FAB2(SCH_1):PAGE272
    11    GND @BASEBOARD_FAB2_LIB.BASEBOARD_FAB2(SCH_1):GND     I1 @BASEBOARD_FAB2_LIB.BASEBOARD_FAB2(SCH_1):PAGE272
    12    GND @BASEBOARD_FAB2_LIB.BASEBOARD_FAB2(SCH_1):GND     I1 @BASEBOARD_FAB2_LIB.BASEBOARD_FAB2(SCH_1):PAGE272
     1 L5_85OHM_10INCH_DP @BASEBOARD_FAB2_LIB.BASEBOARD_FAB2(SCH_1):L5_85OHM_10INCH_DP     I1 @BASEBOARD_FAB2_LIB.BASEBOARD_FAB2(SCH_1):PAGE272
     2 L5_85OHM_10INCH_DN @BASEBOARD_FAB2_LIB.BASEBOARD_FAB2(SCH_1):L5_85OHM_10INCH_DN     I1 @BASEBOARD_FAB2_LIB.BASEBOARD_FAB2(SCH_1):PAGE272

T1D18 TEST-PAD-12P-1-GP-U_DISCRET-GBA
     3    GND @BASEBOARD_FAB2_LIB.BASEBOARD_FAB2(SCH_1):GND     I8 @BASEBOARD_FAB2_LIB.BASEBOARD_FAB2(SCH_1):PAGE272
     4    GND @BASEBOARD_FAB2_LIB.BASEBOARD_FAB2(SCH_1):GND     I8 @BASEBOARD_FAB2_LIB.BASEBOARD_FAB2(SCH_1):PAGE272
     5    GND @BASEBOARD_FAB2_LIB.BASEBOARD_FAB2(SCH_1):GND     I8 @BASEBOARD_FAB2_LIB.BASEBOARD_FAB2(SCH_1):PAGE272
     6    GND @BASEBOARD_FAB2_LIB.BASEBOARD_FAB2(SCH_1):GND     I8 @BASEBOARD_FAB2_LIB.BASEBOARD_FAB2(SCH_1):PAGE272
     7    GND @BASEBOARD_FAB2_LIB.BASEBOARD_FAB2(SCH_1):GND     I8 @BASEBOARD_FAB2_LIB.BASEBOARD_FAB2(SCH_1):PAGE272
     8    GND @BASEBOARD_FAB2_LIB.BASEBOARD_FAB2(SCH_1):GND     I8 @BASEBOARD_FAB2_LIB.BASEBOARD_FAB2(SCH_1):PAGE272
     9    GND @BASEBOARD_FAB2_LIB.BASEBOARD_FAB2(SCH_1):GND     I8 @BASEBOARD_FAB2_LIB.BASEBOARD_FAB2(SCH_1):PAGE272
    10    GND @BASEBOARD_FAB2_LIB.BASEBOARD_FAB2(SCH_1):GND     I8 @BASEBOARD_FAB2_LIB.BASEBOARD_FAB2(SCH_1):PAGE272
    11    GND @BASEBOARD_FAB2_LIB.BASEBOARD_FAB2(SCH_1):GND     I8 @BASEBOARD_FAB2_LIB.BASEBOARD_FAB2(SCH_1):PAGE272
    12    GND @BASEBOARD_FAB2_LIB.BASEBOARD_FAB2(SCH_1):GND     I8 @BASEBOARD_FAB2_LIB.BASEBOARD_FAB2(SCH_1):PAGE272
     1 L5_85OHM_10INCH_DN @BASEBOARD_FAB2_LIB.BASEBOARD_FAB2(SCH_1):L5_85OHM_10INCH_DN     I8 @BASEBOARD_FAB2_LIB.BASEBOARD_FAB2(SCH_1):PAGE272
     2 L5_85OHM_10INCH_DP @BASEBOARD_FAB2_LIB.BASEBOARD_FAB2(SCH_1):L5_85OHM_10INCH_DP     I8 @BASEBOARD_FAB2_LIB.BASEBOARD_FAB2(SCH_1):PAGE272

T1D19 TEST-PAD-12P-1-GP-U_DISCRET-GBA
     3    GND @BASEBOARD_FAB2_LIB.BASEBOARD_FAB2(SCH_1):GND    I23 @BASEBOARD_FAB2_LIB.BASEBOARD_FAB2(SCH_1):PAGE272
     4    GND @BASEBOARD_FAB2_LIB.BASEBOARD_FAB2(SCH_1):GND    I23 @BASEBOARD_FAB2_LIB.BASEBOARD_FAB2(SCH_1):PAGE272
     5    GND @BASEBOARD_FAB2_LIB.BASEBOARD_FAB2(SCH_1):GND    I23 @BASEBOARD_FAB2_LIB.BASEBOARD_FAB2(SCH_1):PAGE272
     6    GND @BASEBOARD_FAB2_LIB.BASEBOARD_FAB2(SCH_1):GND    I23 @BASEBOARD_FAB2_LIB.BASEBOARD_FAB2(SCH_1):PAGE272
     7    GND @BASEBOARD_FAB2_LIB.BASEBOARD_FAB2(SCH_1):GND    I23 @BASEBOARD_FAB2_LIB.BASEBOARD_FAB2(SCH_1):PAGE272
     8    GND @BASEBOARD_FAB2_LIB.BASEBOARD_FAB2(SCH_1):GND    I23 @BASEBOARD_FAB2_LIB.BASEBOARD_FAB2(SCH_1):PAGE272
     9    GND @BASEBOARD_FAB2_LIB.BASEBOARD_FAB2(SCH_1):GND    I23 @BASEBOARD_FAB2_LIB.BASEBOARD_FAB2(SCH_1):PAGE272
    10    GND @BASEBOARD_FAB2_LIB.BASEBOARD_FAB2(SCH_1):GND    I23 @BASEBOARD_FAB2_LIB.BASEBOARD_FAB2(SCH_1):PAGE272
    11    GND @BASEBOARD_FAB2_LIB.BASEBOARD_FAB2(SCH_1):GND    I23 @BASEBOARD_FAB2_LIB.BASEBOARD_FAB2(SCH_1):PAGE272
    12    GND @BASEBOARD_FAB2_LIB.BASEBOARD_FAB2(SCH_1):GND    I23 @BASEBOARD_FAB2_LIB.BASEBOARD_FAB2(SCH_1):PAGE272
     1 L10_85OHM_10INCH_DP @BASEBOARD_FAB2_LIB.BASEBOARD_FAB2(SCH_1):L10_85OHM_10INCH_DP    I23 @BASEBOARD_FAB2_LIB.BASEBOARD_FAB2(SCH_1):PAGE272
     2 L10_85OHM_10INCH_DN @BASEBOARD_FAB2_LIB.BASEBOARD_FAB2(SCH_1):L10_85OHM_10INCH_DN    I23 @BASEBOARD_FAB2_LIB.BASEBOARD_FAB2(SCH_1):PAGE272

T1D20 TEST-PAD-12P-1-GP-U_DISCRET-GBA
     3    GND @BASEBOARD_FAB2_LIB.BASEBOARD_FAB2(SCH_1):GND    I24 @BASEBOARD_FAB2_LIB.BASEBOARD_FAB2(SCH_1):PAGE272
     4    GND @BASEBOARD_FAB2_LIB.BASEBOARD_FAB2(SCH_1):GND    I24 @BASEBOARD_FAB2_LIB.BASEBOARD_FAB2(SCH_1):PAGE272
     5    GND @BASEBOARD_FAB2_LIB.BASEBOARD_FAB2(SCH_1):GND    I24 @BASEBOARD_FAB2_LIB.BASEBOARD_FAB2(SCH_1):PAGE272
     6    GND @BASEBOARD_FAB2_LIB.BASEBOARD_FAB2(SCH_1):GND    I24 @BASEBOARD_FAB2_LIB.BASEBOARD_FAB2(SCH_1):PAGE272
     7    GND @BASEBOARD_FAB2_LIB.BASEBOARD_FAB2(SCH_1):GND    I24 @BASEBOARD_FAB2_LIB.BASEBOARD_FAB2(SCH_1):PAGE272
     8    GND @BASEBOARD_FAB2_LIB.BASEBOARD_FAB2(SCH_1):GND    I24 @BASEBOARD_FAB2_LIB.BASEBOARD_FAB2(SCH_1):PAGE272
     9    GND @BASEBOARD_FAB2_LIB.BASEBOARD_FAB2(SCH_1):GND    I24 @BASEBOARD_FAB2_LIB.BASEBOARD_FAB2(SCH_1):PAGE272
    10    GND @BASEBOARD_FAB2_LIB.BASEBOARD_FAB2(SCH_1):GND    I24 @BASEBOARD_FAB2_LIB.BASEBOARD_FAB2(SCH_1):PAGE272
    11    GND @BASEBOARD_FAB2_LIB.BASEBOARD_FAB2(SCH_1):GND    I24 @BASEBOARD_FAB2_LIB.BASEBOARD_FAB2(SCH_1):PAGE272
    12    GND @BASEBOARD_FAB2_LIB.BASEBOARD_FAB2(SCH_1):GND    I24 @BASEBOARD_FAB2_LIB.BASEBOARD_FAB2(SCH_1):PAGE272
     1 L10_85OHM_10INCH_DN @BASEBOARD_FAB2_LIB.BASEBOARD_FAB2(SCH_1):L10_85OHM_10INCH_DN    I24 @BASEBOARD_FAB2_LIB.BASEBOARD_FAB2(SCH_1):PAGE272
     2 L10_85OHM_10INCH_DP @BASEBOARD_FAB2_LIB.BASEBOARD_FAB2(SCH_1):L10_85OHM_10INCH_DP    I24 @BASEBOARD_FAB2_LIB.BASEBOARD_FAB2(SCH_1):PAGE272

T1D21 TEST-PAD-12P-1-GP-U_DISCRET-GBA
     3    GND @BASEBOARD_FAB2_LIB.BASEBOARD_FAB2(SCH_1):GND    I16 @BASEBOARD_FAB2_LIB.BASEBOARD_FAB2(SCH_1):PAGE272
     4    GND @BASEBOARD_FAB2_LIB.BASEBOARD_FAB2(SCH_1):GND    I16 @BASEBOARD_FAB2_LIB.BASEBOARD_FAB2(SCH_1):PAGE272
     5    GND @BASEBOARD_FAB2_LIB.BASEBOARD_FAB2(SCH_1):GND    I16 @BASEBOARD_FAB2_LIB.BASEBOARD_FAB2(SCH_1):PAGE272
     6    GND @BASEBOARD_FAB2_LIB.BASEBOARD_FAB2(SCH_1):GND    I16 @BASEBOARD_FAB2_LIB.BASEBOARD_FAB2(SCH_1):PAGE272
     7    GND @BASEBOARD_FAB2_LIB.BASEBOARD_FAB2(SCH_1):GND    I16 @BASEBOARD_FAB2_LIB.BASEBOARD_FAB2(SCH_1):PAGE272
     8    GND @BASEBOARD_FAB2_LIB.BASEBOARD_FAB2(SCH_1):GND    I16 @BASEBOARD_FAB2_LIB.BASEBOARD_FAB2(SCH_1):PAGE272
     9    GND @BASEBOARD_FAB2_LIB.BASEBOARD_FAB2(SCH_1):GND    I16 @BASEBOARD_FAB2_LIB.BASEBOARD_FAB2(SCH_1):PAGE272
    10    GND @BASEBOARD_FAB2_LIB.BASEBOARD_FAB2(SCH_1):GND    I16 @BASEBOARD_FAB2_LIB.BASEBOARD_FAB2(SCH_1):PAGE272
    11    GND @BASEBOARD_FAB2_LIB.BASEBOARD_FAB2(SCH_1):GND    I16 @BASEBOARD_FAB2_LIB.BASEBOARD_FAB2(SCH_1):PAGE272
    12    GND @BASEBOARD_FAB2_LIB.BASEBOARD_FAB2(SCH_1):GND    I16 @BASEBOARD_FAB2_LIB.BASEBOARD_FAB2(SCH_1):PAGE272
     1 L12_85OHM_10INCH_DP @BASEBOARD_FAB2_LIB.BASEBOARD_FAB2(SCH_1):L12_85OHM_10INCH_DP    I16 @BASEBOARD_FAB2_LIB.BASEBOARD_FAB2(SCH_1):PAGE272
     2 L12_85OHM_10INCH_DN @BASEBOARD_FAB2_LIB.BASEBOARD_FAB2(SCH_1):L12_85OHM_10INCH_DN    I16 @BASEBOARD_FAB2_LIB.BASEBOARD_FAB2(SCH_1):PAGE272

T1D22 TEST-PAD-12P-1-GP-U_DISCRET-GBA
     3    GND @BASEBOARD_FAB2_LIB.BASEBOARD_FAB2(SCH_1):GND    I21 @BASEBOARD_FAB2_LIB.BASEBOARD_FAB2(SCH_1):PAGE272
     4    GND @BASEBOARD_FAB2_LIB.BASEBOARD_FAB2(SCH_1):GND    I21 @BASEBOARD_FAB2_LIB.BASEBOARD_FAB2(SCH_1):PAGE272
     5    GND @BASEBOARD_FAB2_LIB.BASEBOARD_FAB2(SCH_1):GND    I21 @BASEBOARD_FAB2_LIB.BASEBOARD_FAB2(SCH_1):PAGE272
     6    GND @BASEBOARD_FAB2_LIB.BASEBOARD_FAB2(SCH_1):GND    I21 @BASEBOARD_FAB2_LIB.BASEBOARD_FAB2(SCH_1):PAGE272
     7    GND @BASEBOARD_FAB2_LIB.BASEBOARD_FAB2(SCH_1):GND    I21 @BASEBOARD_FAB2_LIB.BASEBOARD_FAB2(SCH_1):PAGE272
     8    GND @BASEBOARD_FAB2_LIB.BASEBOARD_FAB2(SCH_1):GND    I21 @BASEBOARD_FAB2_LIB.BASEBOARD_FAB2(SCH_1):PAGE272
     9    GND @BASEBOARD_FAB2_LIB.BASEBOARD_FAB2(SCH_1):GND    I21 @BASEBOARD_FAB2_LIB.BASEBOARD_FAB2(SCH_1):PAGE272
    10    GND @BASEBOARD_FAB2_LIB.BASEBOARD_FAB2(SCH_1):GND    I21 @BASEBOARD_FAB2_LIB.BASEBOARD_FAB2(SCH_1):PAGE272
    11    GND @BASEBOARD_FAB2_LIB.BASEBOARD_FAB2(SCH_1):GND    I21 @BASEBOARD_FAB2_LIB.BASEBOARD_FAB2(SCH_1):PAGE272
    12    GND @BASEBOARD_FAB2_LIB.BASEBOARD_FAB2(SCH_1):GND    I21 @BASEBOARD_FAB2_LIB.BASEBOARD_FAB2(SCH_1):PAGE272
     1 L12_85OHM_10INCH_DN @BASEBOARD_FAB2_LIB.BASEBOARD_FAB2(SCH_1):L12_85OHM_10INCH_DN    I21 @BASEBOARD_FAB2_LIB.BASEBOARD_FAB2(SCH_1):PAGE272
     2 L12_85OHM_10INCH_DP @BASEBOARD_FAB2_LIB.BASEBOARD_FAB2(SCH_1):L12_85OHM_10INCH_DP    I21 @BASEBOARD_FAB2_LIB.BASEBOARD_FAB2(SCH_1):PAGE272

T1D23 TEST-PAD-12P-1-GP-U_DISCRET-GBA
     3    GND @BASEBOARD_FAB2_LIB.BASEBOARD_FAB2(SCH_1):GND     I9 @BASEBOARD_FAB2_LIB.BASEBOARD_FAB2(SCH_1):PAGE272
     4    GND @BASEBOARD_FAB2_LIB.BASEBOARD_FAB2(SCH_1):GND     I9 @BASEBOARD_FAB2_LIB.BASEBOARD_FAB2(SCH_1):PAGE272
     5    GND @BASEBOARD_FAB2_LIB.BASEBOARD_FAB2(SCH_1):GND     I9 @BASEBOARD_FAB2_LIB.BASEBOARD_FAB2(SCH_1):PAGE272
     6    GND @BASEBOARD_FAB2_LIB.BASEBOARD_FAB2(SCH_1):GND     I9 @BASEBOARD_FAB2_LIB.BASEBOARD_FAB2(SCH_1):PAGE272
     7    GND @BASEBOARD_FAB2_LIB.BASEBOARD_FAB2(SCH_1):GND     I9 @BASEBOARD_FAB2_LIB.BASEBOARD_FAB2(SCH_1):PAGE272
     8    GND @BASEBOARD_FAB2_LIB.BASEBOARD_FAB2(SCH_1):GND     I9 @BASEBOARD_FAB2_LIB.BASEBOARD_FAB2(SCH_1):PAGE272
     9    GND @BASEBOARD_FAB2_LIB.BASEBOARD_FAB2(SCH_1):GND     I9 @BASEBOARD_FAB2_LIB.BASEBOARD_FAB2(SCH_1):PAGE272
    10    GND @BASEBOARD_FAB2_LIB.BASEBOARD_FAB2(SCH_1):GND     I9 @BASEBOARD_FAB2_LIB.BASEBOARD_FAB2(SCH_1):PAGE272
    11    GND @BASEBOARD_FAB2_LIB.BASEBOARD_FAB2(SCH_1):GND     I9 @BASEBOARD_FAB2_LIB.BASEBOARD_FAB2(SCH_1):PAGE272
    12    GND @BASEBOARD_FAB2_LIB.BASEBOARD_FAB2(SCH_1):GND     I9 @BASEBOARD_FAB2_LIB.BASEBOARD_FAB2(SCH_1):PAGE272
     1 L14_85OHM_10INCH_DP @BASEBOARD_FAB2_LIB.BASEBOARD_FAB2(SCH_1):L14_85OHM_10INCH_DP     I9 @BASEBOARD_FAB2_LIB.BASEBOARD_FAB2(SCH_1):PAGE272
     2 L14_85OHM_10INCH_DN @BASEBOARD_FAB2_LIB.BASEBOARD_FAB2(SCH_1):L14_85OHM_10INCH_DN     I9 @BASEBOARD_FAB2_LIB.BASEBOARD_FAB2(SCH_1):PAGE272

T1D24 TEST-PAD-12P-1-GP-U_DISCRET-GBA
     3    GND @BASEBOARD_FAB2_LIB.BASEBOARD_FAB2(SCH_1):GND    I12 @BASEBOARD_FAB2_LIB.BASEBOARD_FAB2(SCH_1):PAGE272
     4    GND @BASEBOARD_FAB2_LIB.BASEBOARD_FAB2(SCH_1):GND    I12 @BASEBOARD_FAB2_LIB.BASEBOARD_FAB2(SCH_1):PAGE272
     5    GND @BASEBOARD_FAB2_LIB.BASEBOARD_FAB2(SCH_1):GND    I12 @BASEBOARD_FAB2_LIB.BASEBOARD_FAB2(SCH_1):PAGE272
     6    GND @BASEBOARD_FAB2_LIB.BASEBOARD_FAB2(SCH_1):GND    I12 @BASEBOARD_FAB2_LIB.BASEBOARD_FAB2(SCH_1):PAGE272
     7    GND @BASEBOARD_FAB2_LIB.BASEBOARD_FAB2(SCH_1):GND    I12 @BASEBOARD_FAB2_LIB.BASEBOARD_FAB2(SCH_1):PAGE272
     8    GND @BASEBOARD_FAB2_LIB.BASEBOARD_FAB2(SCH_1):GND    I12 @BASEBOARD_FAB2_LIB.BASEBOARD_FAB2(SCH_1):PAGE272
     9    GND @BASEBOARD_FAB2_LIB.BASEBOARD_FAB2(SCH_1):GND    I12 @BASEBOARD_FAB2_LIB.BASEBOARD_FAB2(SCH_1):PAGE272
    10    GND @BASEBOARD_FAB2_LIB.BASEBOARD_FAB2(SCH_1):GND    I12 @BASEBOARD_FAB2_LIB.BASEBOARD_FAB2(SCH_1):PAGE272
    11    GND @BASEBOARD_FAB2_LIB.BASEBOARD_FAB2(SCH_1):GND    I12 @BASEBOARD_FAB2_LIB.BASEBOARD_FAB2(SCH_1):PAGE272
    12    GND @BASEBOARD_FAB2_LIB.BASEBOARD_FAB2(SCH_1):GND    I12 @BASEBOARD_FAB2_LIB.BASEBOARD_FAB2(SCH_1):PAGE272
     1 L14_85OHM_10INCH_DN @BASEBOARD_FAB2_LIB.BASEBOARD_FAB2(SCH_1):L14_85OHM_10INCH_DN    I12 @BASEBOARD_FAB2_LIB.BASEBOARD_FAB2(SCH_1):PAGE272
     2 L14_85OHM_10INCH_DP @BASEBOARD_FAB2_LIB.BASEBOARD_FAB2(SCH_1):L14_85OHM_10INCH_DP    I12 @BASEBOARD_FAB2_LIB.BASEBOARD_FAB2(SCH_1):PAGE272

T1P1 TPAD-DIFF-4P-GP_DISCRET-GB3-TPA
     1 L1_85OHM_6INCH_DP @BASEBOARD_FAB2_LIB.BASEBOARD_FAB2(SCH_1):L1_85OHM_6INCH_DP     I3 @BASEBOARD_FAB2_LIB.BASEBOARD_FAB2(SCH_1):PAGE271
     2 L1_85OHM_6INCH_DN @BASEBOARD_FAB2_LIB.BASEBOARD_FAB2(SCH_1):L1_85OHM_6INCH_DN     I3 @BASEBOARD_FAB2_LIB.BASEBOARD_FAB2(SCH_1):PAGE271
  GND1    GND @BASEBOARD_FAB2_LIB.BASEBOARD_FAB2(SCH_1):GND     I3 @BASEBOARD_FAB2_LIB.BASEBOARD_FAB2(SCH_1):PAGE271
  GND2    GND @BASEBOARD_FAB2_LIB.BASEBOARD_FAB2(SCH_1):GND     I3 @BASEBOARD_FAB2_LIB.BASEBOARD_FAB2(SCH_1):PAGE271

T1P2 TPAD-DIFF-4P-GP_DISCRET-GB3-TPA
     1 L3_85OHM_6INCH_DP @BASEBOARD_FAB2_LIB.BASEBOARD_FAB2(SCH_1):L3_85OHM_6INCH_DP     I5 @BASEBOARD_FAB2_LIB.BASEBOARD_FAB2(SCH_1):PAGE271
     2 L3_85OHM_6INCH_DN @BASEBOARD_FAB2_LIB.BASEBOARD_FAB2(SCH_1):L3_85OHM_6INCH_DN     I5 @BASEBOARD_FAB2_LIB.BASEBOARD_FAB2(SCH_1):PAGE271
  GND1    GND @BASEBOARD_FAB2_LIB.BASEBOARD_FAB2(SCH_1):GND     I5 @BASEBOARD_FAB2_LIB.BASEBOARD_FAB2(SCH_1):PAGE271
  GND2    GND @BASEBOARD_FAB2_LIB.BASEBOARD_FAB2(SCH_1):GND     I5 @BASEBOARD_FAB2_LIB.BASEBOARD_FAB2(SCH_1):PAGE271

T1P3 TPAD-DIFF-4P-GP_DISCRET-GB3-TPA
     1 L5_85OHM_6INCH_DP @BASEBOARD_FAB2_LIB.BASEBOARD_FAB2(SCH_1):L5_85OHM_6INCH_DP     I8 @BASEBOARD_FAB2_LIB.BASEBOARD_FAB2(SCH_1):PAGE271
     2 L5_85OHM_6INCH_DN @BASEBOARD_FAB2_LIB.BASEBOARD_FAB2(SCH_1):L5_85OHM_6INCH_DN     I8 @BASEBOARD_FAB2_LIB.BASEBOARD_FAB2(SCH_1):PAGE271
  GND1    GND @BASEBOARD_FAB2_LIB.BASEBOARD_FAB2(SCH_1):GND     I8 @BASEBOARD_FAB2_LIB.BASEBOARD_FAB2(SCH_1):PAGE271
  GND2    GND @BASEBOARD_FAB2_LIB.BASEBOARD_FAB2(SCH_1):GND     I8 @BASEBOARD_FAB2_LIB.BASEBOARD_FAB2(SCH_1):PAGE271

T1P4 TPAD-DIFF-4P-GP_DISCRET-GB3-TPA
     1 L10_85OHM_6INCH_DP @BASEBOARD_FAB2_LIB.BASEBOARD_FAB2(SCH_1):L10_85OHM_6INCH_DP     I7 @BASEBOARD_FAB2_LIB.BASEBOARD_FAB2(SCH_1):PAGE271
     2 L10_85OHM_6INCH_DN @BASEBOARD_FAB2_LIB.BASEBOARD_FAB2(SCH_1):L10_85OHM_6INCH_DN     I7 @BASEBOARD_FAB2_LIB.BASEBOARD_FAB2(SCH_1):PAGE271
  GND1    GND @BASEBOARD_FAB2_LIB.BASEBOARD_FAB2(SCH_1):GND     I7 @BASEBOARD_FAB2_LIB.BASEBOARD_FAB2(SCH_1):PAGE271
  GND2    GND @BASEBOARD_FAB2_LIB.BASEBOARD_FAB2(SCH_1):GND     I7 @BASEBOARD_FAB2_LIB.BASEBOARD_FAB2(SCH_1):PAGE271

T1P5 TPAD-DIFF-4P-GP_DISCRET-GB3-TPA
     1 L12_85OHM_6INCH_DP @BASEBOARD_FAB2_LIB.BASEBOARD_FAB2(SCH_1):L12_85OHM_6INCH_DP    I11 @BASEBOARD_FAB2_LIB.BASEBOARD_FAB2(SCH_1):PAGE271
     2 L12_85OHM_6INCH_DN @BASEBOARD_FAB2_LIB.BASEBOARD_FAB2(SCH_1):L12_85OHM_6INCH_DN    I11 @BASEBOARD_FAB2_LIB.BASEBOARD_FAB2(SCH_1):PAGE271
  GND1    GND @BASEBOARD_FAB2_LIB.BASEBOARD_FAB2(SCH_1):GND    I11 @BASEBOARD_FAB2_LIB.BASEBOARD_FAB2(SCH_1):PAGE271
  GND2    GND @BASEBOARD_FAB2_LIB.BASEBOARD_FAB2(SCH_1):GND    I11 @BASEBOARD_FAB2_LIB.BASEBOARD_FAB2(SCH_1):PAGE271

T1P6 TPAD-DIFF-4P-GP_DISCRET-GB3-TPA
     1 L14_85OHM_6INCH_DP @BASEBOARD_FAB2_LIB.BASEBOARD_FAB2(SCH_1):L14_85OHM_6INCH_DP    I13 @BASEBOARD_FAB2_LIB.BASEBOARD_FAB2(SCH_1):PAGE271
     2 L14_85OHM_6INCH_DN @BASEBOARD_FAB2_LIB.BASEBOARD_FAB2(SCH_1):L14_85OHM_6INCH_DN    I13 @BASEBOARD_FAB2_LIB.BASEBOARD_FAB2(SCH_1):PAGE271
  GND1    GND @BASEBOARD_FAB2_LIB.BASEBOARD_FAB2(SCH_1):GND    I13 @BASEBOARD_FAB2_LIB.BASEBOARD_FAB2(SCH_1):PAGE271
  GND2    GND @BASEBOARD_FAB2_LIB.BASEBOARD_FAB2(SCH_1):GND    I13 @BASEBOARD_FAB2_LIB.BASEBOARD_FAB2(SCH_1):PAGE271

T1P7 TPAD-DIFF-4P-GP_DISCRET-GB3-TPA
     1 L1_73OHM_6INCH_DP @BASEBOARD_FAB2_LIB.BASEBOARD_FAB2(SCH_1):L1_73OHM_6INCH_DP    I17 @BASEBOARD_FAB2_LIB.BASEBOARD_FAB2(SCH_1):PAGE271
     2 L1_73OHM_6INCH_DN @BASEBOARD_FAB2_LIB.BASEBOARD_FAB2(SCH_1):L1_73OHM_6INCH_DN    I17 @BASEBOARD_FAB2_LIB.BASEBOARD_FAB2(SCH_1):PAGE271
  GND1    GND @BASEBOARD_FAB2_LIB.BASEBOARD_FAB2(SCH_1):GND    I17 @BASEBOARD_FAB2_LIB.BASEBOARD_FAB2(SCH_1):PAGE271
  GND2    GND @BASEBOARD_FAB2_LIB.BASEBOARD_FAB2(SCH_1):GND    I17 @BASEBOARD_FAB2_LIB.BASEBOARD_FAB2(SCH_1):PAGE271

T1P8 TPAD-DIFF-4P-GP_DISCRET-GB3-TPA
     1 L3_73OHM_6INCH_DP @BASEBOARD_FAB2_LIB.BASEBOARD_FAB2(SCH_1):L3_73OHM_6INCH_DP    I16 @BASEBOARD_FAB2_LIB.BASEBOARD_FAB2(SCH_1):PAGE271
     2 L3_73OHM_6INCH_DN @BASEBOARD_FAB2_LIB.BASEBOARD_FAB2(SCH_1):L3_73OHM_6INCH_DN    I16 @BASEBOARD_FAB2_LIB.BASEBOARD_FAB2(SCH_1):PAGE271
  GND1    GND @BASEBOARD_FAB2_LIB.BASEBOARD_FAB2(SCH_1):GND    I16 @BASEBOARD_FAB2_LIB.BASEBOARD_FAB2(SCH_1):PAGE271
  GND2    GND @BASEBOARD_FAB2_LIB.BASEBOARD_FAB2(SCH_1):GND    I16 @BASEBOARD_FAB2_LIB.BASEBOARD_FAB2(SCH_1):PAGE271

T1P9 TPAD-DIFF-4P-GP_DISCRET-GB3-TPA
     1 L5_73OHM_6INCH_DP @BASEBOARD_FAB2_LIB.BASEBOARD_FAB2(SCH_1):L5_73OHM_6INCH_DP    I19 @BASEBOARD_FAB2_LIB.BASEBOARD_FAB2(SCH_1):PAGE271
     2 L5_73OHM_6INCH_DN @BASEBOARD_FAB2_LIB.BASEBOARD_FAB2(SCH_1):L5_73OHM_6INCH_DN    I19 @BASEBOARD_FAB2_LIB.BASEBOARD_FAB2(SCH_1):PAGE271
  GND1    GND @BASEBOARD_FAB2_LIB.BASEBOARD_FAB2(SCH_1):GND    I19 @BASEBOARD_FAB2_LIB.BASEBOARD_FAB2(SCH_1):PAGE271
  GND2    GND @BASEBOARD_FAB2_LIB.BASEBOARD_FAB2(SCH_1):GND    I19 @BASEBOARD_FAB2_LIB.BASEBOARD_FAB2(SCH_1):PAGE271

T1P10 TPAD-DIFF-4P-GP_DISCRET-GB3-TPA
     1 L10_73OHM_6INCH_DP @BASEBOARD_FAB2_LIB.BASEBOARD_FAB2(SCH_1):L10_73OHM_6INCH_DP    I15 @BASEBOARD_FAB2_LIB.BASEBOARD_FAB2(SCH_1):PAGE271
     2 L10_73OHM_6INCH_DN @BASEBOARD_FAB2_LIB.BASEBOARD_FAB2(SCH_1):L10_73OHM_6INCH_DN    I15 @BASEBOARD_FAB2_LIB.BASEBOARD_FAB2(SCH_1):PAGE271
  GND1    GND @BASEBOARD_FAB2_LIB.BASEBOARD_FAB2(SCH_1):GND    I15 @BASEBOARD_FAB2_LIB.BASEBOARD_FAB2(SCH_1):PAGE271
  GND2    GND @BASEBOARD_FAB2_LIB.BASEBOARD_FAB2(SCH_1):GND    I15 @BASEBOARD_FAB2_LIB.BASEBOARD_FAB2(SCH_1):PAGE271

T1P11 TPAD-DIFF-4P-GP_DISCRET-GB3-TPA
     1 L12_73OHM_6INCH_DP @BASEBOARD_FAB2_LIB.BASEBOARD_FAB2(SCH_1):L12_73OHM_6INCH_DP    I23 @BASEBOARD_FAB2_LIB.BASEBOARD_FAB2(SCH_1):PAGE271
     2 L12_73OHM_6INCH_DN @BASEBOARD_FAB2_LIB.BASEBOARD_FAB2(SCH_1):L12_73OHM_6INCH_DN    I23 @BASEBOARD_FAB2_LIB.BASEBOARD_FAB2(SCH_1):PAGE271
  GND1    GND @BASEBOARD_FAB2_LIB.BASEBOARD_FAB2(SCH_1):GND    I23 @BASEBOARD_FAB2_LIB.BASEBOARD_FAB2(SCH_1):PAGE271
  GND2    GND @BASEBOARD_FAB2_LIB.BASEBOARD_FAB2(SCH_1):GND    I23 @BASEBOARD_FAB2_LIB.BASEBOARD_FAB2(SCH_1):PAGE271

T1P12 TPAD-DIFF-4P-GP_DISCRET-GB3-TPA
     1 L14_73OHM_6INCH_DP @BASEBOARD_FAB2_LIB.BASEBOARD_FAB2(SCH_1):L14_73OHM_6INCH_DP    I24 @BASEBOARD_FAB2_LIB.BASEBOARD_FAB2(SCH_1):PAGE271
     2 L14_73OHM_6INCH_DN @BASEBOARD_FAB2_LIB.BASEBOARD_FAB2(SCH_1):L14_73OHM_6INCH_DN    I24 @BASEBOARD_FAB2_LIB.BASEBOARD_FAB2(SCH_1):PAGE271
  GND1    GND @BASEBOARD_FAB2_LIB.BASEBOARD_FAB2(SCH_1):GND    I24 @BASEBOARD_FAB2_LIB.BASEBOARD_FAB2(SCH_1):PAGE271
  GND2    GND @BASEBOARD_FAB2_LIB.BASEBOARD_FAB2(SCH_1):GND    I24 @BASEBOARD_FAB2_LIB.BASEBOARD_FAB2(SCH_1):PAGE271

T1P14 TPAD-DIFF-4P-GP_DISCRET-GB3-TPA
     1 L1_95OHM_6INCH_DP @BASEBOARD_FAB2_LIB.BASEBOARD_FAB2(SCH_1):L1_95OHM_6INCH_DP    I30 @BASEBOARD_FAB2_LIB.BASEBOARD_FAB2(SCH_1):PAGE271
     2 L1_95OHM_6INCH_DN @BASEBOARD_FAB2_LIB.BASEBOARD_FAB2(SCH_1):L1_95OHM_6INCH_DN    I30 @BASEBOARD_FAB2_LIB.BASEBOARD_FAB2(SCH_1):PAGE271
  GND1    GND @BASEBOARD_FAB2_LIB.BASEBOARD_FAB2(SCH_1):GND    I30 @BASEBOARD_FAB2_LIB.BASEBOARD_FAB2(SCH_1):PAGE271
  GND2    GND @BASEBOARD_FAB2_LIB.BASEBOARD_FAB2(SCH_1):GND    I30 @BASEBOARD_FAB2_LIB.BASEBOARD_FAB2(SCH_1):PAGE271

T1P17 TPAD-DIFF-4P-GP_DISCRET-GB3-TPA
     1 L12_95OHM_6INCH_DP @BASEBOARD_FAB2_LIB.BASEBOARD_FAB2(SCH_1):L12_95OHM_6INCH_DP    I36 @BASEBOARD_FAB2_LIB.BASEBOARD_FAB2(SCH_1):PAGE271
     2 L12_95OHM_6INCH_DN @BASEBOARD_FAB2_LIB.BASEBOARD_FAB2(SCH_1):L12_95OHM_6INCH_DN    I36 @BASEBOARD_FAB2_LIB.BASEBOARD_FAB2(SCH_1):PAGE271
  GND1    GND @BASEBOARD_FAB2_LIB.BASEBOARD_FAB2(SCH_1):GND    I36 @BASEBOARD_FAB2_LIB.BASEBOARD_FAB2(SCH_1):PAGE271
  GND2    GND @BASEBOARD_FAB2_LIB.BASEBOARD_FAB2(SCH_1):GND    I36 @BASEBOARD_FAB2_LIB.BASEBOARD_FAB2(SCH_1):PAGE271

T1P19 TPAD-DIFF-4P-GP_DISCRET-GB3-TPA
     1 L1_100OHM_6INCH_DP @BASEBOARD_FAB2_LIB.BASEBOARD_FAB2(SCH_1):L1_100OHM_6INCH_DP    I39 @BASEBOARD_FAB2_LIB.BASEBOARD_FAB2(SCH_1):PAGE271
     2 L1_100OHM_6INCH_DN @BASEBOARD_FAB2_LIB.BASEBOARD_FAB2(SCH_1):L1_100OHM_6INCH_DN    I39 @BASEBOARD_FAB2_LIB.BASEBOARD_FAB2(SCH_1):PAGE271
  GND1    GND @BASEBOARD_FAB2_LIB.BASEBOARD_FAB2(SCH_1):GND    I39 @BASEBOARD_FAB2_LIB.BASEBOARD_FAB2(SCH_1):PAGE271
  GND2    GND @BASEBOARD_FAB2_LIB.BASEBOARD_FAB2(SCH_1):GND    I39 @BASEBOARD_FAB2_LIB.BASEBOARD_FAB2(SCH_1):PAGE271

T1P22 TPAD-DIFF-4P-GP_DISCRET-GB3-TPA
     1 L10_100OHM_6INCH_DP @BASEBOARD_FAB2_LIB.BASEBOARD_FAB2(SCH_1):L10_100OHM_6INCH_DP    I45 @BASEBOARD_FAB2_LIB.BASEBOARD_FAB2(SCH_1):PAGE271
     2 L10_100OHM_6INCH_DN @BASEBOARD_FAB2_LIB.BASEBOARD_FAB2(SCH_1):L10_100OHM_6INCH_DN    I45 @BASEBOARD_FAB2_LIB.BASEBOARD_FAB2(SCH_1):PAGE271
  GND1    GND @BASEBOARD_FAB2_LIB.BASEBOARD_FAB2(SCH_1):GND    I45 @BASEBOARD_FAB2_LIB.BASEBOARD_FAB2(SCH_1):PAGE271
  GND2    GND @BASEBOARD_FAB2_LIB.BASEBOARD_FAB2(SCH_1):GND    I45 @BASEBOARD_FAB2_LIB.BASEBOARD_FAB2(SCH_1):PAGE271

T1P23 TPAD-DIFF-4P-GP_DISCRET-GB3-TPA
     1 L12_100OHM_6INCH_DP @BASEBOARD_FAB2_LIB.BASEBOARD_FAB2(SCH_1):L12_100OHM_6INCH_DP    I47 @BASEBOARD_FAB2_LIB.BASEBOARD_FAB2(SCH_1):PAGE271
     2 L12_100OHM_6INCH_DN @BASEBOARD_FAB2_LIB.BASEBOARD_FAB2(SCH_1):L12_100OHM_6INCH_DN    I47 @BASEBOARD_FAB2_LIB.BASEBOARD_FAB2(SCH_1):PAGE271
  GND1    GND @BASEBOARD_FAB2_LIB.BASEBOARD_FAB2(SCH_1):GND    I47 @BASEBOARD_FAB2_LIB.BASEBOARD_FAB2(SCH_1):PAGE271
  GND2    GND @BASEBOARD_FAB2_LIB.BASEBOARD_FAB2(SCH_1):GND    I47 @BASEBOARD_FAB2_LIB.BASEBOARD_FAB2(SCH_1):PAGE271

T1P24 TPAD-DIFF-4P-GP_DISCRET-GB3-TPA
     1 L14_100OHM_6INCH_DP @BASEBOARD_FAB2_LIB.BASEBOARD_FAB2(SCH_1):L14_100OHM_6INCH_DP    I38 @BASEBOARD_FAB2_LIB.BASEBOARD_FAB2(SCH_1):PAGE271
     2 L14_100OHM_6INCH_DN @BASEBOARD_FAB2_LIB.BASEBOARD_FAB2(SCH_1):L14_100OHM_6INCH_DN    I38 @BASEBOARD_FAB2_LIB.BASEBOARD_FAB2(SCH_1):PAGE271
  GND1    GND @BASEBOARD_FAB2_LIB.BASEBOARD_FAB2(SCH_1):GND    I38 @BASEBOARD_FAB2_LIB.BASEBOARD_FAB2(SCH_1):PAGE271
  GND2    GND @BASEBOARD_FAB2_LIB.BASEBOARD_FAB2(SCH_1):GND    I38 @BASEBOARD_FAB2_LIB.BASEBOARD_FAB2(SCH_1):PAGE271

T1P25 TPAD-SE-2P-GP_DISCRET-GA1-TPADA
     1 L1_40OHM_6INCH @BASEBOARD_FAB2_LIB.BASEBOARD_FAB2(SCH_1):L1_40OHM_6INCH    I50 @BASEBOARD_FAB2_LIB.BASEBOARD_FAB2(SCH_1):PAGE271
  GND1    GND @BASEBOARD_FAB2_LIB.BASEBOARD_FAB2(SCH_1):GND    I50 @BASEBOARD_FAB2_LIB.BASEBOARD_FAB2(SCH_1):PAGE271

T1P26 TPAD-SE-2P-GP_DISCRET-GA1-TPADA
     1 L3_40OHM_6INCH @BASEBOARD_FAB2_LIB.BASEBOARD_FAB2(SCH_1):L3_40OHM_6INCH    I52 @BASEBOARD_FAB2_LIB.BASEBOARD_FAB2(SCH_1):PAGE271
  GND1    GND @BASEBOARD_FAB2_LIB.BASEBOARD_FAB2(SCH_1):GND    I52 @BASEBOARD_FAB2_LIB.BASEBOARD_FAB2(SCH_1):PAGE271

T1P27 TPAD-SE-2P-GP_DISCRET-GA1-TPADA
     1 L5_40OHM_6INCH @BASEBOARD_FAB2_LIB.BASEBOARD_FAB2(SCH_1):L5_40OHM_6INCH    I54 @BASEBOARD_FAB2_LIB.BASEBOARD_FAB2(SCH_1):PAGE271
  GND1    GND @BASEBOARD_FAB2_LIB.BASEBOARD_FAB2(SCH_1):GND    I54 @BASEBOARD_FAB2_LIB.BASEBOARD_FAB2(SCH_1):PAGE271

T1P28 TPAD-SE-2P-GP_DISCRET-GA1-TPADA
     1 L10_40OHM_6INCH @BASEBOARD_FAB2_LIB.BASEBOARD_FAB2(SCH_1):L10_40OHM_6INCH    I60 @BASEBOARD_FAB2_LIB.BASEBOARD_FAB2(SCH_1):PAGE271
  GND1    GND @BASEBOARD_FAB2_LIB.BASEBOARD_FAB2(SCH_1):GND    I60 @BASEBOARD_FAB2_LIB.BASEBOARD_FAB2(SCH_1):PAGE271

T1P29 TPAD-SE-2P-GP_DISCRET-GA1-TPADA
     1 L12_40OHM_6INCH @BASEBOARD_FAB2_LIB.BASEBOARD_FAB2(SCH_1):L12_40OHM_6INCH    I56 @BASEBOARD_FAB2_LIB.BASEBOARD_FAB2(SCH_1):PAGE271
  GND1    GND @BASEBOARD_FAB2_LIB.BASEBOARD_FAB2(SCH_1):GND    I56 @BASEBOARD_FAB2_LIB.BASEBOARD_FAB2(SCH_1):PAGE271

T1P30 TPAD-SE-2P-GP_DISCRET-GA1-TPADA
     1 L14_40OHM_6INCH @BASEBOARD_FAB2_LIB.BASEBOARD_FAB2(SCH_1):L14_40OHM_6INCH    I61 @BASEBOARD_FAB2_LIB.BASEBOARD_FAB2(SCH_1):PAGE271
  GND1    GND @BASEBOARD_FAB2_LIB.BASEBOARD_FAB2(SCH_1):GND    I61 @BASEBOARD_FAB2_LIB.BASEBOARD_FAB2(SCH_1):PAGE271

T1P31 TPAD-SE-2P-GP_DISCRET-GA1-TPADA
     1 L1_50OHM_6INCH @BASEBOARD_FAB2_LIB.BASEBOARD_FAB2(SCH_1):L1_50OHM_6INCH    I71 @BASEBOARD_FAB2_LIB.BASEBOARD_FAB2(SCH_1):PAGE271
  GND1    GND @BASEBOARD_FAB2_LIB.BASEBOARD_FAB2(SCH_1):GND    I71 @BASEBOARD_FAB2_LIB.BASEBOARD_FAB2(SCH_1):PAGE271

T1P32 TPAD-SE-2P-GP_DISCRET-GA1-TPADA
     1 L3_50OHM_6INCH @BASEBOARD_FAB2_LIB.BASEBOARD_FAB2(SCH_1):L3_50OHM_6INCH    I72 @BASEBOARD_FAB2_LIB.BASEBOARD_FAB2(SCH_1):PAGE271
  GND1    GND @BASEBOARD_FAB2_LIB.BASEBOARD_FAB2(SCH_1):GND    I72 @BASEBOARD_FAB2_LIB.BASEBOARD_FAB2(SCH_1):PAGE271

T1P33 TPAD-SE-2P-GP_DISCRET-GA1-TPADA
     1 L5_50OHM_6INCH @BASEBOARD_FAB2_LIB.BASEBOARD_FAB2(SCH_1):L5_50OHM_6INCH    I73 @BASEBOARD_FAB2_LIB.BASEBOARD_FAB2(SCH_1):PAGE271
  GND1    GND @BASEBOARD_FAB2_LIB.BASEBOARD_FAB2(SCH_1):GND    I73 @BASEBOARD_FAB2_LIB.BASEBOARD_FAB2(SCH_1):PAGE271

T1P34 TPAD-SE-2P-GP_DISCRET-GA1-TPADA
     1 L10_50OHM_6INCH @BASEBOARD_FAB2_LIB.BASEBOARD_FAB2(SCH_1):L10_50OHM_6INCH    I62 @BASEBOARD_FAB2_LIB.BASEBOARD_FAB2(SCH_1):PAGE271
  GND1    GND @BASEBOARD_FAB2_LIB.BASEBOARD_FAB2(SCH_1):GND    I62 @BASEBOARD_FAB2_LIB.BASEBOARD_FAB2(SCH_1):PAGE271

T1P35 TPAD-SE-2P-GP_DISCRET-GA1-TPADA
     1 L12_50OHM_6INCH @BASEBOARD_FAB2_LIB.BASEBOARD_FAB2(SCH_1):L12_50OHM_6INCH    I67 @BASEBOARD_FAB2_LIB.BASEBOARD_FAB2(SCH_1):PAGE271
  GND1    GND @BASEBOARD_FAB2_LIB.BASEBOARD_FAB2(SCH_1):GND    I67 @BASEBOARD_FAB2_LIB.BASEBOARD_FAB2(SCH_1):PAGE271

T1P36 TPAD-SE-2P-GP_DISCRET-GA1-TPADA
     1 L14_50OHM_6INCH @BASEBOARD_FAB2_LIB.BASEBOARD_FAB2(SCH_1):L14_50OHM_6INCH    I63 @BASEBOARD_FAB2_LIB.BASEBOARD_FAB2(SCH_1):PAGE271
  GND1    GND @BASEBOARD_FAB2_LIB.BASEBOARD_FAB2(SCH_1):GND    I63 @BASEBOARD_FAB2_LIB.BASEBOARD_FAB2(SCH_1):PAGE271

TH1A1 MTG_KEYHOLE_TH-EMPTY,NA
     1    GND @BASEBOARD_FAB2_LIB.BASEBOARD_FAB2(SCH_1):GND    I56 @BASEBOARD_FAB2_LIB.BASEBOARD_FAB2(SCH_1):PAGE195

TH4A1 MTG_KEYHOLE_TH-EMPTY,NA
     1    GND @BASEBOARD_FAB2_LIB.BASEBOARD_FAB2(SCH_1):GND    I62 @BASEBOARD_FAB2_LIB.BASEBOARD_FAB2(SCH_1):PAGE195

TH4G1 MTG_KEYHOLE_TH-EMPTY,NA
     1    GND @BASEBOARD_FAB2_LIB.BASEBOARD_FAB2(SCH_1):GND    I49 @BASEBOARD_FAB2_LIB.BASEBOARD_FAB2(SCH_1):PAGE195

TH7A1 MTG_KEYHOLE_TH-EMPTY,NA
     1    GND @BASEBOARD_FAB2_LIB.BASEBOARD_FAB2(SCH_1):GND    I65 @BASEBOARD_FAB2_LIB.BASEBOARD_FAB2(SCH_1):PAGE195

TH7G1 MTG_KEYHOLE_TH-EMPTY,NA
     1    GND @BASEBOARD_FAB2_LIB.BASEBOARD_FAB2(SCH_1):GND    I67 @BASEBOARD_FAB2_LIB.BASEBOARD_FAB2(SCH_1):PAGE195

TH9A1 MTG_KEYHOLE_TH-EMPTY,NA
     1    GND @BASEBOARD_FAB2_LIB.BASEBOARD_FAB2(SCH_1):GND    I54 @BASEBOARD_FAB2_LIB.BASEBOARD_FAB2(SCH_1):PAGE195

TH9G1 MTG_KEYHOLE_TH-EMPTY,NA
     1    GND @BASEBOARD_FAB2_LIB.BASEBOARD_FAB2(SCH_1):GND    I52 @BASEBOARD_FAB2_LIB.BASEBOARD_FAB2(SCH_1):PAGE195

U1B2 TCA9517DGKR-GP_DISCRET-G8-TCA9A
     1 PVCCIO_CPU1 @BASEBOARD_FAB2_LIB.BASEBOARD_FAB2(SCH_1):PVCCIO_CPU1    I28 @BASEBOARD_FAB2_LIB.BASEBOARD_FAB2(SCH_1):PAGE163
     2 SMB_CPU1_PE_HP_GTL_R_SCL @BASEBOARD_FAB2_LIB.BASEBOARD_FAB2(SCH_1):SMB_CPU1_PE_HP_GTL_R_SCL    I28 @BASEBOARD_FAB2_LIB.BASEBOARD_FAB2(SCH_1):PAGE163
     3 SMB_CPU1_PE_HP_GTL_R_SDA @BASEBOARD_FAB2_LIB.BASEBOARD_FAB2(SCH_1):SMB_CPU1_PE_HP_GTL_R_SDA    I28 @BASEBOARD_FAB2_LIB.BASEBOARD_FAB2(SCH_1):PAGE163
     4    GND @BASEBOARD_FAB2_LIB.BASEBOARD_FAB2(SCH_1):GND    I28 @BASEBOARD_FAB2_LIB.BASEBOARD_FAB2(SCH_1):PAGE163
     8 P3V3_STBY @BASEBOARD_FAB2_LIB.BASEBOARD_FAB2(SCH_1):P3V3_STBY    I28 @BASEBOARD_FAB2_LIB.BASEBOARD_FAB2(SCH_1):PAGE163
     7 SMB_PEHPCPU1_STBY_LVC3_R_SCL @BASEBOARD_FAB2_LIB.BASEBOARD_FAB2(SCH_1):SMB_PEHPCPU1_STBY_LVC3_R_SCL    I28 @BASEBOARD_FAB2_LIB.BASEBOARD_FAB2(SCH_1):PAGE163
     6 SMB_PEHPCPU1_STBY_LVC3_R_SDA @BASEBOARD_FAB2_LIB.BASEBOARD_FAB2(SCH_1):SMB_PEHPCPU1_STBY_LVC3_R_SDA    I28 @BASEBOARD_FAB2_LIB.BASEBOARD_FAB2(SCH_1):PAGE163
     5 TP_SMB_PEHPCPU1_EN @BASEBOARD_FAB2_LIB.BASEBOARD_FAB2(SCH_1):TP_SMB_PEHPCPU1_EN    I28 @BASEBOARD_FAB2_LIB.BASEBOARD_FAB2(SCH_1):PAGE163

U1D1 TTL1G126_A_SOT-74HC1G126,IC,A7B
     1 FM_OC_DETECT_EN @BASEBOARD_FAB2_LIB.BASEBOARD_FAB2(SCH_1):FM_OC_DETECT_EN   I103 @BASEBOARD_FAB2_LIB.BASEBOARD_FAB2(SCH_1):PAGE200
     2 IRQ_OC_DETECT_N @BASEBOARD_FAB2_LIB.BASEBOARD_FAB2(SCH_1):IRQ_OC_DETECT_N   I103 @BASEBOARD_FAB2_LIB.BASEBOARD_FAB2(SCH_1):PAGE200
     4 FM_OC_DETECT_N @BASEBOARD_FAB2_LIB.BASEBOARD_FAB2(SCH_1):FM_OC_DETECT_N   I103 @BASEBOARD_FAB2_LIB.BASEBOARD_FAB2(SCH_1):PAGE200

U1D2 TPS3700_SM-IC,H69492-001
     5    GND @BASEBOARD_FAB2_LIB.BASEBOARD_FAB2(SCH_1):GND   I170 @BASEBOARD_FAB2_LIB.BASEBOARD_FAB2(SCH_1):PAGE200
     4 A_HSC_LOW @BASEBOARD_FAB2_LIB.BASEBOARD_FAB2(SCH_1):A_HSC_LOW   I170 @BASEBOARD_FAB2_LIB.BASEBOARD_FAB2(SCH_1):PAGE200
     3 A_HSC_HIGH @BASEBOARD_FAB2_LIB.BASEBOARD_FAB2(SCH_1):A_HSC_HIGH   I170 @BASEBOARD_FAB2_LIB.BASEBOARD_FAB2(SCH_1):PAGE200
     6 A_HSC_LOW_GATE @BASEBOARD_FAB2_LIB.BASEBOARD_FAB2(SCH_1):A_HSC_LOW_GATE   I170 @BASEBOARD_FAB2_LIB.BASEBOARD_FAB2(SCH_1):PAGE200
     1 IRQ_OC_DETECT_N @BASEBOARD_FAB2_LIB.BASEBOARD_FAB2(SCH_1):IRQ_OC_DETECT_N   I170 @BASEBOARD_FAB2_LIB.BASEBOARD_FAB2(SCH_1):PAGE200
     2 P12V_STBY @BASEBOARD_FAB2_LIB.BASEBOARD_FAB2(SCH_1):P12V_STBY   I170 @BASEBOARD_FAB2_LIB.BASEBOARD_FAB2(SCH_1):PAGE200

U1E1 TMP421_TSSOP-IC,G62962-001
     3 PD_TMP421_2_A1 @BASEBOARD_FAB2_LIB.BASEBOARD_FAB2(SCH_1):PD_TMP421_2_A1    I30 @BASEBOARD_FAB2_LIB.BASEBOARD_FAB2(SCH_1):PAGE167
     4 PU_TMP421_2_A0 @BASEBOARD_FAB2_LIB.BASEBOARD_FAB2(SCH_1):PU_TMP421_2_A0    I30 @BASEBOARD_FAB2_LIB.BASEBOARD_FAB2(SCH_1):PAGE167
     2 ISENSE_TMP421_2_DXN @BASEBOARD_FAB2_LIB.BASEBOARD_FAB2(SCH_1):ISENSE_TMP421_2_DXN    I30 @BASEBOARD_FAB2_LIB.BASEBOARD_FAB2(SCH_1):PAGE167
     1 ISENSE_TMP421_2_DXP @BASEBOARD_FAB2_LIB.BASEBOARD_FAB2(SCH_1):ISENSE_TMP421_2_DXP    I30 @BASEBOARD_FAB2_LIB.BASEBOARD_FAB2(SCH_1):PAGE167
     5    GND @BASEBOARD_FAB2_LIB.BASEBOARD_FAB2(SCH_1):GND    I30 @BASEBOARD_FAB2_LIB.BASEBOARD_FAB2(SCH_1):PAGE167
     7 SMB_SENSOR_TMP421_2_SCL @BASEBOARD_FAB2_LIB.BASEBOARD_FAB2(SCH_1):SMB_SENSOR_TMP421_2_SCL    I30 @BASEBOARD_FAB2_LIB.BASEBOARD_FAB2(SCH_1):PAGE167
     6 SMB_SENSOR_TMP421_2_SDA @BASEBOARD_FAB2_LIB.BASEBOARD_FAB2(SCH_1):SMB_SENSOR_TMP421_2_SDA    I30 @BASEBOARD_FAB2_LIB.BASEBOARD_FAB2(SCH_1):PAGE167
     8 P3V3_STBY @BASEBOARD_FAB2_LIB.BASEBOARD_FAB2(SCH_1):P3V3_STBY    I30 @BASEBOARD_FAB2_LIB.BASEBOARD_FAB2(SCH_1):PAGE167

U1E2 TTL1G08_SOTLF-NC7SZ08,IC,D1032B
     4 FM_ENABLE_FAN_POWER @BASEBOARD_FAB2_LIB.BASEBOARD_FAB2(SCH_1):FM_ENABLE_FAN_POWER   I121 @BASEBOARD_FAB2_LIB.BASEBOARD_FAB2(SCH_1):PAGE161
     1 FM_CTNR_PS_ON @BASEBOARD_FAB2_LIB.BASEBOARD_FAB2(SCH_1):FM_CTNR_PS_ON   I121 @BASEBOARD_FAB2_LIB.BASEBOARD_FAB2(SCH_1):PAGE161
     2 FM_DISABLE_FAN_N @BASEBOARD_FAB2_LIB.BASEBOARD_FAB2(SCH_1):FM_DISABLE_FAN_N   I121 @BASEBOARD_FAB2_LIB.BASEBOARD_FAB2(SCH_1):PAGE161

U1L1 TTL3126_QFNLF-74CBTLV3126,IC,DB
     1 PWRGD_PVCCIN_CPU0 @BASEBOARD_FAB2_LIB.BASEBOARD_FAB2(SCH_1):PWRGD_PVCCIN_CPU0   I108 @BASEBOARD_FAB2_LIB.BASEBOARD_FAB2(SCH_1):PAGE112
     2 XDP_TRST_N @BASEBOARD_FAB2_LIB.BASEBOARD_FAB2(SCH_1):XDP_TRST_N   I108 @BASEBOARD_FAB2_LIB.BASEBOARD_FAB2(SCH_1):PAGE112
     3 XDP_CPU_TRST_N @BASEBOARD_FAB2_LIB.BASEBOARD_FAB2(SCH_1):XDP_CPU_TRST_N   I108 @BASEBOARD_FAB2_LIB.BASEBOARD_FAB2(SCH_1):PAGE112
     4 PWRGD_PVCCIN_CPU0 @BASEBOARD_FAB2_LIB.BASEBOARD_FAB2(SCH_1):PWRGD_PVCCIN_CPU0   I108 @BASEBOARD_FAB2_LIB.BASEBOARD_FAB2(SCH_1):PAGE112
     5 XDP_TMS @BASEBOARD_FAB2_LIB.BASEBOARD_FAB2(SCH_1):XDP_TMS   I108 @BASEBOARD_FAB2_LIB.BASEBOARD_FAB2(SCH_1):PAGE112
     6 XDP_CPU_TMS @BASEBOARD_FAB2_LIB.BASEBOARD_FAB2(SCH_1):XDP_CPU_TMS   I108 @BASEBOARD_FAB2_LIB.BASEBOARD_FAB2(SCH_1):PAGE112
    10 PWRGD_PVCCIN_CPU0 @BASEBOARD_FAB2_LIB.BASEBOARD_FAB2(SCH_1):PWRGD_PVCCIN_CPU0   I108 @BASEBOARD_FAB2_LIB.BASEBOARD_FAB2(SCH_1):PAGE112
     9 XDP_TDO @BASEBOARD_FAB2_LIB.BASEBOARD_FAB2(SCH_1):XDP_TDO   I108 @BASEBOARD_FAB2_LIB.BASEBOARD_FAB2(SCH_1):PAGE112
     8 XDP_CPU_TDO @BASEBOARD_FAB2_LIB.BASEBOARD_FAB2(SCH_1):XDP_CPU_TDO   I108 @BASEBOARD_FAB2_LIB.BASEBOARD_FAB2(SCH_1):PAGE112
    13 PWRGD_PVCCIN_CPU0 @BASEBOARD_FAB2_LIB.BASEBOARD_FAB2(SCH_1):PWRGD_PVCCIN_CPU0   I108 @BASEBOARD_FAB2_LIB.BASEBOARD_FAB2(SCH_1):PAGE112
    12 XDP_TDI @BASEBOARD_FAB2_LIB.BASEBOARD_FAB2(SCH_1):XDP_TDI   I108 @BASEBOARD_FAB2_LIB.BASEBOARD_FAB2(SCH_1):PAGE112
    11 XDP_CPU_TDI @BASEBOARD_FAB2_LIB.BASEBOARD_FAB2(SCH_1):XDP_CPU_TDI   I108 @BASEBOARD_FAB2_LIB.BASEBOARD_FAB2(SCH_1):PAGE112

U1L2 TTL1G86_SOTLF-74AHCT1G86,IC,D3B
     1 PWRGD_P3V3_R @BASEBOARD_FAB2_LIB.BASEBOARD_FAB2(SCH_1):PWRGD_P3V3_R    I57 @BASEBOARD_FAB2_LIB.BASEBOARD_FAB2(SCH_1):PAGE175
     2 FP_PWR_ID_LED_N @BASEBOARD_FAB2_LIB.BASEBOARD_FAB2(SCH_1):FP_PWR_ID_LED_N    I57 @BASEBOARD_FAB2_LIB.BASEBOARD_FAB2(SCH_1):PAGE175
     4 FP_ID_LED_P5V_STBY_N @BASEBOARD_FAB2_LIB.BASEBOARD_FAB2(SCH_1):FP_ID_LED_P5V_STBY_N    I57 @BASEBOARD_FAB2_LIB.BASEBOARD_FAB2(SCH_1):PAGE175

U1L3 ADM809_SMLF-IC,D23047-001-GND=A
     3   P3V3 @BASEBOARD_FAB2_LIB.BASEBOARD_FAB2(SCH_1):P3V3    I80 @BASEBOARD_FAB2_LIB.BASEBOARD_FAB2(SCH_1):PAGE196
     2 PWRGD_P3V3_R1 @BASEBOARD_FAB2_LIB.BASEBOARD_FAB2(SCH_1):PWRGD_P3V3_R1    I80 @BASEBOARD_FAB2_LIB.BASEBOARD_FAB2(SCH_1):PAGE196

U1L4 TTL1G07_A_SOP-74LVC1G07,IC,C88B
     2 XDP_RST_CO_N @BASEBOARD_FAB2_LIB.BASEBOARD_FAB2(SCH_1):XDP_RST_CO_N    I85 @BASEBOARD_FAB2_LIB.BASEBOARD_FAB2(SCH_1):PAGE111
     4 FM_DEBUG_RST_BTN_R1_N @BASEBOARD_FAB2_LIB.BASEBOARD_FAB2(SCH_1):FM_DEBUG_RST_BTN_R1_N    I85 @BASEBOARD_FAB2_LIB.BASEBOARD_FAB2(SCH_1):PAGE111

U1L5 TTL3126_QFNLF-74CBTLV3126,IC,DB
     1 PWRGD_PVCCIN_CPU0 @BASEBOARD_FAB2_LIB.BASEBOARD_FAB2(SCH_1):PWRGD_PVCCIN_CPU0   I109 @BASEBOARD_FAB2_LIB.BASEBOARD_FAB2(SCH_1):PAGE112
     2 XDP_OBSFN_B1_MBP7_N @BASEBOARD_FAB2_LIB.BASEBOARD_FAB2(SCH_1):XDP_OBSFN_B1_MBP7_N   I109 @BASEBOARD_FAB2_LIB.BASEBOARD_FAB2(SCH_1):PAGE112
     3 XDP_CPU_OBSFN_B1_MBP7_N @BASEBOARD_FAB2_LIB.BASEBOARD_FAB2(SCH_1):XDP_CPU_OBSFN_B1_MBP7_N   I109 @BASEBOARD_FAB2_LIB.BASEBOARD_FAB2(SCH_1):PAGE112
     4 PWRGD_PVCCIN_CPU0 @BASEBOARD_FAB2_LIB.BASEBOARD_FAB2(SCH_1):PWRGD_PVCCIN_CPU0   I109 @BASEBOARD_FAB2_LIB.BASEBOARD_FAB2(SCH_1):PAGE112
     5 XDP_OBSFN_B0_MBP6_N @BASEBOARD_FAB2_LIB.BASEBOARD_FAB2(SCH_1):XDP_OBSFN_B0_MBP6_N   I109 @BASEBOARD_FAB2_LIB.BASEBOARD_FAB2(SCH_1):PAGE112
     6 XDP_CPU_OBSFN_B0_MBP6_N @BASEBOARD_FAB2_LIB.BASEBOARD_FAB2(SCH_1):XDP_CPU_OBSFN_B0_MBP6_N   I109 @BASEBOARD_FAB2_LIB.BASEBOARD_FAB2(SCH_1):PAGE112
    10 PWRGD_PVCCIN_CPU0 @BASEBOARD_FAB2_LIB.BASEBOARD_FAB2(SCH_1):PWRGD_PVCCIN_CPU0   I109 @BASEBOARD_FAB2_LIB.BASEBOARD_FAB2(SCH_1):PAGE112
     9 XDP_PRDY_N @BASEBOARD_FAB2_LIB.BASEBOARD_FAB2(SCH_1):XDP_PRDY_N   I109 @BASEBOARD_FAB2_LIB.BASEBOARD_FAB2(SCH_1):PAGE112
     8 XDP_CPU_PRDY_N @BASEBOARD_FAB2_LIB.BASEBOARD_FAB2(SCH_1):XDP_CPU_PRDY_N   I109 @BASEBOARD_FAB2_LIB.BASEBOARD_FAB2(SCH_1):PAGE112
    13 PWRGD_PVCCIN_CPU0 @BASEBOARD_FAB2_LIB.BASEBOARD_FAB2(SCH_1):PWRGD_PVCCIN_CPU0   I109 @BASEBOARD_FAB2_LIB.BASEBOARD_FAB2(SCH_1):PAGE112
    12 XDP_PREQ_N @BASEBOARD_FAB2_LIB.BASEBOARD_FAB2(SCH_1):XDP_PREQ_N   I109 @BASEBOARD_FAB2_LIB.BASEBOARD_FAB2(SCH_1):PAGE112
    11 XDP_CPU_PREQ_N @BASEBOARD_FAB2_LIB.BASEBOARD_FAB2(SCH_1):XDP_CPU_PREQ_N   I109 @BASEBOARD_FAB2_LIB.BASEBOARD_FAB2(SCH_1):PAGE112

U1L10 TTL3126_QFNLF-74CBTLV3126,IC,DB
     1 BMC_JTAG_SEL_N_MUX @BASEBOARD_FAB2_LIB.BASEBOARD_FAB2(SCH_1):BMC_JTAG_SEL_N_MUX    I67 @BASEBOARD_FAB2_LIB.BASEBOARD_FAB2(SCH_1):PAGE189
     2 JTAG_PLD_TDO_MUX @BASEBOARD_FAB2_LIB.BASEBOARD_FAB2(SCH_1):JTAG_PLD_TDO_MUX    I67 @BASEBOARD_FAB2_LIB.BASEBOARD_FAB2(SCH_1):PAGE189
     3 JTAG_TDO @BASEBOARD_FAB2_LIB.BASEBOARD_FAB2(SCH_1):JTAG_TDO    I67 @BASEBOARD_FAB2_LIB.BASEBOARD_FAB2(SCH_1):PAGE189
     4 BMC_JTAG_SEL_N_MUX @BASEBOARD_FAB2_LIB.BASEBOARD_FAB2(SCH_1):BMC_JTAG_SEL_N_MUX    I67 @BASEBOARD_FAB2_LIB.BASEBOARD_FAB2(SCH_1):PAGE189
     5 JTAG_PLD_TCK_MUX @BASEBOARD_FAB2_LIB.BASEBOARD_FAB2(SCH_1):JTAG_PLD_TCK_MUX    I67 @BASEBOARD_FAB2_LIB.BASEBOARD_FAB2(SCH_1):PAGE189
     6 JTAG_TCK @BASEBOARD_FAB2_LIB.BASEBOARD_FAB2(SCH_1):JTAG_TCK    I67 @BASEBOARD_FAB2_LIB.BASEBOARD_FAB2(SCH_1):PAGE189
    10 BMC_JTAG_SEL_N_MUX @BASEBOARD_FAB2_LIB.BASEBOARD_FAB2(SCH_1):BMC_JTAG_SEL_N_MUX    I67 @BASEBOARD_FAB2_LIB.BASEBOARD_FAB2(SCH_1):PAGE189
     9 JTAG_PLD_TMS_MUX @BASEBOARD_FAB2_LIB.BASEBOARD_FAB2(SCH_1):JTAG_PLD_TMS_MUX    I67 @BASEBOARD_FAB2_LIB.BASEBOARD_FAB2(SCH_1):PAGE189
     8 JTAG_TMS @BASEBOARD_FAB2_LIB.BASEBOARD_FAB2(SCH_1):JTAG_TMS    I67 @BASEBOARD_FAB2_LIB.BASEBOARD_FAB2(SCH_1):PAGE189
    13 BMC_JTAG_SEL_N_MUX @BASEBOARD_FAB2_LIB.BASEBOARD_FAB2(SCH_1):BMC_JTAG_SEL_N_MUX    I67 @BASEBOARD_FAB2_LIB.BASEBOARD_FAB2(SCH_1):PAGE189
    12 JTAG_PLD_TDI_MUX @BASEBOARD_FAB2_LIB.BASEBOARD_FAB2(SCH_1):JTAG_PLD_TDI_MUX    I67 @BASEBOARD_FAB2_LIB.BASEBOARD_FAB2(SCH_1):PAGE189
    11 JTAG_TDI @BASEBOARD_FAB2_LIB.BASEBOARD_FAB2(SCH_1):JTAG_TDI    I67 @BASEBOARD_FAB2_LIB.BASEBOARD_FAB2(SCH_1):PAGE189

U1M1 TTL1G08_SOTLF-NC7SZ08,IC,D1032C
     4 FP_LED_HDD_ACTIVITY_AND_N @BASEBOARD_FAB2_LIB.BASEBOARD_FAB2(SCH_1):FP_LED_HDD_ACTIVITY_AND_N    I70 @BASEBOARD_FAB2_LIB.BASEBOARD_FAB2(SCH_1):PAGE177
     1 LED_SATA_ACT_R_N @BASEBOARD_FAB2_LIB.BASEBOARD_FAB2(SCH_1):LED_SATA_ACT_R_N    I70 @BASEBOARD_FAB2_LIB.BASEBOARD_FAB2(SCH_1):PAGE177
     2 LED_SAS_ACT_R_N @BASEBOARD_FAB2_LIB.BASEBOARD_FAB2(SCH_1):LED_SAS_ACT_R_N    I70 @BASEBOARD_FAB2_LIB.BASEBOARD_FAB2(SCH_1):PAGE177

U1M2 NC7SB3157_SMLF-IC,C99406-001
     6 FM_CPU1_CD_PRES_N @BASEBOARD_FAB2_LIB.BASEBOARD_FAB2(SCH_1):FM_CPU1_CD_PRES_N   I107 @BASEBOARD_FAB2_LIB.BASEBOARD_FAB2(SCH_1):PAGE113
     3 JTAG_MCP_CPU1_TDO @BASEBOARD_FAB2_LIB.BASEBOARD_FAB2(SCH_1):JTAG_MCP_CPU1_TDO   I107 @BASEBOARD_FAB2_LIB.BASEBOARD_FAB2(SCH_1):PAGE113
     1 JTAG_MCP_CPU0_TDO @BASEBOARD_FAB2_LIB.BASEBOARD_FAB2(SCH_1):JTAG_MCP_CPU0_TDO   I107 @BASEBOARD_FAB2_LIB.BASEBOARD_FAB2(SCH_1):PAGE113
     4 JTAG_MCP_MUX_TDO @BASEBOARD_FAB2_LIB.BASEBOARD_FAB2(SCH_1):JTAG_MCP_MUX_TDO   I107 @BASEBOARD_FAB2_LIB.BASEBOARD_FAB2(SCH_1):PAGE113
     5 P3V3_STBY @BASEBOARD_FAB2_LIB.BASEBOARD_FAB2(SCH_1):P3V3_STBY   I107 @BASEBOARD_FAB2_LIB.BASEBOARD_FAB2(SCH_1):PAGE113
     2    GND @BASEBOARD_FAB2_LIB.BASEBOARD_FAB2(SCH_1):GND   I107 @BASEBOARD_FAB2_LIB.BASEBOARD_FAB2(SCH_1):PAGE113

U1M3 TPS2061_SM-IC,H66405-001
     4 FM_USB_P0_EN_R_N @BASEBOARD_FAB2_LIB.BASEBOARD_FAB2(SCH_1):FM_USB_P0_EN_R_N   I100 @BASEBOARD_FAB2_LIB.BASEBOARD_FAB2(SCH_1):PAGE176
     2    GND @BASEBOARD_FAB2_LIB.BASEBOARD_FAB2(SCH_1):GND   I100 @BASEBOARD_FAB2_LIB.BASEBOARD_FAB2(SCH_1):PAGE176
     5 P5V_TPS2061 @BASEBOARD_FAB2_LIB.BASEBOARD_FAB2(SCH_1):P5V_TPS2061   I100 @BASEBOARD_FAB2_LIB.BASEBOARD_FAB2(SCH_1):PAGE176
     3 FM_OC0_USB_N @BASEBOARD_FAB2_LIB.BASEBOARD_FAB2(SCH_1):FM_OC0_USB_N   I100 @BASEBOARD_FAB2_LIB.BASEBOARD_FAB2(SCH_1):PAGE176
     1 P5V_USB @BASEBOARD_FAB2_LIB.BASEBOARD_FAB2(SCH_1):P5V_USB   I100 @BASEBOARD_FAB2_LIB.BASEBOARD_FAB2(SCH_1):PAGE176

U1M4 74CBTLV1G125_SMLF-IC,C88177-00A
     4 XDP_CPU1_TDI @BASEBOARD_FAB2_LIB.BASEBOARD_FAB2(SCH_1):XDP_CPU1_TDI   I127 @BASEBOARD_FAB2_LIB.BASEBOARD_FAB2(SCH_1):PAGE112
     1 FM_CPU1_SKTOCC_LVT3_N @BASEBOARD_FAB2_LIB.BASEBOARD_FAB2(SCH_1):FM_CPU1_SKTOCC_LVT3_N   I127 @BASEBOARD_FAB2_LIB.BASEBOARD_FAB2(SCH_1):PAGE112
     2 XDP_CPU0_TDO @BASEBOARD_FAB2_LIB.BASEBOARD_FAB2(SCH_1):XDP_CPU0_TDO   I127 @BASEBOARD_FAB2_LIB.BASEBOARD_FAB2(SCH_1):PAGE112

U1M5 74CBTLV1G125_SMLF-IC,C88177-00A
     4 JTAG_MCP_TMS_R1 @BASEBOARD_FAB2_LIB.BASEBOARD_FAB2(SCH_1):JTAG_MCP_TMS_R1   I196 @BASEBOARD_FAB2_LIB.BASEBOARD_FAB2(SCH_1):PAGE113
     1 FM_CPU0_OR_CPU1_MCP_PRES @BASEBOARD_FAB2_LIB.BASEBOARD_FAB2(SCH_1):FM_CPU0_OR_CPU1_MCP_PRES   I196 @BASEBOARD_FAB2_LIB.BASEBOARD_FAB2(SCH_1):PAGE113
     2 P1V8_MCP_CPU0 @BASEBOARD_FAB2_LIB.BASEBOARD_FAB2(SCH_1):P1V8_MCP_CPU0   I196 @BASEBOARD_FAB2_LIB.BASEBOARD_FAB2(SCH_1):PAGE113

U1M6 74CBTLV1G125_SMLF-IC,C88177-00A
     4 JTAG_MCP_CPU1_TDI @BASEBOARD_FAB2_LIB.BASEBOARD_FAB2(SCH_1):JTAG_MCP_CPU1_TDI   I127 @BASEBOARD_FAB2_LIB.BASEBOARD_FAB2(SCH_1):PAGE113
     1 FM_CPU0_AND_CPU1_MCP_PRES @BASEBOARD_FAB2_LIB.BASEBOARD_FAB2(SCH_1):FM_CPU0_AND_CPU1_MCP_PRES   I127 @BASEBOARD_FAB2_LIB.BASEBOARD_FAB2(SCH_1):PAGE113
     2 JTAG_MCP_CPU0_TDO @BASEBOARD_FAB2_LIB.BASEBOARD_FAB2(SCH_1):JTAG_MCP_CPU0_TDO   I127 @BASEBOARD_FAB2_LIB.BASEBOARD_FAB2(SCH_1):PAGE113

U1M7 NC7SB3157_SMLF-IC,C99406-001
     6 FM_CPU1_SKTOCC_LVT3_N @BASEBOARD_FAB2_LIB.BASEBOARD_FAB2(SCH_1):FM_CPU1_SKTOCC_LVT3_N    I40 @BASEBOARD_FAB2_LIB.BASEBOARD_FAB2(SCH_1):PAGE112
     3 XDP_CPU1_TDO @BASEBOARD_FAB2_LIB.BASEBOARD_FAB2(SCH_1):XDP_CPU1_TDO    I40 @BASEBOARD_FAB2_LIB.BASEBOARD_FAB2(SCH_1):PAGE112
     1 XDP_CPU0_TDO @BASEBOARD_FAB2_LIB.BASEBOARD_FAB2(SCH_1):XDP_CPU0_TDO    I40 @BASEBOARD_FAB2_LIB.BASEBOARD_FAB2(SCH_1):PAGE112
     4 XDP_CPU_TDO @BASEBOARD_FAB2_LIB.BASEBOARD_FAB2(SCH_1):XDP_CPU_TDO    I40 @BASEBOARD_FAB2_LIB.BASEBOARD_FAB2(SCH_1):PAGE112
     5 P3V3_STBY @BASEBOARD_FAB2_LIB.BASEBOARD_FAB2(SCH_1):P3V3_STBY    I40 @BASEBOARD_FAB2_LIB.BASEBOARD_FAB2(SCH_1):PAGE112
     2    GND @BASEBOARD_FAB2_LIB.BASEBOARD_FAB2(SCH_1):GND    I40 @BASEBOARD_FAB2_LIB.BASEBOARD_FAB2(SCH_1):PAGE112

U1R1 TTL1G07_A_SOP-74LVC1G07,IC,C88B
     2 FM_FAST_PROCHOT_THROTTLE_DLY_BU @BASEBOARD_FAB2_LIB.BASEBOARD_FAB2(SCH_1):FM_FAST_PROCHOT_THROTTLE_DLY_BUF_N    I46 @BASEBOARD_FAB2_LIB.BASEBOARD_FAB2(SCH_1):PAGE170
     4 FM_THROTTLE_R1_N @BASEBOARD_FAB2_LIB.BASEBOARD_FAB2(SCH_1):FM_THROTTLE_R1_N    I46 @BASEBOARD_FAB2_LIB.BASEBOARD_FAB2(SCH_1):PAGE170

U1R2 TTL1G126_A_SOT-74HC1G126,IC,A7B
     1 FM_FAST_PROCHOT_EN @BASEBOARD_FAB2_LIB.BASEBOARD_FAB2(SCH_1):FM_FAST_PROCHOT_EN    I20 @BASEBOARD_FAB2_LIB.BASEBOARD_FAB2(SCH_1):PAGE170
     2 FM_FAST_PROCHOT_THROTTLE_DLY_N @BASEBOARD_FAB2_LIB.BASEBOARD_FAB2(SCH_1):FM_FAST_PROCHOT_THROTTLE_DLY_N    I20 @BASEBOARD_FAB2_LIB.BASEBOARD_FAB2(SCH_1):PAGE170
     4 FM_FAST_PROCHOT_THROTTLE_DLY_BU @BASEBOARD_FAB2_LIB.BASEBOARD_FAB2(SCH_1):FM_FAST_PROCHOT_THROTTLE_DLY_BUF_N    I20 @BASEBOARD_FAB2_LIB.BASEBOARD_FAB2(SCH_1):PAGE170

U1W2 TCA9517DGKR-GP_DISCRET-G8-TCA9A
     1 PVCCIO_CPU0 @BASEBOARD_FAB2_LIB.BASEBOARD_FAB2(SCH_1):PVCCIO_CPU0    I49 @BASEBOARD_FAB2_LIB.BASEBOARD_FAB2(SCH_1):PAGE248
     2 SMB_CPU0_PE_HP_GTL_R_SCL @BASEBOARD_FAB2_LIB.BASEBOARD_FAB2(SCH_1):SMB_CPU0_PE_HP_GTL_R_SCL    I49 @BASEBOARD_FAB2_LIB.BASEBOARD_FAB2(SCH_1):PAGE248
     3 SMB_CPU0_PE_HP_GTL_R_SDA @BASEBOARD_FAB2_LIB.BASEBOARD_FAB2(SCH_1):SMB_CPU0_PE_HP_GTL_R_SDA    I49 @BASEBOARD_FAB2_LIB.BASEBOARD_FAB2(SCH_1):PAGE248
     4    GND @BASEBOARD_FAB2_LIB.BASEBOARD_FAB2(SCH_1):GND    I49 @BASEBOARD_FAB2_LIB.BASEBOARD_FAB2(SCH_1):PAGE248
     8 P3V3_STBY @BASEBOARD_FAB2_LIB.BASEBOARD_FAB2(SCH_1):P3V3_STBY    I49 @BASEBOARD_FAB2_LIB.BASEBOARD_FAB2(SCH_1):PAGE248
     7 SMB_PEHPCPU0_STBY_LVC3_R_SCL @BASEBOARD_FAB2_LIB.BASEBOARD_FAB2(SCH_1):SMB_PEHPCPU0_STBY_LVC3_R_SCL    I49 @BASEBOARD_FAB2_LIB.BASEBOARD_FAB2(SCH_1):PAGE248
     6 SMB_PEHPCPU0_STBY_LVC3_R_SDA @BASEBOARD_FAB2_LIB.BASEBOARD_FAB2(SCH_1):SMB_PEHPCPU0_STBY_LVC3_R_SDA    I49 @BASEBOARD_FAB2_LIB.BASEBOARD_FAB2(SCH_1):PAGE248
     5 TP_SMB_PEHPCPU0_EN @BASEBOARD_FAB2_LIB.BASEBOARD_FAB2(SCH_1):TP_SMB_PEHPCPU0_EN    I49 @BASEBOARD_FAB2_LIB.BASEBOARD_FAB2(SCH_1):PAGE248

U1W3 PCA9617_SSOP-IC,G81764-001-GNDA
     5 DEBUG_CARD2_PRSNT @BASEBOARD_FAB2_LIB.BASEBOARD_FAB2(SCH_1):DEBUG_CARD2_PRSNT   I162 @BASEBOARD_FAB2_LIB.BASEBOARD_FAB2(SCH_1):PAGE176
     2 SMB_DEBUG_STBY_LVC3_SCL_CONN @BASEBOARD_FAB2_LIB.BASEBOARD_FAB2(SCH_1):SMB_DEBUG_STBY_LVC3_SCL_CONN   I162 @BASEBOARD_FAB2_LIB.BASEBOARD_FAB2(SCH_1):PAGE176
     7 SMB_DEBUG_STBY_LVC3_SCL_R1 @BASEBOARD_FAB2_LIB.BASEBOARD_FAB2(SCH_1):SMB_DEBUG_STBY_LVC3_SCL_R1   I162 @BASEBOARD_FAB2_LIB.BASEBOARD_FAB2(SCH_1):PAGE176
     3 SMB_DEBUG_STBY_LVC3_SDA_CONN @BASEBOARD_FAB2_LIB.BASEBOARD_FAB2(SCH_1):SMB_DEBUG_STBY_LVC3_SDA_CONN   I162 @BASEBOARD_FAB2_LIB.BASEBOARD_FAB2(SCH_1):PAGE176
     6 SMB_DEBUG_STBY_LVC3_SDA_R1 @BASEBOARD_FAB2_LIB.BASEBOARD_FAB2(SCH_1):SMB_DEBUG_STBY_LVC3_SDA_R1   I162 @BASEBOARD_FAB2_LIB.BASEBOARD_FAB2(SCH_1):PAGE176
     1 P3V3_STBY @BASEBOARD_FAB2_LIB.BASEBOARD_FAB2(SCH_1):P3V3_STBY   I162 @BASEBOARD_FAB2_LIB.BASEBOARD_FAB2(SCH_1):PAGE176
     8 P3V3_STBY @BASEBOARD_FAB2_LIB.BASEBOARD_FAB2(SCH_1):P3V3_STBY   I162 @BASEBOARD_FAB2_LIB.BASEBOARD_FAB2(SCH_1):PAGE176

U2D1 SKX_EXT_B_BGA1-IC,TBD
  AU24 CLK_100M_CPU1_BCLK0_DN @BASEBOARD_FAB2_LIB.BASEBOARD_FAB2(SCH_1):CLK_100M_CPU1_BCLK0_DN   I172 @BASEBOARD_FAB2_LIB.BASEBOARD_FAB2(SCH_1):PAGE55
  AW24 CLK_100M_CPU1_BCLK0_DP @BASEBOARD_FAB2_LIB.BASEBOARD_FAB2(SCH_1):CLK_100M_CPU1_BCLK0_DP   I172 @BASEBOARD_FAB2_LIB.BASEBOARD_FAB2(SCH_1):PAGE55
  CR26 CLK_100M_CPU1_BCLK1_DN @BASEBOARD_FAB2_LIB.BASEBOARD_FAB2(SCH_1):CLK_100M_CPU1_BCLK1_DN   I172 @BASEBOARD_FAB2_LIB.BASEBOARD_FAB2(SCH_1):PAGE55
  CP27 CLK_100M_CPU1_BCLK1_DP @BASEBOARD_FAB2_LIB.BASEBOARD_FAB2(SCH_1):CLK_100M_CPU1_BCLK1_DP   I172 @BASEBOARD_FAB2_LIB.BASEBOARD_FAB2(SCH_1):PAGE55
  CT25 CLK_100M_CPU1_BCLK2_DN @BASEBOARD_FAB2_LIB.BASEBOARD_FAB2(SCH_1):CLK_100M_CPU1_BCLK2_DN   I172 @BASEBOARD_FAB2_LIB.BASEBOARD_FAB2(SCH_1):PAGE55
  CU26 CLK_100M_CPU1_BCLK2_DP @BASEBOARD_FAB2_LIB.BASEBOARD_FAB2(SCH_1):CLK_100M_CPU1_BCLK2_DP   I172 @BASEBOARD_FAB2_LIB.BASEBOARD_FAB2(SCH_1):PAGE55
  BA20 PD_CPU1_BIST_ENABLE @BASEBOARD_FAB2_LIB.BASEBOARD_FAB2(SCH_1):PD_CPU1_BIST_ENABLE   I172 @BASEBOARD_FAB2_LIB.BASEBOARD_FAB2(SCH_1):PAGE55
  BD23 H_CPU1_BMCINIT @BASEBOARD_FAB2_LIB.BASEBOARD_FAB2(SCH_1):H_CPU1_BMCINIT   I172 @BASEBOARD_FAB2_LIB.BASEBOARD_FAB2(SCH_1):PAGE55
  AC12 XDP_CPU_OBSFN_B1_MBP7_N @BASEBOARD_FAB2_LIB.BASEBOARD_FAB2(SCH_1):XDP_CPU_OBSFN_B1_MBP7_N   I172 @BASEBOARD_FAB2_LIB.BASEBOARD_FAB2(SCH_1):PAGE55
  AE12 XDP_CPU_OBSFN_B0_MBP6_N @BASEBOARD_FAB2_LIB.BASEBOARD_FAB2(SCH_1):XDP_CPU_OBSFN_B0_MBP6_N   I172 @BASEBOARD_FAB2_LIB.BASEBOARD_FAB2(SCH_1):PAGE55
   Y11 TP_XDP_CPU1_OBSDATA_B3_MBP5_N @BASEBOARD_FAB2_LIB.BASEBOARD_FAB2(SCH_1):TP_XDP_CPU1_OBSDATA_B3_MBP5_N   I172 @BASEBOARD_FAB2_LIB.BASEBOARD_FAB2(SCH_1):PAGE55
  AA12 TP_XDP_CPU1_OBSDATA_B2_MBP4_N @BASEBOARD_FAB2_LIB.BASEBOARD_FAB2(SCH_1):TP_XDP_CPU1_OBSDATA_B2_MBP4_N   I172 @BASEBOARD_FAB2_LIB.BASEBOARD_FAB2(SCH_1):PAGE55
  AF11 TP_XDP_CPU1_OBSDATA_B1_MBP3_N @BASEBOARD_FAB2_LIB.BASEBOARD_FAB2(SCH_1):TP_XDP_CPU1_OBSDATA_B1_MBP3_N   I172 @BASEBOARD_FAB2_LIB.BASEBOARD_FAB2(SCH_1):PAGE55
  AG10 TP_XDP_CPU1_OBSDATA_B0_MBP2_N @BASEBOARD_FAB2_LIB.BASEBOARD_FAB2(SCH_1):TP_XDP_CPU1_OBSDATA_B0_MBP2_N   I172 @BASEBOARD_FAB2_LIB.BASEBOARD_FAB2(SCH_1):PAGE55
  AH11 XDP_CPU_MBP1_N @BASEBOARD_FAB2_LIB.BASEBOARD_FAB2(SCH_1):XDP_CPU_MBP1_N   I172 @BASEBOARD_FAB2_LIB.BASEBOARD_FAB2(SCH_1):PAGE55
  AJ10 XDP_CPU_MBP0_N @BASEBOARD_FAB2_LIB.BASEBOARD_FAB2(SCH_1):XDP_CPU_MBP0_N   I172 @BASEBOARD_FAB2_LIB.BASEBOARD_FAB2(SCH_1):PAGE55
  AL14 H_CPU1_CATERR_G_N @BASEBOARD_FAB2_LIB.BASEBOARD_FAB2(SCH_1):H_CPU1_CATERR_G_N   I172 @BASEBOARD_FAB2_LIB.BASEBOARD_FAB2(SCH_1):PAGE55
  AN30 PWRGD_CPU1_DRAMPWROK_GHJ_G @BASEBOARD_FAB2_LIB.BASEBOARD_FAB2(SCH_1):PWRGD_CPU1_DRAMPWROK_GHJ_G   I172 @BASEBOARD_FAB2_LIB.BASEBOARD_FAB2(SCH_1):PAGE55
  AC42 A_CPU1_GHJ_RCOMP2 @BASEBOARD_FAB2_LIB.BASEBOARD_FAB2(SCH_1):A_CPU1_GHJ_RCOMP2   I172 @BASEBOARD_FAB2_LIB.BASEBOARD_FAB2(SCH_1):PAGE55
  AB43 A_CPU1_GHJ_RCOMP1 @BASEBOARD_FAB2_LIB.BASEBOARD_FAB2(SCH_1):A_CPU1_GHJ_RCOMP1   I172 @BASEBOARD_FAB2_LIB.BASEBOARD_FAB2(SCH_1):PAGE55
   Y43 A_CPU1_GHJ_RCOMP0 @BASEBOARD_FAB2_LIB.BASEBOARD_FAB2(SCH_1):A_CPU1_GHJ_RCOMP0   I172 @BASEBOARD_FAB2_LIB.BASEBOARD_FAB2(SCH_1):PAGE55
   U64 M_GHJ_RST_N @BASEBOARD_FAB2_LIB.BASEBOARD_FAB2(SCH_1):M_GHJ_RST_N   I172 @BASEBOARD_FAB2_LIB.BASEBOARD_FAB2(SCH_1):PAGE55
  AJ18 SMB_DDR_GHJ_SCL_G_R @BASEBOARD_FAB2_LIB.BASEBOARD_FAB2(SCH_1):SMB_DDR_GHJ_SCL_G_R   I172 @BASEBOARD_FAB2_LIB.BASEBOARD_FAB2(SCH_1):PAGE55
  AF17 SMB_DDR_GHJ_SDA_G_R @BASEBOARD_FAB2_LIB.BASEBOARD_FAB2(SCH_1):SMB_DDR_GHJ_SDA_G_R   I172 @BASEBOARD_FAB2_LIB.BASEBOARD_FAB2(SCH_1):PAGE55
  AJ64 M_G_CPU_VREF @BASEBOARD_FAB2_LIB.BASEBOARD_FAB2(SCH_1):M_G_CPU_VREF   I172 @BASEBOARD_FAB2_LIB.BASEBOARD_FAB2(SCH_1):PAGE55
  AK63 M_H_CPU_VREF @BASEBOARD_FAB2_LIB.BASEBOARD_FAB2(SCH_1):M_H_CPU_VREF   I172 @BASEBOARD_FAB2_LIB.BASEBOARD_FAB2(SCH_1):PAGE55
  AH63 M_J_CPU_VREF @BASEBOARD_FAB2_LIB.BASEBOARD_FAB2(SCH_1):M_J_CPU_VREF   I172 @BASEBOARD_FAB2_LIB.BASEBOARD_FAB2(SCH_1):PAGE55
  CR28 PWRGD_CPU1_DRAMPWROK_KLM_G @BASEBOARD_FAB2_LIB.BASEBOARD_FAB2(SCH_1):PWRGD_CPU1_DRAMPWROK_KLM_G   I172 @BASEBOARD_FAB2_LIB.BASEBOARD_FAB2(SCH_1):PAGE55
  DD49 A_CPU1_KLM_RCOMP2 @BASEBOARD_FAB2_LIB.BASEBOARD_FAB2(SCH_1):A_CPU1_KLM_RCOMP2   I172 @BASEBOARD_FAB2_LIB.BASEBOARD_FAB2(SCH_1):PAGE55
  DD47 A_CPU1_KLM_RCOMP1 @BASEBOARD_FAB2_LIB.BASEBOARD_FAB2(SCH_1):A_CPU1_KLM_RCOMP1   I172 @BASEBOARD_FAB2_LIB.BASEBOARD_FAB2(SCH_1):PAGE55
  DC48 A_CPU1_KLM_RCOMP0 @BASEBOARD_FAB2_LIB.BASEBOARD_FAB2(SCH_1):A_CPU1_KLM_RCOMP0   I172 @BASEBOARD_FAB2_LIB.BASEBOARD_FAB2(SCH_1):PAGE55
  DV63 M_KLM_RST_N @BASEBOARD_FAB2_LIB.BASEBOARD_FAB2(SCH_1):M_KLM_RST_N   I172 @BASEBOARD_FAB2_LIB.BASEBOARD_FAB2(SCH_1):PAGE55
  AE18 SMB_DDR_KLM_SCL_G_R @BASEBOARD_FAB2_LIB.BASEBOARD_FAB2(SCH_1):SMB_DDR_KLM_SCL_G_R   I172 @BASEBOARD_FAB2_LIB.BASEBOARD_FAB2(SCH_1):PAGE55
  AD17 SMB_DDR_KLM_SDA_G_R @BASEBOARD_FAB2_LIB.BASEBOARD_FAB2(SCH_1):SMB_DDR_KLM_SDA_G_R   I172 @BASEBOARD_FAB2_LIB.BASEBOARD_FAB2(SCH_1):PAGE55
  CP61 M_K_CPU_VREF @BASEBOARD_FAB2_LIB.BASEBOARD_FAB2(SCH_1):M_K_CPU_VREF   I172 @BASEBOARD_FAB2_LIB.BASEBOARD_FAB2(SCH_1):PAGE55
  CT61 M_L_CPU_VREF @BASEBOARD_FAB2_LIB.BASEBOARD_FAB2(SCH_1):M_L_CPU_VREF   I172 @BASEBOARD_FAB2_LIB.BASEBOARD_FAB2(SCH_1):PAGE55
  CV61 M_M_CPU_VREF @BASEBOARD_FAB2_LIB.BASEBOARD_FAB2(SCH_1):M_M_CPU_VREF   I172 @BASEBOARD_FAB2_LIB.BASEBOARD_FAB2(SCH_1):PAGE55
  AJ14 PD_CPU1_EAR_N @BASEBOARD_FAB2_LIB.BASEBOARD_FAB2(SCH_1):PD_CPU1_EAR_N   I172 @BASEBOARD_FAB2_LIB.BASEBOARD_FAB2(SCH_1):PAGE55
  AL12 H_CPU1_ERR2_G_N @BASEBOARD_FAB2_LIB.BASEBOARD_FAB2(SCH_1):H_CPU1_ERR2_G_N   I172 @BASEBOARD_FAB2_LIB.BASEBOARD_FAB2(SCH_1):PAGE55
  AK11 H_CPU1_ERR1_G_N @BASEBOARD_FAB2_LIB.BASEBOARD_FAB2(SCH_1):H_CPU1_ERR1_G_N   I172 @BASEBOARD_FAB2_LIB.BASEBOARD_FAB2(SCH_1):PAGE55
  AJ12 H_CPU1_ERR0_G_N @BASEBOARD_FAB2_LIB.BASEBOARD_FAB2(SCH_1):H_CPU1_ERR0_G_N   I172 @BASEBOARD_FAB2_LIB.BASEBOARD_FAB2(SCH_1):PAGE55
  AV17 PU_CPU1_FRMAGENT @BASEBOARD_FAB2_LIB.BASEBOARD_FAB2(SCH_1):PU_CPU1_FRMAGENT   I172 @BASEBOARD_FAB2_LIB.BASEBOARD_FAB2(SCH_1):PAGE55
  AE20 PU_CPU1_LEGACY_SKT @BASEBOARD_FAB2_LIB.BASEBOARD_FAB2(SCH_1):PU_CPU1_LEGACY_SKT   I172 @BASEBOARD_FAB2_LIB.BASEBOARD_FAB2(SCH_1):PAGE55
  CT31 A_CPU1_MCP01_RBIAS @BASEBOARD_FAB2_LIB.BASEBOARD_FAB2(SCH_1):A_CPU1_MCP01_RBIAS   I172 @BASEBOARD_FAB2_LIB.BASEBOARD_FAB2(SCH_1):PAGE55
  CU32 A_CPU1_MCP01_RBIAS @BASEBOARD_FAB2_LIB.BASEBOARD_FAB2(SCH_1):A_CPU1_MCP01_RBIAS   I172 @BASEBOARD_FAB2_LIB.BASEBOARD_FAB2(SCH_1):PAGE55
  AH13 H_CPU1_MEMGHJ_MEMHOT_G_N @BASEBOARD_FAB2_LIB.BASEBOARD_FAB2(SCH_1):H_CPU1_MEMGHJ_MEMHOT_G_N   I172 @BASEBOARD_FAB2_LIB.BASEBOARD_FAB2(SCH_1):PAGE55
  AF13 H_CPU1_MEMKLM_MEMHOT_G_N @BASEBOARD_FAB2_LIB.BASEBOARD_FAB2(SCH_1):H_CPU1_MEMKLM_MEMHOT_G_N   I172 @BASEBOARD_FAB2_LIB.BASEBOARD_FAB2(SCH_1):PAGE55
  AN20 H_CPU1_MSMI_G_N @BASEBOARD_FAB2_LIB.BASEBOARD_FAB2(SCH_1):H_CPU1_MSMI_G_N   I172 @BASEBOARD_FAB2_LIB.BASEBOARD_FAB2(SCH_1):PAGE55
  AP11 TP_CPU1_NMI @BASEBOARD_FAB2_LIB.BASEBOARD_FAB2(SCH_1):TP_CPU1_NMI   I172 @BASEBOARD_FAB2_LIB.BASEBOARD_FAB2(SCH_1):PAGE55
  CL30 A_CPU1_PE012_RBIAS @BASEBOARD_FAB2_LIB.BASEBOARD_FAB2(SCH_1):A_CPU1_PE012_RBIAS   I172 @BASEBOARD_FAB2_LIB.BASEBOARD_FAB2(SCH_1):PAGE55
  CN30 A_CPU1_PE012_RBIAS @BASEBOARD_FAB2_LIB.BASEBOARD_FAB2(SCH_1):A_CPU1_PE012_RBIAS   I172 @BASEBOARD_FAB2_LIB.BASEBOARD_FAB2(SCH_1):PAGE55
  CR30 A_CPU1_PE3_RBIAS @BASEBOARD_FAB2_LIB.BASEBOARD_FAB2(SCH_1):A_CPU1_PE3_RBIAS   I172 @BASEBOARD_FAB2_LIB.BASEBOARD_FAB2(SCH_1):PAGE55
  CP29 A_CPU1_PE3_RBIAS @BASEBOARD_FAB2_LIB.BASEBOARD_FAB2(SCH_1):A_CPU1_PE3_RBIAS   I172 @BASEBOARD_FAB2_LIB.BASEBOARD_FAB2(SCH_1):PAGE55
  AU12 PECI_CPU_G @BASEBOARD_FAB2_LIB.BASEBOARD_FAB2(SCH_1):PECI_CPU_G   I172 @BASEBOARD_FAB2_LIB.BASEBOARD_FAB2(SCH_1):PAGE55
  AM19 SMB_CPU1_PE_HP_GTL_SCL @BASEBOARD_FAB2_LIB.BASEBOARD_FAB2(SCH_1):SMB_CPU1_PE_HP_GTL_SCL   I172 @BASEBOARD_FAB2_LIB.BASEBOARD_FAB2(SCH_1):PAGE55
  AL18 SMB_CPU1_PE_HP_GTL_SDA @BASEBOARD_FAB2_LIB.BASEBOARD_FAB2(SCH_1):SMB_CPU1_PE_HP_GTL_SDA   I172 @BASEBOARD_FAB2_LIB.BASEBOARD_FAB2(SCH_1):PAGE55
  CW56 PD_PIROM_CPU1_ADDR2 @BASEBOARD_FAB2_LIB.BASEBOARD_FAB2(SCH_1):PD_PIROM_CPU1_ADDR2   I172 @BASEBOARD_FAB2_LIB.BASEBOARD_FAB2(SCH_1):PAGE55
  CV57 PD_PIROM_CPU1_ADDR1 @BASEBOARD_FAB2_LIB.BASEBOARD_FAB2(SCH_1):PD_PIROM_CPU1_ADDR1   I172 @BASEBOARD_FAB2_LIB.BASEBOARD_FAB2(SCH_1):PAGE55
  CU58 PU_PIROM_CPU1_ADDR0 @BASEBOARD_FAB2_LIB.BASEBOARD_FAB2(SCH_1):PU_PIROM_CPU1_ADDR0   I172 @BASEBOARD_FAB2_LIB.BASEBOARD_FAB2(SCH_1):PAGE55
  DA72 FM_CPU1_PKGID2 @BASEBOARD_FAB2_LIB.BASEBOARD_FAB2(SCH_1):FM_CPU1_PKGID2   I172 @BASEBOARD_FAB2_LIB.BASEBOARD_FAB2(SCH_1):PAGE55
  CW72 FM_CPU1_PKGID1 @BASEBOARD_FAB2_LIB.BASEBOARD_FAB2(SCH_1):FM_CPU1_PKGID1   I172 @BASEBOARD_FAB2_LIB.BASEBOARD_FAB2(SCH_1):PAGE55
  DC72 FM_CPU1_PKGID0 @BASEBOARD_FAB2_LIB.BASEBOARD_FAB2(SCH_1):FM_CPU1_PKGID0   I172 @BASEBOARD_FAB2_LIB.BASEBOARD_FAB2(SCH_1):PAGE55
  AR14 H_PM_SYNC_GTL_R2 @BASEBOARD_FAB2_LIB.BASEBOARD_FAB2(SCH_1):H_PM_SYNC_GTL_R2   I172 @BASEBOARD_FAB2_LIB.BASEBOARD_FAB2(SCH_1):PAGE55
  AT19 H_PMSYNC_CLK_24M_CPU1 @BASEBOARD_FAB2_LIB.BASEBOARD_FAB2(SCH_1):H_PMSYNC_CLK_24M_CPU1   I172 @BASEBOARD_FAB2_LIB.BASEBOARD_FAB2(SCH_1):PAGE55
  AF15 H_CPU1_FAST_WAKE_N @BASEBOARD_FAB2_LIB.BASEBOARD_FAB2(SCH_1):H_CPU1_FAST_WAKE_N   I172 @BASEBOARD_FAB2_LIB.BASEBOARD_FAB2(SCH_1):PAGE55
  AG16 XDP_CPU_PRDY_N @BASEBOARD_FAB2_LIB.BASEBOARD_FAB2(SCH_1):XDP_CPU_PRDY_N   I172 @BASEBOARD_FAB2_LIB.BASEBOARD_FAB2(SCH_1):PAGE55
  AR12 XDP_CPU_PREQ_N @BASEBOARD_FAB2_LIB.BASEBOARD_FAB2(SCH_1):XDP_CPU_PREQ_N   I172 @BASEBOARD_FAB2_LIB.BASEBOARD_FAB2(SCH_1):PAGE55
  AB17 TP_CPU1_PROC_DIS_G_N @BASEBOARD_FAB2_LIB.BASEBOARD_FAB2(SCH_1):TP_CPU1_PROC_DIS_G_N   I172 @BASEBOARD_FAB2_LIB.BASEBOARD_FAB2(SCH_1):PAGE55
  AC16 H_CPU1_PROCHOT_G_N @BASEBOARD_FAB2_LIB.BASEBOARD_FAB2(SCH_1):H_CPU1_PROCHOT_G_N   I172 @BASEBOARD_FAB2_LIB.BASEBOARD_FAB2(SCH_1):PAGE55
  DB71 FM_CPU1_PROC_ID1 @BASEBOARD_FAB2_LIB.BASEBOARD_FAB2(SCH_1):FM_CPU1_PROC_ID1   I172 @BASEBOARD_FAB2_LIB.BASEBOARD_FAB2(SCH_1):PAGE55
  CY71 FM_CPU1_PROC_ID0 @BASEBOARD_FAB2_LIB.BASEBOARD_FAB2(SCH_1):FM_CPU1_PROC_ID0   I172 @BASEBOARD_FAB2_LIB.BASEBOARD_FAB2(SCH_1):PAGE55
  BC24 PWRGD_CPU1_G @BASEBOARD_FAB2_LIB.BASEBOARD_FAB2(SCH_1):PWRGD_CPU1_G   I172 @BASEBOARD_FAB2_LIB.BASEBOARD_FAB2(SCH_1):PAGE55
  AP21 RST_CPU1_G_N @BASEBOARD_FAB2_LIB.BASEBOARD_FAB2(SCH_1):RST_CPU1_G_N   I172 @BASEBOARD_FAB2_LIB.BASEBOARD_FAB2(SCH_1):PAGE55
  AR18 PU_CPU1_SAFE_MODE_BOOT @BASEBOARD_FAB2_LIB.BASEBOARD_FAB2(SCH_1):PU_CPU1_SAFE_MODE_BOOT   I172 @BASEBOARD_FAB2_LIB.BASEBOARD_FAB2(SCH_1):PAGE55
  AB13 FM_CPU1_SKTOCC_LVT3_N @BASEBOARD_FAB2_LIB.BASEBOARD_FAB2(SCH_1):FM_CPU1_SKTOCC_LVT3_N   I172 @BASEBOARD_FAB2_LIB.BASEBOARD_FAB2(SCH_1):PAGE55
  CT59 SMB_PIROM_CPU1_SCL @BASEBOARD_FAB2_LIB.BASEBOARD_FAB2(SCH_1):SMB_PIROM_CPU1_SCL   I172 @BASEBOARD_FAB2_LIB.BASEBOARD_FAB2(SCH_1):PAGE55
  CW58 SMB_PIROM_CPU1_SDA @BASEBOARD_FAB2_LIB.BASEBOARD_FAB2(SCH_1):SMB_PIROM_CPU1_SDA   I172 @BASEBOARD_FAB2_LIB.BASEBOARD_FAB2(SCH_1):PAGE55
  CV59 FM_CPU1_SM_WP @BASEBOARD_FAB2_LIB.BASEBOARD_FAB2(SCH_1):FM_CPU1_SM_WP   I172 @BASEBOARD_FAB2_LIB.BASEBOARD_FAB2(SCH_1):PAGE55
  AU20 TP_CPU1_SOCKET_ID_2 @BASEBOARD_FAB2_LIB.BASEBOARD_FAB2(SCH_1):TP_CPU1_SOCKET_ID_2   I172 @BASEBOARD_FAB2_LIB.BASEBOARD_FAB2(SCH_1):PAGE55
  AU16 PU_CPU1_SOCKET_ID_1 @BASEBOARD_FAB2_LIB.BASEBOARD_FAB2(SCH_1):PU_CPU1_SOCKET_ID_1   I172 @BASEBOARD_FAB2_LIB.BASEBOARD_FAB2(SCH_1):PAGE55
  AU22 PU_CPU1_SOCKET_ID_0 @BASEBOARD_FAB2_LIB.BASEBOARD_FAB2(SCH_1):PU_CPU1_SOCKET_ID_0   I172 @BASEBOARD_FAB2_LIB.BASEBOARD_FAB2(SCH_1):PAGE55
  DL44 SVID_ALERT1_CPU1_N @BASEBOARD_FAB2_LIB.BASEBOARD_FAB2(SCH_1):SVID_ALERT1_CPU1_N   I172 @BASEBOARD_FAB2_LIB.BASEBOARD_FAB2(SCH_1):PAGE55
  DE44 SVID_ALERT0_CPU1_N @BASEBOARD_FAB2_LIB.BASEBOARD_FAB2(SCH_1):SVID_ALERT0_CPU1_N   I172 @BASEBOARD_FAB2_LIB.BASEBOARD_FAB2(SCH_1):PAGE55
  DG44 SVID_CLK1_CPU1 @BASEBOARD_FAB2_LIB.BASEBOARD_FAB2(SCH_1):SVID_CLK1_CPU1   I172 @BASEBOARD_FAB2_LIB.BASEBOARD_FAB2(SCH_1):PAGE55
  DC44 SVID_CLK0_CPU1 @BASEBOARD_FAB2_LIB.BASEBOARD_FAB2(SCH_1):SVID_CLK0_CPU1   I172 @BASEBOARD_FAB2_LIB.BASEBOARD_FAB2(SCH_1):PAGE55
  DJ44 SVID_DIO1_CPU1 @BASEBOARD_FAB2_LIB.BASEBOARD_FAB2(SCH_1):SVID_DIO1_CPU1   I172 @BASEBOARD_FAB2_LIB.BASEBOARD_FAB2(SCH_1):PAGE55
  DB45 SVID_DIO0_CPU1 @BASEBOARD_FAB2_LIB.BASEBOARD_FAB2(SCH_1):SVID_DIO0_CPU1   I172 @BASEBOARD_FAB2_LIB.BASEBOARD_FAB2(SCH_1):PAGE55
  AA14 XDP_CPU_TCK0 @BASEBOARD_FAB2_LIB.BASEBOARD_FAB2(SCH_1):XDP_CPU_TCK0   I172 @BASEBOARD_FAB2_LIB.BASEBOARD_FAB2(SCH_1):PAGE55
  AC14 XDP_CPU1_TDI @BASEBOARD_FAB2_LIB.BASEBOARD_FAB2(SCH_1):XDP_CPU1_TDI   I172 @BASEBOARD_FAB2_LIB.BASEBOARD_FAB2(SCH_1):PAGE55
  AE14 XDP_CPU1_TDO @BASEBOARD_FAB2_LIB.BASEBOARD_FAB2(SCH_1):XDP_CPU1_TDO   I172 @BASEBOARD_FAB2_LIB.BASEBOARD_FAB2(SCH_1):PAGE55
  AY19 PD_CPU1_TEST12 @BASEBOARD_FAB2_LIB.BASEBOARD_FAB2(SCH_1):PD_CPU1_TEST12   I172 @BASEBOARD_FAB2_LIB.BASEBOARD_FAB2(SCH_1):PAGE55
  DB51 PD_CPU1_TEST13 @BASEBOARD_FAB2_LIB.BASEBOARD_FAB2(SCH_1):PD_CPU1_TEST13   I172 @BASEBOARD_FAB2_LIB.BASEBOARD_FAB2(SCH_1):PAGE55
  DC50 PD_CPU1_TEST14 @BASEBOARD_FAB2_LIB.BASEBOARD_FAB2(SCH_1):PD_CPU1_TEST14   I172 @BASEBOARD_FAB2_LIB.BASEBOARD_FAB2(SCH_1):PAGE55
  AW14 PD_CPU1_KSFC_DIS @BASEBOARD_FAB2_LIB.BASEBOARD_FAB2(SCH_1):PD_CPU1_KSFC_DIS   I172 @BASEBOARD_FAB2_LIB.BASEBOARD_FAB2(SCH_1):PAGE55
  AB15 H_CPU1_THERMTRIP_G_N @BASEBOARD_FAB2_LIB.BASEBOARD_FAB2(SCH_1):H_CPU1_THERMTRIP_G_N   I172 @BASEBOARD_FAB2_LIB.BASEBOARD_FAB2(SCH_1):PAGE55
   W14 XDP_CPU_TMS @BASEBOARD_FAB2_LIB.BASEBOARD_FAB2(SCH_1):XDP_CPU_TMS   I172 @BASEBOARD_FAB2_LIB.BASEBOARD_FAB2(SCH_1):PAGE55
   Y13 XDP_CPU_TRST_N @BASEBOARD_FAB2_LIB.BASEBOARD_FAB2(SCH_1):XDP_CPU_TRST_N   I172 @BASEBOARD_FAB2_LIB.BASEBOARD_FAB2(SCH_1):PAGE55
  AM11 PU_CPU1_TSC_SYNC @BASEBOARD_FAB2_LIB.BASEBOARD_FAB2(SCH_1):PU_CPU1_TSC_SYNC   I172 @BASEBOARD_FAB2_LIB.BASEBOARD_FAB2(SCH_1):PAGE55
  AW18 PU_CPU1_TXT_AGENT @BASEBOARD_FAB2_LIB.BASEBOARD_FAB2(SCH_1):PU_CPU1_TXT_AGENT   I172 @BASEBOARD_FAB2_LIB.BASEBOARD_FAB2(SCH_1):PAGE55
  AV15 PD_CPU1_TXT_PLTEN @BASEBOARD_FAB2_LIB.BASEBOARD_FAB2(SCH_1):PD_CPU1_TXT_PLTEN   I172 @BASEBOARD_FAB2_LIB.BASEBOARD_FAB2(SCH_1):PAGE55
  AP29 A_CPU1_UPI01_RBIAS @BASEBOARD_FAB2_LIB.BASEBOARD_FAB2(SCH_1):A_CPU1_UPI01_RBIAS   I172 @BASEBOARD_FAB2_LIB.BASEBOARD_FAB2(SCH_1):PAGE55
  AT29 A_CPU1_UPI01_RBIAS @BASEBOARD_FAB2_LIB.BASEBOARD_FAB2(SCH_1):A_CPU1_UPI01_RBIAS   I172 @BASEBOARD_FAB2_LIB.BASEBOARD_FAB2(SCH_1):PAGE55
  CK29 A_CPU1_UPI2_RBIAS @BASEBOARD_FAB2_LIB.BASEBOARD_FAB2(SCH_1):A_CPU1_UPI2_RBIAS   I172 @BASEBOARD_FAB2_LIB.BASEBOARD_FAB2(SCH_1):PAGE55
  CL28 A_CPU1_UPI2_RBIAS @BASEBOARD_FAB2_LIB.BASEBOARD_FAB2(SCH_1):A_CPU1_UPI2_RBIAS   I172 @BASEBOARD_FAB2_LIB.BASEBOARD_FAB2(SCH_1):PAGE55
  AV21 CPU_XDP_PRESENT_N @BASEBOARD_FAB2_LIB.BASEBOARD_FAB2(SCH_1):CPU_XDP_PRESENT_N   I169 @BASEBOARD_FAB2_LIB.BASEBOARD_FAB2(SCH_1):PAGE56
  AW12 PD_CPU1_DMIMODE_OVERRIDE @BASEBOARD_FAB2_LIB.BASEBOARD_FAB2(SCH_1):PD_CPU1_DMIMODE_OVERRIDE   I169 @BASEBOARD_FAB2_LIB.BASEBOARD_FAB2(SCH_1):PAGE56
  AU14 H_CPU1_FIVR_FAULT_G @BASEBOARD_FAB2_LIB.BASEBOARD_FAB2(SCH_1):H_CPU1_FIVR_FAULT_G   I169 @BASEBOARD_FAB2_LIB.BASEBOARD_FAB2(SCH_1):PAGE56
  AP17 XDP_CPU_PWR_DEBUG_N @BASEBOARD_FAB2_LIB.BASEBOARD_FAB2(SCH_1):XDP_CPU_PWR_DEBUG_N   I169 @BASEBOARD_FAB2_LIB.BASEBOARD_FAB2(SCH_1):PAGE56
    A4 TP_CPU1_RSVD_304 @BASEBOARD_FAB2_LIB.BASEBOARD_FAB2(SCH_1):TP_CPU1_RSVD_304   I169 @BASEBOARD_FAB2_LIB.BASEBOARD_FAB2(SCH_1):PAGE56
    A6 TP_CPU1_RSVD_303 @BASEBOARD_FAB2_LIB.BASEBOARD_FAB2(SCH_1):TP_CPU1_RSVD_303   I169 @BASEBOARD_FAB2_LIB.BASEBOARD_FAB2(SCH_1):PAGE56
   A14 P1V8_MCP_CPU1 @BASEBOARD_FAB2_LIB.BASEBOARD_FAB2(SCH_1):P1V8_MCP_CPU1   I169 @BASEBOARD_FAB2_LIB.BASEBOARD_FAB2(SCH_1):PAGE56
   A16 P1V8_MCP_CPU1 @BASEBOARD_FAB2_LIB.BASEBOARD_FAB2(SCH_1):P1V8_MCP_CPU1   I169 @BASEBOARD_FAB2_LIB.BASEBOARD_FAB2(SCH_1):PAGE56
   A24 TP_CPU1_RSVD_300 @BASEBOARD_FAB2_LIB.BASEBOARD_FAB2(SCH_1):TP_CPU1_RSVD_300   I169 @BASEBOARD_FAB2_LIB.BASEBOARD_FAB2(SCH_1):PAGE56
    B3 TP_CPU1_RSVD_299 @BASEBOARD_FAB2_LIB.BASEBOARD_FAB2(SCH_1):TP_CPU1_RSVD_299   I169 @BASEBOARD_FAB2_LIB.BASEBOARD_FAB2(SCH_1):PAGE56
    B7 TP_CPU1_RSVD_298 @BASEBOARD_FAB2_LIB.BASEBOARD_FAB2(SCH_1):TP_CPU1_RSVD_298   I169 @BASEBOARD_FAB2_LIB.BASEBOARD_FAB2(SCH_1):PAGE56
   B13 P1V8_MCP_CPU1 @BASEBOARD_FAB2_LIB.BASEBOARD_FAB2(SCH_1):P1V8_MCP_CPU1   I169 @BASEBOARD_FAB2_LIB.BASEBOARD_FAB2(SCH_1):PAGE56
   B15 P1V8_MCP_CPU1 @BASEBOARD_FAB2_LIB.BASEBOARD_FAB2(SCH_1):P1V8_MCP_CPU1   I169 @BASEBOARD_FAB2_LIB.BASEBOARD_FAB2(SCH_1):PAGE56
   B17 P1V8_MCP_CPU1 @BASEBOARD_FAB2_LIB.BASEBOARD_FAB2(SCH_1):P1V8_MCP_CPU1   I169 @BASEBOARD_FAB2_LIB.BASEBOARD_FAB2(SCH_1):PAGE56
   B77 TP_CPU1_RSVD_293 @BASEBOARD_FAB2_LIB.BASEBOARD_FAB2(SCH_1):TP_CPU1_RSVD_293   I169 @BASEBOARD_FAB2_LIB.BASEBOARD_FAB2(SCH_1):PAGE56
   B81 TP_CPU1_RSVD_292 @BASEBOARD_FAB2_LIB.BASEBOARD_FAB2(SCH_1):TP_CPU1_RSVD_292   I169 @BASEBOARD_FAB2_LIB.BASEBOARD_FAB2(SCH_1):PAGE56
    C6 TP_CPU1_RSVD_291 @BASEBOARD_FAB2_LIB.BASEBOARD_FAB2(SCH_1):TP_CPU1_RSVD_291   I169 @BASEBOARD_FAB2_LIB.BASEBOARD_FAB2(SCH_1):PAGE56
   C18 TP_CPU1_RSVD_290 @BASEBOARD_FAB2_LIB.BASEBOARD_FAB2(SCH_1):TP_CPU1_RSVD_290   I169 @BASEBOARD_FAB2_LIB.BASEBOARD_FAB2(SCH_1):PAGE56
   C24 TP_CPU1_RSVD_289 @BASEBOARD_FAB2_LIB.BASEBOARD_FAB2(SCH_1):TP_CPU1_RSVD_289   I169 @BASEBOARD_FAB2_LIB.BASEBOARD_FAB2(SCH_1):PAGE56
   C82 TP_CPU1_RSVD_288 @BASEBOARD_FAB2_LIB.BASEBOARD_FAB2(SCH_1):TP_CPU1_RSVD_288   I169 @BASEBOARD_FAB2_LIB.BASEBOARD_FAB2(SCH_1):PAGE56
    D5 TP_CPU1_RSVD_287 @BASEBOARD_FAB2_LIB.BASEBOARD_FAB2(SCH_1):TP_CPU1_RSVD_287   I169 @BASEBOARD_FAB2_LIB.BASEBOARD_FAB2(SCH_1):PAGE56
   D17 TP_CPU1_RSVD_286 @BASEBOARD_FAB2_LIB.BASEBOARD_FAB2(SCH_1):TP_CPU1_RSVD_286   I169 @BASEBOARD_FAB2_LIB.BASEBOARD_FAB2(SCH_1):PAGE56
   D65 TP_CPU1_RSVD_285 @BASEBOARD_FAB2_LIB.BASEBOARD_FAB2(SCH_1):TP_CPU1_RSVD_285   I169 @BASEBOARD_FAB2_LIB.BASEBOARD_FAB2(SCH_1):PAGE56
   D83 TP_CPU1_RSVD_284 @BASEBOARD_FAB2_LIB.BASEBOARD_FAB2(SCH_1):TP_CPU1_RSVD_284   I169 @BASEBOARD_FAB2_LIB.BASEBOARD_FAB2(SCH_1):PAGE56
    E2 TP_CPU1_RSVD_283 @BASEBOARD_FAB2_LIB.BASEBOARD_FAB2(SCH_1):TP_CPU1_RSVD_283   I169 @BASEBOARD_FAB2_LIB.BASEBOARD_FAB2(SCH_1):PAGE56
    E4 TP_CPU1_RSVD_282 @BASEBOARD_FAB2_LIB.BASEBOARD_FAB2(SCH_1):TP_CPU1_RSVD_282   I169 @BASEBOARD_FAB2_LIB.BASEBOARD_FAB2(SCH_1):PAGE56
   E24 TP_CPU1_RSVD_281 @BASEBOARD_FAB2_LIB.BASEBOARD_FAB2(SCH_1):TP_CPU1_RSVD_281   I169 @BASEBOARD_FAB2_LIB.BASEBOARD_FAB2(SCH_1):PAGE56
   E84 TP_CPU1_RSVD_280 @BASEBOARD_FAB2_LIB.BASEBOARD_FAB2(SCH_1):TP_CPU1_RSVD_280   I169 @BASEBOARD_FAB2_LIB.BASEBOARD_FAB2(SCH_1):PAGE56
    F3 TP_CPU1_RSVD_279 @BASEBOARD_FAB2_LIB.BASEBOARD_FAB2(SCH_1):TP_CPU1_RSVD_279   I169 @BASEBOARD_FAB2_LIB.BASEBOARD_FAB2(SCH_1):PAGE56
   F23 TP_CPU1_RSVD_278 @BASEBOARD_FAB2_LIB.BASEBOARD_FAB2(SCH_1):TP_CPU1_RSVD_278   I169 @BASEBOARD_FAB2_LIB.BASEBOARD_FAB2(SCH_1):PAGE56
   F65 TP_CPU1_RSVD_277 @BASEBOARD_FAB2_LIB.BASEBOARD_FAB2(SCH_1):TP_CPU1_RSVD_277   I169 @BASEBOARD_FAB2_LIB.BASEBOARD_FAB2(SCH_1):PAGE56
   F83 TP_CPU1_RSVD_276 @BASEBOARD_FAB2_LIB.BASEBOARD_FAB2(SCH_1):TP_CPU1_RSVD_276   I169 @BASEBOARD_FAB2_LIB.BASEBOARD_FAB2(SCH_1):PAGE56
    G2 TP_CPU1_RSVD_275 @BASEBOARD_FAB2_LIB.BASEBOARD_FAB2(SCH_1):TP_CPU1_RSVD_275   I169 @BASEBOARD_FAB2_LIB.BASEBOARD_FAB2(SCH_1):PAGE56
   G64 TP_CPU1_RSVD_274 @BASEBOARD_FAB2_LIB.BASEBOARD_FAB2(SCH_1):TP_CPU1_RSVD_274   I169 @BASEBOARD_FAB2_LIB.BASEBOARD_FAB2(SCH_1):PAGE56
   G84 TP_CPU1_RSVD_273 @BASEBOARD_FAB2_LIB.BASEBOARD_FAB2(SCH_1):TP_CPU1_RSVD_273   I169 @BASEBOARD_FAB2_LIB.BASEBOARD_FAB2(SCH_1):PAGE56
    H1 TP_CPU1_RSVD_272 @BASEBOARD_FAB2_LIB.BASEBOARD_FAB2(SCH_1):TP_CPU1_RSVD_272   I169 @BASEBOARD_FAB2_LIB.BASEBOARD_FAB2(SCH_1):PAGE56
   H83 TP_CPU1_RSVD_271 @BASEBOARD_FAB2_LIB.BASEBOARD_FAB2(SCH_1):TP_CPU1_RSVD_271   I169 @BASEBOARD_FAB2_LIB.BASEBOARD_FAB2(SCH_1):PAGE56
   H85 TP_CPU1_RSVD_270 @BASEBOARD_FAB2_LIB.BASEBOARD_FAB2(SCH_1):TP_CPU1_RSVD_270   I169 @BASEBOARD_FAB2_LIB.BASEBOARD_FAB2(SCH_1):PAGE56
   J46 TP_CPU1_RSVD_269 @BASEBOARD_FAB2_LIB.BASEBOARD_FAB2(SCH_1):TP_CPU1_RSVD_269   I169 @BASEBOARD_FAB2_LIB.BASEBOARD_FAB2(SCH_1):PAGE56
   J62 TP_CPU1_RSVD_268 @BASEBOARD_FAB2_LIB.BASEBOARD_FAB2(SCH_1):TP_CPU1_RSVD_268   I169 @BASEBOARD_FAB2_LIB.BASEBOARD_FAB2(SCH_1):PAGE56
   K61 TP_CPU1_RSVD_267 @BASEBOARD_FAB2_LIB.BASEBOARD_FAB2(SCH_1):TP_CPU1_RSVD_267   I169 @BASEBOARD_FAB2_LIB.BASEBOARD_FAB2(SCH_1):PAGE56
   M63 TP_CPU1_RSVD_266 @BASEBOARD_FAB2_LIB.BASEBOARD_FAB2(SCH_1):TP_CPU1_RSVD_266   I169 @BASEBOARD_FAB2_LIB.BASEBOARD_FAB2(SCH_1):PAGE56
   P65 TP_CPU1_RSVD_265 @BASEBOARD_FAB2_LIB.BASEBOARD_FAB2(SCH_1):TP_CPU1_RSVD_265   I169 @BASEBOARD_FAB2_LIB.BASEBOARD_FAB2(SCH_1):PAGE56
   R62 TP_CPU1_RSVD_264 @BASEBOARD_FAB2_LIB.BASEBOARD_FAB2(SCH_1):TP_CPU1_RSVD_264   I169 @BASEBOARD_FAB2_LIB.BASEBOARD_FAB2(SCH_1):PAGE56
   R66 TP_CPU1_RSVD_263 @BASEBOARD_FAB2_LIB.BASEBOARD_FAB2(SCH_1):TP_CPU1_RSVD_263   I169 @BASEBOARD_FAB2_LIB.BASEBOARD_FAB2(SCH_1):PAGE56
   T67 TP_CPU1_RSVD_262 @BASEBOARD_FAB2_LIB.BASEBOARD_FAB2(SCH_1):TP_CPU1_RSVD_262   I169 @BASEBOARD_FAB2_LIB.BASEBOARD_FAB2(SCH_1):PAGE56
   U66 TP_CPU1_RSVD_261 @BASEBOARD_FAB2_LIB.BASEBOARD_FAB2(SCH_1):TP_CPU1_RSVD_261   I169 @BASEBOARD_FAB2_LIB.BASEBOARD_FAB2(SCH_1):PAGE56
   V65 TP_CPU1_RSVD_260 @BASEBOARD_FAB2_LIB.BASEBOARD_FAB2(SCH_1):TP_CPU1_RSVD_260   I169 @BASEBOARD_FAB2_LIB.BASEBOARD_FAB2(SCH_1):PAGE56
   V67 TP_CPU1_RSVD_259 @BASEBOARD_FAB2_LIB.BASEBOARD_FAB2(SCH_1):TP_CPU1_RSVD_259   I169 @BASEBOARD_FAB2_LIB.BASEBOARD_FAB2(SCH_1):PAGE56
   W66 TP_CPU1_RSVD_258 @BASEBOARD_FAB2_LIB.BASEBOARD_FAB2(SCH_1):TP_CPU1_RSVD_258   I169 @BASEBOARD_FAB2_LIB.BASEBOARD_FAB2(SCH_1):PAGE56
   Y23 FM_CPU1_RC_ERROR_N @BASEBOARD_FAB2_LIB.BASEBOARD_FAB2(SCH_1):FM_CPU1_RC_ERROR_N   I169 @BASEBOARD_FAB2_LIB.BASEBOARD_FAB2(SCH_1):PAGE56
   Y65 TP_CPU1_RSVD_256 @BASEBOARD_FAB2_LIB.BASEBOARD_FAB2(SCH_1):TP_CPU1_RSVD_256   I169 @BASEBOARD_FAB2_LIB.BASEBOARD_FAB2(SCH_1):PAGE56
  AD47 TP_CPU1_RSVD_254 @BASEBOARD_FAB2_LIB.BASEBOARD_FAB2(SCH_1):TP_CPU1_RSVD_254   I169 @BASEBOARD_FAB2_LIB.BASEBOARD_FAB2(SCH_1):PAGE56
  AD49 TP_CPU1_RSVD_253 @BASEBOARD_FAB2_LIB.BASEBOARD_FAB2(SCH_1):TP_CPU1_RSVD_253   I169 @BASEBOARD_FAB2_LIB.BASEBOARD_FAB2(SCH_1):PAGE56
  AD51 TP_CPU1_RSVD_252 @BASEBOARD_FAB2_LIB.BASEBOARD_FAB2(SCH_1):TP_CPU1_RSVD_252   I169 @BASEBOARD_FAB2_LIB.BASEBOARD_FAB2(SCH_1):PAGE56
  AE46 TP_CPU1_RSVD_251 @BASEBOARD_FAB2_LIB.BASEBOARD_FAB2(SCH_1):TP_CPU1_RSVD_251   I169 @BASEBOARD_FAB2_LIB.BASEBOARD_FAB2(SCH_1):PAGE56
  AE48 TP_CPU1_RSVD_250 @BASEBOARD_FAB2_LIB.BASEBOARD_FAB2(SCH_1):TP_CPU1_RSVD_250   I169 @BASEBOARD_FAB2_LIB.BASEBOARD_FAB2(SCH_1):PAGE56
  AE50 TP_CPU1_RSVD_249 @BASEBOARD_FAB2_LIB.BASEBOARD_FAB2(SCH_1):TP_CPU1_RSVD_249   I169 @BASEBOARD_FAB2_LIB.BASEBOARD_FAB2(SCH_1):PAGE56
  AE52 TP_CPU1_RSVD_248 @BASEBOARD_FAB2_LIB.BASEBOARD_FAB2(SCH_1):TP_CPU1_RSVD_248   I169 @BASEBOARD_FAB2_LIB.BASEBOARD_FAB2(SCH_1):PAGE56
  AE72 TP_CPU1_RSVD_247 @BASEBOARD_FAB2_LIB.BASEBOARD_FAB2(SCH_1):TP_CPU1_RSVD_247   I169 @BASEBOARD_FAB2_LIB.BASEBOARD_FAB2(SCH_1):PAGE56
  AF19 TP_CPU1_RSVD_246 @BASEBOARD_FAB2_LIB.BASEBOARD_FAB2(SCH_1):TP_CPU1_RSVD_246   I169 @BASEBOARD_FAB2_LIB.BASEBOARD_FAB2(SCH_1):PAGE56
  AF47 TP_CPU1_RSVD_245 @BASEBOARD_FAB2_LIB.BASEBOARD_FAB2(SCH_1):TP_CPU1_RSVD_245   I169 @BASEBOARD_FAB2_LIB.BASEBOARD_FAB2(SCH_1):PAGE56
  AF49 TP_CPU1_RSVD_244 @BASEBOARD_FAB2_LIB.BASEBOARD_FAB2(SCH_1):TP_CPU1_RSVD_244   I169 @BASEBOARD_FAB2_LIB.BASEBOARD_FAB2(SCH_1):PAGE56
  AF51 TP_CPU1_RSVD_243 @BASEBOARD_FAB2_LIB.BASEBOARD_FAB2(SCH_1):TP_CPU1_RSVD_243   I169 @BASEBOARD_FAB2_LIB.BASEBOARD_FAB2(SCH_1):PAGE56
  AF53 TP_CPU1_RSVD_242 @BASEBOARD_FAB2_LIB.BASEBOARD_FAB2(SCH_1):TP_CPU1_RSVD_242   I169 @BASEBOARD_FAB2_LIB.BASEBOARD_FAB2(SCH_1):PAGE56
  AF71 TP_CPU1_RSVD_241 @BASEBOARD_FAB2_LIB.BASEBOARD_FAB2(SCH_1):TP_CPU1_RSVD_241   I169 @BASEBOARD_FAB2_LIB.BASEBOARD_FAB2(SCH_1):PAGE56
  AG20 TP_CPU1_RSVD_240 @BASEBOARD_FAB2_LIB.BASEBOARD_FAB2(SCH_1):TP_CPU1_RSVD_240   I169 @BASEBOARD_FAB2_LIB.BASEBOARD_FAB2(SCH_1):PAGE56
  AG48 TP_CPU1_RSVD_239 @BASEBOARD_FAB2_LIB.BASEBOARD_FAB2(SCH_1):TP_CPU1_RSVD_239   I169 @BASEBOARD_FAB2_LIB.BASEBOARD_FAB2(SCH_1):PAGE56
  AG50 TP_CPU1_RSVD_238 @BASEBOARD_FAB2_LIB.BASEBOARD_FAB2(SCH_1):TP_CPU1_RSVD_238   I169 @BASEBOARD_FAB2_LIB.BASEBOARD_FAB2(SCH_1):PAGE56
  AG52 TP_CPU1_RSVD_237 @BASEBOARD_FAB2_LIB.BASEBOARD_FAB2(SCH_1):TP_CPU1_RSVD_237   I169 @BASEBOARD_FAB2_LIB.BASEBOARD_FAB2(SCH_1):PAGE56
  AG54 TP_CPU1_RSVD_236 @BASEBOARD_FAB2_LIB.BASEBOARD_FAB2(SCH_1):TP_CPU1_RSVD_236   I169 @BASEBOARD_FAB2_LIB.BASEBOARD_FAB2(SCH_1):PAGE56
  AG56 TP_CPU1_RSVD_235 @BASEBOARD_FAB2_LIB.BASEBOARD_FAB2(SCH_1):TP_CPU1_RSVD_235   I169 @BASEBOARD_FAB2_LIB.BASEBOARD_FAB2(SCH_1):PAGE56
  AG72 TP_CPU1_RSVD_234 @BASEBOARD_FAB2_LIB.BASEBOARD_FAB2(SCH_1):TP_CPU1_RSVD_234   I169 @BASEBOARD_FAB2_LIB.BASEBOARD_FAB2(SCH_1):PAGE56
  AH15 TP_CPU1_RSVD_233 @BASEBOARD_FAB2_LIB.BASEBOARD_FAB2(SCH_1):TP_CPU1_RSVD_233   I169 @BASEBOARD_FAB2_LIB.BASEBOARD_FAB2(SCH_1):PAGE56
  AH19 TP_CPU1_RSVD_232 @BASEBOARD_FAB2_LIB.BASEBOARD_FAB2(SCH_1):TP_CPU1_RSVD_232   I169 @BASEBOARD_FAB2_LIB.BASEBOARD_FAB2(SCH_1):PAGE56
  AH55 TP_CPU1_RSVD_231 @BASEBOARD_FAB2_LIB.BASEBOARD_FAB2(SCH_1):TP_CPU1_RSVD_231   I169 @BASEBOARD_FAB2_LIB.BASEBOARD_FAB2(SCH_1):PAGE56
  AH57 TP_CPU1_RSVD_230 @BASEBOARD_FAB2_LIB.BASEBOARD_FAB2(SCH_1):TP_CPU1_RSVD_230   I169 @BASEBOARD_FAB2_LIB.BASEBOARD_FAB2(SCH_1):PAGE56
  AH71 TP_CPU1_RSVD_229 @BASEBOARD_FAB2_LIB.BASEBOARD_FAB2(SCH_1):TP_CPU1_RSVD_229   I169 @BASEBOARD_FAB2_LIB.BASEBOARD_FAB2(SCH_1):PAGE56
  AH73 TP_CPU1_RSVD_228 @BASEBOARD_FAB2_LIB.BASEBOARD_FAB2(SCH_1):TP_CPU1_RSVD_228   I169 @BASEBOARD_FAB2_LIB.BASEBOARD_FAB2(SCH_1):PAGE56
  AJ20 TP_CPU1_RSVD_227 @BASEBOARD_FAB2_LIB.BASEBOARD_FAB2(SCH_1):TP_CPU1_RSVD_227   I169 @BASEBOARD_FAB2_LIB.BASEBOARD_FAB2(SCH_1):PAGE56
  AJ56 TP_CPU1_RSVD_226 @BASEBOARD_FAB2_LIB.BASEBOARD_FAB2(SCH_1):TP_CPU1_RSVD_226   I169 @BASEBOARD_FAB2_LIB.BASEBOARD_FAB2(SCH_1):PAGE56
  AJ58 TP_CPU1_RSVD_225 @BASEBOARD_FAB2_LIB.BASEBOARD_FAB2(SCH_1):TP_CPU1_RSVD_225   I169 @BASEBOARD_FAB2_LIB.BASEBOARD_FAB2(SCH_1):PAGE56
  AJ60 TP_CPU1_RSVD_224 @BASEBOARD_FAB2_LIB.BASEBOARD_FAB2(SCH_1):TP_CPU1_RSVD_224   I169 @BASEBOARD_FAB2_LIB.BASEBOARD_FAB2(SCH_1):PAGE56
  AJ62 TP_CPU1_RSVD_223 @BASEBOARD_FAB2_LIB.BASEBOARD_FAB2(SCH_1):TP_CPU1_RSVD_223   I169 @BASEBOARD_FAB2_LIB.BASEBOARD_FAB2(SCH_1):PAGE56
  AJ70 TP_CPU1_RSVD_222 @BASEBOARD_FAB2_LIB.BASEBOARD_FAB2(SCH_1):TP_CPU1_RSVD_222   I169 @BASEBOARD_FAB2_LIB.BASEBOARD_FAB2(SCH_1):PAGE56
  AK21 VSENSE_P1V8MCP_CPU1_SKT_VSEN @BASEBOARD_FAB2_LIB.BASEBOARD_FAB2(SCH_1):VSENSE_P1V8MCP_CPU1_SKT_VSEN   I169 @BASEBOARD_FAB2_LIB.BASEBOARD_FAB2(SCH_1):PAGE56
  AK27 CLK_322M_OSC_CPU1_RC_DP @BASEBOARD_FAB2_LIB.BASEBOARD_FAB2(SCH_1):CLK_322M_OSC_CPU1_RC_DP   I169 @BASEBOARD_FAB2_LIB.BASEBOARD_FAB2(SCH_1):PAGE56
  AK57 TP_CPU1_RSVD_219 @BASEBOARD_FAB2_LIB.BASEBOARD_FAB2(SCH_1):TP_CPU1_RSVD_219   I169 @BASEBOARD_FAB2_LIB.BASEBOARD_FAB2(SCH_1):PAGE56
  AK59 TP_CPU1_RSVD_218 @BASEBOARD_FAB2_LIB.BASEBOARD_FAB2(SCH_1):TP_CPU1_RSVD_218   I169 @BASEBOARD_FAB2_LIB.BASEBOARD_FAB2(SCH_1):PAGE56
  AK61 TP_CPU1_RSVD_217 @BASEBOARD_FAB2_LIB.BASEBOARD_FAB2(SCH_1):TP_CPU1_RSVD_217   I169 @BASEBOARD_FAB2_LIB.BASEBOARD_FAB2(SCH_1):PAGE56
  AK69 TP_CPU1_RSVD_216 @BASEBOARD_FAB2_LIB.BASEBOARD_FAB2(SCH_1):TP_CPU1_RSVD_216   I169 @BASEBOARD_FAB2_LIB.BASEBOARD_FAB2(SCH_1):PAGE56
  AL20 VSENSE_P1V8MCP_CPU1_SKT_VRTN @BASEBOARD_FAB2_LIB.BASEBOARD_FAB2(SCH_1):VSENSE_P1V8MCP_CPU1_SKT_VRTN   I169 @BASEBOARD_FAB2_LIB.BASEBOARD_FAB2(SCH_1):PAGE56
  AL22 TP_CPU1_RSVD_214 @BASEBOARD_FAB2_LIB.BASEBOARD_FAB2(SCH_1):TP_CPU1_RSVD_214   I169 @BASEBOARD_FAB2_LIB.BASEBOARD_FAB2(SCH_1):PAGE56
  AL26 CLK_322M_OSC_CPU1_RC_DN @BASEBOARD_FAB2_LIB.BASEBOARD_FAB2(SCH_1):CLK_322M_OSC_CPU1_RC_DN   I169 @BASEBOARD_FAB2_LIB.BASEBOARD_FAB2(SCH_1):PAGE56
  AL58 TP_CPU1_RSVD_212 @BASEBOARD_FAB2_LIB.BASEBOARD_FAB2(SCH_1):TP_CPU1_RSVD_212   I169 @BASEBOARD_FAB2_LIB.BASEBOARD_FAB2(SCH_1):PAGE56
  AL60 TP_CPU1_RSVD_211 @BASEBOARD_FAB2_LIB.BASEBOARD_FAB2(SCH_1):TP_CPU1_RSVD_211   I169 @BASEBOARD_FAB2_LIB.BASEBOARD_FAB2(SCH_1):PAGE56
  AL62 TP_CPU1_RSVD_210 @BASEBOARD_FAB2_LIB.BASEBOARD_FAB2(SCH_1):TP_CPU1_RSVD_210   I169 @BASEBOARD_FAB2_LIB.BASEBOARD_FAB2(SCH_1):PAGE56
  AM21 PVCCMCP_CPU1 @BASEBOARD_FAB2_LIB.BASEBOARD_FAB2(SCH_1):PVCCMCP_CPU1   I169 @BASEBOARD_FAB2_LIB.BASEBOARD_FAB2(SCH_1):PAGE56
  AM23 TP_CPU1_RSVD_208 @BASEBOARD_FAB2_LIB.BASEBOARD_FAB2(SCH_1):TP_CPU1_RSVD_208   I169 @BASEBOARD_FAB2_LIB.BASEBOARD_FAB2(SCH_1):PAGE56
  AM25 PVCCMCP_CPU1 @BASEBOARD_FAB2_LIB.BASEBOARD_FAB2(SCH_1):PVCCMCP_CPU1   I169 @BASEBOARD_FAB2_LIB.BASEBOARD_FAB2(SCH_1):PAGE56
  AM27 CLK_100M_CPU1_RC_REFCLK0_DP @BASEBOARD_FAB2_LIB.BASEBOARD_FAB2(SCH_1):CLK_100M_CPU1_RC_REFCLK0_DP   I169 @BASEBOARD_FAB2_LIB.BASEBOARD_FAB2(SCH_1):PAGE56
  AM59 TP_CPU1_RSVD_205 @BASEBOARD_FAB2_LIB.BASEBOARD_FAB2(SCH_1):TP_CPU1_RSVD_205   I169 @BASEBOARD_FAB2_LIB.BASEBOARD_FAB2(SCH_1):PAGE56
  AM61 TP_CPU1_RSVD_204 @BASEBOARD_FAB2_LIB.BASEBOARD_FAB2(SCH_1):TP_CPU1_RSVD_204   I169 @BASEBOARD_FAB2_LIB.BASEBOARD_FAB2(SCH_1):PAGE56
  AN18 PVCCMCP_CPU1 @BASEBOARD_FAB2_LIB.BASEBOARD_FAB2(SCH_1):PVCCMCP_CPU1   I169 @BASEBOARD_FAB2_LIB.BASEBOARD_FAB2(SCH_1):PAGE56
  AN22 PVCCMCP_CPU1 @BASEBOARD_FAB2_LIB.BASEBOARD_FAB2(SCH_1):PVCCMCP_CPU1   I169 @BASEBOARD_FAB2_LIB.BASEBOARD_FAB2(SCH_1):PAGE56
  AN24 PVCCMCP_CPU1 @BASEBOARD_FAB2_LIB.BASEBOARD_FAB2(SCH_1):PVCCMCP_CPU1   I169 @BASEBOARD_FAB2_LIB.BASEBOARD_FAB2(SCH_1):PAGE56
  AN26 PVCCMCP_CPU1 @BASEBOARD_FAB2_LIB.BASEBOARD_FAB2(SCH_1):PVCCMCP_CPU1   I169 @BASEBOARD_FAB2_LIB.BASEBOARD_FAB2(SCH_1):PAGE56
  AN60 TP_CPU1_RSVD_199 @BASEBOARD_FAB2_LIB.BASEBOARD_FAB2(SCH_1):TP_CPU1_RSVD_199   I169 @BASEBOARD_FAB2_LIB.BASEBOARD_FAB2(SCH_1):PAGE56
  AN62 TP_CPU1_RSVD_198 @BASEBOARD_FAB2_LIB.BASEBOARD_FAB2(SCH_1):TP_CPU1_RSVD_198   I169 @BASEBOARD_FAB2_LIB.BASEBOARD_FAB2(SCH_1):PAGE56
  AP23 PVCCMCP_CPU1 @BASEBOARD_FAB2_LIB.BASEBOARD_FAB2(SCH_1):PVCCMCP_CPU1   I169 @BASEBOARD_FAB2_LIB.BASEBOARD_FAB2(SCH_1):PAGE56
  AP25 PVCCMCP_CPU1 @BASEBOARD_FAB2_LIB.BASEBOARD_FAB2(SCH_1):PVCCMCP_CPU1   I169 @BASEBOARD_FAB2_LIB.BASEBOARD_FAB2(SCH_1):PAGE56
  AP27 CLK_100M_CPU1_RC_REFCLK0_DN @BASEBOARD_FAB2_LIB.BASEBOARD_FAB2(SCH_1):CLK_100M_CPU1_RC_REFCLK0_DN   I169 @BASEBOARD_FAB2_LIB.BASEBOARD_FAB2(SCH_1):PAGE56
  AP61 TP_CPU1_RSVD_194 @BASEBOARD_FAB2_LIB.BASEBOARD_FAB2(SCH_1):TP_CPU1_RSVD_194   I169 @BASEBOARD_FAB2_LIB.BASEBOARD_FAB2(SCH_1):PAGE56
  AF45 PD_CPU1_RSVD_TEST_1 @BASEBOARD_FAB2_LIB.BASEBOARD_FAB2(SCH_1):PD_CPU1_RSVD_TEST_1   I169 @BASEBOARD_FAB2_LIB.BASEBOARD_FAB2(SCH_1):PAGE56
  AY13 TP_CPU1_RSVD_TEST_11 @BASEBOARD_FAB2_LIB.BASEBOARD_FAB2(SCH_1):TP_CPU1_RSVD_TEST_11   I169 @BASEBOARD_FAB2_LIB.BASEBOARD_FAB2(SCH_1):PAGE56
  AG46 PD_CPU1_RSVD_TEST_2 @BASEBOARD_FAB2_LIB.BASEBOARD_FAB2(SCH_1):PD_CPU1_RSVD_TEST_2   I169 @BASEBOARD_FAB2_LIB.BASEBOARD_FAB2(SCH_1):PAGE56
  AM13 TP_CPU1_RSVD_TEST_3 @BASEBOARD_FAB2_LIB.BASEBOARD_FAB2(SCH_1):TP_CPU1_RSVD_TEST_3   I169 @BASEBOARD_FAB2_LIB.BASEBOARD_FAB2(SCH_1):PAGE56
  AN12 TP_CPU1_RSVD_TEST_4 @BASEBOARD_FAB2_LIB.BASEBOARD_FAB2(SCH_1):TP_CPU1_RSVD_TEST_4   I169 @BASEBOARD_FAB2_LIB.BASEBOARD_FAB2(SCH_1):PAGE56
  AN14 TP_CPU1_RSVD_TEST_5 @BASEBOARD_FAB2_LIB.BASEBOARD_FAB2(SCH_1):TP_CPU1_RSVD_TEST_5   I169 @BASEBOARD_FAB2_LIB.BASEBOARD_FAB2(SCH_1):PAGE56
   J60 M_G_ACT_N @BASEBOARD_FAB2_LIB.BASEBOARD_FAB2(SCH_1):M_G_ACT_N   I172 @BASEBOARD_FAB2_LIB.BASEBOARD_FAB2(SCH_1):PAGE57
   B61 M_G_ALERT_N @BASEBOARD_FAB2_LIB.BASEBOARD_FAB2(SCH_1):M_G_ALERT_N   I172 @BASEBOARD_FAB2_LIB.BASEBOARD_FAB2(SCH_1):PAGE57
   G54 M_G_BA<1> @BASEBOARD_FAB2_LIB.BASEBOARD_FAB2(SCH_1):M_G_BA(1)   I172 @BASEBOARD_FAB2_LIB.BASEBOARD_FAB2(SCH_1):PAGE57
   C52 M_G_BA<0> @BASEBOARD_FAB2_LIB.BASEBOARD_FAB2(SCH_1):M_G_BA(0)   I172 @BASEBOARD_FAB2_LIB.BASEBOARD_FAB2(SCH_1):PAGE57
   F63 M_G_BG<1> @BASEBOARD_FAB2_LIB.BASEBOARD_FAB2(SCH_1):M_G_BG(1)   I172 @BASEBOARD_FAB2_LIB.BASEBOARD_FAB2(SCH_1):PAGE57
   D61 M_G_BG<0> @BASEBOARD_FAB2_LIB.BASEBOARD_FAB2(SCH_1):M_G_BG(0)   I172 @BASEBOARD_FAB2_LIB.BASEBOARD_FAB2(SCH_1):PAGE57
   G46 M_G_C<2> @BASEBOARD_FAB2_LIB.BASEBOARD_FAB2(SCH_1):M_G_C(2)   I172 @BASEBOARD_FAB2_LIB.BASEBOARD_FAB2(SCH_1):PAGE57
   D63 M_G_CKE<3> @BASEBOARD_FAB2_LIB.BASEBOARD_FAB2(SCH_1):M_G_CKE(3)   I172 @BASEBOARD_FAB2_LIB.BASEBOARD_FAB2(SCH_1):PAGE57
   B63 M_G_CKE<2> @BASEBOARD_FAB2_LIB.BASEBOARD_FAB2(SCH_1):M_G_CKE(2)   I172 @BASEBOARD_FAB2_LIB.BASEBOARD_FAB2(SCH_1):PAGE57
   C64 M_G_CKE<1> @BASEBOARD_FAB2_LIB.BASEBOARD_FAB2(SCH_1):M_G_CKE(1)   I172 @BASEBOARD_FAB2_LIB.BASEBOARD_FAB2(SCH_1):PAGE57
   C62 M_G_CKE<0> @BASEBOARD_FAB2_LIB.BASEBOARD_FAB2(SCH_1):M_G_CKE(0)   I172 @BASEBOARD_FAB2_LIB.BASEBOARD_FAB2(SCH_1):PAGE57
   C56 M_G_CLK_DN<3> @BASEBOARD_FAB2_LIB.BASEBOARD_FAB2(SCH_1):M_G_CLK_DN(3)   I172 @BASEBOARD_FAB2_LIB.BASEBOARD_FAB2(SCH_1):PAGE57
   J56 M_G_CLK_DN<2> @BASEBOARD_FAB2_LIB.BASEBOARD_FAB2(SCH_1):M_G_CLK_DN(2)   I172 @BASEBOARD_FAB2_LIB.BASEBOARD_FAB2(SCH_1):PAGE57
   C54 M_G_CLK_DN<1> @BASEBOARD_FAB2_LIB.BASEBOARD_FAB2(SCH_1):M_G_CLK_DN(1)   I172 @BASEBOARD_FAB2_LIB.BASEBOARD_FAB2(SCH_1):PAGE57
   F55 M_G_CLK_DN<0> @BASEBOARD_FAB2_LIB.BASEBOARD_FAB2(SCH_1):M_G_CLK_DN(0)   I172 @BASEBOARD_FAB2_LIB.BASEBOARD_FAB2(SCH_1):PAGE57
   B57 M_G_CLK_DP<3> @BASEBOARD_FAB2_LIB.BASEBOARD_FAB2(SCH_1):M_G_CLK_DP(3)   I172 @BASEBOARD_FAB2_LIB.BASEBOARD_FAB2(SCH_1):PAGE57
   G56 M_G_CLK_DP<2> @BASEBOARD_FAB2_LIB.BASEBOARD_FAB2(SCH_1):M_G_CLK_DP(2)   I172 @BASEBOARD_FAB2_LIB.BASEBOARD_FAB2(SCH_1):PAGE57
   B55 M_G_CLK_DP<1> @BASEBOARD_FAB2_LIB.BASEBOARD_FAB2(SCH_1):M_G_CLK_DP(1)   I172 @BASEBOARD_FAB2_LIB.BASEBOARD_FAB2(SCH_1):PAGE57
   D55 M_G_CLK_DP<0> @BASEBOARD_FAB2_LIB.BASEBOARD_FAB2(SCH_1):M_G_CLK_DP(0)   I172 @BASEBOARD_FAB2_LIB.BASEBOARD_FAB2(SCH_1):PAGE57
   K45 M_G_CS_N<7> @BASEBOARD_FAB2_LIB.BASEBOARD_FAB2(SCH_1):M_G_CS_N(7)   I172 @BASEBOARD_FAB2_LIB.BASEBOARD_FAB2(SCH_1):PAGE57
   F45 M_G_CS_N<6> @BASEBOARD_FAB2_LIB.BASEBOARD_FAB2(SCH_1):M_G_CS_N(6)   I172 @BASEBOARD_FAB2_LIB.BASEBOARD_FAB2(SCH_1):PAGE57
   D49 M_G_CS_N<5> @BASEBOARD_FAB2_LIB.BASEBOARD_FAB2(SCH_1):M_G_CS_N(5)   I172 @BASEBOARD_FAB2_LIB.BASEBOARD_FAB2(SCH_1):PAGE57
   B51 M_G_CS_N<4> @BASEBOARD_FAB2_LIB.BASEBOARD_FAB2(SCH_1):M_G_CS_N(4)   I172 @BASEBOARD_FAB2_LIB.BASEBOARD_FAB2(SCH_1):PAGE57
   F47 M_G_CS_N<3> @BASEBOARD_FAB2_LIB.BASEBOARD_FAB2(SCH_1):M_G_CS_N(3)   I172 @BASEBOARD_FAB2_LIB.BASEBOARD_FAB2(SCH_1):PAGE57
   D47 M_G_CS_N<2> @BASEBOARD_FAB2_LIB.BASEBOARD_FAB2(SCH_1):M_G_CS_N(2)   I172 @BASEBOARD_FAB2_LIB.BASEBOARD_FAB2(SCH_1):PAGE57
   F49 M_G_CS_N<1> @BASEBOARD_FAB2_LIB.BASEBOARD_FAB2(SCH_1):M_G_CS_N(1)   I172 @BASEBOARD_FAB2_LIB.BASEBOARD_FAB2(SCH_1):PAGE57
   G52 M_G_CS_N<0> @BASEBOARD_FAB2_LIB.BASEBOARD_FAB2(SCH_1):M_G_CS_N(0)   I172 @BASEBOARD_FAB2_LIB.BASEBOARD_FAB2(SCH_1):PAGE57
   K23 M_G_DQ<63> @BASEBOARD_FAB2_LIB.BASEBOARD_FAB2(SCH_1):M_G_DQ(63)   I172 @BASEBOARD_FAB2_LIB.BASEBOARD_FAB2(SCH_1):PAGE57
   H23 M_G_DQ<62> @BASEBOARD_FAB2_LIB.BASEBOARD_FAB2(SCH_1):M_G_DQ(62)   I172 @BASEBOARD_FAB2_LIB.BASEBOARD_FAB2(SCH_1):PAGE57
   N26 M_G_DQ<61> @BASEBOARD_FAB2_LIB.BASEBOARD_FAB2(SCH_1):M_G_DQ(61)   I172 @BASEBOARD_FAB2_LIB.BASEBOARD_FAB2(SCH_1):PAGE57
   L26 M_G_DQ<60> @BASEBOARD_FAB2_LIB.BASEBOARD_FAB2(SCH_1):M_G_DQ(60)   I172 @BASEBOARD_FAB2_LIB.BASEBOARD_FAB2(SCH_1):PAGE57
   T23 M_G_DQ<59> @BASEBOARD_FAB2_LIB.BASEBOARD_FAB2(SCH_1):M_G_DQ(59)   I172 @BASEBOARD_FAB2_LIB.BASEBOARD_FAB2(SCH_1):PAGE57
   P23 M_G_DQ<58> @BASEBOARD_FAB2_LIB.BASEBOARD_FAB2(SCH_1):M_G_DQ(58)   I172 @BASEBOARD_FAB2_LIB.BASEBOARD_FAB2(SCH_1):PAGE57
   P25 M_G_DQ<57> @BASEBOARD_FAB2_LIB.BASEBOARD_FAB2(SCH_1):M_G_DQ(57)   I172 @BASEBOARD_FAB2_LIB.BASEBOARD_FAB2(SCH_1):PAGE57
   K25 M_G_DQ<56> @BASEBOARD_FAB2_LIB.BASEBOARD_FAB2(SCH_1):M_G_DQ(56)   I172 @BASEBOARD_FAB2_LIB.BASEBOARD_FAB2(SCH_1):PAGE57
   P29 M_G_DQ<55> @BASEBOARD_FAB2_LIB.BASEBOARD_FAB2(SCH_1):M_G_DQ(55)   I172 @BASEBOARD_FAB2_LIB.BASEBOARD_FAB2(SCH_1):PAGE57
   K29 M_G_DQ<54> @BASEBOARD_FAB2_LIB.BASEBOARD_FAB2(SCH_1):M_G_DQ(54)   I172 @BASEBOARD_FAB2_LIB.BASEBOARD_FAB2(SCH_1):PAGE57
   N32 M_G_DQ<53> @BASEBOARD_FAB2_LIB.BASEBOARD_FAB2(SCH_1):M_G_DQ(53)   I172 @BASEBOARD_FAB2_LIB.BASEBOARD_FAB2(SCH_1):PAGE57
   L32 M_G_DQ<52> @BASEBOARD_FAB2_LIB.BASEBOARD_FAB2(SCH_1):M_G_DQ(52)   I172 @BASEBOARD_FAB2_LIB.BASEBOARD_FAB2(SCH_1):PAGE57
   N28 M_G_DQ<51> @BASEBOARD_FAB2_LIB.BASEBOARD_FAB2(SCH_1):M_G_DQ(51)   I172 @BASEBOARD_FAB2_LIB.BASEBOARD_FAB2(SCH_1):PAGE57
   L28 M_G_DQ<50> @BASEBOARD_FAB2_LIB.BASEBOARD_FAB2(SCH_1):M_G_DQ(50)   I172 @BASEBOARD_FAB2_LIB.BASEBOARD_FAB2(SCH_1):PAGE57
   P31 M_G_DQ<49> @BASEBOARD_FAB2_LIB.BASEBOARD_FAB2(SCH_1):M_G_DQ(49)   I172 @BASEBOARD_FAB2_LIB.BASEBOARD_FAB2(SCH_1):PAGE57
   K31 M_G_DQ<48> @BASEBOARD_FAB2_LIB.BASEBOARD_FAB2(SCH_1):M_G_DQ(48)   I172 @BASEBOARD_FAB2_LIB.BASEBOARD_FAB2(SCH_1):PAGE57
   P35 M_G_DQ<47> @BASEBOARD_FAB2_LIB.BASEBOARD_FAB2(SCH_1):M_G_DQ(47)   I172 @BASEBOARD_FAB2_LIB.BASEBOARD_FAB2(SCH_1):PAGE57
   K35 M_G_DQ<46> @BASEBOARD_FAB2_LIB.BASEBOARD_FAB2(SCH_1):M_G_DQ(46)   I172 @BASEBOARD_FAB2_LIB.BASEBOARD_FAB2(SCH_1):PAGE57
   N38 M_G_DQ<45> @BASEBOARD_FAB2_LIB.BASEBOARD_FAB2(SCH_1):M_G_DQ(45)   I172 @BASEBOARD_FAB2_LIB.BASEBOARD_FAB2(SCH_1):PAGE57
   L38 M_G_DQ<44> @BASEBOARD_FAB2_LIB.BASEBOARD_FAB2(SCH_1):M_G_DQ(44)   I172 @BASEBOARD_FAB2_LIB.BASEBOARD_FAB2(SCH_1):PAGE57
   N34 M_G_DQ<43> @BASEBOARD_FAB2_LIB.BASEBOARD_FAB2(SCH_1):M_G_DQ(43)   I172 @BASEBOARD_FAB2_LIB.BASEBOARD_FAB2(SCH_1):PAGE57
   L34 M_G_DQ<42> @BASEBOARD_FAB2_LIB.BASEBOARD_FAB2(SCH_1):M_G_DQ(42)   I172 @BASEBOARD_FAB2_LIB.BASEBOARD_FAB2(SCH_1):PAGE57
   P37 M_G_DQ<41> @BASEBOARD_FAB2_LIB.BASEBOARD_FAB2(SCH_1):M_G_DQ(41)   I172 @BASEBOARD_FAB2_LIB.BASEBOARD_FAB2(SCH_1):PAGE57
   K37 M_G_DQ<40> @BASEBOARD_FAB2_LIB.BASEBOARD_FAB2(SCH_1):M_G_DQ(40)   I172 @BASEBOARD_FAB2_LIB.BASEBOARD_FAB2(SCH_1):PAGE57
   F39 M_G_DQ<39> @BASEBOARD_FAB2_LIB.BASEBOARD_FAB2(SCH_1):M_G_DQ(39)   I172 @BASEBOARD_FAB2_LIB.BASEBOARD_FAB2(SCH_1):PAGE57
   B39 M_G_DQ<38> @BASEBOARD_FAB2_LIB.BASEBOARD_FAB2(SCH_1):M_G_DQ(38)   I172 @BASEBOARD_FAB2_LIB.BASEBOARD_FAB2(SCH_1):PAGE57
   F41 M_G_DQ<37> @BASEBOARD_FAB2_LIB.BASEBOARD_FAB2(SCH_1):M_G_DQ(37)   I172 @BASEBOARD_FAB2_LIB.BASEBOARD_FAB2(SCH_1):PAGE57
   E42 M_G_DQ<36> @BASEBOARD_FAB2_LIB.BASEBOARD_FAB2(SCH_1):M_G_DQ(36)   I172 @BASEBOARD_FAB2_LIB.BASEBOARD_FAB2(SCH_1):PAGE57
   E38 M_G_DQ<35> @BASEBOARD_FAB2_LIB.BASEBOARD_FAB2(SCH_1):M_G_DQ(35)   I172 @BASEBOARD_FAB2_LIB.BASEBOARD_FAB2(SCH_1):PAGE57
   C38 M_G_DQ<34> @BASEBOARD_FAB2_LIB.BASEBOARD_FAB2(SCH_1):M_G_DQ(34)   I172 @BASEBOARD_FAB2_LIB.BASEBOARD_FAB2(SCH_1):PAGE57
   B41 M_G_DQ<33> @BASEBOARD_FAB2_LIB.BASEBOARD_FAB2(SCH_1):M_G_DQ(33)   I172 @BASEBOARD_FAB2_LIB.BASEBOARD_FAB2(SCH_1):PAGE57
   C42 M_G_DQ<32> @BASEBOARD_FAB2_LIB.BASEBOARD_FAB2(SCH_1):M_G_DQ(32)   I172 @BASEBOARD_FAB2_LIB.BASEBOARD_FAB2(SCH_1):PAGE57
   R74 M_G_DQ<31> @BASEBOARD_FAB2_LIB.BASEBOARD_FAB2(SCH_1):M_G_DQ(31)   I172 @BASEBOARD_FAB2_LIB.BASEBOARD_FAB2(SCH_1):PAGE57
   L74 M_G_DQ<30> @BASEBOARD_FAB2_LIB.BASEBOARD_FAB2(SCH_1):M_G_DQ(30)   I172 @BASEBOARD_FAB2_LIB.BASEBOARD_FAB2(SCH_1):PAGE57
   P77 M_G_DQ<29> @BASEBOARD_FAB2_LIB.BASEBOARD_FAB2(SCH_1):M_G_DQ(29)   I172 @BASEBOARD_FAB2_LIB.BASEBOARD_FAB2(SCH_1):PAGE57
   M77 M_G_DQ<28> @BASEBOARD_FAB2_LIB.BASEBOARD_FAB2(SCH_1):M_G_DQ(28)   I172 @BASEBOARD_FAB2_LIB.BASEBOARD_FAB2(SCH_1):PAGE57
   P73 M_G_DQ<27> @BASEBOARD_FAB2_LIB.BASEBOARD_FAB2(SCH_1):M_G_DQ(27)   I172 @BASEBOARD_FAB2_LIB.BASEBOARD_FAB2(SCH_1):PAGE57
   M73 M_G_DQ<26> @BASEBOARD_FAB2_LIB.BASEBOARD_FAB2(SCH_1):M_G_DQ(26)   I172 @BASEBOARD_FAB2_LIB.BASEBOARD_FAB2(SCH_1):PAGE57
   R76 M_G_DQ<25> @BASEBOARD_FAB2_LIB.BASEBOARD_FAB2(SCH_1):M_G_DQ(25)   I172 @BASEBOARD_FAB2_LIB.BASEBOARD_FAB2(SCH_1):PAGE57
   L76 M_G_DQ<24> @BASEBOARD_FAB2_LIB.BASEBOARD_FAB2(SCH_1):M_G_DQ(24)   I172 @BASEBOARD_FAB2_LIB.BASEBOARD_FAB2(SCH_1):PAGE57
   N80 M_G_DQ<23> @BASEBOARD_FAB2_LIB.BASEBOARD_FAB2(SCH_1):M_G_DQ(23)   I172 @BASEBOARD_FAB2_LIB.BASEBOARD_FAB2(SCH_1):PAGE57
   R82 M_G_DQ<22> @BASEBOARD_FAB2_LIB.BASEBOARD_FAB2(SCH_1):M_G_DQ(22)   I172 @BASEBOARD_FAB2_LIB.BASEBOARD_FAB2(SCH_1):PAGE57
   V79 M_G_DQ<21> @BASEBOARD_FAB2_LIB.BASEBOARD_FAB2(SCH_1):M_G_DQ(21)   I172 @BASEBOARD_FAB2_LIB.BASEBOARD_FAB2(SCH_1):PAGE57
   W80 M_G_DQ<20> @BASEBOARD_FAB2_LIB.BASEBOARD_FAB2(SCH_1):M_G_DQ(20)   I172 @BASEBOARD_FAB2_LIB.BASEBOARD_FAB2(SCH_1):PAGE57
   M81 M_G_DQ<19> @BASEBOARD_FAB2_LIB.BASEBOARD_FAB2(SCH_1):M_G_DQ(19)   I172 @BASEBOARD_FAB2_LIB.BASEBOARD_FAB2(SCH_1):PAGE57
   N82 M_G_DQ<18> @BASEBOARD_FAB2_LIB.BASEBOARD_FAB2(SCH_1):M_G_DQ(18)   I172 @BASEBOARD_FAB2_LIB.BASEBOARD_FAB2(SCH_1):PAGE57
   T79 M_G_DQ<17> @BASEBOARD_FAB2_LIB.BASEBOARD_FAB2(SCH_1):M_G_DQ(17)   I172 @BASEBOARD_FAB2_LIB.BASEBOARD_FAB2(SCH_1):PAGE57
   V81 M_G_DQ<16> @BASEBOARD_FAB2_LIB.BASEBOARD_FAB2(SCH_1):M_G_DQ(16)   I172 @BASEBOARD_FAB2_LIB.BASEBOARD_FAB2(SCH_1):PAGE57
   N84 M_G_DQ<15> @BASEBOARD_FAB2_LIB.BASEBOARD_FAB2(SCH_1):M_G_DQ(15)   I172 @BASEBOARD_FAB2_LIB.BASEBOARD_FAB2(SCH_1):PAGE57
   N86 M_G_DQ<14> @BASEBOARD_FAB2_LIB.BASEBOARD_FAB2(SCH_1):M_G_DQ(14)   I172 @BASEBOARD_FAB2_LIB.BASEBOARD_FAB2(SCH_1):PAGE57
  AA84 M_G_DQ<13> @BASEBOARD_FAB2_LIB.BASEBOARD_FAB2(SCH_1):M_G_DQ(13)   I172 @BASEBOARD_FAB2_LIB.BASEBOARD_FAB2(SCH_1):PAGE57
  AA86 M_G_DQ<12> @BASEBOARD_FAB2_LIB.BASEBOARD_FAB2(SCH_1):M_G_DQ(12)   I172 @BASEBOARD_FAB2_LIB.BASEBOARD_FAB2(SCH_1):PAGE57
   L84 M_G_DQ<11> @BASEBOARD_FAB2_LIB.BASEBOARD_FAB2(SCH_1):M_G_DQ(11)   I172 @BASEBOARD_FAB2_LIB.BASEBOARD_FAB2(SCH_1):PAGE57
   L86 M_G_DQ<10> @BASEBOARD_FAB2_LIB.BASEBOARD_FAB2(SCH_1):M_G_DQ(10)   I172 @BASEBOARD_FAB2_LIB.BASEBOARD_FAB2(SCH_1):PAGE57
   W84 M_G_DQ<9> @BASEBOARD_FAB2_LIB.BASEBOARD_FAB2(SCH_1):M_G_DQ(9)   I172 @BASEBOARD_FAB2_LIB.BASEBOARD_FAB2(SCH_1):PAGE57
   W86 M_G_DQ<8> @BASEBOARD_FAB2_LIB.BASEBOARD_FAB2(SCH_1):M_G_DQ(8)   I172 @BASEBOARD_FAB2_LIB.BASEBOARD_FAB2(SCH_1):PAGE57
  AG84 M_G_DQ<7> @BASEBOARD_FAB2_LIB.BASEBOARD_FAB2(SCH_1):M_G_DQ(7)   I172 @BASEBOARD_FAB2_LIB.BASEBOARD_FAB2(SCH_1):PAGE57
  AG86 M_G_DQ<6> @BASEBOARD_FAB2_LIB.BASEBOARD_FAB2(SCH_1):M_G_DQ(6)   I172 @BASEBOARD_FAB2_LIB.BASEBOARD_FAB2(SCH_1):PAGE57
  AR84 M_G_DQ<5> @BASEBOARD_FAB2_LIB.BASEBOARD_FAB2(SCH_1):M_G_DQ(5)   I172 @BASEBOARD_FAB2_LIB.BASEBOARD_FAB2(SCH_1):PAGE57
  AR86 M_G_DQ<4> @BASEBOARD_FAB2_LIB.BASEBOARD_FAB2(SCH_1):M_G_DQ(4)   I172 @BASEBOARD_FAB2_LIB.BASEBOARD_FAB2(SCH_1):PAGE57
  AE84 M_G_DQ<3> @BASEBOARD_FAB2_LIB.BASEBOARD_FAB2(SCH_1):M_G_DQ(3)   I172 @BASEBOARD_FAB2_LIB.BASEBOARD_FAB2(SCH_1):PAGE57
  AE86 M_G_DQ<2> @BASEBOARD_FAB2_LIB.BASEBOARD_FAB2(SCH_1):M_G_DQ(2)   I172 @BASEBOARD_FAB2_LIB.BASEBOARD_FAB2(SCH_1):PAGE57
  AN84 M_G_DQ<1> @BASEBOARD_FAB2_LIB.BASEBOARD_FAB2(SCH_1):M_G_DQ(1)   I172 @BASEBOARD_FAB2_LIB.BASEBOARD_FAB2(SCH_1):PAGE57
  AN86 M_G_DQ<0> @BASEBOARD_FAB2_LIB.BASEBOARD_FAB2(SCH_1):M_G_DQ(0)   I172 @BASEBOARD_FAB2_LIB.BASEBOARD_FAB2(SCH_1):PAGE57
  AB67 M_G_DQS_DN<17> @BASEBOARD_FAB2_LIB.BASEBOARD_FAB2(SCH_1):M_G_DQS_DN(17)   I172 @BASEBOARD_FAB2_LIB.BASEBOARD_FAB2(SCH_1):PAGE57
   J24 M_G_DQS_DN<16> @BASEBOARD_FAB2_LIB.BASEBOARD_FAB2(SCH_1):M_G_DQS_DN(16)   I172 @BASEBOARD_FAB2_LIB.BASEBOARD_FAB2(SCH_1):PAGE57
   J30 M_G_DQS_DN<15> @BASEBOARD_FAB2_LIB.BASEBOARD_FAB2(SCH_1):M_G_DQS_DN(15)   I172 @BASEBOARD_FAB2_LIB.BASEBOARD_FAB2(SCH_1):PAGE57
   J36 M_G_DQS_DN<14> @BASEBOARD_FAB2_LIB.BASEBOARD_FAB2(SCH_1):M_G_DQS_DN(14)   I172 @BASEBOARD_FAB2_LIB.BASEBOARD_FAB2(SCH_1):PAGE57
   A40 M_G_DQS_DN<13> @BASEBOARD_FAB2_LIB.BASEBOARD_FAB2(SCH_1):M_G_DQS_DN(13)   I172 @BASEBOARD_FAB2_LIB.BASEBOARD_FAB2(SCH_1):PAGE57
   K75 M_G_DQS_DN<12> @BASEBOARD_FAB2_LIB.BASEBOARD_FAB2(SCH_1):M_G_DQS_DN(12)   I172 @BASEBOARD_FAB2_LIB.BASEBOARD_FAB2(SCH_1):PAGE57
   U82 M_G_DQS_DN<11> @BASEBOARD_FAB2_LIB.BASEBOARD_FAB2(SCH_1):M_G_DQS_DN(11)   I172 @BASEBOARD_FAB2_LIB.BASEBOARD_FAB2(SCH_1):PAGE57
   U84 M_G_DQS_DN<10> @BASEBOARD_FAB2_LIB.BASEBOARD_FAB2(SCH_1):M_G_DQS_DN(10)   I172 @BASEBOARD_FAB2_LIB.BASEBOARD_FAB2(SCH_1):PAGE57
  AL84 M_G_DQS_DN<9> @BASEBOARD_FAB2_LIB.BASEBOARD_FAB2(SCH_1):M_G_DQS_DN(9)   I172 @BASEBOARD_FAB2_LIB.BASEBOARD_FAB2(SCH_1):PAGE57
  AH67 M_G_DQS_DN<8> @BASEBOARD_FAB2_LIB.BASEBOARD_FAB2(SCH_1):M_G_DQS_DN(8)   I172 @BASEBOARD_FAB2_LIB.BASEBOARD_FAB2(SCH_1):PAGE57
   N24 M_G_DQS_DN<7> @BASEBOARD_FAB2_LIB.BASEBOARD_FAB2(SCH_1):M_G_DQS_DN(7)   I172 @BASEBOARD_FAB2_LIB.BASEBOARD_FAB2(SCH_1):PAGE57
   R30 M_G_DQS_DN<6> @BASEBOARD_FAB2_LIB.BASEBOARD_FAB2(SCH_1):M_G_DQS_DN(6)   I172 @BASEBOARD_FAB2_LIB.BASEBOARD_FAB2(SCH_1):PAGE57
   R36 M_G_DQS_DN<5> @BASEBOARD_FAB2_LIB.BASEBOARD_FAB2(SCH_1):M_G_DQS_DN(5)   I172 @BASEBOARD_FAB2_LIB.BASEBOARD_FAB2(SCH_1):PAGE57
   G40 M_G_DQS_DN<4> @BASEBOARD_FAB2_LIB.BASEBOARD_FAB2(SCH_1):M_G_DQS_DN(4)   I172 @BASEBOARD_FAB2_LIB.BASEBOARD_FAB2(SCH_1):PAGE57
   T75 M_G_DQS_DN<3> @BASEBOARD_FAB2_LIB.BASEBOARD_FAB2(SCH_1):M_G_DQS_DN(3)   I172 @BASEBOARD_FAB2_LIB.BASEBOARD_FAB2(SCH_1):PAGE57
   P79 M_G_DQS_DN<2> @BASEBOARD_FAB2_LIB.BASEBOARD_FAB2(SCH_1):M_G_DQS_DN(2)   I172 @BASEBOARD_FAB2_LIB.BASEBOARD_FAB2(SCH_1):PAGE57
   R84 M_G_DQS_DN<1> @BASEBOARD_FAB2_LIB.BASEBOARD_FAB2(SCH_1):M_G_DQS_DN(1)   I172 @BASEBOARD_FAB2_LIB.BASEBOARD_FAB2(SCH_1):PAGE57
  AJ84 M_G_DQS_DN<0> @BASEBOARD_FAB2_LIB.BASEBOARD_FAB2(SCH_1):M_G_DQS_DN(0)   I172 @BASEBOARD_FAB2_LIB.BASEBOARD_FAB2(SCH_1):PAGE57
  AD67 M_G_DQS_DP<17> @BASEBOARD_FAB2_LIB.BASEBOARD_FAB2(SCH_1):M_G_DQS_DP(17)   I172 @BASEBOARD_FAB2_LIB.BASEBOARD_FAB2(SCH_1):PAGE57
   L24 M_G_DQS_DP<16> @BASEBOARD_FAB2_LIB.BASEBOARD_FAB2(SCH_1):M_G_DQS_DP(16)   I172 @BASEBOARD_FAB2_LIB.BASEBOARD_FAB2(SCH_1):PAGE57
   L30 M_G_DQS_DP<15> @BASEBOARD_FAB2_LIB.BASEBOARD_FAB2(SCH_1):M_G_DQS_DP(15)   I172 @BASEBOARD_FAB2_LIB.BASEBOARD_FAB2(SCH_1):PAGE57
   L36 M_G_DQS_DP<14> @BASEBOARD_FAB2_LIB.BASEBOARD_FAB2(SCH_1):M_G_DQS_DP(14)   I172 @BASEBOARD_FAB2_LIB.BASEBOARD_FAB2(SCH_1):PAGE57
   C40 M_G_DQS_DP<13> @BASEBOARD_FAB2_LIB.BASEBOARD_FAB2(SCH_1):M_G_DQS_DP(13)   I172 @BASEBOARD_FAB2_LIB.BASEBOARD_FAB2(SCH_1):PAGE57
   M75 M_G_DQS_DP<12> @BASEBOARD_FAB2_LIB.BASEBOARD_FAB2(SCH_1):M_G_DQS_DP(12)   I172 @BASEBOARD_FAB2_LIB.BASEBOARD_FAB2(SCH_1):PAGE57
   T81 M_G_DQS_DP<11> @BASEBOARD_FAB2_LIB.BASEBOARD_FAB2(SCH_1):M_G_DQS_DP(11)   I172 @BASEBOARD_FAB2_LIB.BASEBOARD_FAB2(SCH_1):PAGE57
   V85 M_G_DQS_DP<10> @BASEBOARD_FAB2_LIB.BASEBOARD_FAB2(SCH_1):M_G_DQS_DP(10)   I172 @BASEBOARD_FAB2_LIB.BASEBOARD_FAB2(SCH_1):PAGE57
  AM85 M_G_DQS_DP<9> @BASEBOARD_FAB2_LIB.BASEBOARD_FAB2(SCH_1):M_G_DQS_DP(9)   I172 @BASEBOARD_FAB2_LIB.BASEBOARD_FAB2(SCH_1):PAGE57
  AF67 M_G_DQS_DP<8> @BASEBOARD_FAB2_LIB.BASEBOARD_FAB2(SCH_1):M_G_DQS_DP(8)   I172 @BASEBOARD_FAB2_LIB.BASEBOARD_FAB2(SCH_1):PAGE57
   R24 M_G_DQS_DP<7> @BASEBOARD_FAB2_LIB.BASEBOARD_FAB2(SCH_1):M_G_DQS_DP(7)   I172 @BASEBOARD_FAB2_LIB.BASEBOARD_FAB2(SCH_1):PAGE57
   N30 M_G_DQS_DP<6> @BASEBOARD_FAB2_LIB.BASEBOARD_FAB2(SCH_1):M_G_DQS_DP(6)   I172 @BASEBOARD_FAB2_LIB.BASEBOARD_FAB2(SCH_1):PAGE57
   N36 M_G_DQS_DP<5> @BASEBOARD_FAB2_LIB.BASEBOARD_FAB2(SCH_1):M_G_DQS_DP(5)   I172 @BASEBOARD_FAB2_LIB.BASEBOARD_FAB2(SCH_1):PAGE57
   E40 M_G_DQS_DP<4> @BASEBOARD_FAB2_LIB.BASEBOARD_FAB2(SCH_1):M_G_DQS_DP(4)   I172 @BASEBOARD_FAB2_LIB.BASEBOARD_FAB2(SCH_1):PAGE57
   P75 M_G_DQS_DP<3> @BASEBOARD_FAB2_LIB.BASEBOARD_FAB2(SCH_1):M_G_DQS_DP(3)   I172 @BASEBOARD_FAB2_LIB.BASEBOARD_FAB2(SCH_1):PAGE57
   R80 M_G_DQS_DP<2> @BASEBOARD_FAB2_LIB.BASEBOARD_FAB2(SCH_1):M_G_DQS_DP(2)   I172 @BASEBOARD_FAB2_LIB.BASEBOARD_FAB2(SCH_1):PAGE57
   P85 M_G_DQS_DP<1> @BASEBOARD_FAB2_LIB.BASEBOARD_FAB2(SCH_1):M_G_DQS_DP(1)   I172 @BASEBOARD_FAB2_LIB.BASEBOARD_FAB2(SCH_1):PAGE57
  AH85 M_G_DQS_DP<0> @BASEBOARD_FAB2_LIB.BASEBOARD_FAB2(SCH_1):M_G_DQS_DP(0)   I172 @BASEBOARD_FAB2_LIB.BASEBOARD_FAB2(SCH_1):PAGE57
  AG66 M_G_ECC<7> @BASEBOARD_FAB2_LIB.BASEBOARD_FAB2(SCH_1):M_G_ECC(7)   I172 @BASEBOARD_FAB2_LIB.BASEBOARD_FAB2(SCH_1):PAGE57
  AC66 M_G_ECC<6> @BASEBOARD_FAB2_LIB.BASEBOARD_FAB2(SCH_1):M_G_ECC(6)   I172 @BASEBOARD_FAB2_LIB.BASEBOARD_FAB2(SCH_1):PAGE57
  AF69 M_G_ECC<5> @BASEBOARD_FAB2_LIB.BASEBOARD_FAB2(SCH_1):M_G_ECC(5)   I172 @BASEBOARD_FAB2_LIB.BASEBOARD_FAB2(SCH_1):PAGE57
  AD69 M_G_ECC<4> @BASEBOARD_FAB2_LIB.BASEBOARD_FAB2(SCH_1):M_G_ECC(4)   I172 @BASEBOARD_FAB2_LIB.BASEBOARD_FAB2(SCH_1):PAGE57
  AF65 M_G_ECC<3> @BASEBOARD_FAB2_LIB.BASEBOARD_FAB2(SCH_1):M_G_ECC(3)   I172 @BASEBOARD_FAB2_LIB.BASEBOARD_FAB2(SCH_1):PAGE57
  AD65 M_G_ECC<2> @BASEBOARD_FAB2_LIB.BASEBOARD_FAB2(SCH_1):M_G_ECC(2)   I172 @BASEBOARD_FAB2_LIB.BASEBOARD_FAB2(SCH_1):PAGE57
  AG68 M_G_ECC<1> @BASEBOARD_FAB2_LIB.BASEBOARD_FAB2(SCH_1):M_G_ECC(1)   I172 @BASEBOARD_FAB2_LIB.BASEBOARD_FAB2(SCH_1):PAGE57
  AC68 M_G_ECC<0> @BASEBOARD_FAB2_LIB.BASEBOARD_FAB2(SCH_1):M_G_ECC(0)   I172 @BASEBOARD_FAB2_LIB.BASEBOARD_FAB2(SCH_1):PAGE57
   K47 M_G_MA<17> @BASEBOARD_FAB2_LIB.BASEBOARD_FAB2(SCH_1):M_G_MA(17)   I172 @BASEBOARD_FAB2_LIB.BASEBOARD_FAB2(SCH_1):PAGE57
   D51 M_G_MA<16> @BASEBOARD_FAB2_LIB.BASEBOARD_FAB2(SCH_1):M_G_MA(16)   I172 @BASEBOARD_FAB2_LIB.BASEBOARD_FAB2(SCH_1):PAGE57
   K49 M_G_MA<15> @BASEBOARD_FAB2_LIB.BASEBOARD_FAB2(SCH_1):M_G_MA(15)   I172 @BASEBOARD_FAB2_LIB.BASEBOARD_FAB2(SCH_1):PAGE57
   F51 M_G_MA<14> @BASEBOARD_FAB2_LIB.BASEBOARD_FAB2(SCH_1):M_G_MA(14)   I172 @BASEBOARD_FAB2_LIB.BASEBOARD_FAB2(SCH_1):PAGE57
   J48 M_G_MA<13> @BASEBOARD_FAB2_LIB.BASEBOARD_FAB2(SCH_1):M_G_MA(13)   I172 @BASEBOARD_FAB2_LIB.BASEBOARD_FAB2(SCH_1):PAGE57
   J64 M_G_MA<12> @BASEBOARD_FAB2_LIB.BASEBOARD_FAB2(SCH_1):M_G_MA(12)   I172 @BASEBOARD_FAB2_LIB.BASEBOARD_FAB2(SCH_1):PAGE57
   G62 M_G_MA<11> @BASEBOARD_FAB2_LIB.BASEBOARD_FAB2(SCH_1):M_G_MA(11)   I172 @BASEBOARD_FAB2_LIB.BASEBOARD_FAB2(SCH_1):PAGE57
   J54 M_G_MA<10> @BASEBOARD_FAB2_LIB.BASEBOARD_FAB2(SCH_1):M_G_MA(10)   I172 @BASEBOARD_FAB2_LIB.BASEBOARD_FAB2(SCH_1):PAGE57
   F61 M_G_MA<9> @BASEBOARD_FAB2_LIB.BASEBOARD_FAB2(SCH_1):M_G_MA(9)   I172 @BASEBOARD_FAB2_LIB.BASEBOARD_FAB2(SCH_1):PAGE57
   C60 M_G_MA<8> @BASEBOARD_FAB2_LIB.BASEBOARD_FAB2(SCH_1):M_G_MA(8)   I172 @BASEBOARD_FAB2_LIB.BASEBOARD_FAB2(SCH_1):PAGE57
   G60 M_G_MA<7> @BASEBOARD_FAB2_LIB.BASEBOARD_FAB2(SCH_1):M_G_MA(7)   I172 @BASEBOARD_FAB2_LIB.BASEBOARD_FAB2(SCH_1):PAGE57
   D59 M_G_MA<6> @BASEBOARD_FAB2_LIB.BASEBOARD_FAB2(SCH_1):M_G_MA(6)   I172 @BASEBOARD_FAB2_LIB.BASEBOARD_FAB2(SCH_1):PAGE57
   F59 M_G_MA<5> @BASEBOARD_FAB2_LIB.BASEBOARD_FAB2(SCH_1):M_G_MA(5)   I172 @BASEBOARD_FAB2_LIB.BASEBOARD_FAB2(SCH_1):PAGE57
   G58 M_G_MA<4> @BASEBOARD_FAB2_LIB.BASEBOARD_FAB2(SCH_1):M_G_MA(4)   I172 @BASEBOARD_FAB2_LIB.BASEBOARD_FAB2(SCH_1):PAGE57
   C58 M_G_MA<3> @BASEBOARD_FAB2_LIB.BASEBOARD_FAB2(SCH_1):M_G_MA(3)   I172 @BASEBOARD_FAB2_LIB.BASEBOARD_FAB2(SCH_1):PAGE57
   D57 M_G_MA<2> @BASEBOARD_FAB2_LIB.BASEBOARD_FAB2(SCH_1):M_G_MA(2)   I172 @BASEBOARD_FAB2_LIB.BASEBOARD_FAB2(SCH_1):PAGE57
   F57 M_G_MA<1> @BASEBOARD_FAB2_LIB.BASEBOARD_FAB2(SCH_1):M_G_MA(1)   I172 @BASEBOARD_FAB2_LIB.BASEBOARD_FAB2(SCH_1):PAGE57
   F53 M_G_MA<0> @BASEBOARD_FAB2_LIB.BASEBOARD_FAB2(SCH_1):M_G_MA(0)   I172 @BASEBOARD_FAB2_LIB.BASEBOARD_FAB2(SCH_1):PAGE57
   G48 M_G_ODT<3> @BASEBOARD_FAB2_LIB.BASEBOARD_FAB2(SCH_1):M_G_ODT(3)   I172 @BASEBOARD_FAB2_LIB.BASEBOARD_FAB2(SCH_1):PAGE57
   G50 M_G_ODT<2> @BASEBOARD_FAB2_LIB.BASEBOARD_FAB2(SCH_1):M_G_ODT(2)   I172 @BASEBOARD_FAB2_LIB.BASEBOARD_FAB2(SCH_1):PAGE57
   C48 M_G_ODT<1> @BASEBOARD_FAB2_LIB.BASEBOARD_FAB2(SCH_1):M_G_ODT(1)   I172 @BASEBOARD_FAB2_LIB.BASEBOARD_FAB2(SCH_1):PAGE57
   C50 M_G_ODT<0> @BASEBOARD_FAB2_LIB.BASEBOARD_FAB2(SCH_1):M_G_ODT(0)   I172 @BASEBOARD_FAB2_LIB.BASEBOARD_FAB2(SCH_1):PAGE57
   D53 M_G_PAR @BASEBOARD_FAB2_LIB.BASEBOARD_FAB2(SCH_1):M_G_PAR   I172 @BASEBOARD_FAB2_LIB.BASEBOARD_FAB2(SCH_1):PAGE57
   T63 M_H_ACT_N @BASEBOARD_FAB2_LIB.BASEBOARD_FAB2(SCH_1):M_H_ACT_N   I172 @BASEBOARD_FAB2_LIB.BASEBOARD_FAB2(SCH_1):PAGE58
   W62 M_H_ALERT_N @BASEBOARD_FAB2_LIB.BASEBOARD_FAB2(SCH_1):M_H_ALERT_N   I172 @BASEBOARD_FAB2_LIB.BASEBOARD_FAB2(SCH_1):PAGE58
   K55 M_H_BA<1> @BASEBOARD_FAB2_LIB.BASEBOARD_FAB2(SCH_1):M_H_BA(1)   I172 @BASEBOARD_FAB2_LIB.BASEBOARD_FAB2(SCH_1):PAGE58
   T53 M_H_BA<0> @BASEBOARD_FAB2_LIB.BASEBOARD_FAB2(SCH_1):M_H_BA(0)   I172 @BASEBOARD_FAB2_LIB.BASEBOARD_FAB2(SCH_1):PAGE58
   N60 M_H_BG<1> @BASEBOARD_FAB2_LIB.BASEBOARD_FAB2(SCH_1):M_H_BG(1)   I172 @BASEBOARD_FAB2_LIB.BASEBOARD_FAB2(SCH_1):PAGE58
   M61 M_H_BG<0> @BASEBOARD_FAB2_LIB.BASEBOARD_FAB2(SCH_1):M_H_BG(0)   I172 @BASEBOARD_FAB2_LIB.BASEBOARD_FAB2(SCH_1):PAGE58
   M47 M_H_C<2> @BASEBOARD_FAB2_LIB.BASEBOARD_FAB2(SCH_1):M_H_C(2)   I172 @BASEBOARD_FAB2_LIB.BASEBOARD_FAB2(SCH_1):PAGE58
   L64 M_H_CKE<3> @BASEBOARD_FAB2_LIB.BASEBOARD_FAB2(SCH_1):M_H_CKE(3)   I172 @BASEBOARD_FAB2_LIB.BASEBOARD_FAB2(SCH_1):PAGE58
   K63 M_H_CKE<2> @BASEBOARD_FAB2_LIB.BASEBOARD_FAB2(SCH_1):M_H_CKE(2)   I172 @BASEBOARD_FAB2_LIB.BASEBOARD_FAB2(SCH_1):PAGE58
   R64 M_H_CKE<1> @BASEBOARD_FAB2_LIB.BASEBOARD_FAB2(SCH_1):M_H_CKE(1)   I172 @BASEBOARD_FAB2_LIB.BASEBOARD_FAB2(SCH_1):PAGE58
   N62 M_H_CKE<0> @BASEBOARD_FAB2_LIB.BASEBOARD_FAB2(SCH_1):M_H_CKE(0)   I172 @BASEBOARD_FAB2_LIB.BASEBOARD_FAB2(SCH_1):PAGE58
   R56 M_H_CLK_DN<3> @BASEBOARD_FAB2_LIB.BASEBOARD_FAB2(SCH_1):M_H_CLK_DN(3)   I172 @BASEBOARD_FAB2_LIB.BASEBOARD_FAB2(SCH_1):PAGE58
   N56 M_H_CLK_DN<2> @BASEBOARD_FAB2_LIB.BASEBOARD_FAB2(SCH_1):M_H_CLK_DN(2)   I172 @BASEBOARD_FAB2_LIB.BASEBOARD_FAB2(SCH_1):PAGE58
   R54 M_H_CLK_DN<1> @BASEBOARD_FAB2_LIB.BASEBOARD_FAB2(SCH_1):M_H_CLK_DN(1)   I172 @BASEBOARD_FAB2_LIB.BASEBOARD_FAB2(SCH_1):PAGE58
   M53 M_H_CLK_DN<0> @BASEBOARD_FAB2_LIB.BASEBOARD_FAB2(SCH_1):M_H_CLK_DN(0)   I172 @BASEBOARD_FAB2_LIB.BASEBOARD_FAB2(SCH_1):PAGE58
   T57 M_H_CLK_DP<3> @BASEBOARD_FAB2_LIB.BASEBOARD_FAB2(SCH_1):M_H_CLK_DP(3)   I172 @BASEBOARD_FAB2_LIB.BASEBOARD_FAB2(SCH_1):PAGE58
   M57 M_H_CLK_DP<2> @BASEBOARD_FAB2_LIB.BASEBOARD_FAB2(SCH_1):M_H_CLK_DP(2)   I172 @BASEBOARD_FAB2_LIB.BASEBOARD_FAB2(SCH_1):PAGE58
   T55 M_H_CLK_DP<1> @BASEBOARD_FAB2_LIB.BASEBOARD_FAB2(SCH_1):M_H_CLK_DP(1)   I172 @BASEBOARD_FAB2_LIB.BASEBOARD_FAB2(SCH_1):PAGE58
   N54 M_H_CLK_DP<0> @BASEBOARD_FAB2_LIB.BASEBOARD_FAB2(SCH_1):M_H_CLK_DP(0)   I172 @BASEBOARD_FAB2_LIB.BASEBOARD_FAB2(SCH_1):PAGE58
   R46 M_H_CS_N<7> @BASEBOARD_FAB2_LIB.BASEBOARD_FAB2(SCH_1):M_H_CS_N(7)   I172 @BASEBOARD_FAB2_LIB.BASEBOARD_FAB2(SCH_1):PAGE58
   M45 M_H_CS_N<6> @BASEBOARD_FAB2_LIB.BASEBOARD_FAB2(SCH_1):M_H_CS_N(6)   I172 @BASEBOARD_FAB2_LIB.BASEBOARD_FAB2(SCH_1):PAGE58
   T49 M_H_CS_N<5> @BASEBOARD_FAB2_LIB.BASEBOARD_FAB2(SCH_1):M_H_CS_N(5)   I172 @BASEBOARD_FAB2_LIB.BASEBOARD_FAB2(SCH_1):PAGE58
   J50 M_H_CS_N<4> @BASEBOARD_FAB2_LIB.BASEBOARD_FAB2(SCH_1):M_H_CS_N(4)   I172 @BASEBOARD_FAB2_LIB.BASEBOARD_FAB2(SCH_1):PAGE58
   V47 M_H_CS_N<3> @BASEBOARD_FAB2_LIB.BASEBOARD_FAB2(SCH_1):M_H_CS_N(3)   I172 @BASEBOARD_FAB2_LIB.BASEBOARD_FAB2(SCH_1):PAGE58
   N46 M_H_CS_N<2> @BASEBOARD_FAB2_LIB.BASEBOARD_FAB2(SCH_1):M_H_CS_N(2)   I172 @BASEBOARD_FAB2_LIB.BASEBOARD_FAB2(SCH_1):PAGE58
   R50 M_H_CS_N<1> @BASEBOARD_FAB2_LIB.BASEBOARD_FAB2(SCH_1):M_H_CS_N(1)   I172 @BASEBOARD_FAB2_LIB.BASEBOARD_FAB2(SCH_1):PAGE58
   K51 M_H_CS_N<0> @BASEBOARD_FAB2_LIB.BASEBOARD_FAB2(SCH_1):M_H_CS_N(0)   I172 @BASEBOARD_FAB2_LIB.BASEBOARD_FAB2(SCH_1):PAGE58
  AA26 M_H_DQ<63> @BASEBOARD_FAB2_LIB.BASEBOARD_FAB2(SCH_1):M_H_DQ(63)   I172 @BASEBOARD_FAB2_LIB.BASEBOARD_FAB2(SCH_1):PAGE58
   U26 M_H_DQ<62> @BASEBOARD_FAB2_LIB.BASEBOARD_FAB2(SCH_1):M_H_DQ(62)   I172 @BASEBOARD_FAB2_LIB.BASEBOARD_FAB2(SCH_1):PAGE58
   Y29 M_H_DQ<61> @BASEBOARD_FAB2_LIB.BASEBOARD_FAB2(SCH_1):M_H_DQ(61)   I172 @BASEBOARD_FAB2_LIB.BASEBOARD_FAB2(SCH_1):PAGE58
   V29 M_H_DQ<60> @BASEBOARD_FAB2_LIB.BASEBOARD_FAB2(SCH_1):M_H_DQ(60)   I172 @BASEBOARD_FAB2_LIB.BASEBOARD_FAB2(SCH_1):PAGE58
   Y25 M_H_DQ<59> @BASEBOARD_FAB2_LIB.BASEBOARD_FAB2(SCH_1):M_H_DQ(59)   I172 @BASEBOARD_FAB2_LIB.BASEBOARD_FAB2(SCH_1):PAGE58
   V25 M_H_DQ<58> @BASEBOARD_FAB2_LIB.BASEBOARD_FAB2(SCH_1):M_H_DQ(58)   I172 @BASEBOARD_FAB2_LIB.BASEBOARD_FAB2(SCH_1):PAGE58
  AA28 M_H_DQ<57> @BASEBOARD_FAB2_LIB.BASEBOARD_FAB2(SCH_1):M_H_DQ(57)   I172 @BASEBOARD_FAB2_LIB.BASEBOARD_FAB2(SCH_1):PAGE58
   U28 M_H_DQ<56> @BASEBOARD_FAB2_LIB.BASEBOARD_FAB2(SCH_1):M_H_DQ(56)   I172 @BASEBOARD_FAB2_LIB.BASEBOARD_FAB2(SCH_1):PAGE58
   F27 M_H_DQ<55> @BASEBOARD_FAB2_LIB.BASEBOARD_FAB2(SCH_1):M_H_DQ(55)   I172 @BASEBOARD_FAB2_LIB.BASEBOARD_FAB2(SCH_1):PAGE58
   B27 M_H_DQ<54> @BASEBOARD_FAB2_LIB.BASEBOARD_FAB2(SCH_1):M_H_DQ(54)   I172 @BASEBOARD_FAB2_LIB.BASEBOARD_FAB2(SCH_1):PAGE58
   F29 M_H_DQ<53> @BASEBOARD_FAB2_LIB.BASEBOARD_FAB2(SCH_1):M_H_DQ(53)   I172 @BASEBOARD_FAB2_LIB.BASEBOARD_FAB2(SCH_1):PAGE58
   E30 M_H_DQ<52> @BASEBOARD_FAB2_LIB.BASEBOARD_FAB2(SCH_1):M_H_DQ(52)   I172 @BASEBOARD_FAB2_LIB.BASEBOARD_FAB2(SCH_1):PAGE58
   E26 M_H_DQ<51> @BASEBOARD_FAB2_LIB.BASEBOARD_FAB2(SCH_1):M_H_DQ(51)   I172 @BASEBOARD_FAB2_LIB.BASEBOARD_FAB2(SCH_1):PAGE58
   C26 M_H_DQ<50> @BASEBOARD_FAB2_LIB.BASEBOARD_FAB2(SCH_1):M_H_DQ(50)   I172 @BASEBOARD_FAB2_LIB.BASEBOARD_FAB2(SCH_1):PAGE58
   B29 M_H_DQ<49> @BASEBOARD_FAB2_LIB.BASEBOARD_FAB2(SCH_1):M_H_DQ(49)   I172 @BASEBOARD_FAB2_LIB.BASEBOARD_FAB2(SCH_1):PAGE58
   C30 M_H_DQ<48> @BASEBOARD_FAB2_LIB.BASEBOARD_FAB2(SCH_1):M_H_DQ(48)   I172 @BASEBOARD_FAB2_LIB.BASEBOARD_FAB2(SCH_1):PAGE58
   F33 M_H_DQ<47> @BASEBOARD_FAB2_LIB.BASEBOARD_FAB2(SCH_1):M_H_DQ(47)   I172 @BASEBOARD_FAB2_LIB.BASEBOARD_FAB2(SCH_1):PAGE58
   B33 M_H_DQ<46> @BASEBOARD_FAB2_LIB.BASEBOARD_FAB2(SCH_1):M_H_DQ(46)   I172 @BASEBOARD_FAB2_LIB.BASEBOARD_FAB2(SCH_1):PAGE58
   F35 M_H_DQ<45> @BASEBOARD_FAB2_LIB.BASEBOARD_FAB2(SCH_1):M_H_DQ(45)   I172 @BASEBOARD_FAB2_LIB.BASEBOARD_FAB2(SCH_1):PAGE58
   E36 M_H_DQ<44> @BASEBOARD_FAB2_LIB.BASEBOARD_FAB2(SCH_1):M_H_DQ(44)   I172 @BASEBOARD_FAB2_LIB.BASEBOARD_FAB2(SCH_1):PAGE58
   E32 M_H_DQ<43> @BASEBOARD_FAB2_LIB.BASEBOARD_FAB2(SCH_1):M_H_DQ(43)   I172 @BASEBOARD_FAB2_LIB.BASEBOARD_FAB2(SCH_1):PAGE58
   C32 M_H_DQ<42> @BASEBOARD_FAB2_LIB.BASEBOARD_FAB2(SCH_1):M_H_DQ(42)   I172 @BASEBOARD_FAB2_LIB.BASEBOARD_FAB2(SCH_1):PAGE58
   B35 M_H_DQ<41> @BASEBOARD_FAB2_LIB.BASEBOARD_FAB2(SCH_1):M_H_DQ(41)   I172 @BASEBOARD_FAB2_LIB.BASEBOARD_FAB2(SCH_1):PAGE58
   C36 M_H_DQ<40> @BASEBOARD_FAB2_LIB.BASEBOARD_FAB2(SCH_1):M_H_DQ(40)   I172 @BASEBOARD_FAB2_LIB.BASEBOARD_FAB2(SCH_1):PAGE58
   P41 M_H_DQ<39> @BASEBOARD_FAB2_LIB.BASEBOARD_FAB2(SCH_1):M_H_DQ(39)   I172 @BASEBOARD_FAB2_LIB.BASEBOARD_FAB2(SCH_1):PAGE58
   K41 M_H_DQ<38> @BASEBOARD_FAB2_LIB.BASEBOARD_FAB2(SCH_1):M_H_DQ(38)   I172 @BASEBOARD_FAB2_LIB.BASEBOARD_FAB2(SCH_1):PAGE58
   T43 M_H_DQ<37> @BASEBOARD_FAB2_LIB.BASEBOARD_FAB2(SCH_1):M_H_DQ(37)   I172 @BASEBOARD_FAB2_LIB.BASEBOARD_FAB2(SCH_1):PAGE58
   P43 M_H_DQ<36> @BASEBOARD_FAB2_LIB.BASEBOARD_FAB2(SCH_1):M_H_DQ(36)   I172 @BASEBOARD_FAB2_LIB.BASEBOARD_FAB2(SCH_1):PAGE58
   N40 M_H_DQ<35> @BASEBOARD_FAB2_LIB.BASEBOARD_FAB2(SCH_1):M_H_DQ(35)   I172 @BASEBOARD_FAB2_LIB.BASEBOARD_FAB2(SCH_1):PAGE58
   L40 M_H_DQ<34> @BASEBOARD_FAB2_LIB.BASEBOARD_FAB2(SCH_1):M_H_DQ(34)   I172 @BASEBOARD_FAB2_LIB.BASEBOARD_FAB2(SCH_1):PAGE58
   H43 M_H_DQ<33> @BASEBOARD_FAB2_LIB.BASEBOARD_FAB2(SCH_1):M_H_DQ(33)   I172 @BASEBOARD_FAB2_LIB.BASEBOARD_FAB2(SCH_1):PAGE58
   K43 M_H_DQ<32> @BASEBOARD_FAB2_LIB.BASEBOARD_FAB2(SCH_1):M_H_DQ(32)   I172 @BASEBOARD_FAB2_LIB.BASEBOARD_FAB2(SCH_1):PAGE58
   G72 M_H_DQ<31> @BASEBOARD_FAB2_LIB.BASEBOARD_FAB2(SCH_1):M_H_DQ(31)   I172 @BASEBOARD_FAB2_LIB.BASEBOARD_FAB2(SCH_1):PAGE58
   C72 M_H_DQ<30> @BASEBOARD_FAB2_LIB.BASEBOARD_FAB2(SCH_1):M_H_DQ(30)   I172 @BASEBOARD_FAB2_LIB.BASEBOARD_FAB2(SCH_1):PAGE58
   G74 M_H_DQ<29> @BASEBOARD_FAB2_LIB.BASEBOARD_FAB2(SCH_1):M_H_DQ(29)   I172 @BASEBOARD_FAB2_LIB.BASEBOARD_FAB2(SCH_1):PAGE58
   F75 M_H_DQ<28> @BASEBOARD_FAB2_LIB.BASEBOARD_FAB2(SCH_1):M_H_DQ(28)   I172 @BASEBOARD_FAB2_LIB.BASEBOARD_FAB2(SCH_1):PAGE58
   F71 M_H_DQ<27> @BASEBOARD_FAB2_LIB.BASEBOARD_FAB2(SCH_1):M_H_DQ(27)   I172 @BASEBOARD_FAB2_LIB.BASEBOARD_FAB2(SCH_1):PAGE58
   D71 M_H_DQ<26> @BASEBOARD_FAB2_LIB.BASEBOARD_FAB2(SCH_1):M_H_DQ(26)   I172 @BASEBOARD_FAB2_LIB.BASEBOARD_FAB2(SCH_1):PAGE58
   C74 M_H_DQ<25> @BASEBOARD_FAB2_LIB.BASEBOARD_FAB2(SCH_1):M_H_DQ(25)   I172 @BASEBOARD_FAB2_LIB.BASEBOARD_FAB2(SCH_1):PAGE58
   D75 M_H_DQ<24> @BASEBOARD_FAB2_LIB.BASEBOARD_FAB2(SCH_1):M_H_DQ(24)   I172 @BASEBOARD_FAB2_LIB.BASEBOARD_FAB2(SCH_1):PAGE58
   J78 M_H_DQ<23> @BASEBOARD_FAB2_LIB.BASEBOARD_FAB2(SCH_1):M_H_DQ(23)   I172 @BASEBOARD_FAB2_LIB.BASEBOARD_FAB2(SCH_1):PAGE58
   E78 M_H_DQ<22> @BASEBOARD_FAB2_LIB.BASEBOARD_FAB2(SCH_1):M_H_DQ(22)   I172 @BASEBOARD_FAB2_LIB.BASEBOARD_FAB2(SCH_1):PAGE58
   H81 M_H_DQ<21> @BASEBOARD_FAB2_LIB.BASEBOARD_FAB2(SCH_1):M_H_DQ(21)   I172 @BASEBOARD_FAB2_LIB.BASEBOARD_FAB2(SCH_1):PAGE58
   F81 M_H_DQ<20> @BASEBOARD_FAB2_LIB.BASEBOARD_FAB2(SCH_1):M_H_DQ(20)   I172 @BASEBOARD_FAB2_LIB.BASEBOARD_FAB2(SCH_1):PAGE58
   H77 M_H_DQ<19> @BASEBOARD_FAB2_LIB.BASEBOARD_FAB2(SCH_1):M_H_DQ(19)   I172 @BASEBOARD_FAB2_LIB.BASEBOARD_FAB2(SCH_1):PAGE58
   F77 M_H_DQ<18> @BASEBOARD_FAB2_LIB.BASEBOARD_FAB2(SCH_1):M_H_DQ(18)   I172 @BASEBOARD_FAB2_LIB.BASEBOARD_FAB2(SCH_1):PAGE58
   J80 M_H_DQ<17> @BASEBOARD_FAB2_LIB.BASEBOARD_FAB2(SCH_1):M_H_DQ(17)   I172 @BASEBOARD_FAB2_LIB.BASEBOARD_FAB2(SCH_1):PAGE58
   E80 M_H_DQ<16> @BASEBOARD_FAB2_LIB.BASEBOARD_FAB2(SCH_1):M_H_DQ(16)   I172 @BASEBOARD_FAB2_LIB.BASEBOARD_FAB2(SCH_1):PAGE58
  AC80 M_H_DQ<15> @BASEBOARD_FAB2_LIB.BASEBOARD_FAB2(SCH_1):M_H_DQ(15)   I172 @BASEBOARD_FAB2_LIB.BASEBOARD_FAB2(SCH_1):PAGE58
  AE82 M_H_DQ<14> @BASEBOARD_FAB2_LIB.BASEBOARD_FAB2(SCH_1):M_H_DQ(14)   I172 @BASEBOARD_FAB2_LIB.BASEBOARD_FAB2(SCH_1):PAGE58
  AH79 M_H_DQ<13> @BASEBOARD_FAB2_LIB.BASEBOARD_FAB2(SCH_1):M_H_DQ(13)   I172 @BASEBOARD_FAB2_LIB.BASEBOARD_FAB2(SCH_1):PAGE58
  AJ80 M_H_DQ<12> @BASEBOARD_FAB2_LIB.BASEBOARD_FAB2(SCH_1):M_H_DQ(12)   I172 @BASEBOARD_FAB2_LIB.BASEBOARD_FAB2(SCH_1):PAGE58
  AB81 M_H_DQ<11> @BASEBOARD_FAB2_LIB.BASEBOARD_FAB2(SCH_1):M_H_DQ(11)   I172 @BASEBOARD_FAB2_LIB.BASEBOARD_FAB2(SCH_1):PAGE58
  AC82 M_H_DQ<10> @BASEBOARD_FAB2_LIB.BASEBOARD_FAB2(SCH_1):M_H_DQ(10)   I172 @BASEBOARD_FAB2_LIB.BASEBOARD_FAB2(SCH_1):PAGE58
  AF79 M_H_DQ<9> @BASEBOARD_FAB2_LIB.BASEBOARD_FAB2(SCH_1):M_H_DQ(9)   I172 @BASEBOARD_FAB2_LIB.BASEBOARD_FAB2(SCH_1):PAGE58
  AH81 M_H_DQ<8> @BASEBOARD_FAB2_LIB.BASEBOARD_FAB2(SCH_1):M_H_DQ(8)   I172 @BASEBOARD_FAB2_LIB.BASEBOARD_FAB2(SCH_1):PAGE58
  AN80 M_H_DQ<7> @BASEBOARD_FAB2_LIB.BASEBOARD_FAB2(SCH_1):M_H_DQ(7)   I172 @BASEBOARD_FAB2_LIB.BASEBOARD_FAB2(SCH_1):PAGE58
  AR82 M_H_DQ<6> @BASEBOARD_FAB2_LIB.BASEBOARD_FAB2(SCH_1):M_H_DQ(6)   I172 @BASEBOARD_FAB2_LIB.BASEBOARD_FAB2(SCH_1):PAGE58
  AV79 M_H_DQ<5> @BASEBOARD_FAB2_LIB.BASEBOARD_FAB2(SCH_1):M_H_DQ(5)   I172 @BASEBOARD_FAB2_LIB.BASEBOARD_FAB2(SCH_1):PAGE58
  AW80 M_H_DQ<4> @BASEBOARD_FAB2_LIB.BASEBOARD_FAB2(SCH_1):M_H_DQ(4)   I172 @BASEBOARD_FAB2_LIB.BASEBOARD_FAB2(SCH_1):PAGE58
  AM81 M_H_DQ<3> @BASEBOARD_FAB2_LIB.BASEBOARD_FAB2(SCH_1):M_H_DQ(3)   I172 @BASEBOARD_FAB2_LIB.BASEBOARD_FAB2(SCH_1):PAGE58
  AN82 M_H_DQ<2> @BASEBOARD_FAB2_LIB.BASEBOARD_FAB2(SCH_1):M_H_DQ(2)   I172 @BASEBOARD_FAB2_LIB.BASEBOARD_FAB2(SCH_1):PAGE58
  AT79 M_H_DQ<1> @BASEBOARD_FAB2_LIB.BASEBOARD_FAB2(SCH_1):M_H_DQ(1)   I172 @BASEBOARD_FAB2_LIB.BASEBOARD_FAB2(SCH_1):PAGE58
  AV81 M_H_DQ<0> @BASEBOARD_FAB2_LIB.BASEBOARD_FAB2(SCH_1):M_H_DQ(0)   I172 @BASEBOARD_FAB2_LIB.BASEBOARD_FAB2(SCH_1):PAGE58
   G68 M_H_DQS_DN<17> @BASEBOARD_FAB2_LIB.BASEBOARD_FAB2(SCH_1):M_H_DQS_DN(17)   I172 @BASEBOARD_FAB2_LIB.BASEBOARD_FAB2(SCH_1):PAGE58
   T27 M_H_DQS_DN<16> @BASEBOARD_FAB2_LIB.BASEBOARD_FAB2(SCH_1):M_H_DQS_DN(16)   I172 @BASEBOARD_FAB2_LIB.BASEBOARD_FAB2(SCH_1):PAGE58
   A28 M_H_DQS_DN<15> @BASEBOARD_FAB2_LIB.BASEBOARD_FAB2(SCH_1):M_H_DQS_DN(15)   I172 @BASEBOARD_FAB2_LIB.BASEBOARD_FAB2(SCH_1):PAGE58
   A34 M_H_DQS_DN<14> @BASEBOARD_FAB2_LIB.BASEBOARD_FAB2(SCH_1):M_H_DQS_DN(14)   I172 @BASEBOARD_FAB2_LIB.BASEBOARD_FAB2(SCH_1):PAGE58
   J42 M_H_DQS_DN<13> @BASEBOARD_FAB2_LIB.BASEBOARD_FAB2(SCH_1):M_H_DQS_DN(13)   I172 @BASEBOARD_FAB2_LIB.BASEBOARD_FAB2(SCH_1):PAGE58
   B73 M_H_DQS_DN<12> @BASEBOARD_FAB2_LIB.BASEBOARD_FAB2(SCH_1):M_H_DQS_DN(12)   I172 @BASEBOARD_FAB2_LIB.BASEBOARD_FAB2(SCH_1):PAGE58
   D79 M_H_DQS_DN<11> @BASEBOARD_FAB2_LIB.BASEBOARD_FAB2(SCH_1):M_H_DQS_DN(11)   I172 @BASEBOARD_FAB2_LIB.BASEBOARD_FAB2(SCH_1):PAGE58
  AG82 M_H_DQS_DN<10> @BASEBOARD_FAB2_LIB.BASEBOARD_FAB2(SCH_1):M_H_DQS_DN(10)   I172 @BASEBOARD_FAB2_LIB.BASEBOARD_FAB2(SCH_1):PAGE58
  AU82 M_H_DQS_DN<9> @BASEBOARD_FAB2_LIB.BASEBOARD_FAB2(SCH_1):M_H_DQS_DN(9)   I172 @BASEBOARD_FAB2_LIB.BASEBOARD_FAB2(SCH_1):PAGE58
   N68 M_H_DQS_DN<8> @BASEBOARD_FAB2_LIB.BASEBOARD_FAB2(SCH_1):M_H_DQS_DN(8)   I172 @BASEBOARD_FAB2_LIB.BASEBOARD_FAB2(SCH_1):PAGE58
  AB27 M_H_DQS_DN<7> @BASEBOARD_FAB2_LIB.BASEBOARD_FAB2(SCH_1):M_H_DQS_DN(7)   I172 @BASEBOARD_FAB2_LIB.BASEBOARD_FAB2(SCH_1):PAGE58
   G28 M_H_DQS_DN<6> @BASEBOARD_FAB2_LIB.BASEBOARD_FAB2(SCH_1):M_H_DQS_DN(6)   I172 @BASEBOARD_FAB2_LIB.BASEBOARD_FAB2(SCH_1):PAGE58
   G34 M_H_DQS_DN<5> @BASEBOARD_FAB2_LIB.BASEBOARD_FAB2(SCH_1):M_H_DQS_DN(5)   I172 @BASEBOARD_FAB2_LIB.BASEBOARD_FAB2(SCH_1):PAGE58
   N42 M_H_DQS_DN<4> @BASEBOARD_FAB2_LIB.BASEBOARD_FAB2(SCH_1):M_H_DQS_DN(4)   I172 @BASEBOARD_FAB2_LIB.BASEBOARD_FAB2(SCH_1):PAGE58
   H73 M_H_DQS_DN<3> @BASEBOARD_FAB2_LIB.BASEBOARD_FAB2(SCH_1):M_H_DQS_DN(3)   I172 @BASEBOARD_FAB2_LIB.BASEBOARD_FAB2(SCH_1):PAGE58
   K79 M_H_DQS_DN<2> @BASEBOARD_FAB2_LIB.BASEBOARD_FAB2(SCH_1):M_H_DQS_DN(2)   I172 @BASEBOARD_FAB2_LIB.BASEBOARD_FAB2(SCH_1):PAGE58
  AD79 M_H_DQS_DN<1> @BASEBOARD_FAB2_LIB.BASEBOARD_FAB2(SCH_1):M_H_DQS_DN(1)   I172 @BASEBOARD_FAB2_LIB.BASEBOARD_FAB2(SCH_1):PAGE58
  AP79 M_H_DQS_DN<0> @BASEBOARD_FAB2_LIB.BASEBOARD_FAB2(SCH_1):M_H_DQS_DN(0)   I172 @BASEBOARD_FAB2_LIB.BASEBOARD_FAB2(SCH_1):PAGE58
   J68 M_H_DQS_DP<17> @BASEBOARD_FAB2_LIB.BASEBOARD_FAB2(SCH_1):M_H_DQS_DP(17)   I172 @BASEBOARD_FAB2_LIB.BASEBOARD_FAB2(SCH_1):PAGE58
   V27 M_H_DQS_DP<16> @BASEBOARD_FAB2_LIB.BASEBOARD_FAB2(SCH_1):M_H_DQS_DP(16)   I172 @BASEBOARD_FAB2_LIB.BASEBOARD_FAB2(SCH_1):PAGE58
   C28 M_H_DQS_DP<15> @BASEBOARD_FAB2_LIB.BASEBOARD_FAB2(SCH_1):M_H_DQS_DP(15)   I172 @BASEBOARD_FAB2_LIB.BASEBOARD_FAB2(SCH_1):PAGE58
   C34 M_H_DQS_DP<14> @BASEBOARD_FAB2_LIB.BASEBOARD_FAB2(SCH_1):M_H_DQS_DP(14)   I172 @BASEBOARD_FAB2_LIB.BASEBOARD_FAB2(SCH_1):PAGE58
   L42 M_H_DQS_DP<13> @BASEBOARD_FAB2_LIB.BASEBOARD_FAB2(SCH_1):M_H_DQS_DP(13)   I172 @BASEBOARD_FAB2_LIB.BASEBOARD_FAB2(SCH_1):PAGE58
   D73 M_H_DQS_DP<12> @BASEBOARD_FAB2_LIB.BASEBOARD_FAB2(SCH_1):M_H_DQS_DP(12)   I172 @BASEBOARD_FAB2_LIB.BASEBOARD_FAB2(SCH_1):PAGE58
   F79 M_H_DQS_DP<11> @BASEBOARD_FAB2_LIB.BASEBOARD_FAB2(SCH_1):M_H_DQS_DP(11)   I172 @BASEBOARD_FAB2_LIB.BASEBOARD_FAB2(SCH_1):PAGE58
  AF81 M_H_DQS_DP<10> @BASEBOARD_FAB2_LIB.BASEBOARD_FAB2(SCH_1):M_H_DQS_DP(10)   I172 @BASEBOARD_FAB2_LIB.BASEBOARD_FAB2(SCH_1):PAGE58
  AT81 M_H_DQS_DP<9> @BASEBOARD_FAB2_LIB.BASEBOARD_FAB2(SCH_1):M_H_DQS_DP(9)   I172 @BASEBOARD_FAB2_LIB.BASEBOARD_FAB2(SCH_1):PAGE58
   L68 M_H_DQS_DP<8> @BASEBOARD_FAB2_LIB.BASEBOARD_FAB2(SCH_1):M_H_DQS_DP(8)   I172 @BASEBOARD_FAB2_LIB.BASEBOARD_FAB2(SCH_1):PAGE58
   Y27 M_H_DQS_DP<7> @BASEBOARD_FAB2_LIB.BASEBOARD_FAB2(SCH_1):M_H_DQS_DP(7)   I172 @BASEBOARD_FAB2_LIB.BASEBOARD_FAB2(SCH_1):PAGE58
   E28 M_H_DQS_DP<6> @BASEBOARD_FAB2_LIB.BASEBOARD_FAB2(SCH_1):M_H_DQS_DP(6)   I172 @BASEBOARD_FAB2_LIB.BASEBOARD_FAB2(SCH_1):PAGE58
   E34 M_H_DQS_DP<5> @BASEBOARD_FAB2_LIB.BASEBOARD_FAB2(SCH_1):M_H_DQS_DP(5)   I172 @BASEBOARD_FAB2_LIB.BASEBOARD_FAB2(SCH_1):PAGE58
   R42 M_H_DQS_DP<4> @BASEBOARD_FAB2_LIB.BASEBOARD_FAB2(SCH_1):M_H_DQS_DP(4)   I172 @BASEBOARD_FAB2_LIB.BASEBOARD_FAB2(SCH_1):PAGE58
   F73 M_H_DQS_DP<3> @BASEBOARD_FAB2_LIB.BASEBOARD_FAB2(SCH_1):M_H_DQS_DP(3)   I172 @BASEBOARD_FAB2_LIB.BASEBOARD_FAB2(SCH_1):PAGE58
   H79 M_H_DQS_DP<2> @BASEBOARD_FAB2_LIB.BASEBOARD_FAB2(SCH_1):M_H_DQS_DP(2)   I172 @BASEBOARD_FAB2_LIB.BASEBOARD_FAB2(SCH_1):PAGE58
  AE80 M_H_DQS_DP<1> @BASEBOARD_FAB2_LIB.BASEBOARD_FAB2(SCH_1):M_H_DQS_DP(1)   I172 @BASEBOARD_FAB2_LIB.BASEBOARD_FAB2(SCH_1):PAGE58
  AR80 M_H_DQS_DP<0> @BASEBOARD_FAB2_LIB.BASEBOARD_FAB2(SCH_1):M_H_DQS_DP(0)   I172 @BASEBOARD_FAB2_LIB.BASEBOARD_FAB2(SCH_1):PAGE58
   M67 M_H_ECC<7> @BASEBOARD_FAB2_LIB.BASEBOARD_FAB2(SCH_1):M_H_ECC(7)   I172 @BASEBOARD_FAB2_LIB.BASEBOARD_FAB2(SCH_1):PAGE58
   H67 M_H_ECC<6> @BASEBOARD_FAB2_LIB.BASEBOARD_FAB2(SCH_1):M_H_ECC(6)   I172 @BASEBOARD_FAB2_LIB.BASEBOARD_FAB2(SCH_1):PAGE58
   M69 M_H_ECC<5> @BASEBOARD_FAB2_LIB.BASEBOARD_FAB2(SCH_1):M_H_ECC(5)   I172 @BASEBOARD_FAB2_LIB.BASEBOARD_FAB2(SCH_1):PAGE58
   L70 M_H_ECC<4> @BASEBOARD_FAB2_LIB.BASEBOARD_FAB2(SCH_1):M_H_ECC(4)   I172 @BASEBOARD_FAB2_LIB.BASEBOARD_FAB2(SCH_1):PAGE58
   L66 M_H_ECC<3> @BASEBOARD_FAB2_LIB.BASEBOARD_FAB2(SCH_1):M_H_ECC(3)   I172 @BASEBOARD_FAB2_LIB.BASEBOARD_FAB2(SCH_1):PAGE58
   J66 M_H_ECC<2> @BASEBOARD_FAB2_LIB.BASEBOARD_FAB2(SCH_1):M_H_ECC(2)   I172 @BASEBOARD_FAB2_LIB.BASEBOARD_FAB2(SCH_1):PAGE58
   H69 M_H_ECC<1> @BASEBOARD_FAB2_LIB.BASEBOARD_FAB2(SCH_1):M_H_ECC(1)   I172 @BASEBOARD_FAB2_LIB.BASEBOARD_FAB2(SCH_1):PAGE58
   J70 M_H_ECC<0> @BASEBOARD_FAB2_LIB.BASEBOARD_FAB2(SCH_1):M_H_ECC(0)   I172 @BASEBOARD_FAB2_LIB.BASEBOARD_FAB2(SCH_1):PAGE58
   N48 M_H_MA<17> @BASEBOARD_FAB2_LIB.BASEBOARD_FAB2(SCH_1):M_H_MA(17)   I172 @BASEBOARD_FAB2_LIB.BASEBOARD_FAB2(SCH_1):PAGE58
   R52 M_H_MA<16> @BASEBOARD_FAB2_LIB.BASEBOARD_FAB2(SCH_1):M_H_MA(16)   I172 @BASEBOARD_FAB2_LIB.BASEBOARD_FAB2(SCH_1):PAGE58
   N52 M_H_MA<15> @BASEBOARD_FAB2_LIB.BASEBOARD_FAB2(SCH_1):M_H_MA(15)   I172 @BASEBOARD_FAB2_LIB.BASEBOARD_FAB2(SCH_1):PAGE58
   T51 M_H_MA<14> @BASEBOARD_FAB2_LIB.BASEBOARD_FAB2(SCH_1):M_H_MA(14)   I172 @BASEBOARD_FAB2_LIB.BASEBOARD_FAB2(SCH_1):PAGE58
   M51 M_H_MA<13> @BASEBOARD_FAB2_LIB.BASEBOARD_FAB2(SCH_1):M_H_MA(13)   I172 @BASEBOARD_FAB2_LIB.BASEBOARD_FAB2(SCH_1):PAGE58
   T61 M_H_MA<12> @BASEBOARD_FAB2_LIB.BASEBOARD_FAB2(SCH_1):M_H_MA(12)   I172 @BASEBOARD_FAB2_LIB.BASEBOARD_FAB2(SCH_1):PAGE58
   R60 M_H_MA<11> @BASEBOARD_FAB2_LIB.BASEBOARD_FAB2(SCH_1):M_H_MA(11)   I172 @BASEBOARD_FAB2_LIB.BASEBOARD_FAB2(SCH_1):PAGE58
   M55 M_H_MA<10> @BASEBOARD_FAB2_LIB.BASEBOARD_FAB2(SCH_1):M_H_MA(10)   I172 @BASEBOARD_FAB2_LIB.BASEBOARD_FAB2(SCH_1):PAGE58
   K59 M_H_MA<9> @BASEBOARD_FAB2_LIB.BASEBOARD_FAB2(SCH_1):M_H_MA(9)   I172 @BASEBOARD_FAB2_LIB.BASEBOARD_FAB2(SCH_1):PAGE58
   W60 M_H_MA<8> @BASEBOARD_FAB2_LIB.BASEBOARD_FAB2(SCH_1):M_H_MA(8)   I172 @BASEBOARD_FAB2_LIB.BASEBOARD_FAB2(SCH_1):PAGE58
   V61 M_H_MA<7> @BASEBOARD_FAB2_LIB.BASEBOARD_FAB2(SCH_1):M_H_MA(7)   I172 @BASEBOARD_FAB2_LIB.BASEBOARD_FAB2(SCH_1):PAGE58
   T59 M_H_MA<6> @BASEBOARD_FAB2_LIB.BASEBOARD_FAB2(SCH_1):M_H_MA(6)   I172 @BASEBOARD_FAB2_LIB.BASEBOARD_FAB2(SCH_1):PAGE58
   R58 M_H_MA<5> @BASEBOARD_FAB2_LIB.BASEBOARD_FAB2(SCH_1):M_H_MA(5)   I172 @BASEBOARD_FAB2_LIB.BASEBOARD_FAB2(SCH_1):PAGE58
   M59 M_H_MA<4> @BASEBOARD_FAB2_LIB.BASEBOARD_FAB2(SCH_1):M_H_MA(4)   I172 @BASEBOARD_FAB2_LIB.BASEBOARD_FAB2(SCH_1):PAGE58
   N58 M_H_MA<3> @BASEBOARD_FAB2_LIB.BASEBOARD_FAB2(SCH_1):M_H_MA(3)   I172 @BASEBOARD_FAB2_LIB.BASEBOARD_FAB2(SCH_1):PAGE58
   K57 M_H_MA<2> @BASEBOARD_FAB2_LIB.BASEBOARD_FAB2(SCH_1):M_H_MA(2)   I172 @BASEBOARD_FAB2_LIB.BASEBOARD_FAB2(SCH_1):PAGE58
   J58 M_H_MA<1> @BASEBOARD_FAB2_LIB.BASEBOARD_FAB2(SCH_1):M_H_MA(1)   I172 @BASEBOARD_FAB2_LIB.BASEBOARD_FAB2(SCH_1):PAGE58
   J52 M_H_MA<0> @BASEBOARD_FAB2_LIB.BASEBOARD_FAB2(SCH_1):M_H_MA(0)   I172 @BASEBOARD_FAB2_LIB.BASEBOARD_FAB2(SCH_1):PAGE58
   T47 M_H_ODT<3> @BASEBOARD_FAB2_LIB.BASEBOARD_FAB2(SCH_1):M_H_ODT(3)   I172 @BASEBOARD_FAB2_LIB.BASEBOARD_FAB2(SCH_1):PAGE58
   M49 M_H_ODT<2> @BASEBOARD_FAB2_LIB.BASEBOARD_FAB2(SCH_1):M_H_ODT(2)   I172 @BASEBOARD_FAB2_LIB.BASEBOARD_FAB2(SCH_1):PAGE58
   R48 M_H_ODT<1> @BASEBOARD_FAB2_LIB.BASEBOARD_FAB2(SCH_1):M_H_ODT(1)   I172 @BASEBOARD_FAB2_LIB.BASEBOARD_FAB2(SCH_1):PAGE58
   N50 M_H_ODT<0> @BASEBOARD_FAB2_LIB.BASEBOARD_FAB2(SCH_1):M_H_ODT(0)   I172 @BASEBOARD_FAB2_LIB.BASEBOARD_FAB2(SCH_1):PAGE58
   K53 M_H_PAR @BASEBOARD_FAB2_LIB.BASEBOARD_FAB2(SCH_1):M_H_PAR   I172 @BASEBOARD_FAB2_LIB.BASEBOARD_FAB2(SCH_1):PAGE58
  AB61 M_J_ACT_N @BASEBOARD_FAB2_LIB.BASEBOARD_FAB2(SCH_1):M_J_ACT_N   I172 @BASEBOARD_FAB2_LIB.BASEBOARD_FAB2(SCH_1):PAGE59
  AD61 M_J_ALERT_N @BASEBOARD_FAB2_LIB.BASEBOARD_FAB2(SCH_1):M_J_ALERT_N   I172 @BASEBOARD_FAB2_LIB.BASEBOARD_FAB2(SCH_1):PAGE59
  AE56 M_J_BA<1> @BASEBOARD_FAB2_LIB.BASEBOARD_FAB2(SCH_1):M_J_BA(1)   I172 @BASEBOARD_FAB2_LIB.BASEBOARD_FAB2(SCH_1):PAGE59
   W52 M_J_BA<0> @BASEBOARD_FAB2_LIB.BASEBOARD_FAB2(SCH_1):M_J_BA(0)   I172 @BASEBOARD_FAB2_LIB.BASEBOARD_FAB2(SCH_1):PAGE59
  AE62 M_J_BG<1> @BASEBOARD_FAB2_LIB.BASEBOARD_FAB2(SCH_1):M_J_BG(1)   I172 @BASEBOARD_FAB2_LIB.BASEBOARD_FAB2(SCH_1):PAGE59
  AA60 M_J_BG<0> @BASEBOARD_FAB2_LIB.BASEBOARD_FAB2(SCH_1):M_J_BG(0)   I172 @BASEBOARD_FAB2_LIB.BASEBOARD_FAB2(SCH_1):PAGE59
  AB45 M_J_C<2> @BASEBOARD_FAB2_LIB.BASEBOARD_FAB2(SCH_1):M_J_C(2)   I172 @BASEBOARD_FAB2_LIB.BASEBOARD_FAB2(SCH_1):PAGE59
  AB63 M_J_CKE<3> @BASEBOARD_FAB2_LIB.BASEBOARD_FAB2(SCH_1):M_J_CKE(3)   I172 @BASEBOARD_FAB2_LIB.BASEBOARD_FAB2(SCH_1):PAGE59
   V63 M_J_CKE<2> @BASEBOARD_FAB2_LIB.BASEBOARD_FAB2(SCH_1):M_J_CKE(2)   I172 @BASEBOARD_FAB2_LIB.BASEBOARD_FAB2(SCH_1):PAGE59
  AD63 M_J_CKE<1> @BASEBOARD_FAB2_LIB.BASEBOARD_FAB2(SCH_1):M_J_CKE(1)   I172 @BASEBOARD_FAB2_LIB.BASEBOARD_FAB2(SCH_1):PAGE59
  AA62 M_J_CKE<0> @BASEBOARD_FAB2_LIB.BASEBOARD_FAB2(SCH_1):M_J_CKE(0)   I172 @BASEBOARD_FAB2_LIB.BASEBOARD_FAB2(SCH_1):PAGE59
   W56 M_J_CLK_DN<3> @BASEBOARD_FAB2_LIB.BASEBOARD_FAB2(SCH_1):M_J_CLK_DN(3)   I172 @BASEBOARD_FAB2_LIB.BASEBOARD_FAB2(SCH_1):PAGE59
  AA56 M_J_CLK_DN<2> @BASEBOARD_FAB2_LIB.BASEBOARD_FAB2(SCH_1):M_J_CLK_DN(2)   I172 @BASEBOARD_FAB2_LIB.BASEBOARD_FAB2(SCH_1):PAGE59
   W54 M_J_CLK_DN<1> @BASEBOARD_FAB2_LIB.BASEBOARD_FAB2(SCH_1):M_J_CLK_DN(1)   I172 @BASEBOARD_FAB2_LIB.BASEBOARD_FAB2(SCH_1):PAGE59
  AA54 M_J_CLK_DN<0> @BASEBOARD_FAB2_LIB.BASEBOARD_FAB2(SCH_1):M_J_CLK_DN(0)   I172 @BASEBOARD_FAB2_LIB.BASEBOARD_FAB2(SCH_1):PAGE59
   V57 M_J_CLK_DP<3> @BASEBOARD_FAB2_LIB.BASEBOARD_FAB2(SCH_1):M_J_CLK_DP(3)   I172 @BASEBOARD_FAB2_LIB.BASEBOARD_FAB2(SCH_1):PAGE59
  AB57 M_J_CLK_DP<2> @BASEBOARD_FAB2_LIB.BASEBOARD_FAB2(SCH_1):M_J_CLK_DP(2)   I172 @BASEBOARD_FAB2_LIB.BASEBOARD_FAB2(SCH_1):PAGE59
   V55 M_J_CLK_DP<1> @BASEBOARD_FAB2_LIB.BASEBOARD_FAB2(SCH_1):M_J_CLK_DP(1)   I172 @BASEBOARD_FAB2_LIB.BASEBOARD_FAB2(SCH_1):PAGE59
  AB55 M_J_CLK_DP<0> @BASEBOARD_FAB2_LIB.BASEBOARD_FAB2(SCH_1):M_J_CLK_DP(0)   I172 @BASEBOARD_FAB2_LIB.BASEBOARD_FAB2(SCH_1):PAGE59
   V45 M_J_CS_N<7> @BASEBOARD_FAB2_LIB.BASEBOARD_FAB2(SCH_1):M_J_CS_N(7)   I172 @BASEBOARD_FAB2_LIB.BASEBOARD_FAB2(SCH_1):PAGE59
   T45 M_J_CS_N<6> @BASEBOARD_FAB2_LIB.BASEBOARD_FAB2(SCH_1):M_J_CS_N(6)   I172 @BASEBOARD_FAB2_LIB.BASEBOARD_FAB2(SCH_1):PAGE59
   W48 M_J_CS_N<5> @BASEBOARD_FAB2_LIB.BASEBOARD_FAB2(SCH_1):M_J_CS_N(5)   I172 @BASEBOARD_FAB2_LIB.BASEBOARD_FAB2(SCH_1):PAGE59
  AB51 M_J_CS_N<4> @BASEBOARD_FAB2_LIB.BASEBOARD_FAB2(SCH_1):M_J_CS_N(4)   I172 @BASEBOARD_FAB2_LIB.BASEBOARD_FAB2(SCH_1):PAGE59
  AA46 M_J_CS_N<3> @BASEBOARD_FAB2_LIB.BASEBOARD_FAB2(SCH_1):M_J_CS_N(3)   I172 @BASEBOARD_FAB2_LIB.BASEBOARD_FAB2(SCH_1):PAGE59
   W46 M_J_CS_N<2> @BASEBOARD_FAB2_LIB.BASEBOARD_FAB2(SCH_1):M_J_CS_N(2)   I172 @BASEBOARD_FAB2_LIB.BASEBOARD_FAB2(SCH_1):PAGE59
  AB49 M_J_CS_N<1> @BASEBOARD_FAB2_LIB.BASEBOARD_FAB2(SCH_1):M_J_CS_N(1)   I172 @BASEBOARD_FAB2_LIB.BASEBOARD_FAB2(SCH_1):PAGE59
   V51 M_J_CS_N<0> @BASEBOARD_FAB2_LIB.BASEBOARD_FAB2(SCH_1):M_J_CS_N(0)   I172 @BASEBOARD_FAB2_LIB.BASEBOARD_FAB2(SCH_1):PAGE59
  AH23 M_J_DQ<63> @BASEBOARD_FAB2_LIB.BASEBOARD_FAB2(SCH_1):M_J_DQ(63)   I172 @BASEBOARD_FAB2_LIB.BASEBOARD_FAB2(SCH_1):PAGE59
  AD23 M_J_DQ<62> @BASEBOARD_FAB2_LIB.BASEBOARD_FAB2(SCH_1):M_J_DQ(62)   I172 @BASEBOARD_FAB2_LIB.BASEBOARD_FAB2(SCH_1):PAGE59
  AG26 M_J_DQ<61> @BASEBOARD_FAB2_LIB.BASEBOARD_FAB2(SCH_1):M_J_DQ(61)   I172 @BASEBOARD_FAB2_LIB.BASEBOARD_FAB2(SCH_1):PAGE59
  AE26 M_J_DQ<60> @BASEBOARD_FAB2_LIB.BASEBOARD_FAB2(SCH_1):M_J_DQ(60)   I172 @BASEBOARD_FAB2_LIB.BASEBOARD_FAB2(SCH_1):PAGE59
  AG22 M_J_DQ<59> @BASEBOARD_FAB2_LIB.BASEBOARD_FAB2(SCH_1):M_J_DQ(59)   I172 @BASEBOARD_FAB2_LIB.BASEBOARD_FAB2(SCH_1):PAGE59
  AE22 M_J_DQ<58> @BASEBOARD_FAB2_LIB.BASEBOARD_FAB2(SCH_1):M_J_DQ(58)   I172 @BASEBOARD_FAB2_LIB.BASEBOARD_FAB2(SCH_1):PAGE59
  AH25 M_J_DQ<57> @BASEBOARD_FAB2_LIB.BASEBOARD_FAB2(SCH_1):M_J_DQ(57)   I172 @BASEBOARD_FAB2_LIB.BASEBOARD_FAB2(SCH_1):PAGE59
  AD25 M_J_DQ<56> @BASEBOARD_FAB2_LIB.BASEBOARD_FAB2(SCH_1):M_J_DQ(56)   I172 @BASEBOARD_FAB2_LIB.BASEBOARD_FAB2(SCH_1):PAGE59
  AH29 M_J_DQ<55> @BASEBOARD_FAB2_LIB.BASEBOARD_FAB2(SCH_1):M_J_DQ(55)   I172 @BASEBOARD_FAB2_LIB.BASEBOARD_FAB2(SCH_1):PAGE59
  AD29 M_J_DQ<54> @BASEBOARD_FAB2_LIB.BASEBOARD_FAB2(SCH_1):M_J_DQ(54)   I172 @BASEBOARD_FAB2_LIB.BASEBOARD_FAB2(SCH_1):PAGE59
  AG32 M_J_DQ<53> @BASEBOARD_FAB2_LIB.BASEBOARD_FAB2(SCH_1):M_J_DQ(53)   I172 @BASEBOARD_FAB2_LIB.BASEBOARD_FAB2(SCH_1):PAGE59
  AE32 M_J_DQ<52> @BASEBOARD_FAB2_LIB.BASEBOARD_FAB2(SCH_1):M_J_DQ(52)   I172 @BASEBOARD_FAB2_LIB.BASEBOARD_FAB2(SCH_1):PAGE59
  AG28 M_J_DQ<51> @BASEBOARD_FAB2_LIB.BASEBOARD_FAB2(SCH_1):M_J_DQ(51)   I172 @BASEBOARD_FAB2_LIB.BASEBOARD_FAB2(SCH_1):PAGE59
  AE28 M_J_DQ<50> @BASEBOARD_FAB2_LIB.BASEBOARD_FAB2(SCH_1):M_J_DQ(50)   I172 @BASEBOARD_FAB2_LIB.BASEBOARD_FAB2(SCH_1):PAGE59
  AH31 M_J_DQ<49> @BASEBOARD_FAB2_LIB.BASEBOARD_FAB2(SCH_1):M_J_DQ(49)   I172 @BASEBOARD_FAB2_LIB.BASEBOARD_FAB2(SCH_1):PAGE59
  AD31 M_J_DQ<48> @BASEBOARD_FAB2_LIB.BASEBOARD_FAB2(SCH_1):M_J_DQ(48)   I172 @BASEBOARD_FAB2_LIB.BASEBOARD_FAB2(SCH_1):PAGE59
  AA32 M_J_DQ<47> @BASEBOARD_FAB2_LIB.BASEBOARD_FAB2(SCH_1):M_J_DQ(47)   I172 @BASEBOARD_FAB2_LIB.BASEBOARD_FAB2(SCH_1):PAGE59
   U32 M_J_DQ<46> @BASEBOARD_FAB2_LIB.BASEBOARD_FAB2(SCH_1):M_J_DQ(46)   I172 @BASEBOARD_FAB2_LIB.BASEBOARD_FAB2(SCH_1):PAGE59
   Y35 M_J_DQ<45> @BASEBOARD_FAB2_LIB.BASEBOARD_FAB2(SCH_1):M_J_DQ(45)   I172 @BASEBOARD_FAB2_LIB.BASEBOARD_FAB2(SCH_1):PAGE59
   V35 M_J_DQ<44> @BASEBOARD_FAB2_LIB.BASEBOARD_FAB2(SCH_1):M_J_DQ(44)   I172 @BASEBOARD_FAB2_LIB.BASEBOARD_FAB2(SCH_1):PAGE59
   Y31 M_J_DQ<43> @BASEBOARD_FAB2_LIB.BASEBOARD_FAB2(SCH_1):M_J_DQ(43)   I172 @BASEBOARD_FAB2_LIB.BASEBOARD_FAB2(SCH_1):PAGE59
   V31 M_J_DQ<42> @BASEBOARD_FAB2_LIB.BASEBOARD_FAB2(SCH_1):M_J_DQ(42)   I172 @BASEBOARD_FAB2_LIB.BASEBOARD_FAB2(SCH_1):PAGE59
  AA34 M_J_DQ<41> @BASEBOARD_FAB2_LIB.BASEBOARD_FAB2(SCH_1):M_J_DQ(41)   I172 @BASEBOARD_FAB2_LIB.BASEBOARD_FAB2(SCH_1):PAGE59
   U34 M_J_DQ<40> @BASEBOARD_FAB2_LIB.BASEBOARD_FAB2(SCH_1):M_J_DQ(40)   I172 @BASEBOARD_FAB2_LIB.BASEBOARD_FAB2(SCH_1):PAGE59
  AA38 M_J_DQ<39> @BASEBOARD_FAB2_LIB.BASEBOARD_FAB2(SCH_1):M_J_DQ(39)   I172 @BASEBOARD_FAB2_LIB.BASEBOARD_FAB2(SCH_1):PAGE59
   U38 M_J_DQ<38> @BASEBOARD_FAB2_LIB.BASEBOARD_FAB2(SCH_1):M_J_DQ(38)   I172 @BASEBOARD_FAB2_LIB.BASEBOARD_FAB2(SCH_1):PAGE59
   Y41 M_J_DQ<37> @BASEBOARD_FAB2_LIB.BASEBOARD_FAB2(SCH_1):M_J_DQ(37)   I172 @BASEBOARD_FAB2_LIB.BASEBOARD_FAB2(SCH_1):PAGE59
   V41 M_J_DQ<36> @BASEBOARD_FAB2_LIB.BASEBOARD_FAB2(SCH_1):M_J_DQ(36)   I172 @BASEBOARD_FAB2_LIB.BASEBOARD_FAB2(SCH_1):PAGE59
   Y37 M_J_DQ<35> @BASEBOARD_FAB2_LIB.BASEBOARD_FAB2(SCH_1):M_J_DQ(35)   I172 @BASEBOARD_FAB2_LIB.BASEBOARD_FAB2(SCH_1):PAGE59
   V37 M_J_DQ<34> @BASEBOARD_FAB2_LIB.BASEBOARD_FAB2(SCH_1):M_J_DQ(34)   I172 @BASEBOARD_FAB2_LIB.BASEBOARD_FAB2(SCH_1):PAGE59
  AA40 M_J_DQ<33> @BASEBOARD_FAB2_LIB.BASEBOARD_FAB2(SCH_1):M_J_DQ(33)   I172 @BASEBOARD_FAB2_LIB.BASEBOARD_FAB2(SCH_1):PAGE59
   U40 M_J_DQ<32> @BASEBOARD_FAB2_LIB.BASEBOARD_FAB2(SCH_1):M_J_DQ(32)   I172 @BASEBOARD_FAB2_LIB.BASEBOARD_FAB2(SCH_1):PAGE59
  AT65 M_J_DQ<31> @BASEBOARD_FAB2_LIB.BASEBOARD_FAB2(SCH_1):M_J_DQ(31)   I172 @BASEBOARD_FAB2_LIB.BASEBOARD_FAB2(SCH_1):PAGE59
  AM65 M_J_DQ<30> @BASEBOARD_FAB2_LIB.BASEBOARD_FAB2(SCH_1):M_J_DQ(30)   I172 @BASEBOARD_FAB2_LIB.BASEBOARD_FAB2(SCH_1):PAGE59
  AR68 M_J_DQ<29> @BASEBOARD_FAB2_LIB.BASEBOARD_FAB2(SCH_1):M_J_DQ(29)   I172 @BASEBOARD_FAB2_LIB.BASEBOARD_FAB2(SCH_1):PAGE59
  AN68 M_J_DQ<28> @BASEBOARD_FAB2_LIB.BASEBOARD_FAB2(SCH_1):M_J_DQ(28)   I172 @BASEBOARD_FAB2_LIB.BASEBOARD_FAB2(SCH_1):PAGE59
  AR64 M_J_DQ<27> @BASEBOARD_FAB2_LIB.BASEBOARD_FAB2(SCH_1):M_J_DQ(27)   I172 @BASEBOARD_FAB2_LIB.BASEBOARD_FAB2(SCH_1):PAGE59
  AN64 M_J_DQ<26> @BASEBOARD_FAB2_LIB.BASEBOARD_FAB2(SCH_1):M_J_DQ(26)   I172 @BASEBOARD_FAB2_LIB.BASEBOARD_FAB2(SCH_1):PAGE59
  AT67 M_J_DQ<25> @BASEBOARD_FAB2_LIB.BASEBOARD_FAB2(SCH_1):M_J_DQ(25)   I172 @BASEBOARD_FAB2_LIB.BASEBOARD_FAB2(SCH_1):PAGE59
  AM67 M_J_DQ<24> @BASEBOARD_FAB2_LIB.BASEBOARD_FAB2(SCH_1):M_J_DQ(24)   I172 @BASEBOARD_FAB2_LIB.BASEBOARD_FAB2(SCH_1):PAGE59
   V69 M_J_DQ<23> @BASEBOARD_FAB2_LIB.BASEBOARD_FAB2(SCH_1):M_J_DQ(23)   I172 @BASEBOARD_FAB2_LIB.BASEBOARD_FAB2(SCH_1):PAGE59
   T71 M_J_DQ<22> @BASEBOARD_FAB2_LIB.BASEBOARD_FAB2(SCH_1):M_J_DQ(22)   I172 @BASEBOARD_FAB2_LIB.BASEBOARD_FAB2(SCH_1):PAGE59
  AB71 M_J_DQ<21> @BASEBOARD_FAB2_LIB.BASEBOARD_FAB2(SCH_1):M_J_DQ(21)   I172 @BASEBOARD_FAB2_LIB.BASEBOARD_FAB2(SCH_1):PAGE59
  AA72 M_J_DQ<20> @BASEBOARD_FAB2_LIB.BASEBOARD_FAB2(SCH_1):M_J_DQ(20)   I172 @BASEBOARD_FAB2_LIB.BASEBOARD_FAB2(SCH_1):PAGE59
   T69 M_J_DQ<19> @BASEBOARD_FAB2_LIB.BASEBOARD_FAB2(SCH_1):M_J_DQ(19)   I172 @BASEBOARD_FAB2_LIB.BASEBOARD_FAB2(SCH_1):PAGE59
   R70 M_J_DQ<18> @BASEBOARD_FAB2_LIB.BASEBOARD_FAB2(SCH_1):M_J_DQ(18)   I172 @BASEBOARD_FAB2_LIB.BASEBOARD_FAB2(SCH_1):PAGE59
  AA70 M_J_DQ<17> @BASEBOARD_FAB2_LIB.BASEBOARD_FAB2(SCH_1):M_J_DQ(17)   I172 @BASEBOARD_FAB2_LIB.BASEBOARD_FAB2(SCH_1):PAGE59
   W72 M_J_DQ<16> @BASEBOARD_FAB2_LIB.BASEBOARD_FAB2(SCH_1):M_J_DQ(16)   I172 @BASEBOARD_FAB2_LIB.BASEBOARD_FAB2(SCH_1):PAGE59
   Y75 M_J_DQ<15> @BASEBOARD_FAB2_LIB.BASEBOARD_FAB2(SCH_1):M_J_DQ(15)   I172 @BASEBOARD_FAB2_LIB.BASEBOARD_FAB2(SCH_1):PAGE59
  AB77 M_J_DQ<14> @BASEBOARD_FAB2_LIB.BASEBOARD_FAB2(SCH_1):M_J_DQ(14)   I172 @BASEBOARD_FAB2_LIB.BASEBOARD_FAB2(SCH_1):PAGE59
  AE74 M_J_DQ<13> @BASEBOARD_FAB2_LIB.BASEBOARD_FAB2(SCH_1):M_J_DQ(13)   I172 @BASEBOARD_FAB2_LIB.BASEBOARD_FAB2(SCH_1):PAGE59
  AF75 M_J_DQ<12> @BASEBOARD_FAB2_LIB.BASEBOARD_FAB2(SCH_1):M_J_DQ(12)   I172 @BASEBOARD_FAB2_LIB.BASEBOARD_FAB2(SCH_1):PAGE59
   W76 M_J_DQ<11> @BASEBOARD_FAB2_LIB.BASEBOARD_FAB2(SCH_1):M_J_DQ(11)   I172 @BASEBOARD_FAB2_LIB.BASEBOARD_FAB2(SCH_1):PAGE59
   Y77 M_J_DQ<10> @BASEBOARD_FAB2_LIB.BASEBOARD_FAB2(SCH_1):M_J_DQ(10)   I172 @BASEBOARD_FAB2_LIB.BASEBOARD_FAB2(SCH_1):PAGE59
  AC74 M_J_DQ<9> @BASEBOARD_FAB2_LIB.BASEBOARD_FAB2(SCH_1):M_J_DQ(9)   I172 @BASEBOARD_FAB2_LIB.BASEBOARD_FAB2(SCH_1):PAGE59
  AE76 M_J_DQ<8> @BASEBOARD_FAB2_LIB.BASEBOARD_FAB2(SCH_1):M_J_DQ(8)   I172 @BASEBOARD_FAB2_LIB.BASEBOARD_FAB2(SCH_1):PAGE59
  AK75 M_J_DQ<7> @BASEBOARD_FAB2_LIB.BASEBOARD_FAB2(SCH_1):M_J_DQ(7)   I172 @BASEBOARD_FAB2_LIB.BASEBOARD_FAB2(SCH_1):PAGE59
  AM77 M_J_DQ<6> @BASEBOARD_FAB2_LIB.BASEBOARD_FAB2(SCH_1):M_J_DQ(6)   I172 @BASEBOARD_FAB2_LIB.BASEBOARD_FAB2(SCH_1):PAGE59
  AR74 M_J_DQ<5> @BASEBOARD_FAB2_LIB.BASEBOARD_FAB2(SCH_1):M_J_DQ(5)   I172 @BASEBOARD_FAB2_LIB.BASEBOARD_FAB2(SCH_1):PAGE59
  AT75 M_J_DQ<4> @BASEBOARD_FAB2_LIB.BASEBOARD_FAB2(SCH_1):M_J_DQ(4)   I172 @BASEBOARD_FAB2_LIB.BASEBOARD_FAB2(SCH_1):PAGE59
  AJ76 M_J_DQ<3> @BASEBOARD_FAB2_LIB.BASEBOARD_FAB2(SCH_1):M_J_DQ(3)   I172 @BASEBOARD_FAB2_LIB.BASEBOARD_FAB2(SCH_1):PAGE59
  AK77 M_J_DQ<2> @BASEBOARD_FAB2_LIB.BASEBOARD_FAB2(SCH_1):M_J_DQ(2)   I172 @BASEBOARD_FAB2_LIB.BASEBOARD_FAB2(SCH_1):PAGE59
  AN74 M_J_DQ<1> @BASEBOARD_FAB2_LIB.BASEBOARD_FAB2(SCH_1):M_J_DQ(1)   I172 @BASEBOARD_FAB2_LIB.BASEBOARD_FAB2(SCH_1):PAGE59
  AR76 M_J_DQ<0> @BASEBOARD_FAB2_LIB.BASEBOARD_FAB2(SCH_1):M_J_DQ(0)   I172 @BASEBOARD_FAB2_LIB.BASEBOARD_FAB2(SCH_1):PAGE59
  AT71 M_J_DQS_DN<17> @BASEBOARD_FAB2_LIB.BASEBOARD_FAB2(SCH_1):M_J_DQS_DN(17)   I172 @BASEBOARD_FAB2_LIB.BASEBOARD_FAB2(SCH_1):PAGE59
  AC24 M_J_DQS_DN<16> @BASEBOARD_FAB2_LIB.BASEBOARD_FAB2(SCH_1):M_J_DQS_DN(16)   I172 @BASEBOARD_FAB2_LIB.BASEBOARD_FAB2(SCH_1):PAGE59
  AC30 M_J_DQS_DN<15> @BASEBOARD_FAB2_LIB.BASEBOARD_FAB2(SCH_1):M_J_DQS_DN(15)   I172 @BASEBOARD_FAB2_LIB.BASEBOARD_FAB2(SCH_1):PAGE59
   T33 M_J_DQS_DN<14> @BASEBOARD_FAB2_LIB.BASEBOARD_FAB2(SCH_1):M_J_DQS_DN(14)   I172 @BASEBOARD_FAB2_LIB.BASEBOARD_FAB2(SCH_1):PAGE59
   T39 M_J_DQS_DN<13> @BASEBOARD_FAB2_LIB.BASEBOARD_FAB2(SCH_1):M_J_DQS_DN(13)   I172 @BASEBOARD_FAB2_LIB.BASEBOARD_FAB2(SCH_1):PAGE59
  AL66 M_J_DQS_DN<12> @BASEBOARD_FAB2_LIB.BASEBOARD_FAB2(SCH_1):M_J_DQS_DN(12)   I172 @BASEBOARD_FAB2_LIB.BASEBOARD_FAB2(SCH_1):PAGE59
   U72 M_J_DQS_DN<11> @BASEBOARD_FAB2_LIB.BASEBOARD_FAB2(SCH_1):M_J_DQS_DN(11)   I172 @BASEBOARD_FAB2_LIB.BASEBOARD_FAB2(SCH_1):PAGE59
  AD77 M_J_DQS_DN<10> @BASEBOARD_FAB2_LIB.BASEBOARD_FAB2(SCH_1):M_J_DQS_DN(10)   I172 @BASEBOARD_FAB2_LIB.BASEBOARD_FAB2(SCH_1):PAGE59
  AP77 M_J_DQS_DN<9> @BASEBOARD_FAB2_LIB.BASEBOARD_FAB2(SCH_1):M_J_DQS_DN(9)   I172 @BASEBOARD_FAB2_LIB.BASEBOARD_FAB2(SCH_1):PAGE59
  BB71 M_J_DQS_DN<8> @BASEBOARD_FAB2_LIB.BASEBOARD_FAB2(SCH_1):M_J_DQS_DN(8)   I172 @BASEBOARD_FAB2_LIB.BASEBOARD_FAB2(SCH_1):PAGE59
  AJ24 M_J_DQS_DN<7> @BASEBOARD_FAB2_LIB.BASEBOARD_FAB2(SCH_1):M_J_DQS_DN(7)   I172 @BASEBOARD_FAB2_LIB.BASEBOARD_FAB2(SCH_1):PAGE59
  AJ30 M_J_DQS_DN<6> @BASEBOARD_FAB2_LIB.BASEBOARD_FAB2(SCH_1):M_J_DQS_DN(6)   I172 @BASEBOARD_FAB2_LIB.BASEBOARD_FAB2(SCH_1):PAGE59
  AB33 M_J_DQS_DN<5> @BASEBOARD_FAB2_LIB.BASEBOARD_FAB2(SCH_1):M_J_DQS_DN(5)   I172 @BASEBOARD_FAB2_LIB.BASEBOARD_FAB2(SCH_1):PAGE59
  AB39 M_J_DQS_DN<4> @BASEBOARD_FAB2_LIB.BASEBOARD_FAB2(SCH_1):M_J_DQS_DN(4)   I172 @BASEBOARD_FAB2_LIB.BASEBOARD_FAB2(SCH_1):PAGE59
  AU66 M_J_DQS_DN<3> @BASEBOARD_FAB2_LIB.BASEBOARD_FAB2(SCH_1):M_J_DQS_DN(3)   I172 @BASEBOARD_FAB2_LIB.BASEBOARD_FAB2(SCH_1):PAGE59
   Y69 M_J_DQS_DN<2> @BASEBOARD_FAB2_LIB.BASEBOARD_FAB2(SCH_1):M_J_DQS_DN(2)   I172 @BASEBOARD_FAB2_LIB.BASEBOARD_FAB2(SCH_1):PAGE59
  AA74 M_J_DQS_DN<1> @BASEBOARD_FAB2_LIB.BASEBOARD_FAB2(SCH_1):M_J_DQS_DN(1)   I172 @BASEBOARD_FAB2_LIB.BASEBOARD_FAB2(SCH_1):PAGE59
  AL74 M_J_DQS_DN<0> @BASEBOARD_FAB2_LIB.BASEBOARD_FAB2(SCH_1):M_J_DQS_DN(0)   I172 @BASEBOARD_FAB2_LIB.BASEBOARD_FAB2(SCH_1):PAGE59
  AV71 M_J_DQS_DP<17> @BASEBOARD_FAB2_LIB.BASEBOARD_FAB2(SCH_1):M_J_DQS_DP(17)   I172 @BASEBOARD_FAB2_LIB.BASEBOARD_FAB2(SCH_1):PAGE59
  AE24 M_J_DQS_DP<16> @BASEBOARD_FAB2_LIB.BASEBOARD_FAB2(SCH_1):M_J_DQS_DP(16)   I172 @BASEBOARD_FAB2_LIB.BASEBOARD_FAB2(SCH_1):PAGE59
  AE30 M_J_DQS_DP<15> @BASEBOARD_FAB2_LIB.BASEBOARD_FAB2(SCH_1):M_J_DQS_DP(15)   I172 @BASEBOARD_FAB2_LIB.BASEBOARD_FAB2(SCH_1):PAGE59
   V33 M_J_DQS_DP<14> @BASEBOARD_FAB2_LIB.BASEBOARD_FAB2(SCH_1):M_J_DQS_DP(14)   I172 @BASEBOARD_FAB2_LIB.BASEBOARD_FAB2(SCH_1):PAGE59
   V39 M_J_DQS_DP<13> @BASEBOARD_FAB2_LIB.BASEBOARD_FAB2(SCH_1):M_J_DQS_DP(13)   I172 @BASEBOARD_FAB2_LIB.BASEBOARD_FAB2(SCH_1):PAGE59
  AN66 M_J_DQS_DP<12> @BASEBOARD_FAB2_LIB.BASEBOARD_FAB2(SCH_1):M_J_DQS_DP(12)   I172 @BASEBOARD_FAB2_LIB.BASEBOARD_FAB2(SCH_1):PAGE59
   V71 M_J_DQS_DP<11> @BASEBOARD_FAB2_LIB.BASEBOARD_FAB2(SCH_1):M_J_DQS_DP(11)   I172 @BASEBOARD_FAB2_LIB.BASEBOARD_FAB2(SCH_1):PAGE59
  AC76 M_J_DQS_DP<10> @BASEBOARD_FAB2_LIB.BASEBOARD_FAB2(SCH_1):M_J_DQS_DP(10)   I172 @BASEBOARD_FAB2_LIB.BASEBOARD_FAB2(SCH_1):PAGE59
  AN76 M_J_DQS_DP<9> @BASEBOARD_FAB2_LIB.BASEBOARD_FAB2(SCH_1):M_J_DQS_DP(9)   I172 @BASEBOARD_FAB2_LIB.BASEBOARD_FAB2(SCH_1):PAGE59
  AY71 M_J_DQS_DP<8> @BASEBOARD_FAB2_LIB.BASEBOARD_FAB2(SCH_1):M_J_DQS_DP(8)   I172 @BASEBOARD_FAB2_LIB.BASEBOARD_FAB2(SCH_1):PAGE59
  AG24 M_J_DQS_DP<7> @BASEBOARD_FAB2_LIB.BASEBOARD_FAB2(SCH_1):M_J_DQS_DP(7)   I172 @BASEBOARD_FAB2_LIB.BASEBOARD_FAB2(SCH_1):PAGE59
  AG30 M_J_DQS_DP<6> @BASEBOARD_FAB2_LIB.BASEBOARD_FAB2(SCH_1):M_J_DQS_DP(6)   I172 @BASEBOARD_FAB2_LIB.BASEBOARD_FAB2(SCH_1):PAGE59
   Y33 M_J_DQS_DP<5> @BASEBOARD_FAB2_LIB.BASEBOARD_FAB2(SCH_1):M_J_DQS_DP(5)   I172 @BASEBOARD_FAB2_LIB.BASEBOARD_FAB2(SCH_1):PAGE59
   Y39 M_J_DQS_DP<4> @BASEBOARD_FAB2_LIB.BASEBOARD_FAB2(SCH_1):M_J_DQS_DP(4)   I172 @BASEBOARD_FAB2_LIB.BASEBOARD_FAB2(SCH_1):PAGE59
  AR66 M_J_DQS_DP<3> @BASEBOARD_FAB2_LIB.BASEBOARD_FAB2(SCH_1):M_J_DQS_DP(3)   I172 @BASEBOARD_FAB2_LIB.BASEBOARD_FAB2(SCH_1):PAGE59
   W70 M_J_DQS_DP<2> @BASEBOARD_FAB2_LIB.BASEBOARD_FAB2(SCH_1):M_J_DQS_DP(2)   I172 @BASEBOARD_FAB2_LIB.BASEBOARD_FAB2(SCH_1):PAGE59
  AB75 M_J_DQS_DP<1> @BASEBOARD_FAB2_LIB.BASEBOARD_FAB2(SCH_1):M_J_DQS_DP(1)   I172 @BASEBOARD_FAB2_LIB.BASEBOARD_FAB2(SCH_1):PAGE59
  AM75 M_J_DQS_DP<0> @BASEBOARD_FAB2_LIB.BASEBOARD_FAB2(SCH_1):M_J_DQS_DP(0)   I172 @BASEBOARD_FAB2_LIB.BASEBOARD_FAB2(SCH_1):PAGE59
  BA70 M_J_ECC<7> @BASEBOARD_FAB2_LIB.BASEBOARD_FAB2(SCH_1):M_J_ECC(7)   I172 @BASEBOARD_FAB2_LIB.BASEBOARD_FAB2(SCH_1):PAGE59
  AU70 M_J_ECC<6> @BASEBOARD_FAB2_LIB.BASEBOARD_FAB2(SCH_1):M_J_ECC(6)   I172 @BASEBOARD_FAB2_LIB.BASEBOARD_FAB2(SCH_1):PAGE59
  AY73 M_J_ECC<5> @BASEBOARD_FAB2_LIB.BASEBOARD_FAB2(SCH_1):M_J_ECC(5)   I172 @BASEBOARD_FAB2_LIB.BASEBOARD_FAB2(SCH_1):PAGE59
  AV73 M_J_ECC<4> @BASEBOARD_FAB2_LIB.BASEBOARD_FAB2(SCH_1):M_J_ECC(4)   I172 @BASEBOARD_FAB2_LIB.BASEBOARD_FAB2(SCH_1):PAGE59
  AY69 M_J_ECC<3> @BASEBOARD_FAB2_LIB.BASEBOARD_FAB2(SCH_1):M_J_ECC(3)   I172 @BASEBOARD_FAB2_LIB.BASEBOARD_FAB2(SCH_1):PAGE59
  AV69 M_J_ECC<2> @BASEBOARD_FAB2_LIB.BASEBOARD_FAB2(SCH_1):M_J_ECC(2)   I172 @BASEBOARD_FAB2_LIB.BASEBOARD_FAB2(SCH_1):PAGE59
  BA72 M_J_ECC<1> @BASEBOARD_FAB2_LIB.BASEBOARD_FAB2(SCH_1):M_J_ECC(1)   I172 @BASEBOARD_FAB2_LIB.BASEBOARD_FAB2(SCH_1):PAGE59
  AU72 M_J_ECC<0> @BASEBOARD_FAB2_LIB.BASEBOARD_FAB2(SCH_1):M_J_ECC(0)   I172 @BASEBOARD_FAB2_LIB.BASEBOARD_FAB2(SCH_1):PAGE59
  AC46 M_J_MA<17> @BASEBOARD_FAB2_LIB.BASEBOARD_FAB2(SCH_1):M_J_MA(17)   I172 @BASEBOARD_FAB2_LIB.BASEBOARD_FAB2(SCH_1):PAGE59
  AA52 M_J_MA<16> @BASEBOARD_FAB2_LIB.BASEBOARD_FAB2(SCH_1):M_J_MA(16)   I172 @BASEBOARD_FAB2_LIB.BASEBOARD_FAB2(SCH_1):PAGE59
  AE54 M_J_MA<15> @BASEBOARD_FAB2_LIB.BASEBOARD_FAB2(SCH_1):M_J_MA(15)   I172 @BASEBOARD_FAB2_LIB.BASEBOARD_FAB2(SCH_1):PAGE59
   W50 M_J_MA<14> @BASEBOARD_FAB2_LIB.BASEBOARD_FAB2(SCH_1):M_J_MA(14)   I172 @BASEBOARD_FAB2_LIB.BASEBOARD_FAB2(SCH_1):PAGE59
  AD53 M_J_MA<13> @BASEBOARD_FAB2_LIB.BASEBOARD_FAB2(SCH_1):M_J_MA(13)   I172 @BASEBOARD_FAB2_LIB.BASEBOARD_FAB2(SCH_1):PAGE59
  AG62 M_J_MA<12> @BASEBOARD_FAB2_LIB.BASEBOARD_FAB2(SCH_1):M_J_MA(12)   I172 @BASEBOARD_FAB2_LIB.BASEBOARD_FAB2(SCH_1):PAGE59
  AG60 M_J_MA<11> @BASEBOARD_FAB2_LIB.BASEBOARD_FAB2(SCH_1):M_J_MA(11)   I172 @BASEBOARD_FAB2_LIB.BASEBOARD_FAB2(SCH_1):PAGE59
  AD55 M_J_MA<10> @BASEBOARD_FAB2_LIB.BASEBOARD_FAB2(SCH_1):M_J_MA(10)   I172 @BASEBOARD_FAB2_LIB.BASEBOARD_FAB2(SCH_1):PAGE59
  AG58 M_J_MA<9> @BASEBOARD_FAB2_LIB.BASEBOARD_FAB2(SCH_1):M_J_MA(9)   I172 @BASEBOARD_FAB2_LIB.BASEBOARD_FAB2(SCH_1):PAGE59
  AD59 M_J_MA<8> @BASEBOARD_FAB2_LIB.BASEBOARD_FAB2(SCH_1):M_J_MA(8)   I172 @BASEBOARD_FAB2_LIB.BASEBOARD_FAB2(SCH_1):PAGE59
  AE60 M_J_MA<7> @BASEBOARD_FAB2_LIB.BASEBOARD_FAB2(SCH_1):M_J_MA(7)   I172 @BASEBOARD_FAB2_LIB.BASEBOARD_FAB2(SCH_1):PAGE59
  AB59 M_J_MA<6> @BASEBOARD_FAB2_LIB.BASEBOARD_FAB2(SCH_1):M_J_MA(6)   I172 @BASEBOARD_FAB2_LIB.BASEBOARD_FAB2(SCH_1):PAGE59
   V59 M_J_MA<5> @BASEBOARD_FAB2_LIB.BASEBOARD_FAB2(SCH_1):M_J_MA(5)   I172 @BASEBOARD_FAB2_LIB.BASEBOARD_FAB2(SCH_1):PAGE59
  AA58 M_J_MA<4> @BASEBOARD_FAB2_LIB.BASEBOARD_FAB2(SCH_1):M_J_MA(4)   I172 @BASEBOARD_FAB2_LIB.BASEBOARD_FAB2(SCH_1):PAGE59
   W58 M_J_MA<3> @BASEBOARD_FAB2_LIB.BASEBOARD_FAB2(SCH_1):M_J_MA(3)   I172 @BASEBOARD_FAB2_LIB.BASEBOARD_FAB2(SCH_1):PAGE59
  AD57 M_J_MA<2> @BASEBOARD_FAB2_LIB.BASEBOARD_FAB2(SCH_1):M_J_MA(2)   I172 @BASEBOARD_FAB2_LIB.BASEBOARD_FAB2(SCH_1):PAGE59
  AE58 M_J_MA<1> @BASEBOARD_FAB2_LIB.BASEBOARD_FAB2(SCH_1):M_J_MA(1)   I172 @BASEBOARD_FAB2_LIB.BASEBOARD_FAB2(SCH_1):PAGE59
  AB53 M_J_MA<0> @BASEBOARD_FAB2_LIB.BASEBOARD_FAB2(SCH_1):M_J_MA(0)   I172 @BASEBOARD_FAB2_LIB.BASEBOARD_FAB2(SCH_1):PAGE59
  AB47 M_J_ODT<3> @BASEBOARD_FAB2_LIB.BASEBOARD_FAB2(SCH_1):M_J_ODT(3)   I172 @BASEBOARD_FAB2_LIB.BASEBOARD_FAB2(SCH_1):PAGE59
   V49 M_J_ODT<2> @BASEBOARD_FAB2_LIB.BASEBOARD_FAB2(SCH_1):M_J_ODT(2)   I172 @BASEBOARD_FAB2_LIB.BASEBOARD_FAB2(SCH_1):PAGE59
  AA48 M_J_ODT<1> @BASEBOARD_FAB2_LIB.BASEBOARD_FAB2(SCH_1):M_J_ODT(1)   I172 @BASEBOARD_FAB2_LIB.BASEBOARD_FAB2(SCH_1):PAGE59
  AA50 M_J_ODT<0> @BASEBOARD_FAB2_LIB.BASEBOARD_FAB2(SCH_1):M_J_ODT(0)   I172 @BASEBOARD_FAB2_LIB.BASEBOARD_FAB2(SCH_1):PAGE59
   V53 M_J_PAR @BASEBOARD_FAB2_LIB.BASEBOARD_FAB2(SCH_1):M_J_PAR   I172 @BASEBOARD_FAB2_LIB.BASEBOARD_FAB2(SCH_1):PAGE59
  DW60 M_K_ACT_N @BASEBOARD_FAB2_LIB.BASEBOARD_FAB2(SCH_1):M_K_ACT_N   I172 @BASEBOARD_FAB2_LIB.BASEBOARD_FAB2(SCH_1):PAGE60
  ED63 M_K_ALERT_N @BASEBOARD_FAB2_LIB.BASEBOARD_FAB2(SCH_1):M_K_ALERT_N   I172 @BASEBOARD_FAB2_LIB.BASEBOARD_FAB2(SCH_1):PAGE60
  EA54 M_K_BA<1> @BASEBOARD_FAB2_LIB.BASEBOARD_FAB2(SCH_1):M_K_BA(1)   I172 @BASEBOARD_FAB2_LIB.BASEBOARD_FAB2(SCH_1):PAGE60
  EE52 M_K_BA<0> @BASEBOARD_FAB2_LIB.BASEBOARD_FAB2(SCH_1):M_K_BA(0)   I172 @BASEBOARD_FAB2_LIB.BASEBOARD_FAB2(SCH_1):PAGE60
  DW62 M_K_BG<1> @BASEBOARD_FAB2_LIB.BASEBOARD_FAB2(SCH_1):M_K_BG(1)   I172 @BASEBOARD_FAB2_LIB.BASEBOARD_FAB2(SCH_1):PAGE60
  ED61 M_K_BG<0> @BASEBOARD_FAB2_LIB.BASEBOARD_FAB2(SCH_1):M_K_BG(0)   I172 @BASEBOARD_FAB2_LIB.BASEBOARD_FAB2(SCH_1):PAGE60
  DV47 M_K_C<2> @BASEBOARD_FAB2_LIB.BASEBOARD_FAB2(SCH_1):M_K_C(2)   I172 @BASEBOARD_FAB2_LIB.BASEBOARD_FAB2(SCH_1):PAGE60
  EB63 M_K_CKE<3> @BASEBOARD_FAB2_LIB.BASEBOARD_FAB2(SCH_1):M_K_CKE(3)   I172 @BASEBOARD_FAB2_LIB.BASEBOARD_FAB2(SCH_1):PAGE60
  EA62 M_K_CKE<2> @BASEBOARD_FAB2_LIB.BASEBOARD_FAB2(SCH_1):M_K_CKE(2)   I172 @BASEBOARD_FAB2_LIB.BASEBOARD_FAB2(SCH_1):PAGE60
  EF63 M_K_CKE<1> @BASEBOARD_FAB2_LIB.BASEBOARD_FAB2(SCH_1):M_K_CKE(1)   I172 @BASEBOARD_FAB2_LIB.BASEBOARD_FAB2(SCH_1):PAGE60
  EE62 M_K_CKE<0> @BASEBOARD_FAB2_LIB.BASEBOARD_FAB2(SCH_1):M_K_CKE(0)   I172 @BASEBOARD_FAB2_LIB.BASEBOARD_FAB2(SCH_1):PAGE60
  EF57 M_K_CLK_DN<3> @BASEBOARD_FAB2_LIB.BASEBOARD_FAB2(SCH_1):M_K_CLK_DN(3)   I172 @BASEBOARD_FAB2_LIB.BASEBOARD_FAB2(SCH_1):PAGE60
  DW56 M_K_CLK_DN<2> @BASEBOARD_FAB2_LIB.BASEBOARD_FAB2(SCH_1):M_K_CLK_DN(2)   I172 @BASEBOARD_FAB2_LIB.BASEBOARD_FAB2(SCH_1):PAGE60
  EF55 M_K_CLK_DN<1> @BASEBOARD_FAB2_LIB.BASEBOARD_FAB2(SCH_1):M_K_CLK_DN(1)   I172 @BASEBOARD_FAB2_LIB.BASEBOARD_FAB2(SCH_1):PAGE60
  ED55 M_K_CLK_DN<0> @BASEBOARD_FAB2_LIB.BASEBOARD_FAB2(SCH_1):M_K_CLK_DN(0)   I172 @BASEBOARD_FAB2_LIB.BASEBOARD_FAB2(SCH_1):PAGE60
  EE56 M_K_CLK_DP<3> @BASEBOARD_FAB2_LIB.BASEBOARD_FAB2(SCH_1):M_K_CLK_DP(3)   I172 @BASEBOARD_FAB2_LIB.BASEBOARD_FAB2(SCH_1):PAGE60
  EA56 M_K_CLK_DP<2> @BASEBOARD_FAB2_LIB.BASEBOARD_FAB2(SCH_1):M_K_CLK_DP(2)   I172 @BASEBOARD_FAB2_LIB.BASEBOARD_FAB2(SCH_1):PAGE60
  EE54 M_K_CLK_DP<1> @BASEBOARD_FAB2_LIB.BASEBOARD_FAB2(SCH_1):M_K_CLK_DP(1)   I172 @BASEBOARD_FAB2_LIB.BASEBOARD_FAB2(SCH_1):PAGE60
  EB55 M_K_CLK_DP<0> @BASEBOARD_FAB2_LIB.BASEBOARD_FAB2(SCH_1):M_K_CLK_DP(0)   I172 @BASEBOARD_FAB2_LIB.BASEBOARD_FAB2(SCH_1):PAGE60
  EB45 M_K_CS_N<7> @BASEBOARD_FAB2_LIB.BASEBOARD_FAB2(SCH_1):M_K_CS_N(7)   I172 @BASEBOARD_FAB2_LIB.BASEBOARD_FAB2(SCH_1):PAGE60
  DV45 M_K_CS_N<6> @BASEBOARD_FAB2_LIB.BASEBOARD_FAB2(SCH_1):M_K_CS_N(6)   I172 @BASEBOARD_FAB2_LIB.BASEBOARD_FAB2(SCH_1):PAGE60
  EB49 M_K_CS_N<5> @BASEBOARD_FAB2_LIB.BASEBOARD_FAB2(SCH_1):M_K_CS_N(5)   I172 @BASEBOARD_FAB2_LIB.BASEBOARD_FAB2(SCH_1):PAGE60
  EB51 M_K_CS_N<4> @BASEBOARD_FAB2_LIB.BASEBOARD_FAB2(SCH_1):M_K_CS_N(4)   I172 @BASEBOARD_FAB2_LIB.BASEBOARD_FAB2(SCH_1):PAGE60
  EB47 M_K_CS_N<3> @BASEBOARD_FAB2_LIB.BASEBOARD_FAB2(SCH_1):M_K_CS_N(3)   I172 @BASEBOARD_FAB2_LIB.BASEBOARD_FAB2(SCH_1):PAGE60
  ED47 M_K_CS_N<2> @BASEBOARD_FAB2_LIB.BASEBOARD_FAB2(SCH_1):M_K_CS_N(2)   I172 @BASEBOARD_FAB2_LIB.BASEBOARD_FAB2(SCH_1):PAGE60
  ED49 M_K_CS_N<1> @BASEBOARD_FAB2_LIB.BASEBOARD_FAB2(SCH_1):M_K_CS_N(1)   I172 @BASEBOARD_FAB2_LIB.BASEBOARD_FAB2(SCH_1):PAGE60
  EF51 M_K_CS_N<0> @BASEBOARD_FAB2_LIB.BASEBOARD_FAB2(SCH_1):M_K_CS_N(0)   I172 @BASEBOARD_FAB2_LIB.BASEBOARD_FAB2(SCH_1):PAGE60
  DW22 M_K_DQ<63> @BASEBOARD_FAB2_LIB.BASEBOARD_FAB2(SCH_1):M_K_DQ(63)   I172 @BASEBOARD_FAB2_LIB.BASEBOARD_FAB2(SCH_1):PAGE60
  EC22 M_K_DQ<62> @BASEBOARD_FAB2_LIB.BASEBOARD_FAB2(SCH_1):M_K_DQ(62)   I172 @BASEBOARD_FAB2_LIB.BASEBOARD_FAB2(SCH_1):PAGE60
  DT25 M_K_DQ<61> @BASEBOARD_FAB2_LIB.BASEBOARD_FAB2(SCH_1):M_K_DQ(61)   I172 @BASEBOARD_FAB2_LIB.BASEBOARD_FAB2(SCH_1):PAGE60
  DP25 M_K_DQ<60> @BASEBOARD_FAB2_LIB.BASEBOARD_FAB2(SCH_1):M_K_DQ(60)   I172 @BASEBOARD_FAB2_LIB.BASEBOARD_FAB2(SCH_1):PAGE60
  EB21 M_K_DQ<59> @BASEBOARD_FAB2_LIB.BASEBOARD_FAB2(SCH_1):M_K_DQ(59)   I172 @BASEBOARD_FAB2_LIB.BASEBOARD_FAB2(SCH_1):PAGE60
  DY21 M_K_DQ<58> @BASEBOARD_FAB2_LIB.BASEBOARD_FAB2(SCH_1):M_K_DQ(58)   I172 @BASEBOARD_FAB2_LIB.BASEBOARD_FAB2(SCH_1):PAGE60
  DU24 M_K_DQ<57> @BASEBOARD_FAB2_LIB.BASEBOARD_FAB2(SCH_1):M_K_DQ(57)   I172 @BASEBOARD_FAB2_LIB.BASEBOARD_FAB2(SCH_1):PAGE60
  DN24 M_K_DQ<56> @BASEBOARD_FAB2_LIB.BASEBOARD_FAB2(SCH_1):M_K_DQ(56)   I172 @BASEBOARD_FAB2_LIB.BASEBOARD_FAB2(SCH_1):PAGE60
  DU28 M_K_DQ<55> @BASEBOARD_FAB2_LIB.BASEBOARD_FAB2(SCH_1):M_K_DQ(55)   I172 @BASEBOARD_FAB2_LIB.BASEBOARD_FAB2(SCH_1):PAGE60
  DN28 M_K_DQ<54> @BASEBOARD_FAB2_LIB.BASEBOARD_FAB2(SCH_1):M_K_DQ(54)   I172 @BASEBOARD_FAB2_LIB.BASEBOARD_FAB2(SCH_1):PAGE60
  DT31 M_K_DQ<53> @BASEBOARD_FAB2_LIB.BASEBOARD_FAB2(SCH_1):M_K_DQ(53)   I172 @BASEBOARD_FAB2_LIB.BASEBOARD_FAB2(SCH_1):PAGE60
  DP31 M_K_DQ<52> @BASEBOARD_FAB2_LIB.BASEBOARD_FAB2(SCH_1):M_K_DQ(52)   I172 @BASEBOARD_FAB2_LIB.BASEBOARD_FAB2(SCH_1):PAGE60
  DT27 M_K_DQ<51> @BASEBOARD_FAB2_LIB.BASEBOARD_FAB2(SCH_1):M_K_DQ(51)   I172 @BASEBOARD_FAB2_LIB.BASEBOARD_FAB2(SCH_1):PAGE60
  DP27 M_K_DQ<50> @BASEBOARD_FAB2_LIB.BASEBOARD_FAB2(SCH_1):M_K_DQ(50)   I172 @BASEBOARD_FAB2_LIB.BASEBOARD_FAB2(SCH_1):PAGE60
  DU30 M_K_DQ<49> @BASEBOARD_FAB2_LIB.BASEBOARD_FAB2(SCH_1):M_K_DQ(49)   I172 @BASEBOARD_FAB2_LIB.BASEBOARD_FAB2(SCH_1):PAGE60
  DN30 M_K_DQ<48> @BASEBOARD_FAB2_LIB.BASEBOARD_FAB2(SCH_1):M_K_DQ(48)   I172 @BASEBOARD_FAB2_LIB.BASEBOARD_FAB2(SCH_1):PAGE60
  DU34 M_K_DQ<47> @BASEBOARD_FAB2_LIB.BASEBOARD_FAB2(SCH_1):M_K_DQ(47)   I172 @BASEBOARD_FAB2_LIB.BASEBOARD_FAB2(SCH_1):PAGE60
  DN34 M_K_DQ<46> @BASEBOARD_FAB2_LIB.BASEBOARD_FAB2(SCH_1):M_K_DQ(46)   I172 @BASEBOARD_FAB2_LIB.BASEBOARD_FAB2(SCH_1):PAGE60
  DT37 M_K_DQ<45> @BASEBOARD_FAB2_LIB.BASEBOARD_FAB2(SCH_1):M_K_DQ(45)   I172 @BASEBOARD_FAB2_LIB.BASEBOARD_FAB2(SCH_1):PAGE60
  DP37 M_K_DQ<44> @BASEBOARD_FAB2_LIB.BASEBOARD_FAB2(SCH_1):M_K_DQ(44)   I172 @BASEBOARD_FAB2_LIB.BASEBOARD_FAB2(SCH_1):PAGE60
  DT33 M_K_DQ<43> @BASEBOARD_FAB2_LIB.BASEBOARD_FAB2(SCH_1):M_K_DQ(43)   I172 @BASEBOARD_FAB2_LIB.BASEBOARD_FAB2(SCH_1):PAGE60
  DP33 M_K_DQ<42> @BASEBOARD_FAB2_LIB.BASEBOARD_FAB2(SCH_1):M_K_DQ(42)   I172 @BASEBOARD_FAB2_LIB.BASEBOARD_FAB2(SCH_1):PAGE60
  DU36 M_K_DQ<41> @BASEBOARD_FAB2_LIB.BASEBOARD_FAB2(SCH_1):M_K_DQ(41)   I172 @BASEBOARD_FAB2_LIB.BASEBOARD_FAB2(SCH_1):PAGE60
  DN36 M_K_DQ<40> @BASEBOARD_FAB2_LIB.BASEBOARD_FAB2(SCH_1):M_K_DQ(40)   I172 @BASEBOARD_FAB2_LIB.BASEBOARD_FAB2(SCH_1):PAGE60
  ED37 M_K_DQ<39> @BASEBOARD_FAB2_LIB.BASEBOARD_FAB2(SCH_1):M_K_DQ(39)   I172 @BASEBOARD_FAB2_LIB.BASEBOARD_FAB2(SCH_1):PAGE60
  DY37 M_K_DQ<38> @BASEBOARD_FAB2_LIB.BASEBOARD_FAB2(SCH_1):M_K_DQ(38)   I172 @BASEBOARD_FAB2_LIB.BASEBOARD_FAB2(SCH_1):PAGE60
  EA40 M_K_DQ<37> @BASEBOARD_FAB2_LIB.BASEBOARD_FAB2(SCH_1):M_K_DQ(37)   I172 @BASEBOARD_FAB2_LIB.BASEBOARD_FAB2(SCH_1):PAGE60
  DY39 M_K_DQ<36> @BASEBOARD_FAB2_LIB.BASEBOARD_FAB2(SCH_1):M_K_DQ(36)   I172 @BASEBOARD_FAB2_LIB.BASEBOARD_FAB2(SCH_1):PAGE60
  EC36 M_K_DQ<35> @BASEBOARD_FAB2_LIB.BASEBOARD_FAB2(SCH_1):M_K_DQ(35)   I172 @BASEBOARD_FAB2_LIB.BASEBOARD_FAB2(SCH_1):PAGE60
  EA36 M_K_DQ<34> @BASEBOARD_FAB2_LIB.BASEBOARD_FAB2(SCH_1):M_K_DQ(34)   I172 @BASEBOARD_FAB2_LIB.BASEBOARD_FAB2(SCH_1):PAGE60
  ED39 M_K_DQ<33> @BASEBOARD_FAB2_LIB.BASEBOARD_FAB2(SCH_1):M_K_DQ(33)   I172 @BASEBOARD_FAB2_LIB.BASEBOARD_FAB2(SCH_1):PAGE60
  EC40 M_K_DQ<32> @BASEBOARD_FAB2_LIB.BASEBOARD_FAB2(SCH_1):M_K_DQ(32)   I172 @BASEBOARD_FAB2_LIB.BASEBOARD_FAB2(SCH_1):PAGE60
  DU74 M_K_DQ<31> @BASEBOARD_FAB2_LIB.BASEBOARD_FAB2(SCH_1):M_K_DQ(31)   I172 @BASEBOARD_FAB2_LIB.BASEBOARD_FAB2(SCH_1):PAGE60
  DN74 M_K_DQ<30> @BASEBOARD_FAB2_LIB.BASEBOARD_FAB2(SCH_1):M_K_DQ(30)   I172 @BASEBOARD_FAB2_LIB.BASEBOARD_FAB2(SCH_1):PAGE60
  DT77 M_K_DQ<29> @BASEBOARD_FAB2_LIB.BASEBOARD_FAB2(SCH_1):M_K_DQ(29)   I172 @BASEBOARD_FAB2_LIB.BASEBOARD_FAB2(SCH_1):PAGE60
  DP77 M_K_DQ<28> @BASEBOARD_FAB2_LIB.BASEBOARD_FAB2(SCH_1):M_K_DQ(28)   I172 @BASEBOARD_FAB2_LIB.BASEBOARD_FAB2(SCH_1):PAGE60
  DT73 M_K_DQ<27> @BASEBOARD_FAB2_LIB.BASEBOARD_FAB2(SCH_1):M_K_DQ(27)   I172 @BASEBOARD_FAB2_LIB.BASEBOARD_FAB2(SCH_1):PAGE60
  DP73 M_K_DQ<26> @BASEBOARD_FAB2_LIB.BASEBOARD_FAB2(SCH_1):M_K_DQ(26)   I172 @BASEBOARD_FAB2_LIB.BASEBOARD_FAB2(SCH_1):PAGE60
  DU76 M_K_DQ<25> @BASEBOARD_FAB2_LIB.BASEBOARD_FAB2(SCH_1):M_K_DQ(25)   I172 @BASEBOARD_FAB2_LIB.BASEBOARD_FAB2(SCH_1):PAGE60
  DN76 M_K_DQ<24> @BASEBOARD_FAB2_LIB.BASEBOARD_FAB2(SCH_1):M_K_DQ(24)   I172 @BASEBOARD_FAB2_LIB.BASEBOARD_FAB2(SCH_1):PAGE60
  DN82 M_K_DQ<23> @BASEBOARD_FAB2_LIB.BASEBOARD_FAB2(SCH_1):M_K_DQ(23)   I172 @BASEBOARD_FAB2_LIB.BASEBOARD_FAB2(SCH_1):PAGE60
  DR80 M_K_DQ<22> @BASEBOARD_FAB2_LIB.BASEBOARD_FAB2(SCH_1):M_K_DQ(22)   I172 @BASEBOARD_FAB2_LIB.BASEBOARD_FAB2(SCH_1):PAGE60
  DJ80 M_K_DQ<21> @BASEBOARD_FAB2_LIB.BASEBOARD_FAB2(SCH_1):M_K_DQ(21)   I172 @BASEBOARD_FAB2_LIB.BASEBOARD_FAB2(SCH_1):PAGE60
  DK79 M_K_DQ<20> @BASEBOARD_FAB2_LIB.BASEBOARD_FAB2(SCH_1):M_K_DQ(20)   I172 @BASEBOARD_FAB2_LIB.BASEBOARD_FAB2(SCH_1):PAGE60
  DR82 M_K_DQ<19> @BASEBOARD_FAB2_LIB.BASEBOARD_FAB2(SCH_1):M_K_DQ(19)   I172 @BASEBOARD_FAB2_LIB.BASEBOARD_FAB2(SCH_1):PAGE60
  DT81 M_K_DQ<18> @BASEBOARD_FAB2_LIB.BASEBOARD_FAB2(SCH_1):M_K_DQ(18)   I172 @BASEBOARD_FAB2_LIB.BASEBOARD_FAB2(SCH_1):PAGE60
  DK81 M_K_DQ<17> @BASEBOARD_FAB2_LIB.BASEBOARD_FAB2(SCH_1):M_K_DQ(17)   I172 @BASEBOARD_FAB2_LIB.BASEBOARD_FAB2(SCH_1):PAGE60
  DM79 M_K_DQ<16> @BASEBOARD_FAB2_LIB.BASEBOARD_FAB2(SCH_1):M_K_DQ(16)   I172 @BASEBOARD_FAB2_LIB.BASEBOARD_FAB2(SCH_1):PAGE60
  DV85 M_K_DQ<15> @BASEBOARD_FAB2_LIB.BASEBOARD_FAB2(SCH_1):M_K_DQ(15)   I172 @BASEBOARD_FAB2_LIB.BASEBOARD_FAB2(SCH_1):PAGE60
  DR84 M_K_DQ<14> @BASEBOARD_FAB2_LIB.BASEBOARD_FAB2(SCH_1):M_K_DQ(14)   I172 @BASEBOARD_FAB2_LIB.BASEBOARD_FAB2(SCH_1):PAGE60
  DE84 M_K_DQ<13> @BASEBOARD_FAB2_LIB.BASEBOARD_FAB2(SCH_1):M_K_DQ(13)   I172 @BASEBOARD_FAB2_LIB.BASEBOARD_FAB2(SCH_1):PAGE60
  DD85 M_K_DQ<12> @BASEBOARD_FAB2_LIB.BASEBOARD_FAB2(SCH_1):M_K_DQ(12)   I172 @BASEBOARD_FAB2_LIB.BASEBOARD_FAB2(SCH_1):PAGE60
  DY83 M_K_DQ<11> @BASEBOARD_FAB2_LIB.BASEBOARD_FAB2(SCH_1):M_K_DQ(11)   I172 @BASEBOARD_FAB2_LIB.BASEBOARD_FAB2(SCH_1):PAGE60
  DV83 M_K_DQ<10> @BASEBOARD_FAB2_LIB.BASEBOARD_FAB2(SCH_1):M_K_DQ(10)   I172 @BASEBOARD_FAB2_LIB.BASEBOARD_FAB2(SCH_1):PAGE60
  DH85 M_K_DQ<9> @BASEBOARD_FAB2_LIB.BASEBOARD_FAB2(SCH_1):M_K_DQ(9)   I172 @BASEBOARD_FAB2_LIB.BASEBOARD_FAB2(SCH_1):PAGE60
  DG84 M_K_DQ<8> @BASEBOARD_FAB2_LIB.BASEBOARD_FAB2(SCH_1):M_K_DQ(8)   I172 @BASEBOARD_FAB2_LIB.BASEBOARD_FAB2(SCH_1):PAGE60
  CW84 M_K_DQ<7> @BASEBOARD_FAB2_LIB.BASEBOARD_FAB2(SCH_1):M_K_DQ(7)   I172 @BASEBOARD_FAB2_LIB.BASEBOARD_FAB2(SCH_1):PAGE60
  CW86 M_K_DQ<6> @BASEBOARD_FAB2_LIB.BASEBOARD_FAB2(SCH_1):M_K_DQ(6)   I172 @BASEBOARD_FAB2_LIB.BASEBOARD_FAB2(SCH_1):PAGE60
  CL86 M_K_DQ<5> @BASEBOARD_FAB2_LIB.BASEBOARD_FAB2(SCH_1):M_K_DQ(5)   I172 @BASEBOARD_FAB2_LIB.BASEBOARD_FAB2(SCH_1):PAGE60
  CL84 M_K_DQ<4> @BASEBOARD_FAB2_LIB.BASEBOARD_FAB2(SCH_1):M_K_DQ(4)   I172 @BASEBOARD_FAB2_LIB.BASEBOARD_FAB2(SCH_1):PAGE60
  DA84 M_K_DQ<3> @BASEBOARD_FAB2_LIB.BASEBOARD_FAB2(SCH_1):M_K_DQ(3)   I172 @BASEBOARD_FAB2_LIB.BASEBOARD_FAB2(SCH_1):PAGE60
  DA86 M_K_DQ<2> @BASEBOARD_FAB2_LIB.BASEBOARD_FAB2(SCH_1):M_K_DQ(2)   I172 @BASEBOARD_FAB2_LIB.BASEBOARD_FAB2(SCH_1):PAGE60
  CN86 M_K_DQ<1> @BASEBOARD_FAB2_LIB.BASEBOARD_FAB2(SCH_1):M_K_DQ(1)   I172 @BASEBOARD_FAB2_LIB.BASEBOARD_FAB2(SCH_1):PAGE60
  CN84 M_K_DQ<0> @BASEBOARD_FAB2_LIB.BASEBOARD_FAB2(SCH_1):M_K_DQ(0)   I172 @BASEBOARD_FAB2_LIB.BASEBOARD_FAB2(SCH_1):PAGE60
  DB67 M_K_DQS_DN<17> @BASEBOARD_FAB2_LIB.BASEBOARD_FAB2(SCH_1):M_K_DQS_DN(17)   I172 @BASEBOARD_FAB2_LIB.BASEBOARD_FAB2(SCH_1):PAGE60
  DM23 M_K_DQS_DN<16> @BASEBOARD_FAB2_LIB.BASEBOARD_FAB2(SCH_1):M_K_DQS_DN(16)   I172 @BASEBOARD_FAB2_LIB.BASEBOARD_FAB2(SCH_1):PAGE60
  DM29 M_K_DQS_DN<15> @BASEBOARD_FAB2_LIB.BASEBOARD_FAB2(SCH_1):M_K_DQS_DN(15)   I172 @BASEBOARD_FAB2_LIB.BASEBOARD_FAB2(SCH_1):PAGE60
  DP35 M_K_DQS_DN<14> @BASEBOARD_FAB2_LIB.BASEBOARD_FAB2(SCH_1):M_K_DQS_DN(14)   I172 @BASEBOARD_FAB2_LIB.BASEBOARD_FAB2(SCH_1):PAGE60
  EA38 M_K_DQS_DN<13> @BASEBOARD_FAB2_LIB.BASEBOARD_FAB2(SCH_1):M_K_DQS_DN(13)   I172 @BASEBOARD_FAB2_LIB.BASEBOARD_FAB2(SCH_1):PAGE60
  DP75 M_K_DQS_DN<12> @BASEBOARD_FAB2_LIB.BASEBOARD_FAB2(SCH_1):M_K_DQS_DN(12)   I172 @BASEBOARD_FAB2_LIB.BASEBOARD_FAB2(SCH_1):PAGE60
  DN80 M_K_DQS_DN<11> @BASEBOARD_FAB2_LIB.BASEBOARD_FAB2(SCH_1):M_K_DQS_DN(11)   I172 @BASEBOARD_FAB2_LIB.BASEBOARD_FAB2(SCH_1):PAGE60
  DM85 M_K_DQS_DN<10> @BASEBOARD_FAB2_LIB.BASEBOARD_FAB2(SCH_1):M_K_DQS_DN(10)   I172 @BASEBOARD_FAB2_LIB.BASEBOARD_FAB2(SCH_1):PAGE60
  CR84 M_K_DQS_DN<9> @BASEBOARD_FAB2_LIB.BASEBOARD_FAB2(SCH_1):M_K_DQS_DN(9)   I172 @BASEBOARD_FAB2_LIB.BASEBOARD_FAB2(SCH_1):PAGE60
  DF67 M_K_DQS_DN<8> @BASEBOARD_FAB2_LIB.BASEBOARD_FAB2(SCH_1):M_K_DQS_DN(8)   I172 @BASEBOARD_FAB2_LIB.BASEBOARD_FAB2(SCH_1):PAGE60
  DV23 M_K_DQS_DN<7> @BASEBOARD_FAB2_LIB.BASEBOARD_FAB2(SCH_1):M_K_DQS_DN(7)   I172 @BASEBOARD_FAB2_LIB.BASEBOARD_FAB2(SCH_1):PAGE60
  DV29 M_K_DQS_DN<6> @BASEBOARD_FAB2_LIB.BASEBOARD_FAB2(SCH_1):M_K_DQS_DN(6)   I172 @BASEBOARD_FAB2_LIB.BASEBOARD_FAB2(SCH_1):PAGE60
  DV35 M_K_DQS_DN<5> @BASEBOARD_FAB2_LIB.BASEBOARD_FAB2(SCH_1):M_K_DQS_DN(5)   I172 @BASEBOARD_FAB2_LIB.BASEBOARD_FAB2(SCH_1):PAGE60
  EE38 M_K_DQS_DN<4> @BASEBOARD_FAB2_LIB.BASEBOARD_FAB2(SCH_1):M_K_DQS_DN(4)   I172 @BASEBOARD_FAB2_LIB.BASEBOARD_FAB2(SCH_1):PAGE60
  DV75 M_K_DQS_DN<3> @BASEBOARD_FAB2_LIB.BASEBOARD_FAB2(SCH_1):M_K_DQS_DN(3)   I172 @BASEBOARD_FAB2_LIB.BASEBOARD_FAB2(SCH_1):PAGE60
  DL82 M_K_DQS_DN<2> @BASEBOARD_FAB2_LIB.BASEBOARD_FAB2(SCH_1):M_K_DQS_DN(2)   I172 @BASEBOARD_FAB2_LIB.BASEBOARD_FAB2(SCH_1):PAGE60
  DN84 M_K_DQS_DN<1> @BASEBOARD_FAB2_LIB.BASEBOARD_FAB2(SCH_1):M_K_DQS_DN(1)   I172 @BASEBOARD_FAB2_LIB.BASEBOARD_FAB2(SCH_1):PAGE60
  CU84 M_K_DQS_DN<0> @BASEBOARD_FAB2_LIB.BASEBOARD_FAB2(SCH_1):M_K_DQS_DN(0)   I172 @BASEBOARD_FAB2_LIB.BASEBOARD_FAB2(SCH_1):PAGE60
  CY67 M_K_DQS_DP<17> @BASEBOARD_FAB2_LIB.BASEBOARD_FAB2(SCH_1):M_K_DQS_DP(17)   I172 @BASEBOARD_FAB2_LIB.BASEBOARD_FAB2(SCH_1):PAGE60
  DP23 M_K_DQS_DP<16> @BASEBOARD_FAB2_LIB.BASEBOARD_FAB2(SCH_1):M_K_DQS_DP(16)   I172 @BASEBOARD_FAB2_LIB.BASEBOARD_FAB2(SCH_1):PAGE60
  DP29 M_K_DQS_DP<15> @BASEBOARD_FAB2_LIB.BASEBOARD_FAB2(SCH_1):M_K_DQS_DP(15)   I172 @BASEBOARD_FAB2_LIB.BASEBOARD_FAB2(SCH_1):PAGE60
  DM35 M_K_DQS_DP<14> @BASEBOARD_FAB2_LIB.BASEBOARD_FAB2(SCH_1):M_K_DQS_DP(14)   I172 @BASEBOARD_FAB2_LIB.BASEBOARD_FAB2(SCH_1):PAGE60
  DW38 M_K_DQS_DP<13> @BASEBOARD_FAB2_LIB.BASEBOARD_FAB2(SCH_1):M_K_DQS_DP(13)   I172 @BASEBOARD_FAB2_LIB.BASEBOARD_FAB2(SCH_1):PAGE60
  DM75 M_K_DQS_DP<12> @BASEBOARD_FAB2_LIB.BASEBOARD_FAB2(SCH_1):M_K_DQS_DP(12)   I172 @BASEBOARD_FAB2_LIB.BASEBOARD_FAB2(SCH_1):PAGE60
  DP79 M_K_DQS_DP<11> @BASEBOARD_FAB2_LIB.BASEBOARD_FAB2(SCH_1):M_K_DQS_DP(11)   I172 @BASEBOARD_FAB2_LIB.BASEBOARD_FAB2(SCH_1):PAGE60
  DL84 M_K_DQS_DP<10> @BASEBOARD_FAB2_LIB.BASEBOARD_FAB2(SCH_1):M_K_DQS_DP(10)   I172 @BASEBOARD_FAB2_LIB.BASEBOARD_FAB2(SCH_1):PAGE60
  CP85 M_K_DQS_DP<9> @BASEBOARD_FAB2_LIB.BASEBOARD_FAB2(SCH_1):M_K_DQS_DP(9)   I172 @BASEBOARD_FAB2_LIB.BASEBOARD_FAB2(SCH_1):PAGE60
  DD67 M_K_DQS_DP<8> @BASEBOARD_FAB2_LIB.BASEBOARD_FAB2(SCH_1):M_K_DQS_DP(8)   I172 @BASEBOARD_FAB2_LIB.BASEBOARD_FAB2(SCH_1):PAGE60
  DT23 M_K_DQS_DP<7> @BASEBOARD_FAB2_LIB.BASEBOARD_FAB2(SCH_1):M_K_DQS_DP(7)   I172 @BASEBOARD_FAB2_LIB.BASEBOARD_FAB2(SCH_1):PAGE60
  DT29 M_K_DQS_DP<6> @BASEBOARD_FAB2_LIB.BASEBOARD_FAB2(SCH_1):M_K_DQS_DP(6)   I172 @BASEBOARD_FAB2_LIB.BASEBOARD_FAB2(SCH_1):PAGE60
  DT35 M_K_DQS_DP<5> @BASEBOARD_FAB2_LIB.BASEBOARD_FAB2(SCH_1):M_K_DQS_DP(5)   I172 @BASEBOARD_FAB2_LIB.BASEBOARD_FAB2(SCH_1):PAGE60
  EC38 M_K_DQS_DP<4> @BASEBOARD_FAB2_LIB.BASEBOARD_FAB2(SCH_1):M_K_DQS_DP(4)   I172 @BASEBOARD_FAB2_LIB.BASEBOARD_FAB2(SCH_1):PAGE60
  DT75 M_K_DQS_DP<3> @BASEBOARD_FAB2_LIB.BASEBOARD_FAB2(SCH_1):M_K_DQS_DP(3)   I172 @BASEBOARD_FAB2_LIB.BASEBOARD_FAB2(SCH_1):PAGE60
  DM81 M_K_DQS_DP<2> @BASEBOARD_FAB2_LIB.BASEBOARD_FAB2(SCH_1):M_K_DQS_DP(2)   I172 @BASEBOARD_FAB2_LIB.BASEBOARD_FAB2(SCH_1):PAGE60
  DP85 M_K_DQS_DP<1> @BASEBOARD_FAB2_LIB.BASEBOARD_FAB2(SCH_1):M_K_DQS_DP(1)   I172 @BASEBOARD_FAB2_LIB.BASEBOARD_FAB2(SCH_1):PAGE60
  CV85 M_K_DQS_DP<0> @BASEBOARD_FAB2_LIB.BASEBOARD_FAB2(SCH_1):M_K_DQS_DP(0)   I172 @BASEBOARD_FAB2_LIB.BASEBOARD_FAB2(SCH_1):PAGE60
  DE66 M_K_ECC<7> @BASEBOARD_FAB2_LIB.BASEBOARD_FAB2(SCH_1):M_K_ECC(7)   I172 @BASEBOARD_FAB2_LIB.BASEBOARD_FAB2(SCH_1):PAGE60
  DA66 M_K_ECC<6> @BASEBOARD_FAB2_LIB.BASEBOARD_FAB2(SCH_1):M_K_ECC(6)   I172 @BASEBOARD_FAB2_LIB.BASEBOARD_FAB2(SCH_1):PAGE60
  DD69 M_K_ECC<5> @BASEBOARD_FAB2_LIB.BASEBOARD_FAB2(SCH_1):M_K_ECC(5)   I172 @BASEBOARD_FAB2_LIB.BASEBOARD_FAB2(SCH_1):PAGE60
  DB69 M_K_ECC<4> @BASEBOARD_FAB2_LIB.BASEBOARD_FAB2(SCH_1):M_K_ECC(4)   I172 @BASEBOARD_FAB2_LIB.BASEBOARD_FAB2(SCH_1):PAGE60
  DD65 M_K_ECC<3> @BASEBOARD_FAB2_LIB.BASEBOARD_FAB2(SCH_1):M_K_ECC(3)   I172 @BASEBOARD_FAB2_LIB.BASEBOARD_FAB2(SCH_1):PAGE60
  DB65 M_K_ECC<2> @BASEBOARD_FAB2_LIB.BASEBOARD_FAB2(SCH_1):M_K_ECC(2)   I172 @BASEBOARD_FAB2_LIB.BASEBOARD_FAB2(SCH_1):PAGE60
  DE68 M_K_ECC<1> @BASEBOARD_FAB2_LIB.BASEBOARD_FAB2(SCH_1):M_K_ECC(1)   I172 @BASEBOARD_FAB2_LIB.BASEBOARD_FAB2(SCH_1):PAGE60
  DA68 M_K_ECC<0> @BASEBOARD_FAB2_LIB.BASEBOARD_FAB2(SCH_1):M_K_ECC(0)   I172 @BASEBOARD_FAB2_LIB.BASEBOARD_FAB2(SCH_1):PAGE60
  EA46 M_K_MA<17> @BASEBOARD_FAB2_LIB.BASEBOARD_FAB2(SCH_1):M_K_MA(17)   I172 @BASEBOARD_FAB2_LIB.BASEBOARD_FAB2(SCH_1):PAGE60
  EA52 M_K_MA<16> @BASEBOARD_FAB2_LIB.BASEBOARD_FAB2(SCH_1):M_K_MA(16)   I172 @BASEBOARD_FAB2_LIB.BASEBOARD_FAB2(SCH_1):PAGE60
  DV49 M_K_MA<15> @BASEBOARD_FAB2_LIB.BASEBOARD_FAB2(SCH_1):M_K_MA(15)   I172 @BASEBOARD_FAB2_LIB.BASEBOARD_FAB2(SCH_1):PAGE60
  ED51 M_K_MA<14> @BASEBOARD_FAB2_LIB.BASEBOARD_FAB2(SCH_1):M_K_MA(14)   I172 @BASEBOARD_FAB2_LIB.BASEBOARD_FAB2(SCH_1):PAGE60
  DW48 M_K_MA<13> @BASEBOARD_FAB2_LIB.BASEBOARD_FAB2(SCH_1):M_K_MA(13)   I172 @BASEBOARD_FAB2_LIB.BASEBOARD_FAB2(SCH_1):PAGE60
  DT63 M_K_MA<12> @BASEBOARD_FAB2_LIB.BASEBOARD_FAB2(SCH_1):M_K_MA(12)   I172 @BASEBOARD_FAB2_LIB.BASEBOARD_FAB2(SCH_1):PAGE60
  EB61 M_K_MA<11> @BASEBOARD_FAB2_LIB.BASEBOARD_FAB2(SCH_1):M_K_MA(11)   I172 @BASEBOARD_FAB2_LIB.BASEBOARD_FAB2(SCH_1):PAGE60
  DW54 M_K_MA<10> @BASEBOARD_FAB2_LIB.BASEBOARD_FAB2(SCH_1):M_K_MA(10)   I172 @BASEBOARD_FAB2_LIB.BASEBOARD_FAB2(SCH_1):PAGE60
  EF61 M_K_MA<9> @BASEBOARD_FAB2_LIB.BASEBOARD_FAB2(SCH_1):M_K_MA(9)   I172 @BASEBOARD_FAB2_LIB.BASEBOARD_FAB2(SCH_1):PAGE60
  EB59 M_K_MA<8> @BASEBOARD_FAB2_LIB.BASEBOARD_FAB2(SCH_1):M_K_MA(8)   I172 @BASEBOARD_FAB2_LIB.BASEBOARD_FAB2(SCH_1):PAGE60
  EA60 M_K_MA<7> @BASEBOARD_FAB2_LIB.BASEBOARD_FAB2(SCH_1):M_K_MA(7)   I172 @BASEBOARD_FAB2_LIB.BASEBOARD_FAB2(SCH_1):PAGE60
  EE60 M_K_MA<6> @BASEBOARD_FAB2_LIB.BASEBOARD_FAB2(SCH_1):M_K_MA(6)   I172 @BASEBOARD_FAB2_LIB.BASEBOARD_FAB2(SCH_1):PAGE60
  EA58 M_K_MA<5> @BASEBOARD_FAB2_LIB.BASEBOARD_FAB2(SCH_1):M_K_MA(5)   I172 @BASEBOARD_FAB2_LIB.BASEBOARD_FAB2(SCH_1):PAGE60
  ED59 M_K_MA<4> @BASEBOARD_FAB2_LIB.BASEBOARD_FAB2(SCH_1):M_K_MA(4)   I172 @BASEBOARD_FAB2_LIB.BASEBOARD_FAB2(SCH_1):PAGE60
  EB57 M_K_MA<3> @BASEBOARD_FAB2_LIB.BASEBOARD_FAB2(SCH_1):M_K_MA(3)   I172 @BASEBOARD_FAB2_LIB.BASEBOARD_FAB2(SCH_1):PAGE60
  EE58 M_K_MA<2> @BASEBOARD_FAB2_LIB.BASEBOARD_FAB2(SCH_1):M_K_MA(2)   I172 @BASEBOARD_FAB2_LIB.BASEBOARD_FAB2(SCH_1):PAGE60
  ED57 M_K_MA<1> @BASEBOARD_FAB2_LIB.BASEBOARD_FAB2(SCH_1):M_K_MA(1)   I172 @BASEBOARD_FAB2_LIB.BASEBOARD_FAB2(SCH_1):PAGE60
  EB53 M_K_MA<0> @BASEBOARD_FAB2_LIB.BASEBOARD_FAB2(SCH_1):M_K_MA(0)   I172 @BASEBOARD_FAB2_LIB.BASEBOARD_FAB2(SCH_1):PAGE60
  EA48 M_K_ODT<3> @BASEBOARD_FAB2_LIB.BASEBOARD_FAB2(SCH_1):M_K_ODT(3)   I172 @BASEBOARD_FAB2_LIB.BASEBOARD_FAB2(SCH_1):PAGE60
  EA50 M_K_ODT<2> @BASEBOARD_FAB2_LIB.BASEBOARD_FAB2(SCH_1):M_K_ODT(2)   I172 @BASEBOARD_FAB2_LIB.BASEBOARD_FAB2(SCH_1):PAGE60
  EE48 M_K_ODT<1> @BASEBOARD_FAB2_LIB.BASEBOARD_FAB2(SCH_1):M_K_ODT(1)   I172 @BASEBOARD_FAB2_LIB.BASEBOARD_FAB2(SCH_1):PAGE60
  EE50 M_K_ODT<0> @BASEBOARD_FAB2_LIB.BASEBOARD_FAB2(SCH_1):M_K_ODT(0)   I172 @BASEBOARD_FAB2_LIB.BASEBOARD_FAB2(SCH_1):PAGE60
  ED53 M_K_PAR @BASEBOARD_FAB2_LIB.BASEBOARD_FAB2(SCH_1):M_K_PAR   I172 @BASEBOARD_FAB2_LIB.BASEBOARD_FAB2(SCH_1):PAGE60
  DR62 M_L_ACT_N @BASEBOARD_FAB2_LIB.BASEBOARD_FAB2(SCH_1):M_L_ACT_N   I172 @BASEBOARD_FAB2_LIB.BASEBOARD_FAB2(SCH_1):PAGE61
  DT61 M_L_ALERT_N @BASEBOARD_FAB2_LIB.BASEBOARD_FAB2(SCH_1):M_L_ALERT_N   I172 @BASEBOARD_FAB2_LIB.BASEBOARD_FAB2(SCH_1):PAGE61
  DV55 M_L_BA<1> @BASEBOARD_FAB2_LIB.BASEBOARD_FAB2(SCH_1):M_L_BA(1)   I172 @BASEBOARD_FAB2_LIB.BASEBOARD_FAB2(SCH_1):PAGE61
  DM53 M_L_BA<0> @BASEBOARD_FAB2_LIB.BASEBOARD_FAB2(SCH_1):M_L_BA(0)   I172 @BASEBOARD_FAB2_LIB.BASEBOARD_FAB2(SCH_1):PAGE61
  DM61 M_L_BG<1> @BASEBOARD_FAB2_LIB.BASEBOARD_FAB2(SCH_1):M_L_BG(1)   I172 @BASEBOARD_FAB2_LIB.BASEBOARD_FAB2(SCH_1):PAGE61
  DJ62 M_L_BG<0> @BASEBOARD_FAB2_LIB.BASEBOARD_FAB2(SCH_1):M_L_BG(0)   I172 @BASEBOARD_FAB2_LIB.BASEBOARD_FAB2(SCH_1):PAGE61
  DT47 M_L_C<2> @BASEBOARD_FAB2_LIB.BASEBOARD_FAB2(SCH_1):M_L_C(2)   I172 @BASEBOARD_FAB2_LIB.BASEBOARD_FAB2(SCH_1):PAGE61
  DR64 M_L_CKE<3> @BASEBOARD_FAB2_LIB.BASEBOARD_FAB2(SCH_1):M_L_CKE(3)   I172 @BASEBOARD_FAB2_LIB.BASEBOARD_FAB2(SCH_1):PAGE61
  DL64 M_L_CKE<2> @BASEBOARD_FAB2_LIB.BASEBOARD_FAB2(SCH_1):M_L_CKE(2)   I172 @BASEBOARD_FAB2_LIB.BASEBOARD_FAB2(SCH_1):PAGE61
  DN64 M_L_CKE<1> @BASEBOARD_FAB2_LIB.BASEBOARD_FAB2(SCH_1):M_L_CKE(1)   I172 @BASEBOARD_FAB2_LIB.BASEBOARD_FAB2(SCH_1):PAGE61
  DM63 M_L_CKE<0> @BASEBOARD_FAB2_LIB.BASEBOARD_FAB2(SCH_1):M_L_CKE(0)   I172 @BASEBOARD_FAB2_LIB.BASEBOARD_FAB2(SCH_1):PAGE61
  DT57 M_L_CLK_DN<3> @BASEBOARD_FAB2_LIB.BASEBOARD_FAB2(SCH_1):M_L_CLK_DN(3)   I172 @BASEBOARD_FAB2_LIB.BASEBOARD_FAB2(SCH_1):PAGE61
  DM57 M_L_CLK_DN<2> @BASEBOARD_FAB2_LIB.BASEBOARD_FAB2(SCH_1):M_L_CLK_DN(2)   I172 @BASEBOARD_FAB2_LIB.BASEBOARD_FAB2(SCH_1):PAGE61
  DR54 M_L_CLK_DN<1> @BASEBOARD_FAB2_LIB.BASEBOARD_FAB2(SCH_1):M_L_CLK_DN(1)   I172 @BASEBOARD_FAB2_LIB.BASEBOARD_FAB2(SCH_1):PAGE61
  DM55 M_L_CLK_DN<0> @BASEBOARD_FAB2_LIB.BASEBOARD_FAB2(SCH_1):M_L_CLK_DN(0)   I172 @BASEBOARD_FAB2_LIB.BASEBOARD_FAB2(SCH_1):PAGE61
  DR56 M_L_CLK_DP<3> @BASEBOARD_FAB2_LIB.BASEBOARD_FAB2(SCH_1):M_L_CLK_DP(3)   I172 @BASEBOARD_FAB2_LIB.BASEBOARD_FAB2(SCH_1):PAGE61
  DN56 M_L_CLK_DP<2> @BASEBOARD_FAB2_LIB.BASEBOARD_FAB2(SCH_1):M_L_CLK_DP(2)   I172 @BASEBOARD_FAB2_LIB.BASEBOARD_FAB2(SCH_1):PAGE61
  DT53 M_L_CLK_DP<1> @BASEBOARD_FAB2_LIB.BASEBOARD_FAB2(SCH_1):M_L_CLK_DP(1)   I172 @BASEBOARD_FAB2_LIB.BASEBOARD_FAB2(SCH_1):PAGE61
  DN54 M_L_CLK_DP<0> @BASEBOARD_FAB2_LIB.BASEBOARD_FAB2(SCH_1):M_L_CLK_DP(0)   I172 @BASEBOARD_FAB2_LIB.BASEBOARD_FAB2(SCH_1):PAGE61
  DN46 M_L_CS_N<7> @BASEBOARD_FAB2_LIB.BASEBOARD_FAB2(SCH_1):M_L_CS_N(7)   I172 @BASEBOARD_FAB2_LIB.BASEBOARD_FAB2(SCH_1):PAGE61
  DT45 M_L_CS_N<6> @BASEBOARD_FAB2_LIB.BASEBOARD_FAB2(SCH_1):M_L_CS_N(6)   I172 @BASEBOARD_FAB2_LIB.BASEBOARD_FAB2(SCH_1):PAGE61
  DM49 M_L_CS_N<5> @BASEBOARD_FAB2_LIB.BASEBOARD_FAB2(SCH_1):M_L_CS_N(5)   I172 @BASEBOARD_FAB2_LIB.BASEBOARD_FAB2(SCH_1):PAGE61
  DW50 M_L_CS_N<4> @BASEBOARD_FAB2_LIB.BASEBOARD_FAB2(SCH_1):M_L_CS_N(4)   I172 @BASEBOARD_FAB2_LIB.BASEBOARD_FAB2(SCH_1):PAGE61
  DK47 M_L_CS_N<3> @BASEBOARD_FAB2_LIB.BASEBOARD_FAB2(SCH_1):M_L_CS_N(3)   I172 @BASEBOARD_FAB2_LIB.BASEBOARD_FAB2(SCH_1):PAGE61
  DR46 M_L_CS_N<2> @BASEBOARD_FAB2_LIB.BASEBOARD_FAB2(SCH_1):M_L_CS_N(2)   I172 @BASEBOARD_FAB2_LIB.BASEBOARD_FAB2(SCH_1):PAGE61
  DN50 M_L_CS_N<1> @BASEBOARD_FAB2_LIB.BASEBOARD_FAB2(SCH_1):M_L_CS_N(1)   I172 @BASEBOARD_FAB2_LIB.BASEBOARD_FAB2(SCH_1):PAGE61
  DV51 M_L_CS_N<0> @BASEBOARD_FAB2_LIB.BASEBOARD_FAB2(SCH_1):M_L_CS_N(0)   I172 @BASEBOARD_FAB2_LIB.BASEBOARD_FAB2(SCH_1):PAGE61
  DK25 M_L_DQ<63> @BASEBOARD_FAB2_LIB.BASEBOARD_FAB2(SCH_1):M_L_DQ(63)   I172 @BASEBOARD_FAB2_LIB.BASEBOARD_FAB2(SCH_1):PAGE61
  DF25 M_L_DQ<62> @BASEBOARD_FAB2_LIB.BASEBOARD_FAB2(SCH_1):M_L_DQ(62)   I172 @BASEBOARD_FAB2_LIB.BASEBOARD_FAB2(SCH_1):PAGE61
  DJ28 M_L_DQ<61> @BASEBOARD_FAB2_LIB.BASEBOARD_FAB2(SCH_1):M_L_DQ(61)   I172 @BASEBOARD_FAB2_LIB.BASEBOARD_FAB2(SCH_1):PAGE61
  DG28 M_L_DQ<60> @BASEBOARD_FAB2_LIB.BASEBOARD_FAB2(SCH_1):M_L_DQ(60)   I172 @BASEBOARD_FAB2_LIB.BASEBOARD_FAB2(SCH_1):PAGE61
  DJ24 M_L_DQ<59> @BASEBOARD_FAB2_LIB.BASEBOARD_FAB2(SCH_1):M_L_DQ(59)   I172 @BASEBOARD_FAB2_LIB.BASEBOARD_FAB2(SCH_1):PAGE61
  DD25 M_L_DQ<58> @BASEBOARD_FAB2_LIB.BASEBOARD_FAB2(SCH_1):M_L_DQ(58)   I172 @BASEBOARD_FAB2_LIB.BASEBOARD_FAB2(SCH_1):PAGE61
  DK27 M_L_DQ<57> @BASEBOARD_FAB2_LIB.BASEBOARD_FAB2(SCH_1):M_L_DQ(57)   I172 @BASEBOARD_FAB2_LIB.BASEBOARD_FAB2(SCH_1):PAGE61
  DF27 M_L_DQ<56> @BASEBOARD_FAB2_LIB.BASEBOARD_FAB2(SCH_1):M_L_DQ(56)   I172 @BASEBOARD_FAB2_LIB.BASEBOARD_FAB2(SCH_1):PAGE61
  ED25 M_L_DQ<55> @BASEBOARD_FAB2_LIB.BASEBOARD_FAB2(SCH_1):M_L_DQ(55)   I172 @BASEBOARD_FAB2_LIB.BASEBOARD_FAB2(SCH_1):PAGE61
  DY25 M_L_DQ<54> @BASEBOARD_FAB2_LIB.BASEBOARD_FAB2(SCH_1):M_L_DQ(54)   I172 @BASEBOARD_FAB2_LIB.BASEBOARD_FAB2(SCH_1):PAGE61
  EA28 M_L_DQ<53> @BASEBOARD_FAB2_LIB.BASEBOARD_FAB2(SCH_1):M_L_DQ(53)   I172 @BASEBOARD_FAB2_LIB.BASEBOARD_FAB2(SCH_1):PAGE61
  DY27 M_L_DQ<52> @BASEBOARD_FAB2_LIB.BASEBOARD_FAB2(SCH_1):M_L_DQ(52)   I172 @BASEBOARD_FAB2_LIB.BASEBOARD_FAB2(SCH_1):PAGE61
  EC24 M_L_DQ<51> @BASEBOARD_FAB2_LIB.BASEBOARD_FAB2(SCH_1):M_L_DQ(51)   I172 @BASEBOARD_FAB2_LIB.BASEBOARD_FAB2(SCH_1):PAGE61
  EA24 M_L_DQ<50> @BASEBOARD_FAB2_LIB.BASEBOARD_FAB2(SCH_1):M_L_DQ(50)   I172 @BASEBOARD_FAB2_LIB.BASEBOARD_FAB2(SCH_1):PAGE61
  ED27 M_L_DQ<49> @BASEBOARD_FAB2_LIB.BASEBOARD_FAB2(SCH_1):M_L_DQ(49)   I172 @BASEBOARD_FAB2_LIB.BASEBOARD_FAB2(SCH_1):PAGE61
  EC28 M_L_DQ<48> @BASEBOARD_FAB2_LIB.BASEBOARD_FAB2(SCH_1):M_L_DQ(48)   I172 @BASEBOARD_FAB2_LIB.BASEBOARD_FAB2(SCH_1):PAGE61
  ED31 M_L_DQ<47> @BASEBOARD_FAB2_LIB.BASEBOARD_FAB2(SCH_1):M_L_DQ(47)   I172 @BASEBOARD_FAB2_LIB.BASEBOARD_FAB2(SCH_1):PAGE61
  DY31 M_L_DQ<46> @BASEBOARD_FAB2_LIB.BASEBOARD_FAB2(SCH_1):M_L_DQ(46)   I172 @BASEBOARD_FAB2_LIB.BASEBOARD_FAB2(SCH_1):PAGE61
  EA34 M_L_DQ<45> @BASEBOARD_FAB2_LIB.BASEBOARD_FAB2(SCH_1):M_L_DQ(45)   I172 @BASEBOARD_FAB2_LIB.BASEBOARD_FAB2(SCH_1):PAGE61
  DY33 M_L_DQ<44> @BASEBOARD_FAB2_LIB.BASEBOARD_FAB2(SCH_1):M_L_DQ(44)   I172 @BASEBOARD_FAB2_LIB.BASEBOARD_FAB2(SCH_1):PAGE61
  EC30 M_L_DQ<43> @BASEBOARD_FAB2_LIB.BASEBOARD_FAB2(SCH_1):M_L_DQ(43)   I172 @BASEBOARD_FAB2_LIB.BASEBOARD_FAB2(SCH_1):PAGE61
  EA30 M_L_DQ<42> @BASEBOARD_FAB2_LIB.BASEBOARD_FAB2(SCH_1):M_L_DQ(42)   I172 @BASEBOARD_FAB2_LIB.BASEBOARD_FAB2(SCH_1):PAGE61
  ED33 M_L_DQ<41> @BASEBOARD_FAB2_LIB.BASEBOARD_FAB2(SCH_1):M_L_DQ(41)   I172 @BASEBOARD_FAB2_LIB.BASEBOARD_FAB2(SCH_1):PAGE61
  EC34 M_L_DQ<40> @BASEBOARD_FAB2_LIB.BASEBOARD_FAB2(SCH_1):M_L_DQ(40)   I172 @BASEBOARD_FAB2_LIB.BASEBOARD_FAB2(SCH_1):PAGE61
  DU40 M_L_DQ<39> @BASEBOARD_FAB2_LIB.BASEBOARD_FAB2(SCH_1):M_L_DQ(39)   I172 @BASEBOARD_FAB2_LIB.BASEBOARD_FAB2(SCH_1):PAGE61
  DN40 M_L_DQ<38> @BASEBOARD_FAB2_LIB.BASEBOARD_FAB2(SCH_1):M_L_DQ(38)   I172 @BASEBOARD_FAB2_LIB.BASEBOARD_FAB2(SCH_1):PAGE61
  DN42 M_L_DQ<37> @BASEBOARD_FAB2_LIB.BASEBOARD_FAB2(SCH_1):M_L_DQ(37)   I172 @BASEBOARD_FAB2_LIB.BASEBOARD_FAB2(SCH_1):PAGE61
  DL42 M_L_DQ<36> @BASEBOARD_FAB2_LIB.BASEBOARD_FAB2(SCH_1):M_L_DQ(36)   I172 @BASEBOARD_FAB2_LIB.BASEBOARD_FAB2(SCH_1):PAGE61
  DT39 M_L_DQ<35> @BASEBOARD_FAB2_LIB.BASEBOARD_FAB2(SCH_1):M_L_DQ(35)   I172 @BASEBOARD_FAB2_LIB.BASEBOARD_FAB2(SCH_1):PAGE61
  DP39 M_L_DQ<34> @BASEBOARD_FAB2_LIB.BASEBOARD_FAB2(SCH_1):M_L_DQ(34)   I172 @BASEBOARD_FAB2_LIB.BASEBOARD_FAB2(SCH_1):PAGE61
  DW42 M_L_DQ<33> @BASEBOARD_FAB2_LIB.BASEBOARD_FAB2(SCH_1):M_L_DQ(33)   I172 @BASEBOARD_FAB2_LIB.BASEBOARD_FAB2(SCH_1):PAGE61
  DU42 M_L_DQ<32> @BASEBOARD_FAB2_LIB.BASEBOARD_FAB2(SCH_1):M_L_DQ(32)   I172 @BASEBOARD_FAB2_LIB.BASEBOARD_FAB2(SCH_1):PAGE61
  EE72 M_L_DQ<31> @BASEBOARD_FAB2_LIB.BASEBOARD_FAB2(SCH_1):M_L_DQ(31)   I172 @BASEBOARD_FAB2_LIB.BASEBOARD_FAB2(SCH_1):PAGE61
  EA72 M_L_DQ<30> @BASEBOARD_FAB2_LIB.BASEBOARD_FAB2(SCH_1):M_L_DQ(30)   I172 @BASEBOARD_FAB2_LIB.BASEBOARD_FAB2(SCH_1):PAGE61
  EB75 M_L_DQ<29> @BASEBOARD_FAB2_LIB.BASEBOARD_FAB2(SCH_1):M_L_DQ(29)   I172 @BASEBOARD_FAB2_LIB.BASEBOARD_FAB2(SCH_1):PAGE61
  EA74 M_L_DQ<28> @BASEBOARD_FAB2_LIB.BASEBOARD_FAB2(SCH_1):M_L_DQ(28)   I172 @BASEBOARD_FAB2_LIB.BASEBOARD_FAB2(SCH_1):PAGE61
  ED71 M_L_DQ<27> @BASEBOARD_FAB2_LIB.BASEBOARD_FAB2(SCH_1):M_L_DQ(27)   I172 @BASEBOARD_FAB2_LIB.BASEBOARD_FAB2(SCH_1):PAGE61
  EB71 M_L_DQ<26> @BASEBOARD_FAB2_LIB.BASEBOARD_FAB2(SCH_1):M_L_DQ(26)   I172 @BASEBOARD_FAB2_LIB.BASEBOARD_FAB2(SCH_1):PAGE61
  EE74 M_L_DQ<25> @BASEBOARD_FAB2_LIB.BASEBOARD_FAB2(SCH_1):M_L_DQ(25)   I172 @BASEBOARD_FAB2_LIB.BASEBOARD_FAB2(SCH_1):PAGE61
  ED75 M_L_DQ<24> @BASEBOARD_FAB2_LIB.BASEBOARD_FAB2(SCH_1):M_L_DQ(24)   I172 @BASEBOARD_FAB2_LIB.BASEBOARD_FAB2(SCH_1):PAGE61
  EC78 M_L_DQ<23> @BASEBOARD_FAB2_LIB.BASEBOARD_FAB2(SCH_1):M_L_DQ(23)   I172 @BASEBOARD_FAB2_LIB.BASEBOARD_FAB2(SCH_1):PAGE61
  DW78 M_L_DQ<22> @BASEBOARD_FAB2_LIB.BASEBOARD_FAB2(SCH_1):M_L_DQ(22)   I172 @BASEBOARD_FAB2_LIB.BASEBOARD_FAB2(SCH_1):PAGE61
  EB81 M_L_DQ<21> @BASEBOARD_FAB2_LIB.BASEBOARD_FAB2(SCH_1):M_L_DQ(21)   I172 @BASEBOARD_FAB2_LIB.BASEBOARD_FAB2(SCH_1):PAGE61
  DY81 M_L_DQ<20> @BASEBOARD_FAB2_LIB.BASEBOARD_FAB2(SCH_1):M_L_DQ(20)   I172 @BASEBOARD_FAB2_LIB.BASEBOARD_FAB2(SCH_1):PAGE61
  EB77 M_L_DQ<19> @BASEBOARD_FAB2_LIB.BASEBOARD_FAB2(SCH_1):M_L_DQ(19)   I172 @BASEBOARD_FAB2_LIB.BASEBOARD_FAB2(SCH_1):PAGE61
  DY77 M_L_DQ<18> @BASEBOARD_FAB2_LIB.BASEBOARD_FAB2(SCH_1):M_L_DQ(18)   I172 @BASEBOARD_FAB2_LIB.BASEBOARD_FAB2(SCH_1):PAGE61
  EC80 M_L_DQ<17> @BASEBOARD_FAB2_LIB.BASEBOARD_FAB2(SCH_1):M_L_DQ(17)   I172 @BASEBOARD_FAB2_LIB.BASEBOARD_FAB2(SCH_1):PAGE61
  DW80 M_L_DQ<16> @BASEBOARD_FAB2_LIB.BASEBOARD_FAB2(SCH_1):M_L_DQ(16)   I172 @BASEBOARD_FAB2_LIB.BASEBOARD_FAB2(SCH_1):PAGE61
  DE82 M_L_DQ<15> @BASEBOARD_FAB2_LIB.BASEBOARD_FAB2(SCH_1):M_L_DQ(15)   I172 @BASEBOARD_FAB2_LIB.BASEBOARD_FAB2(SCH_1):PAGE61
  DC82 M_L_DQ<14> @BASEBOARD_FAB2_LIB.BASEBOARD_FAB2(SCH_1):M_L_DQ(14)   I172 @BASEBOARD_FAB2_LIB.BASEBOARD_FAB2(SCH_1):PAGE61
  CW80 M_L_DQ<13> @BASEBOARD_FAB2_LIB.BASEBOARD_FAB2(SCH_1):M_L_DQ(13)   I172 @BASEBOARD_FAB2_LIB.BASEBOARD_FAB2(SCH_1):PAGE61
  CY79 M_L_DQ<12> @BASEBOARD_FAB2_LIB.BASEBOARD_FAB2(SCH_1):M_L_DQ(12)   I172 @BASEBOARD_FAB2_LIB.BASEBOARD_FAB2(SCH_1):PAGE61
  DF81 M_L_DQ<11> @BASEBOARD_FAB2_LIB.BASEBOARD_FAB2(SCH_1):M_L_DQ(11)   I172 @BASEBOARD_FAB2_LIB.BASEBOARD_FAB2(SCH_1):PAGE61
  DE80 M_L_DQ<10> @BASEBOARD_FAB2_LIB.BASEBOARD_FAB2(SCH_1):M_L_DQ(10)   I172 @BASEBOARD_FAB2_LIB.BASEBOARD_FAB2(SCH_1):PAGE61
  CY81 M_L_DQ<9> @BASEBOARD_FAB2_LIB.BASEBOARD_FAB2(SCH_1):M_L_DQ(9)   I172 @BASEBOARD_FAB2_LIB.BASEBOARD_FAB2(SCH_1):PAGE61
  DB79 M_L_DQ<8> @BASEBOARD_FAB2_LIB.BASEBOARD_FAB2(SCH_1):M_L_DQ(8)   I172 @BASEBOARD_FAB2_LIB.BASEBOARD_FAB2(SCH_1):PAGE61
  CN82 M_L_DQ<7> @BASEBOARD_FAB2_LIB.BASEBOARD_FAB2(SCH_1):M_L_DQ(7)   I172 @BASEBOARD_FAB2_LIB.BASEBOARD_FAB2(SCH_1):PAGE61
  CR80 M_L_DQ<6> @BASEBOARD_FAB2_LIB.BASEBOARD_FAB2(SCH_1):M_L_DQ(6)   I172 @BASEBOARD_FAB2_LIB.BASEBOARD_FAB2(SCH_1):PAGE61
  CJ80 M_L_DQ<5> @BASEBOARD_FAB2_LIB.BASEBOARD_FAB2(SCH_1):M_L_DQ(5)   I172 @BASEBOARD_FAB2_LIB.BASEBOARD_FAB2(SCH_1):PAGE61
  CK79 M_L_DQ<4> @BASEBOARD_FAB2_LIB.BASEBOARD_FAB2(SCH_1):M_L_DQ(4)   I172 @BASEBOARD_FAB2_LIB.BASEBOARD_FAB2(SCH_1):PAGE61
  CR82 M_L_DQ<3> @BASEBOARD_FAB2_LIB.BASEBOARD_FAB2(SCH_1):M_L_DQ(3)   I172 @BASEBOARD_FAB2_LIB.BASEBOARD_FAB2(SCH_1):PAGE61
  CT81 M_L_DQ<2> @BASEBOARD_FAB2_LIB.BASEBOARD_FAB2(SCH_1):M_L_DQ(2)   I172 @BASEBOARD_FAB2_LIB.BASEBOARD_FAB2(SCH_1):PAGE61
  CK81 M_L_DQ<1> @BASEBOARD_FAB2_LIB.BASEBOARD_FAB2(SCH_1):M_L_DQ(1)   I172 @BASEBOARD_FAB2_LIB.BASEBOARD_FAB2(SCH_1):PAGE61
  CM79 M_L_DQ<0> @BASEBOARD_FAB2_LIB.BASEBOARD_FAB2(SCH_1):M_L_DQ(0)   I172 @BASEBOARD_FAB2_LIB.BASEBOARD_FAB2(SCH_1):PAGE61
  DV67 M_L_DQS_DN<17> @BASEBOARD_FAB2_LIB.BASEBOARD_FAB2(SCH_1):M_L_DQS_DN(17)   I172 @BASEBOARD_FAB2_LIB.BASEBOARD_FAB2(SCH_1):PAGE61
  DG26 M_L_DQS_DN<16> @BASEBOARD_FAB2_LIB.BASEBOARD_FAB2(SCH_1):M_L_DQS_DN(16)   I172 @BASEBOARD_FAB2_LIB.BASEBOARD_FAB2(SCH_1):PAGE61
  EA26 M_L_DQS_DN<15> @BASEBOARD_FAB2_LIB.BASEBOARD_FAB2(SCH_1):M_L_DQS_DN(15)   I172 @BASEBOARD_FAB2_LIB.BASEBOARD_FAB2(SCH_1):PAGE61
  EA32 M_L_DQS_DN<14> @BASEBOARD_FAB2_LIB.BASEBOARD_FAB2(SCH_1):M_L_DQS_DN(14)   I172 @BASEBOARD_FAB2_LIB.BASEBOARD_FAB2(SCH_1):PAGE61
  DP41 M_L_DQS_DN<13> @BASEBOARD_FAB2_LIB.BASEBOARD_FAB2(SCH_1):M_L_DQS_DN(13)   I172 @BASEBOARD_FAB2_LIB.BASEBOARD_FAB2(SCH_1):PAGE61
  EB73 M_L_DQS_DN<12> @BASEBOARD_FAB2_LIB.BASEBOARD_FAB2(SCH_1):M_L_DQS_DN(12)   I172 @BASEBOARD_FAB2_LIB.BASEBOARD_FAB2(SCH_1):PAGE61
  DY79 M_L_DQS_DN<11> @BASEBOARD_FAB2_LIB.BASEBOARD_FAB2(SCH_1):M_L_DQS_DN(11)   I172 @BASEBOARD_FAB2_LIB.BASEBOARD_FAB2(SCH_1):PAGE61
  DC80 M_L_DQS_DN<10> @BASEBOARD_FAB2_LIB.BASEBOARD_FAB2(SCH_1):M_L_DQS_DN(10)   I172 @BASEBOARD_FAB2_LIB.BASEBOARD_FAB2(SCH_1):PAGE61
  CN80 M_L_DQS_DN<9> @BASEBOARD_FAB2_LIB.BASEBOARD_FAB2(SCH_1):M_L_DQS_DN(9)   I172 @BASEBOARD_FAB2_LIB.BASEBOARD_FAB2(SCH_1):PAGE61
  EB67 M_L_DQS_DN<8> @BASEBOARD_FAB2_LIB.BASEBOARD_FAB2(SCH_1):M_L_DQS_DN(8)   I172 @BASEBOARD_FAB2_LIB.BASEBOARD_FAB2(SCH_1):PAGE61
  DL26 M_L_DQS_DN<7> @BASEBOARD_FAB2_LIB.BASEBOARD_FAB2(SCH_1):M_L_DQS_DN(7)   I172 @BASEBOARD_FAB2_LIB.BASEBOARD_FAB2(SCH_1):PAGE61
  EE26 M_L_DQS_DN<6> @BASEBOARD_FAB2_LIB.BASEBOARD_FAB2(SCH_1):M_L_DQS_DN(6)   I172 @BASEBOARD_FAB2_LIB.BASEBOARD_FAB2(SCH_1):PAGE61
  EE32 M_L_DQS_DN<5> @BASEBOARD_FAB2_LIB.BASEBOARD_FAB2(SCH_1):M_L_DQS_DN(5)   I172 @BASEBOARD_FAB2_LIB.BASEBOARD_FAB2(SCH_1):PAGE61
  DV41 M_L_DQS_DN<4> @BASEBOARD_FAB2_LIB.BASEBOARD_FAB2(SCH_1):M_L_DQS_DN(4)   I172 @BASEBOARD_FAB2_LIB.BASEBOARD_FAB2(SCH_1):PAGE61
  EF73 M_L_DQS_DN<3> @BASEBOARD_FAB2_LIB.BASEBOARD_FAB2(SCH_1):M_L_DQS_DN(3)   I172 @BASEBOARD_FAB2_LIB.BASEBOARD_FAB2(SCH_1):PAGE61
  ED79 M_L_DQS_DN<2> @BASEBOARD_FAB2_LIB.BASEBOARD_FAB2(SCH_1):M_L_DQS_DN(2)   I172 @BASEBOARD_FAB2_LIB.BASEBOARD_FAB2(SCH_1):PAGE61
  DA82 M_L_DQS_DN<1> @BASEBOARD_FAB2_LIB.BASEBOARD_FAB2(SCH_1):M_L_DQS_DN(1)   I172 @BASEBOARD_FAB2_LIB.BASEBOARD_FAB2(SCH_1):PAGE61
  CL82 M_L_DQS_DN<0> @BASEBOARD_FAB2_LIB.BASEBOARD_FAB2(SCH_1):M_L_DQS_DN(0)   I172 @BASEBOARD_FAB2_LIB.BASEBOARD_FAB2(SCH_1):PAGE61
  DT67 M_L_DQS_DP<17> @BASEBOARD_FAB2_LIB.BASEBOARD_FAB2(SCH_1):M_L_DQS_DP(17)   I172 @BASEBOARD_FAB2_LIB.BASEBOARD_FAB2(SCH_1):PAGE61
  DE26 M_L_DQS_DP<16> @BASEBOARD_FAB2_LIB.BASEBOARD_FAB2(SCH_1):M_L_DQS_DP(16)   I172 @BASEBOARD_FAB2_LIB.BASEBOARD_FAB2(SCH_1):PAGE61
  DW26 M_L_DQS_DP<15> @BASEBOARD_FAB2_LIB.BASEBOARD_FAB2(SCH_1):M_L_DQS_DP(15)   I172 @BASEBOARD_FAB2_LIB.BASEBOARD_FAB2(SCH_1):PAGE61
  DW32 M_L_DQS_DP<14> @BASEBOARD_FAB2_LIB.BASEBOARD_FAB2(SCH_1):M_L_DQS_DP(14)   I172 @BASEBOARD_FAB2_LIB.BASEBOARD_FAB2(SCH_1):PAGE61
  DM41 M_L_DQS_DP<13> @BASEBOARD_FAB2_LIB.BASEBOARD_FAB2(SCH_1):M_L_DQS_DP(13)   I172 @BASEBOARD_FAB2_LIB.BASEBOARD_FAB2(SCH_1):PAGE61
  DY73 M_L_DQS_DP<12> @BASEBOARD_FAB2_LIB.BASEBOARD_FAB2(SCH_1):M_L_DQS_DP(12)   I172 @BASEBOARD_FAB2_LIB.BASEBOARD_FAB2(SCH_1):PAGE61
  DV79 M_L_DQS_DP<11> @BASEBOARD_FAB2_LIB.BASEBOARD_FAB2(SCH_1):M_L_DQS_DP(11)   I172 @BASEBOARD_FAB2_LIB.BASEBOARD_FAB2(SCH_1):PAGE61
  DD79 M_L_DQS_DP<10> @BASEBOARD_FAB2_LIB.BASEBOARD_FAB2(SCH_1):M_L_DQS_DP(10)   I172 @BASEBOARD_FAB2_LIB.BASEBOARD_FAB2(SCH_1):PAGE61
  CP79 M_L_DQS_DP<9> @BASEBOARD_FAB2_LIB.BASEBOARD_FAB2(SCH_1):M_L_DQS_DP(9)   I172 @BASEBOARD_FAB2_LIB.BASEBOARD_FAB2(SCH_1):PAGE61
  DY67 M_L_DQS_DP<8> @BASEBOARD_FAB2_LIB.BASEBOARD_FAB2(SCH_1):M_L_DQS_DP(8)   I172 @BASEBOARD_FAB2_LIB.BASEBOARD_FAB2(SCH_1):PAGE61
  DJ26 M_L_DQS_DP<7> @BASEBOARD_FAB2_LIB.BASEBOARD_FAB2(SCH_1):M_L_DQS_DP(7)   I172 @BASEBOARD_FAB2_LIB.BASEBOARD_FAB2(SCH_1):PAGE61
  EC26 M_L_DQS_DP<6> @BASEBOARD_FAB2_LIB.BASEBOARD_FAB2(SCH_1):M_L_DQS_DP(6)   I172 @BASEBOARD_FAB2_LIB.BASEBOARD_FAB2(SCH_1):PAGE61
  EC32 M_L_DQS_DP<5> @BASEBOARD_FAB2_LIB.BASEBOARD_FAB2(SCH_1):M_L_DQS_DP(5)   I172 @BASEBOARD_FAB2_LIB.BASEBOARD_FAB2(SCH_1):PAGE61
  DT41 M_L_DQS_DP<4> @BASEBOARD_FAB2_LIB.BASEBOARD_FAB2(SCH_1):M_L_DQS_DP(4)   I172 @BASEBOARD_FAB2_LIB.BASEBOARD_FAB2(SCH_1):PAGE61
  ED73 M_L_DQS_DP<3> @BASEBOARD_FAB2_LIB.BASEBOARD_FAB2(SCH_1):M_L_DQS_DP(3)   I172 @BASEBOARD_FAB2_LIB.BASEBOARD_FAB2(SCH_1):PAGE61
  EB79 M_L_DQS_DP<2> @BASEBOARD_FAB2_LIB.BASEBOARD_FAB2(SCH_1):M_L_DQS_DP(2)   I172 @BASEBOARD_FAB2_LIB.BASEBOARD_FAB2(SCH_1):PAGE61
  DB81 M_L_DQS_DP<1> @BASEBOARD_FAB2_LIB.BASEBOARD_FAB2(SCH_1):M_L_DQS_DP(1)   I172 @BASEBOARD_FAB2_LIB.BASEBOARD_FAB2(SCH_1):PAGE61
  CM81 M_L_DQS_DP<0> @BASEBOARD_FAB2_LIB.BASEBOARD_FAB2(SCH_1):M_L_DQS_DP(0)   I172 @BASEBOARD_FAB2_LIB.BASEBOARD_FAB2(SCH_1):PAGE61
  EA66 M_L_ECC<7> @BASEBOARD_FAB2_LIB.BASEBOARD_FAB2(SCH_1):M_L_ECC(7)   I172 @BASEBOARD_FAB2_LIB.BASEBOARD_FAB2(SCH_1):PAGE61
  DU66 M_L_ECC<6> @BASEBOARD_FAB2_LIB.BASEBOARD_FAB2(SCH_1):M_L_ECC(6)   I172 @BASEBOARD_FAB2_LIB.BASEBOARD_FAB2(SCH_1):PAGE61
  DV69 M_L_ECC<5> @BASEBOARD_FAB2_LIB.BASEBOARD_FAB2(SCH_1):M_L_ECC(5)   I172 @BASEBOARD_FAB2_LIB.BASEBOARD_FAB2(SCH_1):PAGE61
  DU68 M_L_ECC<4> @BASEBOARD_FAB2_LIB.BASEBOARD_FAB2(SCH_1):M_L_ECC(4)   I172 @BASEBOARD_FAB2_LIB.BASEBOARD_FAB2(SCH_1):PAGE61
  DY65 M_L_ECC<3> @BASEBOARD_FAB2_LIB.BASEBOARD_FAB2(SCH_1):M_L_ECC(3)   I172 @BASEBOARD_FAB2_LIB.BASEBOARD_FAB2(SCH_1):PAGE61
  DV65 M_L_ECC<2> @BASEBOARD_FAB2_LIB.BASEBOARD_FAB2(SCH_1):M_L_ECC(2)   I172 @BASEBOARD_FAB2_LIB.BASEBOARD_FAB2(SCH_1):PAGE61
  EA68 M_L_ECC<1> @BASEBOARD_FAB2_LIB.BASEBOARD_FAB2(SCH_1):M_L_ECC(1)   I172 @BASEBOARD_FAB2_LIB.BASEBOARD_FAB2(SCH_1):PAGE61
  DY69 M_L_ECC<0> @BASEBOARD_FAB2_LIB.BASEBOARD_FAB2(SCH_1):M_L_ECC(0)   I172 @BASEBOARD_FAB2_LIB.BASEBOARD_FAB2(SCH_1):PAGE61
  DR48 M_L_MA<17> @BASEBOARD_FAB2_LIB.BASEBOARD_FAB2(SCH_1):M_L_MA(17)   I172 @BASEBOARD_FAB2_LIB.BASEBOARD_FAB2(SCH_1):PAGE61
  DN52 M_L_MA<16> @BASEBOARD_FAB2_LIB.BASEBOARD_FAB2(SCH_1):M_L_MA(16)   I172 @BASEBOARD_FAB2_LIB.BASEBOARD_FAB2(SCH_1):PAGE61
  DR52 M_L_MA<15> @BASEBOARD_FAB2_LIB.BASEBOARD_FAB2(SCH_1):M_L_MA(15)   I172 @BASEBOARD_FAB2_LIB.BASEBOARD_FAB2(SCH_1):PAGE61
  DM51 M_L_MA<14> @BASEBOARD_FAB2_LIB.BASEBOARD_FAB2(SCH_1):M_L_MA(14)   I172 @BASEBOARD_FAB2_LIB.BASEBOARD_FAB2(SCH_1):PAGE61
  DT51 M_L_MA<13> @BASEBOARD_FAB2_LIB.BASEBOARD_FAB2(SCH_1):M_L_MA(13)   I172 @BASEBOARD_FAB2_LIB.BASEBOARD_FAB2(SCH_1):PAGE61
  DN60 M_L_MA<12> @BASEBOARD_FAB2_LIB.BASEBOARD_FAB2(SCH_1):M_L_MA(12)   I172 @BASEBOARD_FAB2_LIB.BASEBOARD_FAB2(SCH_1):PAGE61
  DR60 M_L_MA<11> @BASEBOARD_FAB2_LIB.BASEBOARD_FAB2(SCH_1):M_L_MA(11)   I172 @BASEBOARD_FAB2_LIB.BASEBOARD_FAB2(SCH_1):PAGE61
  DT55 M_L_MA<10> @BASEBOARD_FAB2_LIB.BASEBOARD_FAB2(SCH_1):M_L_MA(10)   I172 @BASEBOARD_FAB2_LIB.BASEBOARD_FAB2(SCH_1):PAGE61
  DV59 M_L_MA<9> @BASEBOARD_FAB2_LIB.BASEBOARD_FAB2(SCH_1):M_L_MA(9)   I172 @BASEBOARD_FAB2_LIB.BASEBOARD_FAB2(SCH_1):PAGE61
  DJ60 M_L_MA<8> @BASEBOARD_FAB2_LIB.BASEBOARD_FAB2(SCH_1):M_L_MA(8)   I172 @BASEBOARD_FAB2_LIB.BASEBOARD_FAB2(SCH_1):PAGE61
  DK61 M_L_MA<7> @BASEBOARD_FAB2_LIB.BASEBOARD_FAB2(SCH_1):M_L_MA(7)   I172 @BASEBOARD_FAB2_LIB.BASEBOARD_FAB2(SCH_1):PAGE61
  DM59 M_L_MA<6> @BASEBOARD_FAB2_LIB.BASEBOARD_FAB2(SCH_1):M_L_MA(6)   I172 @BASEBOARD_FAB2_LIB.BASEBOARD_FAB2(SCH_1):PAGE61
  DN58 M_L_MA<5> @BASEBOARD_FAB2_LIB.BASEBOARD_FAB2(SCH_1):M_L_MA(5)   I172 @BASEBOARD_FAB2_LIB.BASEBOARD_FAB2(SCH_1):PAGE61
  DT59 M_L_MA<4> @BASEBOARD_FAB2_LIB.BASEBOARD_FAB2(SCH_1):M_L_MA(4)   I172 @BASEBOARD_FAB2_LIB.BASEBOARD_FAB2(SCH_1):PAGE61
  DR58 M_L_MA<3> @BASEBOARD_FAB2_LIB.BASEBOARD_FAB2(SCH_1):M_L_MA(3)   I172 @BASEBOARD_FAB2_LIB.BASEBOARD_FAB2(SCH_1):PAGE61
  DV57 M_L_MA<2> @BASEBOARD_FAB2_LIB.BASEBOARD_FAB2(SCH_1):M_L_MA(2)   I172 @BASEBOARD_FAB2_LIB.BASEBOARD_FAB2(SCH_1):PAGE61
  DW58 M_L_MA<1> @BASEBOARD_FAB2_LIB.BASEBOARD_FAB2(SCH_1):M_L_MA(1)   I172 @BASEBOARD_FAB2_LIB.BASEBOARD_FAB2(SCH_1):PAGE61
  DW52 M_L_MA<0> @BASEBOARD_FAB2_LIB.BASEBOARD_FAB2(SCH_1):M_L_MA(0)   I172 @BASEBOARD_FAB2_LIB.BASEBOARD_FAB2(SCH_1):PAGE61
  DM47 M_L_ODT<3> @BASEBOARD_FAB2_LIB.BASEBOARD_FAB2(SCH_1):M_L_ODT(3)   I172 @BASEBOARD_FAB2_LIB.BASEBOARD_FAB2(SCH_1):PAGE61
  DT49 M_L_ODT<2> @BASEBOARD_FAB2_LIB.BASEBOARD_FAB2(SCH_1):M_L_ODT(2)   I172 @BASEBOARD_FAB2_LIB.BASEBOARD_FAB2(SCH_1):PAGE61
  DN48 M_L_ODT<1> @BASEBOARD_FAB2_LIB.BASEBOARD_FAB2(SCH_1):M_L_ODT(1)   I172 @BASEBOARD_FAB2_LIB.BASEBOARD_FAB2(SCH_1):PAGE61
  DR50 M_L_ODT<0> @BASEBOARD_FAB2_LIB.BASEBOARD_FAB2(SCH_1):M_L_ODT(0)   I172 @BASEBOARD_FAB2_LIB.BASEBOARD_FAB2(SCH_1):PAGE61
  DV53 M_L_PAR @BASEBOARD_FAB2_LIB.BASEBOARD_FAB2(SCH_1):M_L_PAR   I172 @BASEBOARD_FAB2_LIB.BASEBOARD_FAB2(SCH_1):PAGE61
  DC62 M_M_ACT_N @BASEBOARD_FAB2_LIB.BASEBOARD_FAB2(SCH_1):M_M_ACT_N   I172 @BASEBOARD_FAB2_LIB.BASEBOARD_FAB2(SCH_1):PAGE62
  DD61 M_M_ALERT_N @BASEBOARD_FAB2_LIB.BASEBOARD_FAB2(SCH_1):M_M_ALERT_N   I172 @BASEBOARD_FAB2_LIB.BASEBOARD_FAB2(SCH_1):PAGE62
  DC56 M_M_BA<1> @BASEBOARD_FAB2_LIB.BASEBOARD_FAB2(SCH_1):M_M_BA(1)   I172 @BASEBOARD_FAB2_LIB.BASEBOARD_FAB2(SCH_1):PAGE62
  DJ52 M_M_BA<0> @BASEBOARD_FAB2_LIB.BASEBOARD_FAB2(SCH_1):M_M_BA(0)   I172 @BASEBOARD_FAB2_LIB.BASEBOARD_FAB2(SCH_1):PAGE62
  DF61 M_M_BG<1> @BASEBOARD_FAB2_LIB.BASEBOARD_FAB2(SCH_1):M_M_BG(1)   I172 @BASEBOARD_FAB2_LIB.BASEBOARD_FAB2(SCH_1):PAGE62
  DA62 M_M_BG<0> @BASEBOARD_FAB2_LIB.BASEBOARD_FAB2(SCH_1):M_M_BG(0)   I172 @BASEBOARD_FAB2_LIB.BASEBOARD_FAB2(SCH_1):PAGE62
  DF45 M_M_C<2> @BASEBOARD_FAB2_LIB.BASEBOARD_FAB2(SCH_1):M_M_C(2)   I172 @BASEBOARD_FAB2_LIB.BASEBOARD_FAB2(SCH_1):PAGE62
  DF63 M_M_CKE<3> @BASEBOARD_FAB2_LIB.BASEBOARD_FAB2(SCH_1):M_M_CKE(3)   I172 @BASEBOARD_FAB2_LIB.BASEBOARD_FAB2(SCH_1):PAGE62
  DK63 M_M_CKE<2> @BASEBOARD_FAB2_LIB.BASEBOARD_FAB2(SCH_1):M_M_CKE(2)   I172 @BASEBOARD_FAB2_LIB.BASEBOARD_FAB2(SCH_1):PAGE62
  DD63 M_M_CKE<1> @BASEBOARD_FAB2_LIB.BASEBOARD_FAB2(SCH_1):M_M_CKE(1)   I172 @BASEBOARD_FAB2_LIB.BASEBOARD_FAB2(SCH_1):PAGE62
  DG62 M_M_CKE<0> @BASEBOARD_FAB2_LIB.BASEBOARD_FAB2(SCH_1):M_M_CKE(0)   I172 @BASEBOARD_FAB2_LIB.BASEBOARD_FAB2(SCH_1):PAGE62
  DF57 M_M_CLK_DN<3> @BASEBOARD_FAB2_LIB.BASEBOARD_FAB2(SCH_1):M_M_CLK_DN(3)   I172 @BASEBOARD_FAB2_LIB.BASEBOARD_FAB2(SCH_1):PAGE62
  DK57 M_M_CLK_DN<2> @BASEBOARD_FAB2_LIB.BASEBOARD_FAB2(SCH_1):M_M_CLK_DN(2)   I172 @BASEBOARD_FAB2_LIB.BASEBOARD_FAB2(SCH_1):PAGE62
  DF55 M_M_CLK_DN<1> @BASEBOARD_FAB2_LIB.BASEBOARD_FAB2(SCH_1):M_M_CLK_DN(1)   I172 @BASEBOARD_FAB2_LIB.BASEBOARD_FAB2(SCH_1):PAGE62
  DK55 M_M_CLK_DN<0> @BASEBOARD_FAB2_LIB.BASEBOARD_FAB2(SCH_1):M_M_CLK_DN(0)   I172 @BASEBOARD_FAB2_LIB.BASEBOARD_FAB2(SCH_1):PAGE62
  DG56 M_M_CLK_DP<3> @BASEBOARD_FAB2_LIB.BASEBOARD_FAB2(SCH_1):M_M_CLK_DP(3)   I172 @BASEBOARD_FAB2_LIB.BASEBOARD_FAB2(SCH_1):PAGE62
  DJ56 M_M_CLK_DP<2> @BASEBOARD_FAB2_LIB.BASEBOARD_FAB2(SCH_1):M_M_CLK_DP(2)   I172 @BASEBOARD_FAB2_LIB.BASEBOARD_FAB2(SCH_1):PAGE62
  DG54 M_M_CLK_DP<1> @BASEBOARD_FAB2_LIB.BASEBOARD_FAB2(SCH_1):M_M_CLK_DP(1)   I172 @BASEBOARD_FAB2_LIB.BASEBOARD_FAB2(SCH_1):PAGE62
  DJ54 M_M_CLK_DP<0> @BASEBOARD_FAB2_LIB.BASEBOARD_FAB2(SCH_1):M_M_CLK_DP(0)   I172 @BASEBOARD_FAB2_LIB.BASEBOARD_FAB2(SCH_1):PAGE62
  DK45 M_M_CS_N<7> @BASEBOARD_FAB2_LIB.BASEBOARD_FAB2(SCH_1):M_M_CS_N(7)   I172 @BASEBOARD_FAB2_LIB.BASEBOARD_FAB2(SCH_1):PAGE62
  DM45 M_M_CS_N<6> @BASEBOARD_FAB2_LIB.BASEBOARD_FAB2(SCH_1):M_M_CS_N(6)   I172 @BASEBOARD_FAB2_LIB.BASEBOARD_FAB2(SCH_1):PAGE62
  DJ48 M_M_CS_N<5> @BASEBOARD_FAB2_LIB.BASEBOARD_FAB2(SCH_1):M_M_CS_N(5)   I172 @BASEBOARD_FAB2_LIB.BASEBOARD_FAB2(SCH_1):PAGE62
  DF51 M_M_CS_N<4> @BASEBOARD_FAB2_LIB.BASEBOARD_FAB2(SCH_1):M_M_CS_N(4)   I172 @BASEBOARD_FAB2_LIB.BASEBOARD_FAB2(SCH_1):PAGE62
  DG46 M_M_CS_N<3> @BASEBOARD_FAB2_LIB.BASEBOARD_FAB2(SCH_1):M_M_CS_N(3)   I172 @BASEBOARD_FAB2_LIB.BASEBOARD_FAB2(SCH_1):PAGE62
  DJ46 M_M_CS_N<2> @BASEBOARD_FAB2_LIB.BASEBOARD_FAB2(SCH_1):M_M_CS_N(2)   I172 @BASEBOARD_FAB2_LIB.BASEBOARD_FAB2(SCH_1):PAGE62
  DF49 M_M_CS_N<1> @BASEBOARD_FAB2_LIB.BASEBOARD_FAB2(SCH_1):M_M_CS_N(1)   I172 @BASEBOARD_FAB2_LIB.BASEBOARD_FAB2(SCH_1):PAGE62
  DK51 M_M_CS_N<0> @BASEBOARD_FAB2_LIB.BASEBOARD_FAB2(SCH_1):M_M_CS_N(0)   I172 @BASEBOARD_FAB2_LIB.BASEBOARD_FAB2(SCH_1):PAGE62
  DC28 M_M_DQ<63> @BASEBOARD_FAB2_LIB.BASEBOARD_FAB2(SCH_1):M_M_DQ(63)   I172 @BASEBOARD_FAB2_LIB.BASEBOARD_FAB2(SCH_1):PAGE62
  CW28 M_M_DQ<62> @BASEBOARD_FAB2_LIB.BASEBOARD_FAB2(SCH_1):M_M_DQ(62)   I172 @BASEBOARD_FAB2_LIB.BASEBOARD_FAB2(SCH_1):PAGE62
  DB31 M_M_DQ<61> @BASEBOARD_FAB2_LIB.BASEBOARD_FAB2(SCH_1):M_M_DQ(61)   I172 @BASEBOARD_FAB2_LIB.BASEBOARD_FAB2(SCH_1):PAGE62
  CY31 M_M_DQ<60> @BASEBOARD_FAB2_LIB.BASEBOARD_FAB2(SCH_1):M_M_DQ(60)   I172 @BASEBOARD_FAB2_LIB.BASEBOARD_FAB2(SCH_1):PAGE62
  DB27 M_M_DQ<59> @BASEBOARD_FAB2_LIB.BASEBOARD_FAB2(SCH_1):M_M_DQ(59)   I172 @BASEBOARD_FAB2_LIB.BASEBOARD_FAB2(SCH_1):PAGE62
  CY27 M_M_DQ<58> @BASEBOARD_FAB2_LIB.BASEBOARD_FAB2(SCH_1):M_M_DQ(58)   I172 @BASEBOARD_FAB2_LIB.BASEBOARD_FAB2(SCH_1):PAGE62
  DC30 M_M_DQ<57> @BASEBOARD_FAB2_LIB.BASEBOARD_FAB2(SCH_1):M_M_DQ(57)   I172 @BASEBOARD_FAB2_LIB.BASEBOARD_FAB2(SCH_1):PAGE62
  CW30 M_M_DQ<56> @BASEBOARD_FAB2_LIB.BASEBOARD_FAB2(SCH_1):M_M_DQ(56)   I172 @BASEBOARD_FAB2_LIB.BASEBOARD_FAB2(SCH_1):PAGE62
  DC34 M_M_DQ<55> @BASEBOARD_FAB2_LIB.BASEBOARD_FAB2(SCH_1):M_M_DQ(55)   I172 @BASEBOARD_FAB2_LIB.BASEBOARD_FAB2(SCH_1):PAGE62
  CW34 M_M_DQ<54> @BASEBOARD_FAB2_LIB.BASEBOARD_FAB2(SCH_1):M_M_DQ(54)   I172 @BASEBOARD_FAB2_LIB.BASEBOARD_FAB2(SCH_1):PAGE62
  DB37 M_M_DQ<53> @BASEBOARD_FAB2_LIB.BASEBOARD_FAB2(SCH_1):M_M_DQ(53)   I172 @BASEBOARD_FAB2_LIB.BASEBOARD_FAB2(SCH_1):PAGE62
  CY37 M_M_DQ<52> @BASEBOARD_FAB2_LIB.BASEBOARD_FAB2(SCH_1):M_M_DQ(52)   I172 @BASEBOARD_FAB2_LIB.BASEBOARD_FAB2(SCH_1):PAGE62
  DB33 M_M_DQ<51> @BASEBOARD_FAB2_LIB.BASEBOARD_FAB2(SCH_1):M_M_DQ(51)   I172 @BASEBOARD_FAB2_LIB.BASEBOARD_FAB2(SCH_1):PAGE62
  CY33 M_M_DQ<50> @BASEBOARD_FAB2_LIB.BASEBOARD_FAB2(SCH_1):M_M_DQ(50)   I172 @BASEBOARD_FAB2_LIB.BASEBOARD_FAB2(SCH_1):PAGE62
  DC36 M_M_DQ<49> @BASEBOARD_FAB2_LIB.BASEBOARD_FAB2(SCH_1):M_M_DQ(49)   I172 @BASEBOARD_FAB2_LIB.BASEBOARD_FAB2(SCH_1):PAGE62
  CW36 M_M_DQ<48> @BASEBOARD_FAB2_LIB.BASEBOARD_FAB2(SCH_1):M_M_DQ(48)   I172 @BASEBOARD_FAB2_LIB.BASEBOARD_FAB2(SCH_1):PAGE62
  DK31 M_M_DQ<47> @BASEBOARD_FAB2_LIB.BASEBOARD_FAB2(SCH_1):M_M_DQ(47)   I172 @BASEBOARD_FAB2_LIB.BASEBOARD_FAB2(SCH_1):PAGE62
  DF31 M_M_DQ<46> @BASEBOARD_FAB2_LIB.BASEBOARD_FAB2(SCH_1):M_M_DQ(46)   I172 @BASEBOARD_FAB2_LIB.BASEBOARD_FAB2(SCH_1):PAGE62
  DJ34 M_M_DQ<45> @BASEBOARD_FAB2_LIB.BASEBOARD_FAB2(SCH_1):M_M_DQ(45)   I172 @BASEBOARD_FAB2_LIB.BASEBOARD_FAB2(SCH_1):PAGE62
  DG34 M_M_DQ<44> @BASEBOARD_FAB2_LIB.BASEBOARD_FAB2(SCH_1):M_M_DQ(44)   I172 @BASEBOARD_FAB2_LIB.BASEBOARD_FAB2(SCH_1):PAGE62
  DJ30 M_M_DQ<43> @BASEBOARD_FAB2_LIB.BASEBOARD_FAB2(SCH_1):M_M_DQ(43)   I172 @BASEBOARD_FAB2_LIB.BASEBOARD_FAB2(SCH_1):PAGE62
  DG30 M_M_DQ<42> @BASEBOARD_FAB2_LIB.BASEBOARD_FAB2(SCH_1):M_M_DQ(42)   I172 @BASEBOARD_FAB2_LIB.BASEBOARD_FAB2(SCH_1):PAGE62
  DK33 M_M_DQ<41> @BASEBOARD_FAB2_LIB.BASEBOARD_FAB2(SCH_1):M_M_DQ(41)   I172 @BASEBOARD_FAB2_LIB.BASEBOARD_FAB2(SCH_1):PAGE62
  DF33 M_M_DQ<40> @BASEBOARD_FAB2_LIB.BASEBOARD_FAB2(SCH_1):M_M_DQ(40)   I172 @BASEBOARD_FAB2_LIB.BASEBOARD_FAB2(SCH_1):PAGE62
  DH39 M_M_DQ<39> @BASEBOARD_FAB2_LIB.BASEBOARD_FAB2(SCH_1):M_M_DQ(39)   I172 @BASEBOARD_FAB2_LIB.BASEBOARD_FAB2(SCH_1):PAGE62
  DD39 M_M_DQ<38> @BASEBOARD_FAB2_LIB.BASEBOARD_FAB2(SCH_1):M_M_DQ(38)   I172 @BASEBOARD_FAB2_LIB.BASEBOARD_FAB2(SCH_1):PAGE62
  DE42 M_M_DQ<37> @BASEBOARD_FAB2_LIB.BASEBOARD_FAB2(SCH_1):M_M_DQ(37)   I172 @BASEBOARD_FAB2_LIB.BASEBOARD_FAB2(SCH_1):PAGE62
  DA42 M_M_DQ<36> @BASEBOARD_FAB2_LIB.BASEBOARD_FAB2(SCH_1):M_M_DQ(36)   I172 @BASEBOARD_FAB2_LIB.BASEBOARD_FAB2(SCH_1):PAGE62
  DG38 M_M_DQ<35> @BASEBOARD_FAB2_LIB.BASEBOARD_FAB2(SCH_1):M_M_DQ(35)   I172 @BASEBOARD_FAB2_LIB.BASEBOARD_FAB2(SCH_1):PAGE62
  DE38 M_M_DQ<34> @BASEBOARD_FAB2_LIB.BASEBOARD_FAB2(SCH_1):M_M_DQ(34)   I172 @BASEBOARD_FAB2_LIB.BASEBOARD_FAB2(SCH_1):PAGE62
  DG42 M_M_DQ<33> @BASEBOARD_FAB2_LIB.BASEBOARD_FAB2(SCH_1):M_M_DQ(33)   I172 @BASEBOARD_FAB2_LIB.BASEBOARD_FAB2(SCH_1):PAGE62
  DD41 M_M_DQ<32> @BASEBOARD_FAB2_LIB.BASEBOARD_FAB2(SCH_1):M_M_DQ(32)   I172 @BASEBOARD_FAB2_LIB.BASEBOARD_FAB2(SCH_1):PAGE62
  CU64 M_M_DQ<31> @BASEBOARD_FAB2_LIB.BASEBOARD_FAB2(SCH_1):M_M_DQ(31)   I172 @BASEBOARD_FAB2_LIB.BASEBOARD_FAB2(SCH_1):PAGE62
  CN64 M_M_DQ<30> @BASEBOARD_FAB2_LIB.BASEBOARD_FAB2(SCH_1):M_M_DQ(30)   I172 @BASEBOARD_FAB2_LIB.BASEBOARD_FAB2(SCH_1):PAGE62
  CT67 M_M_DQ<29> @BASEBOARD_FAB2_LIB.BASEBOARD_FAB2(SCH_1):M_M_DQ(29)   I172 @BASEBOARD_FAB2_LIB.BASEBOARD_FAB2(SCH_1):PAGE62
  CP67 M_M_DQ<28> @BASEBOARD_FAB2_LIB.BASEBOARD_FAB2(SCH_1):M_M_DQ(28)   I172 @BASEBOARD_FAB2_LIB.BASEBOARD_FAB2(SCH_1):PAGE62
  CT63 M_M_DQ<27> @BASEBOARD_FAB2_LIB.BASEBOARD_FAB2(SCH_1):M_M_DQ(27)   I172 @BASEBOARD_FAB2_LIB.BASEBOARD_FAB2(SCH_1):PAGE62
  CP63 M_M_DQ<26> @BASEBOARD_FAB2_LIB.BASEBOARD_FAB2(SCH_1):M_M_DQ(26)   I172 @BASEBOARD_FAB2_LIB.BASEBOARD_FAB2(SCH_1):PAGE62
  CU66 M_M_DQ<25> @BASEBOARD_FAB2_LIB.BASEBOARD_FAB2(SCH_1):M_M_DQ(25)   I172 @BASEBOARD_FAB2_LIB.BASEBOARD_FAB2(SCH_1):PAGE62
  CN66 M_M_DQ<24> @BASEBOARD_FAB2_LIB.BASEBOARD_FAB2(SCH_1):M_M_DQ(24)   I172 @BASEBOARD_FAB2_LIB.BASEBOARD_FAB2(SCH_1):PAGE62
  DM71 M_M_DQ<23> @BASEBOARD_FAB2_LIB.BASEBOARD_FAB2(SCH_1):M_M_DQ(23)   I172 @BASEBOARD_FAB2_LIB.BASEBOARD_FAB2(SCH_1):PAGE62
  DK69 M_M_DQ<22> @BASEBOARD_FAB2_LIB.BASEBOARD_FAB2(SCH_1):M_M_DQ(22)   I172 @BASEBOARD_FAB2_LIB.BASEBOARD_FAB2(SCH_1):PAGE62
  DG72 M_M_DQ<21> @BASEBOARD_FAB2_LIB.BASEBOARD_FAB2(SCH_1):M_M_DQ(21)   I172 @BASEBOARD_FAB2_LIB.BASEBOARD_FAB2(SCH_1):PAGE62
  DF71 M_M_DQ<20> @BASEBOARD_FAB2_LIB.BASEBOARD_FAB2(SCH_1):M_M_DQ(20)   I172 @BASEBOARD_FAB2_LIB.BASEBOARD_FAB2(SCH_1):PAGE62
  DN70 M_M_DQ<19> @BASEBOARD_FAB2_LIB.BASEBOARD_FAB2(SCH_1):M_M_DQ(19)   I172 @BASEBOARD_FAB2_LIB.BASEBOARD_FAB2(SCH_1):PAGE62
  DM69 M_M_DQ<18> @BASEBOARD_FAB2_LIB.BASEBOARD_FAB2(SCH_1):M_M_DQ(18)   I172 @BASEBOARD_FAB2_LIB.BASEBOARD_FAB2(SCH_1):PAGE62
  DJ72 M_M_DQ<17> @BASEBOARD_FAB2_LIB.BASEBOARD_FAB2(SCH_1):M_M_DQ(17)   I172 @BASEBOARD_FAB2_LIB.BASEBOARD_FAB2(SCH_1):PAGE62
  DG70 M_M_DQ<16> @BASEBOARD_FAB2_LIB.BASEBOARD_FAB2(SCH_1):M_M_DQ(16)   I172 @BASEBOARD_FAB2_LIB.BASEBOARD_FAB2(SCH_1):PAGE62
  DH77 M_M_DQ<15> @BASEBOARD_FAB2_LIB.BASEBOARD_FAB2(SCH_1):M_M_DQ(15)   I172 @BASEBOARD_FAB2_LIB.BASEBOARD_FAB2(SCH_1):PAGE62
  DF77 M_M_DQ<14> @BASEBOARD_FAB2_LIB.BASEBOARD_FAB2(SCH_1):M_M_DQ(14)   I172 @BASEBOARD_FAB2_LIB.BASEBOARD_FAB2(SCH_1):PAGE62
  DB75 M_M_DQ<13> @BASEBOARD_FAB2_LIB.BASEBOARD_FAB2(SCH_1):M_M_DQ(13)   I172 @BASEBOARD_FAB2_LIB.BASEBOARD_FAB2(SCH_1):PAGE62
  DC74 M_M_DQ<12> @BASEBOARD_FAB2_LIB.BASEBOARD_FAB2(SCH_1):M_M_DQ(12)   I172 @BASEBOARD_FAB2_LIB.BASEBOARD_FAB2(SCH_1):PAGE62
  DJ76 M_M_DQ<11> @BASEBOARD_FAB2_LIB.BASEBOARD_FAB2(SCH_1):M_M_DQ(11)   I172 @BASEBOARD_FAB2_LIB.BASEBOARD_FAB2(SCH_1):PAGE62
  DH75 M_M_DQ<10> @BASEBOARD_FAB2_LIB.BASEBOARD_FAB2(SCH_1):M_M_DQ(10)   I172 @BASEBOARD_FAB2_LIB.BASEBOARD_FAB2(SCH_1):PAGE62
  DC76 M_M_DQ<9> @BASEBOARD_FAB2_LIB.BASEBOARD_FAB2(SCH_1):M_M_DQ(9)   I172 @BASEBOARD_FAB2_LIB.BASEBOARD_FAB2(SCH_1):PAGE62
  DE74 M_M_DQ<8> @BASEBOARD_FAB2_LIB.BASEBOARD_FAB2(SCH_1):M_M_DQ(8)   I172 @BASEBOARD_FAB2_LIB.BASEBOARD_FAB2(SCH_1):PAGE62
  CT77 M_M_DQ<7> @BASEBOARD_FAB2_LIB.BASEBOARD_FAB2(SCH_1):M_M_DQ(7)   I172 @BASEBOARD_FAB2_LIB.BASEBOARD_FAB2(SCH_1):PAGE62
  CV75 M_M_DQ<6> @BASEBOARD_FAB2_LIB.BASEBOARD_FAB2(SCH_1):M_M_DQ(6)   I172 @BASEBOARD_FAB2_LIB.BASEBOARD_FAB2(SCH_1):PAGE62
  CM75 M_M_DQ<5> @BASEBOARD_FAB2_LIB.BASEBOARD_FAB2(SCH_1):M_M_DQ(5)   I172 @BASEBOARD_FAB2_LIB.BASEBOARD_FAB2(SCH_1):PAGE62
  CN74 M_M_DQ<4> @BASEBOARD_FAB2_LIB.BASEBOARD_FAB2(SCH_1):M_M_DQ(4)   I172 @BASEBOARD_FAB2_LIB.BASEBOARD_FAB2(SCH_1):PAGE62
  CV77 M_M_DQ<3> @BASEBOARD_FAB2_LIB.BASEBOARD_FAB2(SCH_1):M_M_DQ(3)   I172 @BASEBOARD_FAB2_LIB.BASEBOARD_FAB2(SCH_1):PAGE62
  CW76 M_M_DQ<2> @BASEBOARD_FAB2_LIB.BASEBOARD_FAB2(SCH_1):M_M_DQ(2)   I172 @BASEBOARD_FAB2_LIB.BASEBOARD_FAB2(SCH_1):PAGE62
  CN76 M_M_DQ<1> @BASEBOARD_FAB2_LIB.BASEBOARD_FAB2(SCH_1):M_M_DQ(1)   I172 @BASEBOARD_FAB2_LIB.BASEBOARD_FAB2(SCH_1):PAGE62
  CR74 M_M_DQ<0> @BASEBOARD_FAB2_LIB.BASEBOARD_FAB2(SCH_1):M_M_DQ(0)   I172 @BASEBOARD_FAB2_LIB.BASEBOARD_FAB2(SCH_1):PAGE62
  CJ70 M_M_DQS_DN<17> @BASEBOARD_FAB2_LIB.BASEBOARD_FAB2(SCH_1):M_M_DQS_DN(17)   I172 @BASEBOARD_FAB2_LIB.BASEBOARD_FAB2(SCH_1):PAGE62
  CY29 M_M_DQS_DN<16> @BASEBOARD_FAB2_LIB.BASEBOARD_FAB2(SCH_1):M_M_DQS_DN(16)   I172 @BASEBOARD_FAB2_LIB.BASEBOARD_FAB2(SCH_1):PAGE62
  CY35 M_M_DQS_DN<15> @BASEBOARD_FAB2_LIB.BASEBOARD_FAB2(SCH_1):M_M_DQS_DN(15)   I172 @BASEBOARD_FAB2_LIB.BASEBOARD_FAB2(SCH_1):PAGE62
  DG32 M_M_DQS_DN<14> @BASEBOARD_FAB2_LIB.BASEBOARD_FAB2(SCH_1):M_M_DQS_DN(14)   I172 @BASEBOARD_FAB2_LIB.BASEBOARD_FAB2(SCH_1):PAGE62
  DE40 M_M_DQS_DN<13> @BASEBOARD_FAB2_LIB.BASEBOARD_FAB2(SCH_1):M_M_DQS_DN(13)   I172 @BASEBOARD_FAB2_LIB.BASEBOARD_FAB2(SCH_1):PAGE62
  CP65 M_M_DQS_DN<12> @BASEBOARD_FAB2_LIB.BASEBOARD_FAB2(SCH_1):M_M_DQS_DN(12)   I172 @BASEBOARD_FAB2_LIB.BASEBOARD_FAB2(SCH_1):PAGE62
  DJ70 M_M_DQS_DN<11> @BASEBOARD_FAB2_LIB.BASEBOARD_FAB2(SCH_1):M_M_DQS_DN(11)   I172 @BASEBOARD_FAB2_LIB.BASEBOARD_FAB2(SCH_1):PAGE62
  DF75 M_M_DQS_DN<10> @BASEBOARD_FAB2_LIB.BASEBOARD_FAB2(SCH_1):M_M_DQS_DN(10)   I172 @BASEBOARD_FAB2_LIB.BASEBOARD_FAB2(SCH_1):PAGE62
  CT75 M_M_DQS_DN<9> @BASEBOARD_FAB2_LIB.BASEBOARD_FAB2(SCH_1):M_M_DQS_DN(9)   I172 @BASEBOARD_FAB2_LIB.BASEBOARD_FAB2(SCH_1):PAGE62
  CN70 M_M_DQS_DN<8> @BASEBOARD_FAB2_LIB.BASEBOARD_FAB2(SCH_1):M_M_DQS_DN(8)   I172 @BASEBOARD_FAB2_LIB.BASEBOARD_FAB2(SCH_1):PAGE62
  DD29 M_M_DQS_DN<7> @BASEBOARD_FAB2_LIB.BASEBOARD_FAB2(SCH_1):M_M_DQS_DN(7)   I172 @BASEBOARD_FAB2_LIB.BASEBOARD_FAB2(SCH_1):PAGE62
  DD35 M_M_DQS_DN<6> @BASEBOARD_FAB2_LIB.BASEBOARD_FAB2(SCH_1):M_M_DQS_DN(6)   I172 @BASEBOARD_FAB2_LIB.BASEBOARD_FAB2(SCH_1):PAGE62
  DL32 M_M_DQS_DN<5> @BASEBOARD_FAB2_LIB.BASEBOARD_FAB2(SCH_1):M_M_DQS_DN(5)   I172 @BASEBOARD_FAB2_LIB.BASEBOARD_FAB2(SCH_1):PAGE62
  DG40 M_M_DQS_DN<4> @BASEBOARD_FAB2_LIB.BASEBOARD_FAB2(SCH_1):M_M_DQS_DN(4)   I172 @BASEBOARD_FAB2_LIB.BASEBOARD_FAB2(SCH_1):PAGE62
  CV65 M_M_DQS_DN<3> @BASEBOARD_FAB2_LIB.BASEBOARD_FAB2(SCH_1):M_M_DQS_DN(3)   I172 @BASEBOARD_FAB2_LIB.BASEBOARD_FAB2(SCH_1):PAGE62
  DL72 M_M_DQS_DN<2> @BASEBOARD_FAB2_LIB.BASEBOARD_FAB2(SCH_1):M_M_DQS_DN(2)   I172 @BASEBOARD_FAB2_LIB.BASEBOARD_FAB2(SCH_1):PAGE62
  DD77 M_M_DQS_DN<1> @BASEBOARD_FAB2_LIB.BASEBOARD_FAB2(SCH_1):M_M_DQS_DN(1)   I172 @BASEBOARD_FAB2_LIB.BASEBOARD_FAB2(SCH_1):PAGE62
  CP77 M_M_DQS_DN<0> @BASEBOARD_FAB2_LIB.BASEBOARD_FAB2(SCH_1):M_M_DQS_DN(0)   I172 @BASEBOARD_FAB2_LIB.BASEBOARD_FAB2(SCH_1):PAGE62
  CG70 M_M_DQS_DP<17> @BASEBOARD_FAB2_LIB.BASEBOARD_FAB2(SCH_1):M_M_DQS_DP(17)   I172 @BASEBOARD_FAB2_LIB.BASEBOARD_FAB2(SCH_1):PAGE62
  CV29 M_M_DQS_DP<16> @BASEBOARD_FAB2_LIB.BASEBOARD_FAB2(SCH_1):M_M_DQS_DP(16)   I172 @BASEBOARD_FAB2_LIB.BASEBOARD_FAB2(SCH_1):PAGE62
  CV35 M_M_DQS_DP<15> @BASEBOARD_FAB2_LIB.BASEBOARD_FAB2(SCH_1):M_M_DQS_DP(15)   I172 @BASEBOARD_FAB2_LIB.BASEBOARD_FAB2(SCH_1):PAGE62
  DE32 M_M_DQS_DP<14> @BASEBOARD_FAB2_LIB.BASEBOARD_FAB2(SCH_1):M_M_DQS_DP(14)   I172 @BASEBOARD_FAB2_LIB.BASEBOARD_FAB2(SCH_1):PAGE62
  DC40 M_M_DQS_DP<13> @BASEBOARD_FAB2_LIB.BASEBOARD_FAB2(SCH_1):M_M_DQS_DP(13)   I172 @BASEBOARD_FAB2_LIB.BASEBOARD_FAB2(SCH_1):PAGE62
  CM65 M_M_DQS_DP<12> @BASEBOARD_FAB2_LIB.BASEBOARD_FAB2(SCH_1):M_M_DQS_DP(12)   I172 @BASEBOARD_FAB2_LIB.BASEBOARD_FAB2(SCH_1):PAGE62
  DH69 M_M_DQS_DP<11> @BASEBOARD_FAB2_LIB.BASEBOARD_FAB2(SCH_1):M_M_DQS_DP(11)   I172 @BASEBOARD_FAB2_LIB.BASEBOARD_FAB2(SCH_1):PAGE62
  DG74 M_M_DQS_DP<10> @BASEBOARD_FAB2_LIB.BASEBOARD_FAB2(SCH_1):M_M_DQS_DP(10)   I172 @BASEBOARD_FAB2_LIB.BASEBOARD_FAB2(SCH_1):PAGE62
  CU74 M_M_DQS_DP<9> @BASEBOARD_FAB2_LIB.BASEBOARD_FAB2(SCH_1):M_M_DQS_DP(9)   I172 @BASEBOARD_FAB2_LIB.BASEBOARD_FAB2(SCH_1):PAGE62
  CL70 M_M_DQS_DP<8> @BASEBOARD_FAB2_LIB.BASEBOARD_FAB2(SCH_1):M_M_DQS_DP(8)   I172 @BASEBOARD_FAB2_LIB.BASEBOARD_FAB2(SCH_1):PAGE62
  DB29 M_M_DQS_DP<7> @BASEBOARD_FAB2_LIB.BASEBOARD_FAB2(SCH_1):M_M_DQS_DP(7)   I172 @BASEBOARD_FAB2_LIB.BASEBOARD_FAB2(SCH_1):PAGE62
  DB35 M_M_DQS_DP<6> @BASEBOARD_FAB2_LIB.BASEBOARD_FAB2(SCH_1):M_M_DQS_DP(6)   I172 @BASEBOARD_FAB2_LIB.BASEBOARD_FAB2(SCH_1):PAGE62
  DJ32 M_M_DQS_DP<5> @BASEBOARD_FAB2_LIB.BASEBOARD_FAB2(SCH_1):M_M_DQS_DP(5)   I172 @BASEBOARD_FAB2_LIB.BASEBOARD_FAB2(SCH_1):PAGE62
  DJ40 M_M_DQS_DP<4> @BASEBOARD_FAB2_LIB.BASEBOARD_FAB2(SCH_1):M_M_DQS_DP(4)   I172 @BASEBOARD_FAB2_LIB.BASEBOARD_FAB2(SCH_1):PAGE62
  CT65 M_M_DQS_DP<3> @BASEBOARD_FAB2_LIB.BASEBOARD_FAB2(SCH_1):M_M_DQS_DP(3)   I172 @BASEBOARD_FAB2_LIB.BASEBOARD_FAB2(SCH_1):PAGE62
  DK71 M_M_DQS_DP<2> @BASEBOARD_FAB2_LIB.BASEBOARD_FAB2(SCH_1):M_M_DQS_DP(2)   I172 @BASEBOARD_FAB2_LIB.BASEBOARD_FAB2(SCH_1):PAGE62
  DE76 M_M_DQS_DP<1> @BASEBOARD_FAB2_LIB.BASEBOARD_FAB2(SCH_1):M_M_DQS_DP(1)   I172 @BASEBOARD_FAB2_LIB.BASEBOARD_FAB2(SCH_1):PAGE62
  CR76 M_M_DQS_DP<0> @BASEBOARD_FAB2_LIB.BASEBOARD_FAB2(SCH_1):M_M_DQS_DP(0)   I172 @BASEBOARD_FAB2_LIB.BASEBOARD_FAB2(SCH_1):PAGE62
  CM69 M_M_ECC<7> @BASEBOARD_FAB2_LIB.BASEBOARD_FAB2(SCH_1):M_M_ECC(7)   I172 @BASEBOARD_FAB2_LIB.BASEBOARD_FAB2(SCH_1):PAGE62
  CH69 M_M_ECC<6> @BASEBOARD_FAB2_LIB.BASEBOARD_FAB2(SCH_1):M_M_ECC(6)   I172 @BASEBOARD_FAB2_LIB.BASEBOARD_FAB2(SCH_1):PAGE62
  CL72 M_M_ECC<5> @BASEBOARD_FAB2_LIB.BASEBOARD_FAB2(SCH_1):M_M_ECC(5)   I172 @BASEBOARD_FAB2_LIB.BASEBOARD_FAB2(SCH_1):PAGE62
  CJ72 M_M_ECC<4> @BASEBOARD_FAB2_LIB.BASEBOARD_FAB2(SCH_1):M_M_ECC(4)   I172 @BASEBOARD_FAB2_LIB.BASEBOARD_FAB2(SCH_1):PAGE62
  CL68 M_M_ECC<3> @BASEBOARD_FAB2_LIB.BASEBOARD_FAB2(SCH_1):M_M_ECC(3)   I172 @BASEBOARD_FAB2_LIB.BASEBOARD_FAB2(SCH_1):PAGE62
  CJ68 M_M_ECC<2> @BASEBOARD_FAB2_LIB.BASEBOARD_FAB2(SCH_1):M_M_ECC(2)   I172 @BASEBOARD_FAB2_LIB.BASEBOARD_FAB2(SCH_1):PAGE62
  CM71 M_M_ECC<1> @BASEBOARD_FAB2_LIB.BASEBOARD_FAB2(SCH_1):M_M_ECC(1)   I172 @BASEBOARD_FAB2_LIB.BASEBOARD_FAB2(SCH_1):PAGE62
  CH71 M_M_ECC<0> @BASEBOARD_FAB2_LIB.BASEBOARD_FAB2(SCH_1):M_M_ECC(0)   I172 @BASEBOARD_FAB2_LIB.BASEBOARD_FAB2(SCH_1):PAGE62
  DE46 M_M_MA<17> @BASEBOARD_FAB2_LIB.BASEBOARD_FAB2(SCH_1):M_M_MA(17)   I172 @BASEBOARD_FAB2_LIB.BASEBOARD_FAB2(SCH_1):PAGE62
  DG52 M_M_MA<16> @BASEBOARD_FAB2_LIB.BASEBOARD_FAB2(SCH_1):M_M_MA(16)   I172 @BASEBOARD_FAB2_LIB.BASEBOARD_FAB2(SCH_1):PAGE62
  DC54 M_M_MA<15> @BASEBOARD_FAB2_LIB.BASEBOARD_FAB2(SCH_1):M_M_MA(15)   I172 @BASEBOARD_FAB2_LIB.BASEBOARD_FAB2(SCH_1):PAGE62
  DJ50 M_M_MA<14> @BASEBOARD_FAB2_LIB.BASEBOARD_FAB2(SCH_1):M_M_MA(14)   I172 @BASEBOARD_FAB2_LIB.BASEBOARD_FAB2(SCH_1):PAGE62
  DD53 M_M_MA<13> @BASEBOARD_FAB2_LIB.BASEBOARD_FAB2(SCH_1):M_M_MA(13)   I172 @BASEBOARD_FAB2_LIB.BASEBOARD_FAB2(SCH_1):PAGE62
  DG60 M_M_MA<12> @BASEBOARD_FAB2_LIB.BASEBOARD_FAB2(SCH_1):M_M_MA(12)   I172 @BASEBOARD_FAB2_LIB.BASEBOARD_FAB2(SCH_1):PAGE62
  DA60 M_M_MA<11> @BASEBOARD_FAB2_LIB.BASEBOARD_FAB2(SCH_1):M_M_MA(11)   I172 @BASEBOARD_FAB2_LIB.BASEBOARD_FAB2(SCH_1):PAGE62
  DD55 M_M_MA<10> @BASEBOARD_FAB2_LIB.BASEBOARD_FAB2(SCH_1):M_M_MA(10)   I172 @BASEBOARD_FAB2_LIB.BASEBOARD_FAB2(SCH_1):PAGE62
  DA58 M_M_MA<9> @BASEBOARD_FAB2_LIB.BASEBOARD_FAB2(SCH_1):M_M_MA(9)   I172 @BASEBOARD_FAB2_LIB.BASEBOARD_FAB2(SCH_1):PAGE62
  DD59 M_M_MA<8> @BASEBOARD_FAB2_LIB.BASEBOARD_FAB2(SCH_1):M_M_MA(8)   I172 @BASEBOARD_FAB2_LIB.BASEBOARD_FAB2(SCH_1):PAGE62
  DC60 M_M_MA<7> @BASEBOARD_FAB2_LIB.BASEBOARD_FAB2(SCH_1):M_M_MA(7)   I172 @BASEBOARD_FAB2_LIB.BASEBOARD_FAB2(SCH_1):PAGE62
  DK59 M_M_MA<6> @BASEBOARD_FAB2_LIB.BASEBOARD_FAB2(SCH_1):M_M_MA(6)   I172 @BASEBOARD_FAB2_LIB.BASEBOARD_FAB2(SCH_1):PAGE62
  DF59 M_M_MA<5> @BASEBOARD_FAB2_LIB.BASEBOARD_FAB2(SCH_1):M_M_MA(5)   I172 @BASEBOARD_FAB2_LIB.BASEBOARD_FAB2(SCH_1):PAGE62
  DJ58 M_M_MA<4> @BASEBOARD_FAB2_LIB.BASEBOARD_FAB2(SCH_1):M_M_MA(4)   I172 @BASEBOARD_FAB2_LIB.BASEBOARD_FAB2(SCH_1):PAGE62
  DG58 M_M_MA<3> @BASEBOARD_FAB2_LIB.BASEBOARD_FAB2(SCH_1):M_M_MA(3)   I172 @BASEBOARD_FAB2_LIB.BASEBOARD_FAB2(SCH_1):PAGE62
  DD57 M_M_MA<2> @BASEBOARD_FAB2_LIB.BASEBOARD_FAB2(SCH_1):M_M_MA(2)   I172 @BASEBOARD_FAB2_LIB.BASEBOARD_FAB2(SCH_1):PAGE62
  DC58 M_M_MA<1> @BASEBOARD_FAB2_LIB.BASEBOARD_FAB2(SCH_1):M_M_MA(1)   I172 @BASEBOARD_FAB2_LIB.BASEBOARD_FAB2(SCH_1):PAGE62
  DF53 M_M_MA<0> @BASEBOARD_FAB2_LIB.BASEBOARD_FAB2(SCH_1):M_M_MA(0)   I172 @BASEBOARD_FAB2_LIB.BASEBOARD_FAB2(SCH_1):PAGE62
  DF47 M_M_ODT<3> @BASEBOARD_FAB2_LIB.BASEBOARD_FAB2(SCH_1):M_M_ODT(3)   I172 @BASEBOARD_FAB2_LIB.BASEBOARD_FAB2(SCH_1):PAGE62
  DK49 M_M_ODT<2> @BASEBOARD_FAB2_LIB.BASEBOARD_FAB2(SCH_1):M_M_ODT(2)   I172 @BASEBOARD_FAB2_LIB.BASEBOARD_FAB2(SCH_1):PAGE62
  DG48 M_M_ODT<1> @BASEBOARD_FAB2_LIB.BASEBOARD_FAB2(SCH_1):M_M_ODT(1)   I172 @BASEBOARD_FAB2_LIB.BASEBOARD_FAB2(SCH_1):PAGE62
  DG50 M_M_ODT<0> @BASEBOARD_FAB2_LIB.BASEBOARD_FAB2(SCH_1):M_M_ODT(0)   I172 @BASEBOARD_FAB2_LIB.BASEBOARD_FAB2(SCH_1):PAGE62
  DK53 M_M_PAR @BASEBOARD_FAB2_LIB.BASEBOARD_FAB2(SCH_1):M_M_PAR   I172 @BASEBOARD_FAB2_LIB.BASEBOARD_FAB2(SCH_1):PAGE62
  BN22 TP_SMB_CPU1_CD_HFI0_I2CCLK @BASEBOARD_FAB2_LIB.BASEBOARD_FAB2(SCH_1):TP_SMB_CPU1_CD_HFI0_I2CCLK    I23 @BASEBOARD_FAB2_LIB.BASEBOARD_FAB2(SCH_1):PAGE63
  BP23 TP_SMB_CPU1_CD_HFI0_I2CDAT @BASEBOARD_FAB2_LIB.BASEBOARD_FAB2(SCH_1):TP_SMB_CPU1_CD_HFI0_I2CDAT    I23 @BASEBOARD_FAB2_LIB.BASEBOARD_FAB2(SCH_1):PAGE63
  BP19 TP_IRQ_CPU1_CD_HFI0_N @BASEBOARD_FAB2_LIB.BASEBOARD_FAB2(SCH_1):TP_IRQ_CPU1_CD_HFI0_N    I23 @BASEBOARD_FAB2_LIB.BASEBOARD_FAB2(SCH_1):PAGE63
  BK21 TP_LED_CPU1_CD_HFI0_N @BASEBOARD_FAB2_LIB.BASEBOARD_FAB2(SCH_1):TP_LED_CPU1_CD_HFI0_N    I23 @BASEBOARD_FAB2_LIB.BASEBOARD_FAB2(SCH_1):PAGE63
  BR20 TP_FM_CPU1_CD_HFI0_MODPRST_N @BASEBOARD_FAB2_LIB.BASEBOARD_FAB2(SCH_1):TP_FM_CPU1_CD_HFI0_MODPRST_N    I23 @BASEBOARD_FAB2_LIB.BASEBOARD_FAB2(SCH_1):PAGE63
  BN24 TP_RST_CPU1_CD_HFI0_N @BASEBOARD_FAB2_LIB.BASEBOARD_FAB2(SCH_1):TP_RST_CPU1_CD_HFI0_N    I23 @BASEBOARD_FAB2_LIB.BASEBOARD_FAB2(SCH_1):PAGE63
  BJ22 TP_CD_HFI1_CPU1_I2CLK @BASEBOARD_FAB2_LIB.BASEBOARD_FAB2(SCH_1):TP_CD_HFI1_CPU1_I2CLK    I23 @BASEBOARD_FAB2_LIB.BASEBOARD_FAB2(SCH_1):PAGE63
  BH23 TP_CD_HFI1_CPU1_I2CDAT @BASEBOARD_FAB2_LIB.BASEBOARD_FAB2(SCH_1):TP_CD_HFI1_CPU1_I2CDAT    I23 @BASEBOARD_FAB2_LIB.BASEBOARD_FAB2(SCH_1):PAGE63
  BM21 TP_CD_HFI1_CPU1_INT_N @BASEBOARD_FAB2_LIB.BASEBOARD_FAB2(SCH_1):TP_CD_HFI1_CPU1_INT_N    I23 @BASEBOARD_FAB2_LIB.BASEBOARD_FAB2(SCH_1):PAGE63
  BM23 TP_CD_HFI1_CPU1_LED_N @BASEBOARD_FAB2_LIB.BASEBOARD_FAB2(SCH_1):TP_CD_HFI1_CPU1_LED_N    I23 @BASEBOARD_FAB2_LIB.BASEBOARD_FAB2(SCH_1):PAGE63
  BT19 TP_CD_HFI1_CPU1_MODPRST_N @BASEBOARD_FAB2_LIB.BASEBOARD_FAB2(SCH_1):TP_CD_HFI1_CPU1_MODPRST_N    I23 @BASEBOARD_FAB2_LIB.BASEBOARD_FAB2(SCH_1):PAGE63
  BK23 TP_CD_HFI1_CPU1_RESET_N @BASEBOARD_FAB2_LIB.BASEBOARD_FAB2(SCH_1):TP_CD_HFI1_CPU1_RESET_N    I23 @BASEBOARD_FAB2_LIB.BASEBOARD_FAB2(SCH_1):PAGE63
  BE16 CLK_156M_OSC_CPU1_HFI_DN @BASEBOARD_FAB2_LIB.BASEBOARD_FAB2(SCH_1):CLK_156M_OSC_CPU1_HFI_DN    I23 @BASEBOARD_FAB2_LIB.BASEBOARD_FAB2(SCH_1):PAGE63
  BG16 CLK_156M_OSC_CPU1_HFI_DP @BASEBOARD_FAB2_LIB.BASEBOARD_FAB2(SCH_1):CLK_156M_OSC_CPU1_HFI_DP    I23 @BASEBOARD_FAB2_LIB.BASEBOARD_FAB2(SCH_1):PAGE63
  BU24 CLK_100M_CPU1_PE_REFCLK_DN @BASEBOARD_FAB2_LIB.BASEBOARD_FAB2(SCH_1):CLK_100M_CPU1_PE_REFCLK_DN    I23 @BASEBOARD_FAB2_LIB.BASEBOARD_FAB2(SCH_1):PAGE63
  BW24 CLK_100M_CPU1_PE_REFCLK_DP @BASEBOARD_FAB2_LIB.BASEBOARD_FAB2(SCH_1):CLK_100M_CPU1_PE_REFCLK_DP    I23 @BASEBOARD_FAB2_LIB.BASEBOARD_FAB2(SCH_1):PAGE63
  CF25 RST_CD_CPU1_POR_N @BASEBOARD_FAB2_LIB.BASEBOARD_FAB2(SCH_1):RST_CD_CPU1_POR_N    I23 @BASEBOARD_FAB2_LIB.BASEBOARD_FAB2(SCH_1):PAGE63
  CB23 JTAG_MCP_TCK @BASEBOARD_FAB2_LIB.BASEBOARD_FAB2(SCH_1):JTAG_MCP_TCK    I23 @BASEBOARD_FAB2_LIB.BASEBOARD_FAB2(SCH_1):PAGE63
  BY21 JTAG_MCP_CPU1_TDI @BASEBOARD_FAB2_LIB.BASEBOARD_FAB2(SCH_1):JTAG_MCP_CPU1_TDI    I23 @BASEBOARD_FAB2_LIB.BASEBOARD_FAB2(SCH_1):PAGE63
  CC22 JTAG_MCP_CPU1_TDO @BASEBOARD_FAB2_LIB.BASEBOARD_FAB2(SCH_1):JTAG_MCP_CPU1_TDO    I23 @BASEBOARD_FAB2_LIB.BASEBOARD_FAB2(SCH_1):PAGE63
  CE24 JTAG_MCP_TMS @BASEBOARD_FAB2_LIB.BASEBOARD_FAB2(SCH_1):JTAG_MCP_TMS    I23 @BASEBOARD_FAB2_LIB.BASEBOARD_FAB2(SCH_1):PAGE63
  CD23 JTAG_MCP_TRST_N @BASEBOARD_FAB2_LIB.BASEBOARD_FAB2(SCH_1):JTAG_MCP_TRST_N    I23 @BASEBOARD_FAB2_LIB.BASEBOARD_FAB2(SCH_1):PAGE63
  CT11 TP_CPU1_DMI_RX_DN3 @BASEBOARD_FAB2_LIB.BASEBOARD_FAB2(SCH_1):TP_CPU1_DMI_RX_DN3    I23 @BASEBOARD_FAB2_LIB.BASEBOARD_FAB2(SCH_1):PAGE63
  CR12 TP_CPU1_DMI_RX_DN2 @BASEBOARD_FAB2_LIB.BASEBOARD_FAB2(SCH_1):TP_CPU1_DMI_RX_DN2    I23 @BASEBOARD_FAB2_LIB.BASEBOARD_FAB2(SCH_1):PAGE63
  CM11 TP_CPU1_DMI_RX_DN1 @BASEBOARD_FAB2_LIB.BASEBOARD_FAB2(SCH_1):TP_CPU1_DMI_RX_DN1    I23 @BASEBOARD_FAB2_LIB.BASEBOARD_FAB2(SCH_1):PAGE63
   CK9 TP_CPU1_DMI_RX_DN0 @BASEBOARD_FAB2_LIB.BASEBOARD_FAB2(SCH_1):TP_CPU1_DMI_RX_DN0    I23 @BASEBOARD_FAB2_LIB.BASEBOARD_FAB2(SCH_1):PAGE63
  CV11 TP_CPU1_DMI_RX_DP3 @BASEBOARD_FAB2_LIB.BASEBOARD_FAB2(SCH_1):TP_CPU1_DMI_RX_DP3    I23 @BASEBOARD_FAB2_LIB.BASEBOARD_FAB2(SCH_1):PAGE63
  CP11 TP_CPU1_DMI_RX_DP2 @BASEBOARD_FAB2_LIB.BASEBOARD_FAB2(SCH_1):TP_CPU1_DMI_RX_DP2    I23 @BASEBOARD_FAB2_LIB.BASEBOARD_FAB2(SCH_1):PAGE63
  CN10 TP_CPU1_DMI_RX_DP1 @BASEBOARD_FAB2_LIB.BASEBOARD_FAB2(SCH_1):TP_CPU1_DMI_RX_DP1    I23 @BASEBOARD_FAB2_LIB.BASEBOARD_FAB2(SCH_1):PAGE63
  CL10 TP_CPU1_DMI_RX_DP0 @BASEBOARD_FAB2_LIB.BASEBOARD_FAB2(SCH_1):TP_CPU1_DMI_RX_DP0    I23 @BASEBOARD_FAB2_LIB.BASEBOARD_FAB2(SCH_1):PAGE63
   CP5 TP_CPU1_DMI_TX_DN3 @BASEBOARD_FAB2_LIB.BASEBOARD_FAB2(SCH_1):TP_CPU1_DMI_TX_DN3    I23 @BASEBOARD_FAB2_LIB.BASEBOARD_FAB2(SCH_1):PAGE63
   CN4 TP_CPU1_DMI_TX_DN2 @BASEBOARD_FAB2_LIB.BASEBOARD_FAB2(SCH_1):TP_CPU1_DMI_TX_DN2    I23 @BASEBOARD_FAB2_LIB.BASEBOARD_FAB2(SCH_1):PAGE63
   CJ4 TP_CPU1_DMI_TX_DN1 @BASEBOARD_FAB2_LIB.BASEBOARD_FAB2(SCH_1):TP_CPU1_DMI_TX_DN1    I23 @BASEBOARD_FAB2_LIB.BASEBOARD_FAB2(SCH_1):PAGE63
   CG4 TP_CPU1_DMI_TX_DN0 @BASEBOARD_FAB2_LIB.BASEBOARD_FAB2(SCH_1):TP_CPU1_DMI_TX_DN0    I23 @BASEBOARD_FAB2_LIB.BASEBOARD_FAB2(SCH_1):PAGE63
   CR4 TP_CPU1_DMI_TX_DP3 @BASEBOARD_FAB2_LIB.BASEBOARD_FAB2(SCH_1):TP_CPU1_DMI_TX_DP3    I23 @BASEBOARD_FAB2_LIB.BASEBOARD_FAB2(SCH_1):PAGE63
   CM3 TP_CPU1_DMI_TX_DP2 @BASEBOARD_FAB2_LIB.BASEBOARD_FAB2(SCH_1):TP_CPU1_DMI_TX_DP2    I23 @BASEBOARD_FAB2_LIB.BASEBOARD_FAB2(SCH_1):PAGE63
   CL4 TP_CPU1_DMI_TX_DP1 @BASEBOARD_FAB2_LIB.BASEBOARD_FAB2(SCH_1):TP_CPU1_DMI_TX_DP1    I23 @BASEBOARD_FAB2_LIB.BASEBOARD_FAB2(SCH_1):PAGE63
   CH5 TP_CPU1_DMI_TX_DP0 @BASEBOARD_FAB2_LIB.BASEBOARD_FAB2(SCH_1):TP_CPU1_DMI_TX_DP0    I23 @BASEBOARD_FAB2_LIB.BASEBOARD_FAB2(SCH_1):PAGE63
  AR20 PVCCMCP_CPU1 @BASEBOARD_FAB2_LIB.BASEBOARD_FAB2(SCH_1):PVCCMCP_CPU1    I23 @BASEBOARD_FAB2_LIB.BASEBOARD_FAB2(SCH_1):PAGE63
  AR22 PVCCMCP_CPU1 @BASEBOARD_FAB2_LIB.BASEBOARD_FAB2(SCH_1):PVCCMCP_CPU1    I23 @BASEBOARD_FAB2_LIB.BASEBOARD_FAB2(SCH_1):PAGE63
  AR26 PVCCMCP_CPU1 @BASEBOARD_FAB2_LIB.BASEBOARD_FAB2(SCH_1):PVCCMCP_CPU1    I23 @BASEBOARD_FAB2_LIB.BASEBOARD_FAB2(SCH_1):PAGE63
  AR62 TP_CPU1_RSVD_190 @BASEBOARD_FAB2_LIB.BASEBOARD_FAB2(SCH_1):TP_CPU1_RSVD_190    I23 @BASEBOARD_FAB2_LIB.BASEBOARD_FAB2(SCH_1):PAGE63
  AT13 TP_CPU1_RSVD_189 @BASEBOARD_FAB2_LIB.BASEBOARD_FAB2(SCH_1):TP_CPU1_RSVD_189    I23 @BASEBOARD_FAB2_LIB.BASEBOARD_FAB2(SCH_1):PAGE63
  AT23 PVCCMCP_CPU1 @BASEBOARD_FAB2_LIB.BASEBOARD_FAB2(SCH_1):PVCCMCP_CPU1    I23 @BASEBOARD_FAB2_LIB.BASEBOARD_FAB2(SCH_1):PAGE63
  AT25 PVCCMCP_CPU1 @BASEBOARD_FAB2_LIB.BASEBOARD_FAB2(SCH_1):PVCCMCP_CPU1    I23 @BASEBOARD_FAB2_LIB.BASEBOARD_FAB2(SCH_1):PAGE63
  AV77 TP_CPU1_RSVD_186 @BASEBOARD_FAB2_LIB.BASEBOARD_FAB2(SCH_1):TP_CPU1_RSVD_186    I23 @BASEBOARD_FAB2_LIB.BASEBOARD_FAB2(SCH_1):PAGE63
  AW64 TP_CPU1_RSVD_184 @BASEBOARD_FAB2_LIB.BASEBOARD_FAB2(SCH_1):TP_CPU1_RSVD_184    I23 @BASEBOARD_FAB2_LIB.BASEBOARD_FAB2(SCH_1):PAGE63
  AW76 TP_CPU1_RSVD_183 @BASEBOARD_FAB2_LIB.BASEBOARD_FAB2(SCH_1):TP_CPU1_RSVD_183    I23 @BASEBOARD_FAB2_LIB.BASEBOARD_FAB2(SCH_1):PAGE63
  AY65 TP_CPU1_RSVD_182 @BASEBOARD_FAB2_LIB.BASEBOARD_FAB2(SCH_1):TP_CPU1_RSVD_182    I23 @BASEBOARD_FAB2_LIB.BASEBOARD_FAB2(SCH_1):PAGE63
  AY67 TP_CPU1_RSVD_181 @BASEBOARD_FAB2_LIB.BASEBOARD_FAB2(SCH_1):TP_CPU1_RSVD_181    I23 @BASEBOARD_FAB2_LIB.BASEBOARD_FAB2(SCH_1):PAGE63
  AY75 TP_CPU1_RSVD_180 @BASEBOARD_FAB2_LIB.BASEBOARD_FAB2(SCH_1):TP_CPU1_RSVD_180    I23 @BASEBOARD_FAB2_LIB.BASEBOARD_FAB2(SCH_1):PAGE63
  AY77 TP_CPU1_RSVD_179 @BASEBOARD_FAB2_LIB.BASEBOARD_FAB2(SCH_1):TP_CPU1_RSVD_179    I23 @BASEBOARD_FAB2_LIB.BASEBOARD_FAB2(SCH_1):PAGE63
  BA14 TP_CPU1_RSVD_178 @BASEBOARD_FAB2_LIB.BASEBOARD_FAB2(SCH_1):TP_CPU1_RSVD_178    I23 @BASEBOARD_FAB2_LIB.BASEBOARD_FAB2(SCH_1):PAGE63
  BA16 TP_CPU1_RSVD_177 @BASEBOARD_FAB2_LIB.BASEBOARD_FAB2(SCH_1):TP_CPU1_RSVD_177    I23 @BASEBOARD_FAB2_LIB.BASEBOARD_FAB2(SCH_1):PAGE63
  BA18 TP_CPU1_RSVD_176 @BASEBOARD_FAB2_LIB.BASEBOARD_FAB2(SCH_1):TP_CPU1_RSVD_176    I23 @BASEBOARD_FAB2_LIB.BASEBOARD_FAB2(SCH_1):PAGE63
  BA22 TP_CPU1_RSVD_175 @BASEBOARD_FAB2_LIB.BASEBOARD_FAB2(SCH_1):TP_CPU1_RSVD_175    I23 @BASEBOARD_FAB2_LIB.BASEBOARD_FAB2(SCH_1):PAGE63
  BA64 TP_CPU1_RSVD_174 @BASEBOARD_FAB2_LIB.BASEBOARD_FAB2(SCH_1):TP_CPU1_RSVD_174    I23 @BASEBOARD_FAB2_LIB.BASEBOARD_FAB2(SCH_1):PAGE63
  BA66 TP_CPU1_RSVD_173 @BASEBOARD_FAB2_LIB.BASEBOARD_FAB2(SCH_1):TP_CPU1_RSVD_173    I23 @BASEBOARD_FAB2_LIB.BASEBOARD_FAB2(SCH_1):PAGE63
  BA76 TP_CPU1_RSVD_172 @BASEBOARD_FAB2_LIB.BASEBOARD_FAB2(SCH_1):TP_CPU1_RSVD_172    I23 @BASEBOARD_FAB2_LIB.BASEBOARD_FAB2(SCH_1):PAGE63
  DU16 TP_P3E_CPU1_PE1_RSR3_RXN<15> @BASEBOARD_FAB2_LIB.BASEBOARD_FAB2(SCH_1):TP_P3E_CPU1_PE1_RSR3_RXN(15)    I68 @BASEBOARD_FAB2_LIB.BASEBOARD_FAB2(SCH_1):PAGE64
  DY15 TP_P3E_CPU1_PE1_RSR3_RXN<14> @BASEBOARD_FAB2_LIB.BASEBOARD_FAB2(SCH_1):TP_P3E_CPU1_PE1_RSR3_RXN(14)    I68 @BASEBOARD_FAB2_LIB.BASEBOARD_FAB2(SCH_1):PAGE64
  DW14 TP_P3E_CPU1_PE1_RSR3_RXN<13> @BASEBOARD_FAB2_LIB.BASEBOARD_FAB2(SCH_1):TP_P3E_CPU1_PE1_RSR3_RXN(13)    I68 @BASEBOARD_FAB2_LIB.BASEBOARD_FAB2(SCH_1):PAGE64
  DV13 TP_P3E_CPU1_PE1_RSR3_RXN<12> @BASEBOARD_FAB2_LIB.BASEBOARD_FAB2(SCH_1):TP_P3E_CPU1_PE1_RSR3_RXN(12)    I68 @BASEBOARD_FAB2_LIB.BASEBOARD_FAB2(SCH_1):PAGE64
  DT13 TP_P3E_CPU1_PE1_RSR3_RXN<11> @BASEBOARD_FAB2_LIB.BASEBOARD_FAB2(SCH_1):TP_P3E_CPU1_PE1_RSR3_RXN(11)    I68 @BASEBOARD_FAB2_LIB.BASEBOARD_FAB2(SCH_1):PAGE64
  DT11 TP_P3E_CPU1_PE1_RSR3_RXN<10> @BASEBOARD_FAB2_LIB.BASEBOARD_FAB2(SCH_1):TP_P3E_CPU1_PE1_RSR3_RXN(10)    I68 @BASEBOARD_FAB2_LIB.BASEBOARD_FAB2(SCH_1):PAGE64
  DP11 TP_P3E_CPU1_PE1_RSR3_RXN<9> @BASEBOARD_FAB2_LIB.BASEBOARD_FAB2(SCH_1):TP_P3E_CPU1_PE1_RSR3_RXN(9)    I68 @BASEBOARD_FAB2_LIB.BASEBOARD_FAB2(SCH_1):PAGE64
  DM11 TP_P3E_CPU1_PE1_RSR3_RXN<8> @BASEBOARD_FAB2_LIB.BASEBOARD_FAB2(SCH_1):TP_P3E_CPU1_PE1_RSR3_RXN(8)    I68 @BASEBOARD_FAB2_LIB.BASEBOARD_FAB2(SCH_1):PAGE64
   DM9 TP_P3E_CPU1_PE1_MP_RXN<7> @BASEBOARD_FAB2_LIB.BASEBOARD_FAB2(SCH_1):TP_P3E_CPU1_PE1_MP_RXN(7)    I68 @BASEBOARD_FAB2_LIB.BASEBOARD_FAB2(SCH_1):PAGE64
   DK9 TP_P3E_CPU1_PE1_MP_RXN<6> @BASEBOARD_FAB2_LIB.BASEBOARD_FAB2(SCH_1):TP_P3E_CPU1_PE1_MP_RXN(6)    I68 @BASEBOARD_FAB2_LIB.BASEBOARD_FAB2(SCH_1):PAGE64
   DH9 TP_P3E_CPU1_PE1_MP_RXN<5> @BASEBOARD_FAB2_LIB.BASEBOARD_FAB2(SCH_1):TP_P3E_CPU1_PE1_MP_RXN(5)    I68 @BASEBOARD_FAB2_LIB.BASEBOARD_FAB2(SCH_1):PAGE64
  DE10 TP_P3E_CPU1_PE1_MP_RXN<4> @BASEBOARD_FAB2_LIB.BASEBOARD_FAB2(SCH_1):TP_P3E_CPU1_PE1_MP_RXN(4)    I68 @BASEBOARD_FAB2_LIB.BASEBOARD_FAB2(SCH_1):PAGE64
  DC10 TP_P3E_CPU1_PE1_MP_RXN<3> @BASEBOARD_FAB2_LIB.BASEBOARD_FAB2(SCH_1):TP_P3E_CPU1_PE1_MP_RXN(3)    I68 @BASEBOARD_FAB2_LIB.BASEBOARD_FAB2(SCH_1):PAGE64
   DC8 TP_P3E_CPU1_PE1_MP_RXN<2> @BASEBOARD_FAB2_LIB.BASEBOARD_FAB2(SCH_1):TP_P3E_CPU1_PE1_MP_RXN(2)    I68 @BASEBOARD_FAB2_LIB.BASEBOARD_FAB2(SCH_1):PAGE64
   DA8 TP_P3E_CPU1_PE1_MP_RXN<1> @BASEBOARD_FAB2_LIB.BASEBOARD_FAB2(SCH_1):TP_P3E_CPU1_PE1_MP_RXN(1)    I68 @BASEBOARD_FAB2_LIB.BASEBOARD_FAB2(SCH_1):PAGE64
   CW8 TP_P3E_CPU1_PE1_MP_RXN<0> @BASEBOARD_FAB2_LIB.BASEBOARD_FAB2(SCH_1):TP_P3E_CPU1_PE1_MP_RXN(0)    I68 @BASEBOARD_FAB2_LIB.BASEBOARD_FAB2(SCH_1):PAGE64
  DT15 TP_P3E_CPU1_PE1_RSR3_RXP<15> @BASEBOARD_FAB2_LIB.BASEBOARD_FAB2(SCH_1):TP_P3E_CPU1_PE1_RSR3_RXP(15)    I68 @BASEBOARD_FAB2_LIB.BASEBOARD_FAB2(SCH_1):PAGE64
  DV15 TP_P3E_CPU1_PE1_RSR3_RXP<14> @BASEBOARD_FAB2_LIB.BASEBOARD_FAB2(SCH_1):TP_P3E_CPU1_PE1_RSR3_RXP(14)    I68 @BASEBOARD_FAB2_LIB.BASEBOARD_FAB2(SCH_1):PAGE64
  DY13 TP_P3E_CPU1_PE1_RSR3_RXP<13> @BASEBOARD_FAB2_LIB.BASEBOARD_FAB2(SCH_1):TP_P3E_CPU1_PE1_RSR3_RXP(13)    I68 @BASEBOARD_FAB2_LIB.BASEBOARD_FAB2(SCH_1):PAGE64
  DU12 TP_P3E_CPU1_PE1_RSR3_RXP<12> @BASEBOARD_FAB2_LIB.BASEBOARD_FAB2(SCH_1):TP_P3E_CPU1_PE1_RSR3_RXP(12)    I68 @BASEBOARD_FAB2_LIB.BASEBOARD_FAB2(SCH_1):PAGE64
  DP13 TP_P3E_CPU1_PE1_RSR3_RXP<11> @BASEBOARD_FAB2_LIB.BASEBOARD_FAB2(SCH_1):TP_P3E_CPU1_PE1_RSR3_RXP(11)    I68 @BASEBOARD_FAB2_LIB.BASEBOARD_FAB2(SCH_1):PAGE64
  DR12 TP_P3E_CPU1_PE1_RSR3_RXP<10> @BASEBOARD_FAB2_LIB.BASEBOARD_FAB2(SCH_1):TP_P3E_CPU1_PE1_RSR3_RXP(10)    I68 @BASEBOARD_FAB2_LIB.BASEBOARD_FAB2(SCH_1):PAGE64
  DN10 TP_P3E_CPU1_PE1_RSR3_RXP<9> @BASEBOARD_FAB2_LIB.BASEBOARD_FAB2(SCH_1):TP_P3E_CPU1_PE1_RSR3_RXP(9)    I68 @BASEBOARD_FAB2_LIB.BASEBOARD_FAB2(SCH_1):PAGE64
  DK11 TP_P3E_CPU1_PE1_RSR3_RXP<8> @BASEBOARD_FAB2_LIB.BASEBOARD_FAB2(SCH_1):TP_P3E_CPU1_PE1_RSR3_RXP(8)    I68 @BASEBOARD_FAB2_LIB.BASEBOARD_FAB2(SCH_1):PAGE64
  DL10 TP_P3E_CPU1_PE1_MP_RXP<7> @BASEBOARD_FAB2_LIB.BASEBOARD_FAB2(SCH_1):TP_P3E_CPU1_PE1_MP_RXP(7)    I68 @BASEBOARD_FAB2_LIB.BASEBOARD_FAB2(SCH_1):PAGE64
   DJ8 TP_P3E_CPU1_PE1_MP_RXP<6> @BASEBOARD_FAB2_LIB.BASEBOARD_FAB2(SCH_1):TP_P3E_CPU1_PE1_MP_RXP(6)    I68 @BASEBOARD_FAB2_LIB.BASEBOARD_FAB2(SCH_1):PAGE64
   DF9 TP_P3E_CPU1_PE1_MP_RXP<5> @BASEBOARD_FAB2_LIB.BASEBOARD_FAB2(SCH_1):TP_P3E_CPU1_PE1_MP_RXP(5)    I68 @BASEBOARD_FAB2_LIB.BASEBOARD_FAB2(SCH_1):PAGE64
   DD9 TP_P3E_CPU1_PE1_MP_RXP<4> @BASEBOARD_FAB2_LIB.BASEBOARD_FAB2(SCH_1):TP_P3E_CPU1_PE1_MP_RXP(4)    I68 @BASEBOARD_FAB2_LIB.BASEBOARD_FAB2(SCH_1):PAGE64
  DA10 TP_P3E_CPU1_PE1_MP_RXP<3> @BASEBOARD_FAB2_LIB.BASEBOARD_FAB2(SCH_1):TP_P3E_CPU1_PE1_MP_RXP(3)    I68 @BASEBOARD_FAB2_LIB.BASEBOARD_FAB2(SCH_1):PAGE64
   DB9 TP_P3E_CPU1_PE1_MP_RXP<2> @BASEBOARD_FAB2_LIB.BASEBOARD_FAB2(SCH_1):TP_P3E_CPU1_PE1_MP_RXP(2)    I68 @BASEBOARD_FAB2_LIB.BASEBOARD_FAB2(SCH_1):PAGE64
   CY7 TP_P3E_CPU1_PE1_MP_RXP<1> @BASEBOARD_FAB2_LIB.BASEBOARD_FAB2(SCH_1):TP_P3E_CPU1_PE1_MP_RXP(1)    I68 @BASEBOARD_FAB2_LIB.BASEBOARD_FAB2(SCH_1):PAGE64
   CU8 TP_P3E_CPU1_PE1_MP_RXP<0> @BASEBOARD_FAB2_LIB.BASEBOARD_FAB2(SCH_1):TP_P3E_CPU1_PE1_MP_RXP(0)    I68 @BASEBOARD_FAB2_LIB.BASEBOARD_FAB2(SCH_1):PAGE64
   ED9 TP_P3E_CPU1_PE1_RSR3_TXN<15> @BASEBOARD_FAB2_LIB.BASEBOARD_FAB2(SCH_1):TP_P3E_CPU1_PE1_RSR3_TXN(15)    I68 @BASEBOARD_FAB2_LIB.BASEBOARD_FAB2(SCH_1):PAGE64
   EA8 TP_P3E_CPU1_PE1_RSR3_TXN<14> @BASEBOARD_FAB2_LIB.BASEBOARD_FAB2(SCH_1):TP_P3E_CPU1_PE1_RSR3_TXN(14)    I68 @BASEBOARD_FAB2_LIB.BASEBOARD_FAB2(SCH_1):PAGE64
   DY7 TP_P3E_CPU1_PE1_RSR3_TXN<13> @BASEBOARD_FAB2_LIB.BASEBOARD_FAB2(SCH_1):TP_P3E_CPU1_PE1_RSR3_TXN(13)    I68 @BASEBOARD_FAB2_LIB.BASEBOARD_FAB2(SCH_1):PAGE64
   DV7 TP_P3E_CPU1_PE1_RSR3_TXN<12> @BASEBOARD_FAB2_LIB.BASEBOARD_FAB2(SCH_1):TP_P3E_CPU1_PE1_RSR3_TXN(12)    I68 @BASEBOARD_FAB2_LIB.BASEBOARD_FAB2(SCH_1):PAGE64
   DU6 TP_P3E_CPU1_PE1_RSR3_TXN<11> @BASEBOARD_FAB2_LIB.BASEBOARD_FAB2(SCH_1):TP_P3E_CPU1_PE1_RSR3_TXN(11)    I68 @BASEBOARD_FAB2_LIB.BASEBOARD_FAB2(SCH_1):PAGE64
   DW4 TP_P3E_CPU1_PE1_RSR3_TXN<10> @BASEBOARD_FAB2_LIB.BASEBOARD_FAB2(SCH_1):TP_P3E_CPU1_PE1_RSR3_TXN(10)    I68 @BASEBOARD_FAB2_LIB.BASEBOARD_FAB2(SCH_1):PAGE64
   DV3 TP_P3E_CPU1_PE1_RSR3_TXN<9> @BASEBOARD_FAB2_LIB.BASEBOARD_FAB2(SCH_1):TP_P3E_CPU1_PE1_RSR3_TXN(9)    I68 @BASEBOARD_FAB2_LIB.BASEBOARD_FAB2(SCH_1):PAGE64
   DT5 TP_P3E_CPU1_PE1_RSR3_TXN<8> @BASEBOARD_FAB2_LIB.BASEBOARD_FAB2(SCH_1):TP_P3E_CPU1_PE1_RSR3_TXN(8)    I68 @BASEBOARD_FAB2_LIB.BASEBOARD_FAB2(SCH_1):PAGE64
   DN4 TP_P3E_CPU1_PE1_MP_TXN<7> @BASEBOARD_FAB2_LIB.BASEBOARD_FAB2(SCH_1):TP_P3E_CPU1_PE1_MP_TXN(7)    I68 @BASEBOARD_FAB2_LIB.BASEBOARD_FAB2(SCH_1):PAGE64
   DM3 TP_P3E_CPU1_PE1_MP_TXN<6> @BASEBOARD_FAB2_LIB.BASEBOARD_FAB2(SCH_1):TP_P3E_CPU1_PE1_MP_TXN(6)    I68 @BASEBOARD_FAB2_LIB.BASEBOARD_FAB2(SCH_1):PAGE64
   DK3 TP_P3E_CPU1_PE1_MP_TXN<5> @BASEBOARD_FAB2_LIB.BASEBOARD_FAB2(SCH_1):TP_P3E_CPU1_PE1_MP_TXN(5)    I68 @BASEBOARD_FAB2_LIB.BASEBOARD_FAB2(SCH_1):PAGE64
   DG4 TP_P3E_CPU1_PE1_MP_TXN<4> @BASEBOARD_FAB2_LIB.BASEBOARD_FAB2(SCH_1):TP_P3E_CPU1_PE1_MP_TXN(4)    I68 @BASEBOARD_FAB2_LIB.BASEBOARD_FAB2(SCH_1):PAGE64
   DE4 TP_P3E_CPU1_PE1_MP_TXN<3> @BASEBOARD_FAB2_LIB.BASEBOARD_FAB2(SCH_1):TP_P3E_CPU1_PE1_MP_TXN(3)    I68 @BASEBOARD_FAB2_LIB.BASEBOARD_FAB2(SCH_1):PAGE64
   DE2 TP_P3E_CPU1_PE1_MP_TXN<2> @BASEBOARD_FAB2_LIB.BASEBOARD_FAB2(SCH_1):TP_P3E_CPU1_PE1_MP_TXN(2)    I68 @BASEBOARD_FAB2_LIB.BASEBOARD_FAB2(SCH_1):PAGE64
   DC2 TP_P3E_CPU1_PE1_MP_TXN<1> @BASEBOARD_FAB2_LIB.BASEBOARD_FAB2(SCH_1):TP_P3E_CPU1_PE1_MP_TXN(1)    I68 @BASEBOARD_FAB2_LIB.BASEBOARD_FAB2(SCH_1):PAGE64
   DA2 TP_P3E_CPU1_PE1_MP_TXN<0> @BASEBOARD_FAB2_LIB.BASEBOARD_FAB2(SCH_1):TP_P3E_CPU1_PE1_MP_TXN(0)    I68 @BASEBOARD_FAB2_LIB.BASEBOARD_FAB2(SCH_1):PAGE64
   EC8 TP_P3E_CPU1_PE1_RSR3_TXP<15> @BASEBOARD_FAB2_LIB.BASEBOARD_FAB2(SCH_1):TP_P3E_CPU1_PE1_RSR3_TXP(15)    I68 @BASEBOARD_FAB2_LIB.BASEBOARD_FAB2(SCH_1):PAGE64
   EB7 TP_P3E_CPU1_PE1_RSR3_TXP<14> @BASEBOARD_FAB2_LIB.BASEBOARD_FAB2(SCH_1):TP_P3E_CPU1_PE1_RSR3_TXP(14)    I68 @BASEBOARD_FAB2_LIB.BASEBOARD_FAB2(SCH_1):PAGE64
   DW6 TP_P3E_CPU1_PE1_RSR3_TXP<13> @BASEBOARD_FAB2_LIB.BASEBOARD_FAB2(SCH_1):TP_P3E_CPU1_PE1_RSR3_TXP(13)    I68 @BASEBOARD_FAB2_LIB.BASEBOARD_FAB2(SCH_1):PAGE64
   DT7 TP_P3E_CPU1_PE1_RSR3_TXP<12> @BASEBOARD_FAB2_LIB.BASEBOARD_FAB2(SCH_1):TP_P3E_CPU1_PE1_RSR3_TXP(12)    I68 @BASEBOARD_FAB2_LIB.BASEBOARD_FAB2(SCH_1):PAGE64
   DV5 TP_P3E_CPU1_PE1_RSR3_TXP<11> @BASEBOARD_FAB2_LIB.BASEBOARD_FAB2(SCH_1):TP_P3E_CPU1_PE1_RSR3_TXP(11)    I68 @BASEBOARD_FAB2_LIB.BASEBOARD_FAB2(SCH_1):PAGE64
   DU4 TP_P3E_CPU1_PE1_RSR3_TXP<10> @BASEBOARD_FAB2_LIB.BASEBOARD_FAB2(SCH_1):TP_P3E_CPU1_PE1_RSR3_TXP(10)    I68 @BASEBOARD_FAB2_LIB.BASEBOARD_FAB2(SCH_1):PAGE64
   DU2 TP_P3E_CPU1_PE1_RSR3_TXP<9> @BASEBOARD_FAB2_LIB.BASEBOARD_FAB2(SCH_1):TP_P3E_CPU1_PE1_RSR3_TXP(9)    I68 @BASEBOARD_FAB2_LIB.BASEBOARD_FAB2(SCH_1):PAGE64
   DR4 TP_P3E_CPU1_PE1_RSR3_TXP<8> @BASEBOARD_FAB2_LIB.BASEBOARD_FAB2(SCH_1):TP_P3E_CPU1_PE1_RSR3_TXP(8)    I68 @BASEBOARD_FAB2_LIB.BASEBOARD_FAB2(SCH_1):PAGE64
   DP3 TP_P3E_CPU1_PE1_MP_TXP<7> @BASEBOARD_FAB2_LIB.BASEBOARD_FAB2(SCH_1):TP_P3E_CPU1_PE1_MP_TXP(7)    I68 @BASEBOARD_FAB2_LIB.BASEBOARD_FAB2(SCH_1):PAGE64
   DL2 TP_P3E_CPU1_PE1_MP_TXP<6> @BASEBOARD_FAB2_LIB.BASEBOARD_FAB2(SCH_1):TP_P3E_CPU1_PE1_MP_TXP(6)    I68 @BASEBOARD_FAB2_LIB.BASEBOARD_FAB2(SCH_1):PAGE64
   DH3 TP_P3E_CPU1_PE1_MP_TXP<5> @BASEBOARD_FAB2_LIB.BASEBOARD_FAB2(SCH_1):TP_P3E_CPU1_PE1_MP_TXP(5)    I68 @BASEBOARD_FAB2_LIB.BASEBOARD_FAB2(SCH_1):PAGE64
   DF3 TP_P3E_CPU1_PE1_MP_TXP<4> @BASEBOARD_FAB2_LIB.BASEBOARD_FAB2(SCH_1):TP_P3E_CPU1_PE1_MP_TXP(4)    I68 @BASEBOARD_FAB2_LIB.BASEBOARD_FAB2(SCH_1):PAGE64
   DC4 TP_P3E_CPU1_PE1_MP_TXP<3> @BASEBOARD_FAB2_LIB.BASEBOARD_FAB2(SCH_1):TP_P3E_CPU1_PE1_MP_TXP(3)    I68 @BASEBOARD_FAB2_LIB.BASEBOARD_FAB2(SCH_1):PAGE64
   DD3 TP_P3E_CPU1_PE1_MP_TXP<2> @BASEBOARD_FAB2_LIB.BASEBOARD_FAB2(SCH_1):TP_P3E_CPU1_PE1_MP_TXP(2)    I68 @BASEBOARD_FAB2_LIB.BASEBOARD_FAB2(SCH_1):PAGE64
   DB1 TP_P3E_CPU1_PE1_MP_TXP<1> @BASEBOARD_FAB2_LIB.BASEBOARD_FAB2(SCH_1):TP_P3E_CPU1_PE1_MP_TXP(1)    I68 @BASEBOARD_FAB2_LIB.BASEBOARD_FAB2(SCH_1):PAGE64
   CW2 TP_P3E_CPU1_PE1_MP_TXP<0> @BASEBOARD_FAB2_LIB.BASEBOARD_FAB2(SCH_1):TP_P3E_CPU1_PE1_MP_TXP(0)    I68 @BASEBOARD_FAB2_LIB.BASEBOARD_FAB2(SCH_1):PAGE64
   BK9 TP_P3E_CPU1_PE2_RSR_RXN<15> @BASEBOARD_FAB2_LIB.BASEBOARD_FAB2(SCH_1):TP_P3E_CPU1_PE2_RSR_RXN(15)    I68 @BASEBOARD_FAB2_LIB.BASEBOARD_FAB2(SCH_1):PAGE65
   BL8 TP_P3E_CPU1_PE2_RSR_RXN<14> @BASEBOARD_FAB2_LIB.BASEBOARD_FAB2(SCH_1):TP_P3E_CPU1_PE2_RSR_RXN(14)    I68 @BASEBOARD_FAB2_LIB.BASEBOARD_FAB2(SCH_1):PAGE65
   BN8 TP_P3E_CPU1_PE2_RSR_RXN<13> @BASEBOARD_FAB2_LIB.BASEBOARD_FAB2(SCH_1):TP_P3E_CPU1_PE2_RSR_RXN(13)    I68 @BASEBOARD_FAB2_LIB.BASEBOARD_FAB2(SCH_1):PAGE65
   BR8 TP_P3E_CPU1_PE2_RSR_RXN<12> @BASEBOARD_FAB2_LIB.BASEBOARD_FAB2(SCH_1):TP_P3E_CPU1_PE2_RSR_RXN(12)    I68 @BASEBOARD_FAB2_LIB.BASEBOARD_FAB2(SCH_1):PAGE65
   BT7 TP_P3E_CPU1_PE2_RSR_RXN<11> @BASEBOARD_FAB2_LIB.BASEBOARD_FAB2(SCH_1):TP_P3E_CPU1_PE2_RSR_RXN(11)    I68 @BASEBOARD_FAB2_LIB.BASEBOARD_FAB2(SCH_1):PAGE65
   BV7 TP_P3E_CPU1_PE2_RSR_RXN<10> @BASEBOARD_FAB2_LIB.BASEBOARD_FAB2(SCH_1):TP_P3E_CPU1_PE2_RSR_RXN(10)    I68 @BASEBOARD_FAB2_LIB.BASEBOARD_FAB2(SCH_1):PAGE65
   BY7 TP_P3E_CPU1_PE2_RSR_RXN<9> @BASEBOARD_FAB2_LIB.BASEBOARD_FAB2(SCH_1):TP_P3E_CPU1_PE2_RSR_RXN(9)    I68 @BASEBOARD_FAB2_LIB.BASEBOARD_FAB2(SCH_1):PAGE65
   BY9 TP_P3E_CPU1_PE2_RSR_RXN<8> @BASEBOARD_FAB2_LIB.BASEBOARD_FAB2(SCH_1):TP_P3E_CPU1_PE2_RSR_RXN(8)    I68 @BASEBOARD_FAB2_LIB.BASEBOARD_FAB2(SCH_1):PAGE65
   CE8 TP_P3E_CPU1_PE2_RSR_RXN<7> @BASEBOARD_FAB2_LIB.BASEBOARD_FAB2(SCH_1):TP_P3E_CPU1_PE2_RSR_RXN(7)    I68 @BASEBOARD_FAB2_LIB.BASEBOARD_FAB2(SCH_1):PAGE65
   CE6 TP_P3E_CPU1_PE2_RSR_RXN<6> @BASEBOARD_FAB2_LIB.BASEBOARD_FAB2(SCH_1):TP_P3E_CPU1_PE2_RSR_RXN(6)    I68 @BASEBOARD_FAB2_LIB.BASEBOARD_FAB2(SCH_1):PAGE65
   CG8 TP_P3E_CPU1_PE2_RSR_RXN<5> @BASEBOARD_FAB2_LIB.BASEBOARD_FAB2(SCH_1):TP_P3E_CPU1_PE2_RSR_RXN(5)    I68 @BASEBOARD_FAB2_LIB.BASEBOARD_FAB2(SCH_1):PAGE65
   CK7 TP_P3E_CPU1_PE2_RSR_RXN<4> @BASEBOARD_FAB2_LIB.BASEBOARD_FAB2(SCH_1):TP_P3E_CPU1_PE2_RSR_RXN(4)    I68 @BASEBOARD_FAB2_LIB.BASEBOARD_FAB2(SCH_1):PAGE65
   CM7 TP_P3E_CPU1_PE2_RSR_RXN<3> @BASEBOARD_FAB2_LIB.BASEBOARD_FAB2(SCH_1):TP_P3E_CPU1_PE2_RSR_RXN(3)    I68 @BASEBOARD_FAB2_LIB.BASEBOARD_FAB2(SCH_1):PAGE65
   CP7 TP_P3E_CPU1_PE2_RSR_RXN<2> @BASEBOARD_FAB2_LIB.BASEBOARD_FAB2(SCH_1):TP_P3E_CPU1_PE2_RSR_RXN(2)    I68 @BASEBOARD_FAB2_LIB.BASEBOARD_FAB2(SCH_1):PAGE65
   CP9 TP_P3E_CPU1_PE2_RSR_RXN<1> @BASEBOARD_FAB2_LIB.BASEBOARD_FAB2(SCH_1):TP_P3E_CPU1_PE2_RSR_RXN(1)    I68 @BASEBOARD_FAB2_LIB.BASEBOARD_FAB2(SCH_1):PAGE65
   CT9 TP_P3E_CPU1_PE2_RSR_RXN<0> @BASEBOARD_FAB2_LIB.BASEBOARD_FAB2(SCH_1):TP_P3E_CPU1_PE2_RSR_RXN(0)    I68 @BASEBOARD_FAB2_LIB.BASEBOARD_FAB2(SCH_1):PAGE65
  BJ10 TP_P3E_CPU1_PE2_RSR_RXP<15> @BASEBOARD_FAB2_LIB.BASEBOARD_FAB2(SCH_1):TP_P3E_CPU1_PE2_RSR_RXP(15)    I68 @BASEBOARD_FAB2_LIB.BASEBOARD_FAB2(SCH_1):PAGE65
   BJ8 TP_P3E_CPU1_PE2_RSR_RXP<14> @BASEBOARD_FAB2_LIB.BASEBOARD_FAB2(SCH_1):TP_P3E_CPU1_PE2_RSR_RXP(14)    I68 @BASEBOARD_FAB2_LIB.BASEBOARD_FAB2(SCH_1):PAGE65
   BM7 TP_P3E_CPU1_PE2_RSR_RXP<13> @BASEBOARD_FAB2_LIB.BASEBOARD_FAB2(SCH_1):TP_P3E_CPU1_PE2_RSR_RXP(13)    I68 @BASEBOARD_FAB2_LIB.BASEBOARD_FAB2(SCH_1):PAGE65
   BP9 TP_P3E_CPU1_PE2_RSR_RXP<12> @BASEBOARD_FAB2_LIB.BASEBOARD_FAB2(SCH_1):TP_P3E_CPU1_PE2_RSR_RXP(12)    I68 @BASEBOARD_FAB2_LIB.BASEBOARD_FAB2(SCH_1):PAGE65
   BP7 TP_P3E_CPU1_PE2_RSR_RXP<11> @BASEBOARD_FAB2_LIB.BASEBOARD_FAB2(SCH_1):TP_P3E_CPU1_PE2_RSR_RXP(11)    I68 @BASEBOARD_FAB2_LIB.BASEBOARD_FAB2(SCH_1):PAGE65
   BU6 TP_P3E_CPU1_PE2_RSR_RXP<10> @BASEBOARD_FAB2_LIB.BASEBOARD_FAB2(SCH_1):TP_P3E_CPU1_PE2_RSR_RXP(10)    I68 @BASEBOARD_FAB2_LIB.BASEBOARD_FAB2(SCH_1):PAGE65
   BW8 TP_P3E_CPU1_PE2_RSR_RXP<9> @BASEBOARD_FAB2_LIB.BASEBOARD_FAB2(SCH_1):TP_P3E_CPU1_PE2_RSR_RXP(9)    I68 @BASEBOARD_FAB2_LIB.BASEBOARD_FAB2(SCH_1):PAGE65
   BV9 TP_P3E_CPU1_PE2_RSR_RXP<8> @BASEBOARD_FAB2_LIB.BASEBOARD_FAB2(SCH_1):TP_P3E_CPU1_PE2_RSR_RXP(8)    I68 @BASEBOARD_FAB2_LIB.BASEBOARD_FAB2(SCH_1):PAGE65
   CC8 TP_P3E_CPU1_PE2_RSR_RXP<7> @BASEBOARD_FAB2_LIB.BASEBOARD_FAB2(SCH_1):TP_P3E_CPU1_PE2_RSR_RXP(7)    I68 @BASEBOARD_FAB2_LIB.BASEBOARD_FAB2(SCH_1):PAGE65
   CD7 TP_P3E_CPU1_PE2_RSR_RXP<6> @BASEBOARD_FAB2_LIB.BASEBOARD_FAB2(SCH_1):TP_P3E_CPU1_PE2_RSR_RXP(6)    I68 @BASEBOARD_FAB2_LIB.BASEBOARD_FAB2(SCH_1):PAGE65
   CF7 TP_P3E_CPU1_PE2_RSR_RXP<5> @BASEBOARD_FAB2_LIB.BASEBOARD_FAB2(SCH_1):TP_P3E_CPU1_PE2_RSR_RXP(5)    I68 @BASEBOARD_FAB2_LIB.BASEBOARD_FAB2(SCH_1):PAGE65
   CH7 TP_P3E_CPU1_PE2_RSR_RXP<4> @BASEBOARD_FAB2_LIB.BASEBOARD_FAB2(SCH_1):TP_P3E_CPU1_PE2_RSR_RXP(4)    I68 @BASEBOARD_FAB2_LIB.BASEBOARD_FAB2(SCH_1):PAGE65
   CL6 TP_P3E_CPU1_PE2_RSR_RXP<3> @BASEBOARD_FAB2_LIB.BASEBOARD_FAB2(SCH_1):TP_P3E_CPU1_PE2_RSR_RXP(3)    I68 @BASEBOARD_FAB2_LIB.BASEBOARD_FAB2(SCH_1):PAGE65
   CN8 TP_P3E_CPU1_PE2_RSR_RXP<2> @BASEBOARD_FAB2_LIB.BASEBOARD_FAB2(SCH_1):TP_P3E_CPU1_PE2_RSR_RXP(2)    I68 @BASEBOARD_FAB2_LIB.BASEBOARD_FAB2(SCH_1):PAGE65
   CM9 TP_P3E_CPU1_PE2_RSR_RXP<1> @BASEBOARD_FAB2_LIB.BASEBOARD_FAB2(SCH_1):TP_P3E_CPU1_PE2_RSR_RXP(1)    I68 @BASEBOARD_FAB2_LIB.BASEBOARD_FAB2(SCH_1):PAGE65
   CR8 TP_P3E_CPU1_PE2_RSR_RXP<0> @BASEBOARD_FAB2_LIB.BASEBOARD_FAB2(SCH_1):TP_P3E_CPU1_PE2_RSR_RXP(0)    I68 @BASEBOARD_FAB2_LIB.BASEBOARD_FAB2(SCH_1):PAGE65
   BM5 TP_P3E_CPU1_PE2_RSR_TXN<15> @BASEBOARD_FAB2_LIB.BASEBOARD_FAB2(SCH_1):TP_P3E_CPU1_PE2_RSR_TXN(15)    I68 @BASEBOARD_FAB2_LIB.BASEBOARD_FAB2(SCH_1):PAGE65
   BL4 TP_P3E_CPU1_PE2_RSR_TXN<14> @BASEBOARD_FAB2_LIB.BASEBOARD_FAB2(SCH_1):TP_P3E_CPU1_PE2_RSR_TXN(14)    I68 @BASEBOARD_FAB2_LIB.BASEBOARD_FAB2(SCH_1):PAGE65
   BP5 TP_P3E_CPU1_PE2_RSR_TXN<13> @BASEBOARD_FAB2_LIB.BASEBOARD_FAB2(SCH_1):TP_P3E_CPU1_PE2_RSR_TXN(13)    I68 @BASEBOARD_FAB2_LIB.BASEBOARD_FAB2(SCH_1):PAGE65
   BU4 TP_P3E_CPU1_PE2_RSR_TXN<12> @BASEBOARD_FAB2_LIB.BASEBOARD_FAB2(SCH_1):TP_P3E_CPU1_PE2_RSR_TXN(12)    I68 @BASEBOARD_FAB2_LIB.BASEBOARD_FAB2(SCH_1):PAGE65
   BW4 TP_P3E_CPU1_PE2_RSR_TXN<11> @BASEBOARD_FAB2_LIB.BASEBOARD_FAB2(SCH_1):TP_P3E_CPU1_PE2_RSR_TXN(11)    I68 @BASEBOARD_FAB2_LIB.BASEBOARD_FAB2(SCH_1):PAGE65
   CA4 TP_P3E_CPU1_PE2_RSR_TXN<10> @BASEBOARD_FAB2_LIB.BASEBOARD_FAB2(SCH_1):TP_P3E_CPU1_PE2_RSR_TXN(10)    I68 @BASEBOARD_FAB2_LIB.BASEBOARD_FAB2(SCH_1):PAGE65
   CB3 TP_P3E_CPU1_PE2_RSR_TXN<9> @BASEBOARD_FAB2_LIB.BASEBOARD_FAB2(SCH_1):TP_P3E_CPU1_PE2_RSR_TXN(9)    I68 @BASEBOARD_FAB2_LIB.BASEBOARD_FAB2(SCH_1):PAGE65
   CC2 TP_P3E_CPU1_PE2_RSR_TXN<8> @BASEBOARD_FAB2_LIB.BASEBOARD_FAB2(SCH_1):TP_P3E_CPU1_PE2_RSR_TXN(8)    I68 @BASEBOARD_FAB2_LIB.BASEBOARD_FAB2(SCH_1):PAGE65
   CF3 TP_P3E_CPU1_PE2_RSR_TXN<7> @BASEBOARD_FAB2_LIB.BASEBOARD_FAB2(SCH_1):TP_P3E_CPU1_PE2_RSR_TXN(7)    I68 @BASEBOARD_FAB2_LIB.BASEBOARD_FAB2(SCH_1):PAGE65
   CG2 TP_P3E_CPU1_PE2_RSR_TXN<6> @BASEBOARD_FAB2_LIB.BASEBOARD_FAB2(SCH_1):TP_P3E_CPU1_PE2_RSR_TXN(6)    I68 @BASEBOARD_FAB2_LIB.BASEBOARD_FAB2(SCH_1):PAGE65
   CL2 TP_P3E_CPU1_PE2_RSR_TXN<5> @BASEBOARD_FAB2_LIB.BASEBOARD_FAB2(SCH_1):TP_P3E_CPU1_PE2_RSR_TXN(5)    I68 @BASEBOARD_FAB2_LIB.BASEBOARD_FAB2(SCH_1):PAGE65
   CM1 TP_P3E_CPU1_PE2_RSR_TXN<4> @BASEBOARD_FAB2_LIB.BASEBOARD_FAB2(SCH_1):TP_P3E_CPU1_PE2_RSR_TXN(4)    I68 @BASEBOARD_FAB2_LIB.BASEBOARD_FAB2(SCH_1):PAGE65
   CT3 TP_P3E_CPU1_PE2_RSR_TXN<3> @BASEBOARD_FAB2_LIB.BASEBOARD_FAB2(SCH_1):TP_P3E_CPU1_PE2_RSR_TXN(3)    I68 @BASEBOARD_FAB2_LIB.BASEBOARD_FAB2(SCH_1):PAGE65
   CT1 TP_P3E_CPU1_PE2_RSR_TXN<2> @BASEBOARD_FAB2_LIB.BASEBOARD_FAB2(SCH_1):TP_P3E_CPU1_PE2_RSR_TXN(2)    I68 @BASEBOARD_FAB2_LIB.BASEBOARD_FAB2(SCH_1):PAGE65
   CV3 TP_P3E_CPU1_PE2_RSR_TXN<1> @BASEBOARD_FAB2_LIB.BASEBOARD_FAB2(SCH_1):TP_P3E_CPU1_PE2_RSR_TXN(1)    I68 @BASEBOARD_FAB2_LIB.BASEBOARD_FAB2(SCH_1):PAGE65
   CY3 TP_P3E_CPU1_PE2_RSR_TXN<0> @BASEBOARD_FAB2_LIB.BASEBOARD_FAB2(SCH_1):TP_P3E_CPU1_PE2_RSR_TXN(0)    I68 @BASEBOARD_FAB2_LIB.BASEBOARD_FAB2(SCH_1):PAGE65
   BK5 TP_P3E_CPU1_PE2_RSR_TXP<15> @BASEBOARD_FAB2_LIB.BASEBOARD_FAB2(SCH_1):TP_P3E_CPU1_PE2_RSR_TXP(15)    I68 @BASEBOARD_FAB2_LIB.BASEBOARD_FAB2(SCH_1):PAGE65
   BM3 TP_P3E_CPU1_PE2_RSR_TXP<14> @BASEBOARD_FAB2_LIB.BASEBOARD_FAB2(SCH_1):TP_P3E_CPU1_PE2_RSR_TXP(14)    I68 @BASEBOARD_FAB2_LIB.BASEBOARD_FAB2(SCH_1):PAGE65
   BN4 TP_P3E_CPU1_PE2_RSR_TXP<13> @BASEBOARD_FAB2_LIB.BASEBOARD_FAB2(SCH_1):TP_P3E_CPU1_PE2_RSR_TXP(13)    I68 @BASEBOARD_FAB2_LIB.BASEBOARD_FAB2(SCH_1):PAGE65
   BR4 TP_P3E_CPU1_PE2_RSR_TXP<12> @BASEBOARD_FAB2_LIB.BASEBOARD_FAB2(SCH_1):TP_P3E_CPU1_PE2_RSR_TXP(12)    I68 @BASEBOARD_FAB2_LIB.BASEBOARD_FAB2(SCH_1):PAGE65
   BV3 TP_P3E_CPU1_PE2_RSR_TXP<11> @BASEBOARD_FAB2_LIB.BASEBOARD_FAB2(SCH_1):TP_P3E_CPU1_PE2_RSR_TXP(11)    I68 @BASEBOARD_FAB2_LIB.BASEBOARD_FAB2(SCH_1):PAGE65
   BY5 TP_P3E_CPU1_PE2_RSR_TXP<10> @BASEBOARD_FAB2_LIB.BASEBOARD_FAB2(SCH_1):TP_P3E_CPU1_PE2_RSR_TXP(10)    I68 @BASEBOARD_FAB2_LIB.BASEBOARD_FAB2(SCH_1):PAGE65
   BY3 TP_P3E_CPU1_PE2_RSR_TXP<9> @BASEBOARD_FAB2_LIB.BASEBOARD_FAB2(SCH_1):TP_P3E_CPU1_PE2_RSR_TXP(9)    I68 @BASEBOARD_FAB2_LIB.BASEBOARD_FAB2(SCH_1):PAGE65
   CD3 TP_P3E_CPU1_PE2_RSR_TXP<8> @BASEBOARD_FAB2_LIB.BASEBOARD_FAB2(SCH_1):TP_P3E_CPU1_PE2_RSR_TXP(8)    I68 @BASEBOARD_FAB2_LIB.BASEBOARD_FAB2(SCH_1):PAGE65
   CE4 TP_P3E_CPU1_PE2_RSR_TXP<7> @BASEBOARD_FAB2_LIB.BASEBOARD_FAB2(SCH_1):TP_P3E_CPU1_PE2_RSR_TXP(7)    I68 @BASEBOARD_FAB2_LIB.BASEBOARD_FAB2(SCH_1):PAGE65
   CE2 TP_P3E_CPU1_PE2_RSR_TXP<6> @BASEBOARD_FAB2_LIB.BASEBOARD_FAB2(SCH_1):TP_P3E_CPU1_PE2_RSR_TXP(6)    I68 @BASEBOARD_FAB2_LIB.BASEBOARD_FAB2(SCH_1):PAGE65
   CK3 TP_P3E_CPU1_PE2_RSR_TXP<5> @BASEBOARD_FAB2_LIB.BASEBOARD_FAB2(SCH_1):TP_P3E_CPU1_PE2_RSR_TXP(5)    I68 @BASEBOARD_FAB2_LIB.BASEBOARD_FAB2(SCH_1):PAGE65
   CK1 TP_P3E_CPU1_PE2_RSR_TXP<4> @BASEBOARD_FAB2_LIB.BASEBOARD_FAB2(SCH_1):TP_P3E_CPU1_PE2_RSR_TXP(4)    I68 @BASEBOARD_FAB2_LIB.BASEBOARD_FAB2(SCH_1):PAGE65
   CP3 TP_P3E_CPU1_PE2_RSR_TXP<3> @BASEBOARD_FAB2_LIB.BASEBOARD_FAB2(SCH_1):TP_P3E_CPU1_PE2_RSR_TXP(3)    I68 @BASEBOARD_FAB2_LIB.BASEBOARD_FAB2(SCH_1):PAGE65
   CR2 TP_P3E_CPU1_PE2_RSR_TXP<2> @BASEBOARD_FAB2_LIB.BASEBOARD_FAB2(SCH_1):TP_P3E_CPU1_PE2_RSR_TXP(2)    I68 @BASEBOARD_FAB2_LIB.BASEBOARD_FAB2(SCH_1):PAGE65
   CU2 TP_P3E_CPU1_PE2_RSR_TXP<1> @BASEBOARD_FAB2_LIB.BASEBOARD_FAB2(SCH_1):TP_P3E_CPU1_PE2_RSR_TXP(1)    I68 @BASEBOARD_FAB2_LIB.BASEBOARD_FAB2(SCH_1):PAGE65
   CW4 TP_P3E_CPU1_PE2_RSR_TXP<0> @BASEBOARD_FAB2_LIB.BASEBOARD_FAB2(SCH_1):TP_P3E_CPU1_PE2_RSR_TXP(0)    I68 @BASEBOARD_FAB2_LIB.BASEBOARD_FAB2(SCH_1):PAGE65
   CV9 P3E_CPU1_PE3_MP_RXN<15> @BASEBOARD_FAB2_LIB.BASEBOARD_FAB2(SCH_1):P3E_CPU1_PE3_MP_RXN(15)    I84 @BASEBOARD_FAB2_LIB.BASEBOARD_FAB2(SCH_1):PAGE66
  CY11 P3E_CPU1_PE3_MP_RXN<14> @BASEBOARD_FAB2_LIB.BASEBOARD_FAB2(SCH_1):P3E_CPU1_PE3_MP_RXN(14)    I84 @BASEBOARD_FAB2_LIB.BASEBOARD_FAB2(SCH_1):PAGE66
  DB11 P3E_CPU1_PE3_MP_RXN<13> @BASEBOARD_FAB2_LIB.BASEBOARD_FAB2(SCH_1):P3E_CPU1_PE3_MP_RXN(13)    I84 @BASEBOARD_FAB2_LIB.BASEBOARD_FAB2(SCH_1):PAGE66
  DD13 P3E_CPU1_PE3_MP_RXP<12> @BASEBOARD_FAB2_LIB.BASEBOARD_FAB2(SCH_1):P3E_CPU1_PE3_MP_RXP(12)    I84 @BASEBOARD_FAB2_LIB.BASEBOARD_FAB2(SCH_1):PAGE66
  DG10 P3E_CPU1_PE3_MP_RXN<11> @BASEBOARD_FAB2_LIB.BASEBOARD_FAB2(SCH_1):P3E_CPU1_PE3_MP_RXN(11)    I84 @BASEBOARD_FAB2_LIB.BASEBOARD_FAB2(SCH_1):PAGE66
  DG12 P3E_CPU1_PE3_MP_RXN<10> @BASEBOARD_FAB2_LIB.BASEBOARD_FAB2(SCH_1):P3E_CPU1_PE3_MP_RXN(10)    I84 @BASEBOARD_FAB2_LIB.BASEBOARD_FAB2(SCH_1):PAGE66
  DJ12 P3E_CPU1_PE3_MP_RXN<9> @BASEBOARD_FAB2_LIB.BASEBOARD_FAB2(SCH_1):P3E_CPU1_PE3_MP_RXN(9)    I84 @BASEBOARD_FAB2_LIB.BASEBOARD_FAB2(SCH_1):PAGE66
  DL12 P3E_CPU1_PE3_MP_RXN<8> @BASEBOARD_FAB2_LIB.BASEBOARD_FAB2(SCH_1):P3E_CPU1_PE3_MP_RXN(8)    I84 @BASEBOARD_FAB2_LIB.BASEBOARD_FAB2(SCH_1):PAGE66
  DL14 P3E_CPU1_PE3_MP_RXN<7> @BASEBOARD_FAB2_LIB.BASEBOARD_FAB2(SCH_1):P3E_CPU1_PE3_MP_RXN(7)    I84 @BASEBOARD_FAB2_LIB.BASEBOARD_FAB2(SCH_1):PAGE66
  DN14 P3E_CPU1_PE3_MP_RXN<6> @BASEBOARD_FAB2_LIB.BASEBOARD_FAB2(SCH_1):P3E_CPU1_PE3_MP_RXN(6)    I84 @BASEBOARD_FAB2_LIB.BASEBOARD_FAB2(SCH_1):PAGE66
  DR14 P3E_CPU1_PE3_MP_RXN<5> @BASEBOARD_FAB2_LIB.BASEBOARD_FAB2(SCH_1):P3E_CPU1_PE3_MP_RXN(5)    I84 @BASEBOARD_FAB2_LIB.BASEBOARD_FAB2(SCH_1):PAGE66
  DR16 P3E_CPU1_PE3_MP_RXN<4> @BASEBOARD_FAB2_LIB.BASEBOARD_FAB2(SCH_1):P3E_CPU1_PE3_MP_RXN(4)    I84 @BASEBOARD_FAB2_LIB.BASEBOARD_FAB2(SCH_1):PAGE66
  DT19 P3E_CPU1_PE3_MP_RXN<3> @BASEBOARD_FAB2_LIB.BASEBOARD_FAB2(SCH_1):P3E_CPU1_PE3_MP_RXN(3)    I84 @BASEBOARD_FAB2_LIB.BASEBOARD_FAB2(SCH_1):PAGE66
  DW16 P3E_CPU1_PE3_MP_RXN<2> @BASEBOARD_FAB2_LIB.BASEBOARD_FAB2(SCH_1):P3E_CPU1_PE3_MP_RXN(2)    I84 @BASEBOARD_FAB2_LIB.BASEBOARD_FAB2(SCH_1):PAGE66
  DW18 P3E_CPU1_PE3_MP_RXN<1> @BASEBOARD_FAB2_LIB.BASEBOARD_FAB2(SCH_1):P3E_CPU1_PE3_MP_RXN(1)    I84 @BASEBOARD_FAB2_LIB.BASEBOARD_FAB2(SCH_1):PAGE66
  EA18 P3E_CPU1_PE3_MP_RXN<0> @BASEBOARD_FAB2_LIB.BASEBOARD_FAB2(SCH_1):P3E_CPU1_PE3_MP_RXN(0)    I84 @BASEBOARD_FAB2_LIB.BASEBOARD_FAB2(SCH_1):PAGE66
  CU10 P3E_CPU1_PE3_MP_RXP<15> @BASEBOARD_FAB2_LIB.BASEBOARD_FAB2(SCH_1):P3E_CPU1_PE3_MP_RXP(15)    I84 @BASEBOARD_FAB2_LIB.BASEBOARD_FAB2(SCH_1):PAGE66
  CW10 P3E_CPU1_PE3_MP_RXP<14> @BASEBOARD_FAB2_LIB.BASEBOARD_FAB2(SCH_1):P3E_CPU1_PE3_MP_RXP(14)    I84 @BASEBOARD_FAB2_LIB.BASEBOARD_FAB2(SCH_1):PAGE66
  DA12 P3E_CPU1_PE3_MP_RXP<13> @BASEBOARD_FAB2_LIB.BASEBOARD_FAB2(SCH_1):P3E_CPU1_PE3_MP_RXP(13)    I84 @BASEBOARD_FAB2_LIB.BASEBOARD_FAB2(SCH_1):PAGE66
  DC12 P3E_CPU1_PE3_MP_RXN<12> @BASEBOARD_FAB2_LIB.BASEBOARD_FAB2(SCH_1):P3E_CPU1_PE3_MP_RXN(12)    I84 @BASEBOARD_FAB2_LIB.BASEBOARD_FAB2(SCH_1):PAGE66
  DF11 P3E_CPU1_PE3_MP_RXP<11> @BASEBOARD_FAB2_LIB.BASEBOARD_FAB2(SCH_1):P3E_CPU1_PE3_MP_RXP(11)    I84 @BASEBOARD_FAB2_LIB.BASEBOARD_FAB2(SCH_1):PAGE66
  DE12 P3E_CPU1_PE3_MP_RXP<10> @BASEBOARD_FAB2_LIB.BASEBOARD_FAB2(SCH_1):P3E_CPU1_PE3_MP_RXP(10)    I84 @BASEBOARD_FAB2_LIB.BASEBOARD_FAB2(SCH_1):PAGE66
  DH11 P3E_CPU1_PE3_MP_RXP<9> @BASEBOARD_FAB2_LIB.BASEBOARD_FAB2(SCH_1):P3E_CPU1_PE3_MP_RXP(9)    I84 @BASEBOARD_FAB2_LIB.BASEBOARD_FAB2(SCH_1):PAGE66
  DK13 P3E_CPU1_PE3_MP_RXP<8> @BASEBOARD_FAB2_LIB.BASEBOARD_FAB2(SCH_1):P3E_CPU1_PE3_MP_RXP(8)    I84 @BASEBOARD_FAB2_LIB.BASEBOARD_FAB2(SCH_1):PAGE66
  DJ14 P3E_CPU1_PE3_MP_RXP<7> @BASEBOARD_FAB2_LIB.BASEBOARD_FAB2(SCH_1):P3E_CPU1_PE3_MP_RXP(7)    I84 @BASEBOARD_FAB2_LIB.BASEBOARD_FAB2(SCH_1):PAGE66
  DM13 P3E_CPU1_PE3_MP_RXP<6> @BASEBOARD_FAB2_LIB.BASEBOARD_FAB2(SCH_1):P3E_CPU1_PE3_MP_RXP(6)    I84 @BASEBOARD_FAB2_LIB.BASEBOARD_FAB2(SCH_1):PAGE66
  DP15 P3E_CPU1_PE3_MP_RXP<5> @BASEBOARD_FAB2_LIB.BASEBOARD_FAB2(SCH_1):P3E_CPU1_PE3_MP_RXP(5)    I84 @BASEBOARD_FAB2_LIB.BASEBOARD_FAB2(SCH_1):PAGE66
  DN16 P3E_CPU1_PE3_MP_RXP<4> @BASEBOARD_FAB2_LIB.BASEBOARD_FAB2(SCH_1):P3E_CPU1_PE3_MP_RXP(4)    I84 @BASEBOARD_FAB2_LIB.BASEBOARD_FAB2(SCH_1):PAGE66
  DR18 P3E_CPU1_PE3_MP_RXP<3> @BASEBOARD_FAB2_LIB.BASEBOARD_FAB2(SCH_1):P3E_CPU1_PE3_MP_RXP(3)    I84 @BASEBOARD_FAB2_LIB.BASEBOARD_FAB2(SCH_1):PAGE66
  DV17 P3E_CPU1_PE3_MP_RXP<2> @BASEBOARD_FAB2_LIB.BASEBOARD_FAB2(SCH_1):P3E_CPU1_PE3_MP_RXP(2)    I84 @BASEBOARD_FAB2_LIB.BASEBOARD_FAB2(SCH_1):PAGE66
  DU18 P3E_CPU1_PE3_MP_RXP<1> @BASEBOARD_FAB2_LIB.BASEBOARD_FAB2(SCH_1):P3E_CPU1_PE3_MP_RXP(1)    I84 @BASEBOARD_FAB2_LIB.BASEBOARD_FAB2(SCH_1):PAGE66
  DY17 P3E_CPU1_PE3_MP_RXP<0> @BASEBOARD_FAB2_LIB.BASEBOARD_FAB2(SCH_1):P3E_CPU1_PE3_MP_RXP(0)    I84 @BASEBOARD_FAB2_LIB.BASEBOARD_FAB2(SCH_1):PAGE66
   CY5 P3E_CPU1_PE3_MP_TXN<15> @BASEBOARD_FAB2_LIB.BASEBOARD_FAB2(SCH_1):P3E_CPU1_PE3_MP_TXN(15)    I84 @BASEBOARD_FAB2_LIB.BASEBOARD_FAB2(SCH_1):PAGE66
   DB5 P3E_CPU1_PE3_MP_TXN<14> @BASEBOARD_FAB2_LIB.BASEBOARD_FAB2(SCH_1):P3E_CPU1_PE3_MP_TXN(14)    I84 @BASEBOARD_FAB2_LIB.BASEBOARD_FAB2(SCH_1):PAGE66
   DD5 P3E_CPU1_PE3_MP_TXN<13> @BASEBOARD_FAB2_LIB.BASEBOARD_FAB2(SCH_1):P3E_CPU1_PE3_MP_TXN(13)    I84 @BASEBOARD_FAB2_LIB.BASEBOARD_FAB2(SCH_1):PAGE66
   DJ6 P3E_CPU1_PE3_MP_TXN<12> @BASEBOARD_FAB2_LIB.BASEBOARD_FAB2(SCH_1):P3E_CPU1_PE3_MP_TXN(12)    I84 @BASEBOARD_FAB2_LIB.BASEBOARD_FAB2(SCH_1):PAGE66
   DJ4 P3E_CPU1_PE3_MP_TXN<11> @BASEBOARD_FAB2_LIB.BASEBOARD_FAB2(SCH_1):P3E_CPU1_PE3_MP_TXN(11)    I84 @BASEBOARD_FAB2_LIB.BASEBOARD_FAB2(SCH_1):PAGE66
   DL6 P3E_CPU1_PE3_MP_TXN<10> @BASEBOARD_FAB2_LIB.BASEBOARD_FAB2(SCH_1):P3E_CPU1_PE3_MP_TXN(10)    I84 @BASEBOARD_FAB2_LIB.BASEBOARD_FAB2(SCH_1):PAGE66
   DP5 P3E_CPU1_PE3_MP_TXN<9> @BASEBOARD_FAB2_LIB.BASEBOARD_FAB2(SCH_1):P3E_CPU1_PE3_MP_TXN(9)    I84 @BASEBOARD_FAB2_LIB.BASEBOARD_FAB2(SCH_1):PAGE66
   DM7 P3E_CPU1_PE3_MP_TXN<8> @BASEBOARD_FAB2_LIB.BASEBOARD_FAB2(SCH_1):P3E_CPU1_PE3_MP_TXN(8)    I84 @BASEBOARD_FAB2_LIB.BASEBOARD_FAB2(SCH_1):PAGE66
   DR8 P3E_CPU1_PE3_MP_TXN<7> @BASEBOARD_FAB2_LIB.BASEBOARD_FAB2(SCH_1):P3E_CPU1_PE3_MP_TXN(7)    I84 @BASEBOARD_FAB2_LIB.BASEBOARD_FAB2(SCH_1):PAGE66
   DU8 P3E_CPU1_PE3_MP_TXN<6> @BASEBOARD_FAB2_LIB.BASEBOARD_FAB2(SCH_1):P3E_CPU1_PE3_MP_TXN(6)    I84 @BASEBOARD_FAB2_LIB.BASEBOARD_FAB2(SCH_1):PAGE66
  DW10 P3E_CPU1_PE3_MP_TXN<5> @BASEBOARD_FAB2_LIB.BASEBOARD_FAB2(SCH_1):P3E_CPU1_PE3_MP_TXN(5)    I84 @BASEBOARD_FAB2_LIB.BASEBOARD_FAB2(SCH_1):PAGE66
   EB9 P3E_CPU1_PE3_MP_TXN<4> @BASEBOARD_FAB2_LIB.BASEBOARD_FAB2(SCH_1):P3E_CPU1_PE3_MP_TXN(4)    I84 @BASEBOARD_FAB2_LIB.BASEBOARD_FAB2(SCH_1):PAGE66
  DY11 P3E_CPU1_PE3_MP_TXN<3> @BASEBOARD_FAB2_LIB.BASEBOARD_FAB2(SCH_1):P3E_CPU1_PE3_MP_TXN(3)    I84 @BASEBOARD_FAB2_LIB.BASEBOARD_FAB2(SCH_1):PAGE66
  EC12 P3E_CPU1_PE3_MP_TXN<2> @BASEBOARD_FAB2_LIB.BASEBOARD_FAB2(SCH_1):P3E_CPU1_PE3_MP_TXN(2)    I84 @BASEBOARD_FAB2_LIB.BASEBOARD_FAB2(SCH_1):PAGE66
  EE12 P3E_CPU1_PE3_MP_TXN<1> @BASEBOARD_FAB2_LIB.BASEBOARD_FAB2(SCH_1):P3E_CPU1_PE3_MP_TXN(1)    I84 @BASEBOARD_FAB2_LIB.BASEBOARD_FAB2(SCH_1):PAGE66
  EE14 P3E_CPU1_PE3_MP_TXN<0> @BASEBOARD_FAB2_LIB.BASEBOARD_FAB2(SCH_1):P3E_CPU1_PE3_MP_TXN(0)    I84 @BASEBOARD_FAB2_LIB.BASEBOARD_FAB2(SCH_1):PAGE66
   CV5 P3E_CPU1_PE3_MP_TXP<15> @BASEBOARD_FAB2_LIB.BASEBOARD_FAB2(SCH_1):P3E_CPU1_PE3_MP_TXP(15)    I84 @BASEBOARD_FAB2_LIB.BASEBOARD_FAB2(SCH_1):PAGE66
   DA4 P3E_CPU1_PE3_MP_TXP<14> @BASEBOARD_FAB2_LIB.BASEBOARD_FAB2(SCH_1):P3E_CPU1_PE3_MP_TXP(14)    I84 @BASEBOARD_FAB2_LIB.BASEBOARD_FAB2(SCH_1):PAGE66
   DC6 P3E_CPU1_PE3_MP_TXP<13> @BASEBOARD_FAB2_LIB.BASEBOARD_FAB2(SCH_1):P3E_CPU1_PE3_MP_TXP(13)    I84 @BASEBOARD_FAB2_LIB.BASEBOARD_FAB2(SCH_1):PAGE66
   DG6 P3E_CPU1_PE3_MP_TXP<12> @BASEBOARD_FAB2_LIB.BASEBOARD_FAB2(SCH_1):P3E_CPU1_PE3_MP_TXP(12)    I84 @BASEBOARD_FAB2_LIB.BASEBOARD_FAB2(SCH_1):PAGE66
   DH5 P3E_CPU1_PE3_MP_TXP<11> @BASEBOARD_FAB2_LIB.BASEBOARD_FAB2(SCH_1):P3E_CPU1_PE3_MP_TXP(11)    I84 @BASEBOARD_FAB2_LIB.BASEBOARD_FAB2(SCH_1):PAGE66
   DK5 P3E_CPU1_PE3_MP_TXP<10> @BASEBOARD_FAB2_LIB.BASEBOARD_FAB2(SCH_1):P3E_CPU1_PE3_MP_TXP(10)    I84 @BASEBOARD_FAB2_LIB.BASEBOARD_FAB2(SCH_1):PAGE66
   DM5 P3E_CPU1_PE3_MP_TXP<9> @BASEBOARD_FAB2_LIB.BASEBOARD_FAB2(SCH_1):P3E_CPU1_PE3_MP_TXP(9)    I84 @BASEBOARD_FAB2_LIB.BASEBOARD_FAB2(SCH_1):PAGE66
   DN6 P3E_CPU1_PE3_MP_TXP<8> @BASEBOARD_FAB2_LIB.BASEBOARD_FAB2(SCH_1):P3E_CPU1_PE3_MP_TXP(8)    I84 @BASEBOARD_FAB2_LIB.BASEBOARD_FAB2(SCH_1):PAGE66
   DP7 P3E_CPU1_PE3_MP_TXP<7> @BASEBOARD_FAB2_LIB.BASEBOARD_FAB2(SCH_1):P3E_CPU1_PE3_MP_TXP(7)    I84 @BASEBOARD_FAB2_LIB.BASEBOARD_FAB2(SCH_1):PAGE66
   DT9 P3E_CPU1_PE3_MP_TXP<6> @BASEBOARD_FAB2_LIB.BASEBOARD_FAB2(SCH_1):P3E_CPU1_PE3_MP_TXP(6)    I84 @BASEBOARD_FAB2_LIB.BASEBOARD_FAB2(SCH_1):PAGE66
   DV9 P3E_CPU1_PE3_MP_TXP<5> @BASEBOARD_FAB2_LIB.BASEBOARD_FAB2(SCH_1):P3E_CPU1_PE3_MP_TXP(5)    I84 @BASEBOARD_FAB2_LIB.BASEBOARD_FAB2(SCH_1):PAGE66
   DY9 P3E_CPU1_PE3_MP_TXP<4> @BASEBOARD_FAB2_LIB.BASEBOARD_FAB2(SCH_1):P3E_CPU1_PE3_MP_TXP(4)    I84 @BASEBOARD_FAB2_LIB.BASEBOARD_FAB2(SCH_1):PAGE66
  EA10 P3E_CPU1_PE3_MP_TXP<3> @BASEBOARD_FAB2_LIB.BASEBOARD_FAB2(SCH_1):P3E_CPU1_PE3_MP_TXP(3)    I84 @BASEBOARD_FAB2_LIB.BASEBOARD_FAB2(SCH_1):PAGE66
  EB11 P3E_CPU1_PE3_MP_TXP<2> @BASEBOARD_FAB2_LIB.BASEBOARD_FAB2(SCH_1):P3E_CPU1_PE3_MP_TXP(2)    I84 @BASEBOARD_FAB2_LIB.BASEBOARD_FAB2(SCH_1):PAGE66
  ED13 P3E_CPU1_PE3_MP_TXP<1> @BASEBOARD_FAB2_LIB.BASEBOARD_FAB2(SCH_1):P3E_CPU1_PE3_MP_TXP(1)    I84 @BASEBOARD_FAB2_LIB.BASEBOARD_FAB2(SCH_1):PAGE66
  EC14 P3E_CPU1_PE3_MP_TXP<0> @BASEBOARD_FAB2_LIB.BASEBOARD_FAB2(SCH_1):P3E_CPU1_PE3_MP_TXP(0)    I84 @BASEBOARD_FAB2_LIB.BASEBOARD_FAB2(SCH_1):PAGE66
  BB11 UPI_CPU0_CPU1_P0P0_DP<19> @BASEBOARD_FAB2_LIB.BASEBOARD_FAB2(SCH_1):UPI_CPU0_CPU1_P0P0_DP(19)   I132 @BASEBOARD_FAB2_LIB.BASEBOARD_FAB2(SCH_1):PAGE67
   BD9 UPI_CPU0_CPU1_P0P0_DP<18> @BASEBOARD_FAB2_LIB.BASEBOARD_FAB2(SCH_1):UPI_CPU0_CPU1_P0P0_DP(18)   I132 @BASEBOARD_FAB2_LIB.BASEBOARD_FAB2(SCH_1):PAGE67
   AY9 UPI_CPU0_CPU1_P0P0_DN<17> @BASEBOARD_FAB2_LIB.BASEBOARD_FAB2(SCH_1):UPI_CPU0_CPU1_P0P0_DN(17)   I132 @BASEBOARD_FAB2_LIB.BASEBOARD_FAB2(SCH_1):PAGE67
   AW8 UPI_CPU0_CPU1_P0P0_DN<16> @BASEBOARD_FAB2_LIB.BASEBOARD_FAB2(SCH_1):UPI_CPU0_CPU1_P0P0_DN(16)   I132 @BASEBOARD_FAB2_LIB.BASEBOARD_FAB2(SCH_1):PAGE67
   BD7 UPI_CPU0_CPU1_P0P0_DN<15> @BASEBOARD_FAB2_LIB.BASEBOARD_FAB2(SCH_1):UPI_CPU0_CPU1_P0P0_DN(15)   I132 @BASEBOARD_FAB2_LIB.BASEBOARD_FAB2(SCH_1):PAGE67
   BC6 UPI_CPU0_CPU1_P0P0_DP<14> @BASEBOARD_FAB2_LIB.BASEBOARD_FAB2(SCH_1):UPI_CPU0_CPU1_P0P0_DP(14)   I132 @BASEBOARD_FAB2_LIB.BASEBOARD_FAB2(SCH_1):PAGE67
   BA8 UPI_CPU0_CPU1_P0P0_DN<13> @BASEBOARD_FAB2_LIB.BASEBOARD_FAB2(SCH_1):UPI_CPU0_CPU1_P0P0_DN(13)   I132 @BASEBOARD_FAB2_LIB.BASEBOARD_FAB2(SCH_1):PAGE67
  AU10 UPI_CPU0_CPU1_P0P0_DN<12> @BASEBOARD_FAB2_LIB.BASEBOARD_FAB2(SCH_1):UPI_CPU0_CPU1_P0P0_DN(12)   I132 @BASEBOARD_FAB2_LIB.BASEBOARD_FAB2(SCH_1):PAGE67
   AR8 UPI_CPU0_CPU1_P0P0_DP<11> @BASEBOARD_FAB2_LIB.BASEBOARD_FAB2(SCH_1):UPI_CPU0_CPU1_P0P0_DP(11)   I132 @BASEBOARD_FAB2_LIB.BASEBOARD_FAB2(SCH_1):PAGE67
   AP7 UPI_CPU0_CPU1_P0P0_DN<10> @BASEBOARD_FAB2_LIB.BASEBOARD_FAB2(SCH_1):UPI_CPU0_CPU1_P0P0_DN(10)   I132 @BASEBOARD_FAB2_LIB.BASEBOARD_FAB2(SCH_1):PAGE67
   AM9 UPI_CPU0_CPU1_P0P0_DP<9> @BASEBOARD_FAB2_LIB.BASEBOARD_FAB2(SCH_1):UPI_CPU0_CPU1_P0P0_DP(9)   I132 @BASEBOARD_FAB2_LIB.BASEBOARD_FAB2(SCH_1):PAGE67
   AK7 UPI_CPU0_CPU1_P0P0_DP<8> @BASEBOARD_FAB2_LIB.BASEBOARD_FAB2(SCH_1):UPI_CPU0_CPU1_P0P0_DP(8)   I132 @BASEBOARD_FAB2_LIB.BASEBOARD_FAB2(SCH_1):PAGE67
   AL6 UPI_CPU0_CPU1_P0P0_DP<7> @BASEBOARD_FAB2_LIB.BASEBOARD_FAB2(SCH_1):UPI_CPU0_CPU1_P0P0_DP(7)   I132 @BASEBOARD_FAB2_LIB.BASEBOARD_FAB2(SCH_1):PAGE67
   AJ6 UPI_CPU0_CPU1_P0P0_DP<6> @BASEBOARD_FAB2_LIB.BASEBOARD_FAB2(SCH_1):UPI_CPU0_CPU1_P0P0_DP(6)   I132 @BASEBOARD_FAB2_LIB.BASEBOARD_FAB2(SCH_1):PAGE67
   AG8 UPI_CPU0_CPU1_P0P0_DP<5> @BASEBOARD_FAB2_LIB.BASEBOARD_FAB2(SCH_1):UPI_CPU0_CPU1_P0P0_DP(5)   I132 @BASEBOARD_FAB2_LIB.BASEBOARD_FAB2(SCH_1):PAGE67
   AE6 UPI_CPU0_CPU1_P0P0_DP<4> @BASEBOARD_FAB2_LIB.BASEBOARD_FAB2(SCH_1):UPI_CPU0_CPU1_P0P0_DP(4)   I132 @BASEBOARD_FAB2_LIB.BASEBOARD_FAB2(SCH_1):PAGE67
   AD5 UPI_CPU0_CPU1_P0P0_DP<3> @BASEBOARD_FAB2_LIB.BASEBOARD_FAB2(SCH_1):UPI_CPU0_CPU1_P0P0_DP(3)   I132 @BASEBOARD_FAB2_LIB.BASEBOARD_FAB2(SCH_1):PAGE67
   AB7 UPI_CPU0_CPU1_P0P0_DN<2> @BASEBOARD_FAB2_LIB.BASEBOARD_FAB2(SCH_1):UPI_CPU0_CPU1_P0P0_DN(2)   I132 @BASEBOARD_FAB2_LIB.BASEBOARD_FAB2(SCH_1):PAGE67
   AA8 UPI_CPU0_CPU1_P0P0_DN<1> @BASEBOARD_FAB2_LIB.BASEBOARD_FAB2(SCH_1):UPI_CPU0_CPU1_P0P0_DN(1)   I132 @BASEBOARD_FAB2_LIB.BASEBOARD_FAB2(SCH_1):PAGE67
  AC10 UPI_CPU0_CPU1_P0P0_DP<0> @BASEBOARD_FAB2_LIB.BASEBOARD_FAB2(SCH_1):UPI_CPU0_CPU1_P0P0_DP(0)   I132 @BASEBOARD_FAB2_LIB.BASEBOARD_FAB2(SCH_1):PAGE67
  BA10 UPI_CPU0_CPU1_P0P0_DN<19> @BASEBOARD_FAB2_LIB.BASEBOARD_FAB2(SCH_1):UPI_CPU0_CPU1_P0P0_DN(19)   I132 @BASEBOARD_FAB2_LIB.BASEBOARD_FAB2(SCH_1):PAGE67
  BC10 UPI_CPU0_CPU1_P0P0_DN<18> @BASEBOARD_FAB2_LIB.BASEBOARD_FAB2(SCH_1):UPI_CPU0_CPU1_P0P0_DN(18)   I132 @BASEBOARD_FAB2_LIB.BASEBOARD_FAB2(SCH_1):PAGE67
   BB9 UPI_CPU0_CPU1_P0P0_DP<17> @BASEBOARD_FAB2_LIB.BASEBOARD_FAB2(SCH_1):UPI_CPU0_CPU1_P0P0_DP(17)   I132 @BASEBOARD_FAB2_LIB.BASEBOARD_FAB2(SCH_1):PAGE67
   AV9 UPI_CPU0_CPU1_P0P0_DP<16> @BASEBOARD_FAB2_LIB.BASEBOARD_FAB2(SCH_1):UPI_CPU0_CPU1_P0P0_DP(16)   I132 @BASEBOARD_FAB2_LIB.BASEBOARD_FAB2(SCH_1):PAGE67
   BF7 UPI_CPU0_CPU1_P0P0_DP<15> @BASEBOARD_FAB2_LIB.BASEBOARD_FAB2(SCH_1):UPI_CPU0_CPU1_P0P0_DP(15)   I132 @BASEBOARD_FAB2_LIB.BASEBOARD_FAB2(SCH_1):PAGE67
   BB7 UPI_CPU0_CPU1_P0P0_DN<14> @BASEBOARD_FAB2_LIB.BASEBOARD_FAB2(SCH_1):UPI_CPU0_CPU1_P0P0_DN(14)   I132 @BASEBOARD_FAB2_LIB.BASEBOARD_FAB2(SCH_1):PAGE67
   AY7 UPI_CPU0_CPU1_P0P0_DP<13> @BASEBOARD_FAB2_LIB.BASEBOARD_FAB2(SCH_1):UPI_CPU0_CPU1_P0P0_DP(13)   I132 @BASEBOARD_FAB2_LIB.BASEBOARD_FAB2(SCH_1):PAGE67
   AT9 UPI_CPU0_CPU1_P0P0_DP<12> @BASEBOARD_FAB2_LIB.BASEBOARD_FAB2(SCH_1):UPI_CPU0_CPU1_P0P0_DP(12)   I132 @BASEBOARD_FAB2_LIB.BASEBOARD_FAB2(SCH_1):PAGE67
   AU8 UPI_CPU0_CPU1_P0P0_DN<11> @BASEBOARD_FAB2_LIB.BASEBOARD_FAB2(SCH_1):UPI_CPU0_CPU1_P0P0_DN(11)   I132 @BASEBOARD_FAB2_LIB.BASEBOARD_FAB2(SCH_1):PAGE67
   AN8 UPI_CPU0_CPU1_P0P0_DP<10> @BASEBOARD_FAB2_LIB.BASEBOARD_FAB2(SCH_1):UPI_CPU0_CPU1_P0P0_DP(10)   I132 @BASEBOARD_FAB2_LIB.BASEBOARD_FAB2(SCH_1):PAGE67
   AL8 UPI_CPU0_CPU1_P0P0_DN<9> @BASEBOARD_FAB2_LIB.BASEBOARD_FAB2(SCH_1):UPI_CPU0_CPU1_P0P0_DN(9)   I132 @BASEBOARD_FAB2_LIB.BASEBOARD_FAB2(SCH_1):PAGE67
   AM7 UPI_CPU0_CPU1_P0P0_DN<8> @BASEBOARD_FAB2_LIB.BASEBOARD_FAB2(SCH_1):UPI_CPU0_CPU1_P0P0_DN(8)   I132 @BASEBOARD_FAB2_LIB.BASEBOARD_FAB2(SCH_1):PAGE67
   AK5 UPI_CPU0_CPU1_P0P0_DN<7> @BASEBOARD_FAB2_LIB.BASEBOARD_FAB2(SCH_1):UPI_CPU0_CPU1_P0P0_DN(7)   I132 @BASEBOARD_FAB2_LIB.BASEBOARD_FAB2(SCH_1):PAGE67
   AH7 UPI_CPU0_CPU1_P0P0_DN<6> @BASEBOARD_FAB2_LIB.BASEBOARD_FAB2(SCH_1):UPI_CPU0_CPU1_P0P0_DN(6)   I132 @BASEBOARD_FAB2_LIB.BASEBOARD_FAB2(SCH_1):PAGE67
   AF7 UPI_CPU0_CPU1_P0P0_DN<5> @BASEBOARD_FAB2_LIB.BASEBOARD_FAB2(SCH_1):UPI_CPU0_CPU1_P0P0_DN(5)   I132 @BASEBOARD_FAB2_LIB.BASEBOARD_FAB2(SCH_1):PAGE67
   AG6 UPI_CPU0_CPU1_P0P0_DN<4> @BASEBOARD_FAB2_LIB.BASEBOARD_FAB2(SCH_1):UPI_CPU0_CPU1_P0P0_DN(4)   I132 @BASEBOARD_FAB2_LIB.BASEBOARD_FAB2(SCH_1):PAGE67
   AC6 UPI_CPU0_CPU1_P0P0_DN<3> @BASEBOARD_FAB2_LIB.BASEBOARD_FAB2(SCH_1):UPI_CPU0_CPU1_P0P0_DN(3)   I132 @BASEBOARD_FAB2_LIB.BASEBOARD_FAB2(SCH_1):PAGE67
   AA6 UPI_CPU0_CPU1_P0P0_DP<2> @BASEBOARD_FAB2_LIB.BASEBOARD_FAB2(SCH_1):UPI_CPU0_CPU1_P0P0_DP(2)   I132 @BASEBOARD_FAB2_LIB.BASEBOARD_FAB2(SCH_1):PAGE67
   AC8 UPI_CPU0_CPU1_P0P0_DP<1> @BASEBOARD_FAB2_LIB.BASEBOARD_FAB2(SCH_1):UPI_CPU0_CPU1_P0P0_DP(1)   I132 @BASEBOARD_FAB2_LIB.BASEBOARD_FAB2(SCH_1):PAGE67
   AB9 UPI_CPU0_CPU1_P0P0_DN<0> @BASEBOARD_FAB2_LIB.BASEBOARD_FAB2(SCH_1):UPI_CPU0_CPU1_P0P0_DN(0)   I132 @BASEBOARD_FAB2_LIB.BASEBOARD_FAB2(SCH_1):PAGE67
   BG4 UPI_CPU1_CPU0_P0P0_DP<19> @BASEBOARD_FAB2_LIB.BASEBOARD_FAB2(SCH_1):UPI_CPU1_CPU0_P0P0_DP(19)   I132 @BASEBOARD_FAB2_LIB.BASEBOARD_FAB2(SCH_1):PAGE67
   BF3 UPI_CPU1_CPU0_P0P0_DN<18> @BASEBOARD_FAB2_LIB.BASEBOARD_FAB2(SCH_1):UPI_CPU1_CPU0_P0P0_DN(18)   I132 @BASEBOARD_FAB2_LIB.BASEBOARD_FAB2(SCH_1):PAGE67
   BB3 UPI_CPU1_CPU0_P0P0_DN<17> @BASEBOARD_FAB2_LIB.BASEBOARD_FAB2(SCH_1):UPI_CPU1_CPU0_P0P0_DN(17)   I132 @BASEBOARD_FAB2_LIB.BASEBOARD_FAB2(SCH_1):PAGE67
   BA4 UPI_CPU1_CPU0_P0P0_DP<16> @BASEBOARD_FAB2_LIB.BASEBOARD_FAB2(SCH_1):UPI_CPU1_CPU0_P0P0_DP(16)   I132 @BASEBOARD_FAB2_LIB.BASEBOARD_FAB2(SCH_1):PAGE67
   AV5 UPI_CPU1_CPU0_P0P0_DP<15> @BASEBOARD_FAB2_LIB.BASEBOARD_FAB2(SCH_1):UPI_CPU1_CPU0_P0P0_DP(15)   I132 @BASEBOARD_FAB2_LIB.BASEBOARD_FAB2(SCH_1):PAGE67
   AU4 UPI_CPU1_CPU0_P0P0_DP<14> @BASEBOARD_FAB2_LIB.BASEBOARD_FAB2(SCH_1):UPI_CPU1_CPU0_P0P0_DP(14)   I132 @BASEBOARD_FAB2_LIB.BASEBOARD_FAB2(SCH_1):PAGE67
   AT3 UPI_CPU1_CPU0_P0P0_DP<13> @BASEBOARD_FAB2_LIB.BASEBOARD_FAB2(SCH_1):UPI_CPU1_CPU0_P0P0_DP(13)   I132 @BASEBOARD_FAB2_LIB.BASEBOARD_FAB2(SCH_1):PAGE67
   AT1 UPI_CPU1_CPU0_P0P0_DP<12> @BASEBOARD_FAB2_LIB.BASEBOARD_FAB2(SCH_1):UPI_CPU1_CPU0_P0P0_DP(12)   I132 @BASEBOARD_FAB2_LIB.BASEBOARD_FAB2(SCH_1):PAGE67
   AN4 UPI_CPU1_CPU0_P0P0_DP<11> @BASEBOARD_FAB2_LIB.BASEBOARD_FAB2(SCH_1):UPI_CPU1_CPU0_P0P0_DP(11)   I132 @BASEBOARD_FAB2_LIB.BASEBOARD_FAB2(SCH_1):PAGE67
   AM3 UPI_CPU1_CPU0_P0P0_DP<10> @BASEBOARD_FAB2_LIB.BASEBOARD_FAB2(SCH_1):UPI_CPU1_CPU0_P0P0_DP(10)   I132 @BASEBOARD_FAB2_LIB.BASEBOARD_FAB2(SCH_1):PAGE67
   AL2 UPI_CPU1_CPU0_P0P0_DN<9> @BASEBOARD_FAB2_LIB.BASEBOARD_FAB2(SCH_1):UPI_CPU1_CPU0_P0P0_DN(9)   I132 @BASEBOARD_FAB2_LIB.BASEBOARD_FAB2(SCH_1):PAGE67
   AH3 UPI_CPU1_CPU0_P0P0_DP<8> @BASEBOARD_FAB2_LIB.BASEBOARD_FAB2(SCH_1):UPI_CPU1_CPU0_P0P0_DP(8)   I132 @BASEBOARD_FAB2_LIB.BASEBOARD_FAB2(SCH_1):PAGE67
   AE2 UPI_CPU1_CPU0_P0P0_DN<7> @BASEBOARD_FAB2_LIB.BASEBOARD_FAB2(SCH_1):UPI_CPU1_CPU0_P0P0_DN(7)   I132 @BASEBOARD_FAB2_LIB.BASEBOARD_FAB2(SCH_1):PAGE67
   AG4 UPI_CPU1_CPU0_P0P0_DN<6> @BASEBOARD_FAB2_LIB.BASEBOARD_FAB2(SCH_1):UPI_CPU1_CPU0_P0P0_DN(6)   I132 @BASEBOARD_FAB2_LIB.BASEBOARD_FAB2(SCH_1):PAGE67
   AC2 UPI_CPU1_CPU0_P0P0_DP<5> @BASEBOARD_FAB2_LIB.BASEBOARD_FAB2(SCH_1):UPI_CPU1_CPU0_P0P0_DP(5)   I132 @BASEBOARD_FAB2_LIB.BASEBOARD_FAB2(SCH_1):PAGE67
   AB3 UPI_CPU1_CPU0_P0P0_DN<4> @BASEBOARD_FAB2_LIB.BASEBOARD_FAB2(SCH_1):UPI_CPU1_CPU0_P0P0_DN(4)   I132 @BASEBOARD_FAB2_LIB.BASEBOARD_FAB2(SCH_1):PAGE67
    Y1 UPI_CPU1_CPU0_P0P0_DN<3> @BASEBOARD_FAB2_LIB.BASEBOARD_FAB2(SCH_1):UPI_CPU1_CPU0_P0P0_DN(3)   I132 @BASEBOARD_FAB2_LIB.BASEBOARD_FAB2(SCH_1):PAGE67
    V3 UPI_CPU1_CPU0_P0P0_DN<2> @BASEBOARD_FAB2_LIB.BASEBOARD_FAB2(SCH_1):UPI_CPU1_CPU0_P0P0_DN(2)   I132 @BASEBOARD_FAB2_LIB.BASEBOARD_FAB2(SCH_1):PAGE67
    P1 UPI_CPU1_CPU0_P0P0_DP<1> @BASEBOARD_FAB2_LIB.BASEBOARD_FAB2(SCH_1):UPI_CPU1_CPU0_P0P0_DP(1)   I132 @BASEBOARD_FAB2_LIB.BASEBOARD_FAB2(SCH_1):PAGE67
    N2 UPI_CPU1_CPU0_P0P0_DP<0> @BASEBOARD_FAB2_LIB.BASEBOARD_FAB2(SCH_1):UPI_CPU1_CPU0_P0P0_DP(0)   I132 @BASEBOARD_FAB2_LIB.BASEBOARD_FAB2(SCH_1):PAGE67
   BH3 UPI_CPU1_CPU0_P0P0_DN<19> @BASEBOARD_FAB2_LIB.BASEBOARD_FAB2(SCH_1):UPI_CPU1_CPU0_P0P0_DN(19)   I132 @BASEBOARD_FAB2_LIB.BASEBOARD_FAB2(SCH_1):PAGE67
   BD3 UPI_CPU1_CPU0_P0P0_DP<18> @BASEBOARD_FAB2_LIB.BASEBOARD_FAB2(SCH_1):UPI_CPU1_CPU0_P0P0_DP(18)   I132 @BASEBOARD_FAB2_LIB.BASEBOARD_FAB2(SCH_1):PAGE67
   BC2 UPI_CPU1_CPU0_P0P0_DP<17> @BASEBOARD_FAB2_LIB.BASEBOARD_FAB2(SCH_1):UPI_CPU1_CPU0_P0P0_DP(17)   I132 @BASEBOARD_FAB2_LIB.BASEBOARD_FAB2(SCH_1):PAGE67
   AY3 UPI_CPU1_CPU0_P0P0_DN<16> @BASEBOARD_FAB2_LIB.BASEBOARD_FAB2(SCH_1):UPI_CPU1_CPU0_P0P0_DN(16)   I132 @BASEBOARD_FAB2_LIB.BASEBOARD_FAB2(SCH_1):PAGE67
   AW4 UPI_CPU1_CPU0_P0P0_DN<15> @BASEBOARD_FAB2_LIB.BASEBOARD_FAB2(SCH_1):UPI_CPU1_CPU0_P0P0_DN(15)   I132 @BASEBOARD_FAB2_LIB.BASEBOARD_FAB2(SCH_1):PAGE67
   AR4 UPI_CPU1_CPU0_P0P0_DN<14> @BASEBOARD_FAB2_LIB.BASEBOARD_FAB2(SCH_1):UPI_CPU1_CPU0_P0P0_DN(14)   I132 @BASEBOARD_FAB2_LIB.BASEBOARD_FAB2(SCH_1):PAGE67
   AR2 UPI_CPU1_CPU0_P0P0_DN<13> @BASEBOARD_FAB2_LIB.BASEBOARD_FAB2(SCH_1):UPI_CPU1_CPU0_P0P0_DN(13)   I132 @BASEBOARD_FAB2_LIB.BASEBOARD_FAB2(SCH_1):PAGE67
   AP1 UPI_CPU1_CPU0_P0P0_DN<12> @BASEBOARD_FAB2_LIB.BASEBOARD_FAB2(SCH_1):UPI_CPU1_CPU0_P0P0_DN(12)   I132 @BASEBOARD_FAB2_LIB.BASEBOARD_FAB2(SCH_1):PAGE67
   AP3 UPI_CPU1_CPU0_P0P0_DN<11> @BASEBOARD_FAB2_LIB.BASEBOARD_FAB2(SCH_1):UPI_CPU1_CPU0_P0P0_DN(11)   I132 @BASEBOARD_FAB2_LIB.BASEBOARD_FAB2(SCH_1):PAGE67
   AK3 UPI_CPU1_CPU0_P0P0_DN<10> @BASEBOARD_FAB2_LIB.BASEBOARD_FAB2(SCH_1):UPI_CPU1_CPU0_P0P0_DN(10)   I132 @BASEBOARD_FAB2_LIB.BASEBOARD_FAB2(SCH_1):PAGE67
   AK1 UPI_CPU1_CPU0_P0P0_DP<9> @BASEBOARD_FAB2_LIB.BASEBOARD_FAB2(SCH_1):UPI_CPU1_CPU0_P0P0_DP(9)   I132 @BASEBOARD_FAB2_LIB.BASEBOARD_FAB2(SCH_1):PAGE67
   AJ2 UPI_CPU1_CPU0_P0P0_DN<8> @BASEBOARD_FAB2_LIB.BASEBOARD_FAB2(SCH_1):UPI_CPU1_CPU0_P0P0_DN(8)   I132 @BASEBOARD_FAB2_LIB.BASEBOARD_FAB2(SCH_1):PAGE67
   AG2 UPI_CPU1_CPU0_P0P0_DP<7> @BASEBOARD_FAB2_LIB.BASEBOARD_FAB2(SCH_1):UPI_CPU1_CPU0_P0P0_DP(7)   I132 @BASEBOARD_FAB2_LIB.BASEBOARD_FAB2(SCH_1):PAGE67
   AF3 UPI_CPU1_CPU0_P0P0_DP<6> @BASEBOARD_FAB2_LIB.BASEBOARD_FAB2(SCH_1):UPI_CPU1_CPU0_P0P0_DP(6)   I132 @BASEBOARD_FAB2_LIB.BASEBOARD_FAB2(SCH_1):PAGE67
   AD1 UPI_CPU1_CPU0_P0P0_DN<5> @BASEBOARD_FAB2_LIB.BASEBOARD_FAB2(SCH_1):UPI_CPU1_CPU0_P0P0_DN(5)   I132 @BASEBOARD_FAB2_LIB.BASEBOARD_FAB2(SCH_1):PAGE67
   AA2 UPI_CPU1_CPU0_P0P0_DP<4> @BASEBOARD_FAB2_LIB.BASEBOARD_FAB2(SCH_1):UPI_CPU1_CPU0_P0P0_DP(4)   I132 @BASEBOARD_FAB2_LIB.BASEBOARD_FAB2(SCH_1):PAGE67
    W2 UPI_CPU1_CPU0_P0P0_DP<3> @BASEBOARD_FAB2_LIB.BASEBOARD_FAB2(SCH_1):UPI_CPU1_CPU0_P0P0_DP(3)   I132 @BASEBOARD_FAB2_LIB.BASEBOARD_FAB2(SCH_1):PAGE67
    Y3 UPI_CPU1_CPU0_P0P0_DP<2> @BASEBOARD_FAB2_LIB.BASEBOARD_FAB2(SCH_1):UPI_CPU1_CPU0_P0P0_DP(2)   I132 @BASEBOARD_FAB2_LIB.BASEBOARD_FAB2(SCH_1):PAGE67
    T1 UPI_CPU1_CPU0_P0P0_DN<1> @BASEBOARD_FAB2_LIB.BASEBOARD_FAB2(SCH_1):UPI_CPU1_CPU0_P0P0_DN(1)   I132 @BASEBOARD_FAB2_LIB.BASEBOARD_FAB2(SCH_1):PAGE67
    M1 UPI_CPU1_CPU0_P0P0_DN<0> @BASEBOARD_FAB2_LIB.BASEBOARD_FAB2(SCH_1):UPI_CPU1_CPU0_P0P0_DN(0)   I132 @BASEBOARD_FAB2_LIB.BASEBOARD_FAB2(SCH_1):PAGE67
  AB19 UPI_CPU0_CPU1_P1P1_DP<19> @BASEBOARD_FAB2_LIB.BASEBOARD_FAB2(SCH_1):UPI_CPU0_CPU1_P1P1_DP(19)   I125 @BASEBOARD_FAB2_LIB.BASEBOARD_FAB2(SCH_1):PAGE68
   Y21 UPI_CPU0_CPU1_P1P1_DP<18> @BASEBOARD_FAB2_LIB.BASEBOARD_FAB2(SCH_1):UPI_CPU0_CPU1_P1P1_DP(18)   I125 @BASEBOARD_FAB2_LIB.BASEBOARD_FAB2(SCH_1):PAGE68
   V19 UPI_CPU0_CPU1_P1P1_DN<17> @BASEBOARD_FAB2_LIB.BASEBOARD_FAB2(SCH_1):UPI_CPU0_CPU1_P1P1_DN(17)   I125 @BASEBOARD_FAB2_LIB.BASEBOARD_FAB2(SCH_1):PAGE68
   P21 UPI_CPU0_CPU1_P1P1_DN<16> @BASEBOARD_FAB2_LIB.BASEBOARD_FAB2(SCH_1):UPI_CPU0_CPU1_P1P1_DN(16)   I125 @BASEBOARD_FAB2_LIB.BASEBOARD_FAB2(SCH_1):PAGE68
   U18 UPI_CPU0_CPU1_P1P1_DN<15> @BASEBOARD_FAB2_LIB.BASEBOARD_FAB2(SCH_1):UPI_CPU0_CPU1_P1P1_DN(15)   I125 @BASEBOARD_FAB2_LIB.BASEBOARD_FAB2(SCH_1):PAGE68
   R20 UPI_CPU0_CPU1_P1P1_DN<14> @BASEBOARD_FAB2_LIB.BASEBOARD_FAB2(SCH_1):UPI_CPU0_CPU1_P1P1_DN(14)   I125 @BASEBOARD_FAB2_LIB.BASEBOARD_FAB2(SCH_1):PAGE68
   W18 UPI_CPU0_CPU1_P1P1_DP<13> @BASEBOARD_FAB2_LIB.BASEBOARD_FAB2(SCH_1):UPI_CPU0_CPU1_P1P1_DP(13)   I125 @BASEBOARD_FAB2_LIB.BASEBOARD_FAB2(SCH_1):PAGE68
   U16 UPI_CPU0_CPU1_P1P1_DP<12> @BASEBOARD_FAB2_LIB.BASEBOARD_FAB2(SCH_1):UPI_CPU0_CPU1_P1P1_DP(12)   I125 @BASEBOARD_FAB2_LIB.BASEBOARD_FAB2(SCH_1):PAGE68
   P17 UPI_CPU0_CPU1_P1P1_DP<11> @BASEBOARD_FAB2_LIB.BASEBOARD_FAB2(SCH_1):UPI_CPU0_CPU1_P1P1_DP(11)   I125 @BASEBOARD_FAB2_LIB.BASEBOARD_FAB2(SCH_1):PAGE68
   R16 UPI_CPU0_CPU1_P1P1_DN<10> @BASEBOARD_FAB2_LIB.BASEBOARD_FAB2(SCH_1):UPI_CPU0_CPU1_P1P1_DN(10)   I125 @BASEBOARD_FAB2_LIB.BASEBOARD_FAB2(SCH_1):PAGE68
   R12 UPI_CPU0_CPU1_P1P1_DN<9> @BASEBOARD_FAB2_LIB.BASEBOARD_FAB2(SCH_1):UPI_CPU0_CPU1_P1P1_DN(9)   I125 @BASEBOARD_FAB2_LIB.BASEBOARD_FAB2(SCH_1):PAGE68
   N14 UPI_CPU0_CPU1_P1P1_DP<8> @BASEBOARD_FAB2_LIB.BASEBOARD_FAB2(SCH_1):UPI_CPU0_CPU1_P1P1_DP(8)   I125 @BASEBOARD_FAB2_LIB.BASEBOARD_FAB2(SCH_1):PAGE68
   L12 UPI_CPU0_CPU1_P1P1_DN<7> @BASEBOARD_FAB2_LIB.BASEBOARD_FAB2(SCH_1):UPI_CPU0_CPU1_P1P1_DN(7)   I125 @BASEBOARD_FAB2_LIB.BASEBOARD_FAB2(SCH_1):PAGE68
   U12 UPI_CPU0_CPU1_P1P1_DN<6> @BASEBOARD_FAB2_LIB.BASEBOARD_FAB2(SCH_1):UPI_CPU0_CPU1_P1P1_DN(6)   I125 @BASEBOARD_FAB2_LIB.BASEBOARD_FAB2(SCH_1):PAGE68
   R10 UPI_CPU0_CPU1_P1P1_DN<5> @BASEBOARD_FAB2_LIB.BASEBOARD_FAB2(SCH_1):UPI_CPU0_CPU1_P1P1_DN(5)   I125 @BASEBOARD_FAB2_LIB.BASEBOARD_FAB2(SCH_1):PAGE68
    P9 UPI_CPU0_CPU1_P1P1_DN<4> @BASEBOARD_FAB2_LIB.BASEBOARD_FAB2(SCH_1):UPI_CPU0_CPU1_P1P1_DN(4)   I125 @BASEBOARD_FAB2_LIB.BASEBOARD_FAB2(SCH_1):PAGE68
    T9 UPI_CPU0_CPU1_P1P1_DN<3> @BASEBOARD_FAB2_LIB.BASEBOARD_FAB2(SCH_1):UPI_CPU0_CPU1_P1P1_DN(3)   I125 @BASEBOARD_FAB2_LIB.BASEBOARD_FAB2(SCH_1):PAGE68
    V7 UPI_CPU0_CPU1_P1P1_DN<2> @BASEBOARD_FAB2_LIB.BASEBOARD_FAB2(SCH_1):UPI_CPU0_CPU1_P1P1_DN(2)   I125 @BASEBOARD_FAB2_LIB.BASEBOARD_FAB2(SCH_1):PAGE68
    P7 UPI_CPU0_CPU1_P1P1_DN<1> @BASEBOARD_FAB2_LIB.BASEBOARD_FAB2(SCH_1):UPI_CPU0_CPU1_P1P1_DN(1)   I125 @BASEBOARD_FAB2_LIB.BASEBOARD_FAB2(SCH_1):PAGE68
    T5 UPI_CPU0_CPU1_P1P1_DP<0> @BASEBOARD_FAB2_LIB.BASEBOARD_FAB2(SCH_1):UPI_CPU0_CPU1_P1P1_DP(0)   I125 @BASEBOARD_FAB2_LIB.BASEBOARD_FAB2(SCH_1):PAGE68
  AA20 UPI_CPU0_CPU1_P1P1_DN<19> @BASEBOARD_FAB2_LIB.BASEBOARD_FAB2(SCH_1):UPI_CPU0_CPU1_P1P1_DN(19)   I125 @BASEBOARD_FAB2_LIB.BASEBOARD_FAB2(SCH_1):PAGE68
   W20 UPI_CPU0_CPU1_P1P1_DN<18> @BASEBOARD_FAB2_LIB.BASEBOARD_FAB2(SCH_1):UPI_CPU0_CPU1_P1P1_DN(18)   I125 @BASEBOARD_FAB2_LIB.BASEBOARD_FAB2(SCH_1):PAGE68
   Y19 UPI_CPU0_CPU1_P1P1_DP<17> @BASEBOARD_FAB2_LIB.BASEBOARD_FAB2(SCH_1):UPI_CPU0_CPU1_P1P1_DP(17)   I125 @BASEBOARD_FAB2_LIB.BASEBOARD_FAB2(SCH_1):PAGE68
   T21 UPI_CPU0_CPU1_P1P1_DP<16> @BASEBOARD_FAB2_LIB.BASEBOARD_FAB2(SCH_1):UPI_CPU0_CPU1_P1P1_DP(16)   I125 @BASEBOARD_FAB2_LIB.BASEBOARD_FAB2(SCH_1):PAGE68
   T19 UPI_CPU0_CPU1_P1P1_DP<15> @BASEBOARD_FAB2_LIB.BASEBOARD_FAB2(SCH_1):UPI_CPU0_CPU1_P1P1_DP(15)   I125 @BASEBOARD_FAB2_LIB.BASEBOARD_FAB2(SCH_1):PAGE68
   P19 UPI_CPU0_CPU1_P1P1_DP<14> @BASEBOARD_FAB2_LIB.BASEBOARD_FAB2(SCH_1):UPI_CPU0_CPU1_P1P1_DP(14)   I125 @BASEBOARD_FAB2_LIB.BASEBOARD_FAB2(SCH_1):PAGE68
   V17 UPI_CPU0_CPU1_P1P1_DN<13> @BASEBOARD_FAB2_LIB.BASEBOARD_FAB2(SCH_1):UPI_CPU0_CPU1_P1P1_DN(13)   I125 @BASEBOARD_FAB2_LIB.BASEBOARD_FAB2(SCH_1):PAGE68
   W16 UPI_CPU0_CPU1_P1P1_DN<12> @BASEBOARD_FAB2_LIB.BASEBOARD_FAB2(SCH_1):UPI_CPU0_CPU1_P1P1_DN(12)   I125 @BASEBOARD_FAB2_LIB.BASEBOARD_FAB2(SCH_1):PAGE68
   N16 UPI_CPU0_CPU1_P1P1_DN<11> @BASEBOARD_FAB2_LIB.BASEBOARD_FAB2(SCH_1):UPI_CPU0_CPU1_P1P1_DN(11)   I125 @BASEBOARD_FAB2_LIB.BASEBOARD_FAB2(SCH_1):PAGE68
   T15 UPI_CPU0_CPU1_P1P1_DP<10> @BASEBOARD_FAB2_LIB.BASEBOARD_FAB2(SCH_1):UPI_CPU0_CPU1_P1P1_DP(10)   I125 @BASEBOARD_FAB2_LIB.BASEBOARD_FAB2(SCH_1):PAGE68
   P13 UPI_CPU0_CPU1_P1P1_DP<9> @BASEBOARD_FAB2_LIB.BASEBOARD_FAB2(SCH_1):UPI_CPU0_CPU1_P1P1_DP(9)   I125 @BASEBOARD_FAB2_LIB.BASEBOARD_FAB2(SCH_1):PAGE68
   M13 UPI_CPU0_CPU1_P1P1_DN<8> @BASEBOARD_FAB2_LIB.BASEBOARD_FAB2(SCH_1):UPI_CPU0_CPU1_P1P1_DN(8)   I125 @BASEBOARD_FAB2_LIB.BASEBOARD_FAB2(SCH_1):PAGE68
   N12 UPI_CPU0_CPU1_P1P1_DP<7> @BASEBOARD_FAB2_LIB.BASEBOARD_FAB2(SCH_1):UPI_CPU0_CPU1_P1P1_DP(7)   I125 @BASEBOARD_FAB2_LIB.BASEBOARD_FAB2(SCH_1):PAGE68
   T11 UPI_CPU0_CPU1_P1P1_DP<6> @BASEBOARD_FAB2_LIB.BASEBOARD_FAB2(SCH_1):UPI_CPU0_CPU1_P1P1_DP(6)   I125 @BASEBOARD_FAB2_LIB.BASEBOARD_FAB2(SCH_1):PAGE68
   U10 UPI_CPU0_CPU1_P1P1_DP<5> @BASEBOARD_FAB2_LIB.BASEBOARD_FAB2(SCH_1):UPI_CPU0_CPU1_P1P1_DP(5)   I125 @BASEBOARD_FAB2_LIB.BASEBOARD_FAB2(SCH_1):PAGE68
   N10 UPI_CPU0_CPU1_P1P1_DP<4> @BASEBOARD_FAB2_LIB.BASEBOARD_FAB2(SCH_1):UPI_CPU0_CPU1_P1P1_DP(4)   I125 @BASEBOARD_FAB2_LIB.BASEBOARD_FAB2(SCH_1):PAGE68
    R8 UPI_CPU0_CPU1_P1P1_DP<3> @BASEBOARD_FAB2_LIB.BASEBOARD_FAB2(SCH_1):UPI_CPU0_CPU1_P1P1_DP(3)   I125 @BASEBOARD_FAB2_LIB.BASEBOARD_FAB2(SCH_1):PAGE68
    U8 UPI_CPU0_CPU1_P1P1_DP<2> @BASEBOARD_FAB2_LIB.BASEBOARD_FAB2(SCH_1):UPI_CPU0_CPU1_P1P1_DP(2)   I125 @BASEBOARD_FAB2_LIB.BASEBOARD_FAB2(SCH_1):PAGE68
    T7 UPI_CPU0_CPU1_P1P1_DP<1> @BASEBOARD_FAB2_LIB.BASEBOARD_FAB2(SCH_1):UPI_CPU0_CPU1_P1P1_DP(1)   I125 @BASEBOARD_FAB2_LIB.BASEBOARD_FAB2(SCH_1):PAGE68
    R6 UPI_CPU0_CPU1_P1P1_DN<0> @BASEBOARD_FAB2_LIB.BASEBOARD_FAB2(SCH_1):UPI_CPU0_CPU1_P1P1_DN(0)   I125 @BASEBOARD_FAB2_LIB.BASEBOARD_FAB2(SCH_1):PAGE68
   H21 UPI_CPU1_CPU0_P1P1_DP<19> @BASEBOARD_FAB2_LIB.BASEBOARD_FAB2(SCH_1):UPI_CPU1_CPU0_P1P1_DP(19)   I125 @BASEBOARD_FAB2_LIB.BASEBOARD_FAB2(SCH_1):PAGE68
   F21 UPI_CPU1_CPU0_P1P1_DP<18> @BASEBOARD_FAB2_LIB.BASEBOARD_FAB2(SCH_1):UPI_CPU1_CPU0_P1P1_DP(18)   I125 @BASEBOARD_FAB2_LIB.BASEBOARD_FAB2(SCH_1):PAGE68
   J20 UPI_CPU1_CPU0_P1P1_DN<17> @BASEBOARD_FAB2_LIB.BASEBOARD_FAB2(SCH_1):UPI_CPU1_CPU0_P1P1_DN(17)   I125 @BASEBOARD_FAB2_LIB.BASEBOARD_FAB2(SCH_1):PAGE68
   G18 UPI_CPU1_CPU0_P1P1_DN<16> @BASEBOARD_FAB2_LIB.BASEBOARD_FAB2(SCH_1):UPI_CPU1_CPU0_P1P1_DN(16)   I125 @BASEBOARD_FAB2_LIB.BASEBOARD_FAB2(SCH_1):PAGE68
   K19 UPI_CPU1_CPU0_P1P1_DN<15> @BASEBOARD_FAB2_LIB.BASEBOARD_FAB2(SCH_1):UPI_CPU1_CPU0_P1P1_DN(15)   I125 @BASEBOARD_FAB2_LIB.BASEBOARD_FAB2(SCH_1):PAGE68
   H17 UPI_CPU1_CPU0_P1P1_DN<14> @BASEBOARD_FAB2_LIB.BASEBOARD_FAB2(SCH_1):UPI_CPU1_CPU0_P1P1_DN(14)   I125 @BASEBOARD_FAB2_LIB.BASEBOARD_FAB2(SCH_1):PAGE68
   F15 UPI_CPU1_CPU0_P1P1_DN<13> @BASEBOARD_FAB2_LIB.BASEBOARD_FAB2(SCH_1):UPI_CPU1_CPU0_P1P1_DN(13)   I125 @BASEBOARD_FAB2_LIB.BASEBOARD_FAB2(SCH_1):PAGE68
   D15 UPI_CPU1_CPU0_P1P1_DN<12> @BASEBOARD_FAB2_LIB.BASEBOARD_FAB2(SCH_1):UPI_CPU1_CPU0_P1P1_DN(12)   I125 @BASEBOARD_FAB2_LIB.BASEBOARD_FAB2(SCH_1):PAGE68
   G14 UPI_CPU1_CPU0_P1P1_DP<11> @BASEBOARD_FAB2_LIB.BASEBOARD_FAB2(SCH_1):UPI_CPU1_CPU0_P1P1_DP(11)   I125 @BASEBOARD_FAB2_LIB.BASEBOARD_FAB2(SCH_1):PAGE68
   E12 UPI_CPU1_CPU0_P1P1_DN<10> @BASEBOARD_FAB2_LIB.BASEBOARD_FAB2(SCH_1):UPI_CPU1_CPU0_P1P1_DN(10)   I125 @BASEBOARD_FAB2_LIB.BASEBOARD_FAB2(SCH_1):PAGE68
   G10 UPI_CPU1_CPU0_P1P1_DN<9> @BASEBOARD_FAB2_LIB.BASEBOARD_FAB2(SCH_1):UPI_CPU1_CPU0_P1P1_DN(9)   I125 @BASEBOARD_FAB2_LIB.BASEBOARD_FAB2(SCH_1):PAGE68
   F11 UPI_CPU1_CPU0_P1P1_DP<8> @BASEBOARD_FAB2_LIB.BASEBOARD_FAB2(SCH_1):UPI_CPU1_CPU0_P1P1_DP(8)   I125 @BASEBOARD_FAB2_LIB.BASEBOARD_FAB2(SCH_1):PAGE68
    D9 UPI_CPU1_CPU0_P1P1_DP<7> @BASEBOARD_FAB2_LIB.BASEBOARD_FAB2(SCH_1):UPI_CPU1_CPU0_P1P1_DP(7)   I125 @BASEBOARD_FAB2_LIB.BASEBOARD_FAB2(SCH_1):PAGE68
    K9 UPI_CPU1_CPU0_P1P1_DP<6> @BASEBOARD_FAB2_LIB.BASEBOARD_FAB2(SCH_1):UPI_CPU1_CPU0_P1P1_DP(6)   I125 @BASEBOARD_FAB2_LIB.BASEBOARD_FAB2(SCH_1):PAGE68
    H7 UPI_CPU1_CPU0_P1P1_DN<5> @BASEBOARD_FAB2_LIB.BASEBOARD_FAB2(SCH_1):UPI_CPU1_CPU0_P1P1_DN(5)   I125 @BASEBOARD_FAB2_LIB.BASEBOARD_FAB2(SCH_1):PAGE68
    G6 UPI_CPU1_CPU0_P1P1_DN<4> @BASEBOARD_FAB2_LIB.BASEBOARD_FAB2(SCH_1):UPI_CPU1_CPU0_P1P1_DN(4)   I125 @BASEBOARD_FAB2_LIB.BASEBOARD_FAB2(SCH_1):PAGE68
    J6 UPI_CPU1_CPU0_P1P1_DN<3> @BASEBOARD_FAB2_LIB.BASEBOARD_FAB2(SCH_1):UPI_CPU1_CPU0_P1P1_DN(3)   I125 @BASEBOARD_FAB2_LIB.BASEBOARD_FAB2(SCH_1):PAGE68
    K5 UPI_CPU1_CPU0_P1P1_DN<2> @BASEBOARD_FAB2_LIB.BASEBOARD_FAB2(SCH_1):UPI_CPU1_CPU0_P1P1_DN(2)   I125 @BASEBOARD_FAB2_LIB.BASEBOARD_FAB2(SCH_1):PAGE68
    L4 UPI_CPU1_CPU0_P1P1_DP<1> @BASEBOARD_FAB2_LIB.BASEBOARD_FAB2(SCH_1):UPI_CPU1_CPU0_P1P1_DP(1)   I125 @BASEBOARD_FAB2_LIB.BASEBOARD_FAB2(SCH_1):PAGE68
    M3 UPI_CPU1_CPU0_P1P1_DP<0> @BASEBOARD_FAB2_LIB.BASEBOARD_FAB2(SCH_1):UPI_CPU1_CPU0_P1P1_DP(0)   I125 @BASEBOARD_FAB2_LIB.BASEBOARD_FAB2(SCH_1):PAGE68
   K21 UPI_CPU1_CPU0_P1P1_DN<19> @BASEBOARD_FAB2_LIB.BASEBOARD_FAB2(SCH_1):UPI_CPU1_CPU0_P1P1_DN(19)   I125 @BASEBOARD_FAB2_LIB.BASEBOARD_FAB2(SCH_1):PAGE68
   G20 UPI_CPU1_CPU0_P1P1_DN<18> @BASEBOARD_FAB2_LIB.BASEBOARD_FAB2(SCH_1):UPI_CPU1_CPU0_P1P1_DN(18)   I125 @BASEBOARD_FAB2_LIB.BASEBOARD_FAB2(SCH_1):PAGE68
   H19 UPI_CPU1_CPU0_P1P1_DP<17> @BASEBOARD_FAB2_LIB.BASEBOARD_FAB2(SCH_1):UPI_CPU1_CPU0_P1P1_DP(17)   I125 @BASEBOARD_FAB2_LIB.BASEBOARD_FAB2(SCH_1):PAGE68
   J18 UPI_CPU1_CPU0_P1P1_DP<16> @BASEBOARD_FAB2_LIB.BASEBOARD_FAB2(SCH_1):UPI_CPU1_CPU0_P1P1_DP(16)   I125 @BASEBOARD_FAB2_LIB.BASEBOARD_FAB2(SCH_1):PAGE68
   L18 UPI_CPU1_CPU0_P1P1_DP<15> @BASEBOARD_FAB2_LIB.BASEBOARD_FAB2(SCH_1):UPI_CPU1_CPU0_P1P1_DP(15)   I125 @BASEBOARD_FAB2_LIB.BASEBOARD_FAB2(SCH_1):PAGE68
   G16 UPI_CPU1_CPU0_P1P1_DP<14> @BASEBOARD_FAB2_LIB.BASEBOARD_FAB2(SCH_1):UPI_CPU1_CPU0_P1P1_DP(14)   I125 @BASEBOARD_FAB2_LIB.BASEBOARD_FAB2(SCH_1):PAGE68
   H15 UPI_CPU1_CPU0_P1P1_DP<13> @BASEBOARD_FAB2_LIB.BASEBOARD_FAB2(SCH_1):UPI_CPU1_CPU0_P1P1_DP(13)   I125 @BASEBOARD_FAB2_LIB.BASEBOARD_FAB2(SCH_1):PAGE68
   E14 UPI_CPU1_CPU0_P1P1_DP<12> @BASEBOARD_FAB2_LIB.BASEBOARD_FAB2(SCH_1):UPI_CPU1_CPU0_P1P1_DP(12)   I125 @BASEBOARD_FAB2_LIB.BASEBOARD_FAB2(SCH_1):PAGE68
   F13 UPI_CPU1_CPU0_P1P1_DN<11> @BASEBOARD_FAB2_LIB.BASEBOARD_FAB2(SCH_1):UPI_CPU1_CPU0_P1P1_DN(11)   I125 @BASEBOARD_FAB2_LIB.BASEBOARD_FAB2(SCH_1):PAGE68
   G12 UPI_CPU1_CPU0_P1P1_DP<10> @BASEBOARD_FAB2_LIB.BASEBOARD_FAB2(SCH_1):UPI_CPU1_CPU0_P1P1_DP(10)   I125 @BASEBOARD_FAB2_LIB.BASEBOARD_FAB2(SCH_1):PAGE68
    H9 UPI_CPU1_CPU0_P1P1_DP<9> @BASEBOARD_FAB2_LIB.BASEBOARD_FAB2(SCH_1):UPI_CPU1_CPU0_P1P1_DP(9)   I125 @BASEBOARD_FAB2_LIB.BASEBOARD_FAB2(SCH_1):PAGE68
   E10 UPI_CPU1_CPU0_P1P1_DN<8> @BASEBOARD_FAB2_LIB.BASEBOARD_FAB2(SCH_1):UPI_CPU1_CPU0_P1P1_DN(8)   I125 @BASEBOARD_FAB2_LIB.BASEBOARD_FAB2(SCH_1):PAGE68
    F9 UPI_CPU1_CPU0_P1P1_DN<7> @BASEBOARD_FAB2_LIB.BASEBOARD_FAB2(SCH_1):UPI_CPU1_CPU0_P1P1_DN(7)   I125 @BASEBOARD_FAB2_LIB.BASEBOARD_FAB2(SCH_1):PAGE68
    J8 UPI_CPU1_CPU0_P1P1_DN<6> @BASEBOARD_FAB2_LIB.BASEBOARD_FAB2(SCH_1):UPI_CPU1_CPU0_P1P1_DN(6)   I125 @BASEBOARD_FAB2_LIB.BASEBOARD_FAB2(SCH_1):PAGE68
    K7 UPI_CPU1_CPU0_P1P1_DP<5> @BASEBOARD_FAB2_LIB.BASEBOARD_FAB2(SCH_1):UPI_CPU1_CPU0_P1P1_DP(5)   I125 @BASEBOARD_FAB2_LIB.BASEBOARD_FAB2(SCH_1):PAGE68
    F7 UPI_CPU1_CPU0_P1P1_DP<4> @BASEBOARD_FAB2_LIB.BASEBOARD_FAB2(SCH_1):UPI_CPU1_CPU0_P1P1_DP(4)   I125 @BASEBOARD_FAB2_LIB.BASEBOARD_FAB2(SCH_1):PAGE68
    H5 UPI_CPU1_CPU0_P1P1_DP<3> @BASEBOARD_FAB2_LIB.BASEBOARD_FAB2(SCH_1):UPI_CPU1_CPU0_P1P1_DP(3)   I125 @BASEBOARD_FAB2_LIB.BASEBOARD_FAB2(SCH_1):PAGE68
    M5 UPI_CPU1_CPU0_P1P1_DP<2> @BASEBOARD_FAB2_LIB.BASEBOARD_FAB2(SCH_1):UPI_CPU1_CPU0_P1P1_DP(2)   I125 @BASEBOARD_FAB2_LIB.BASEBOARD_FAB2(SCH_1):PAGE68
    K3 UPI_CPU1_CPU0_P1P1_DN<1> @BASEBOARD_FAB2_LIB.BASEBOARD_FAB2(SCH_1):UPI_CPU1_CPU0_P1P1_DN(1)   I125 @BASEBOARD_FAB2_LIB.BASEBOARD_FAB2(SCH_1):PAGE68
    P3 UPI_CPU1_CPU0_P1P1_DN<0> @BASEBOARD_FAB2_LIB.BASEBOARD_FAB2(SCH_1):UPI_CPU1_CPU0_P1P1_DN(0)   I125 @BASEBOARD_FAB2_LIB.BASEBOARD_FAB2(SCH_1):PAGE68
  BY17    GND @BASEBOARD_FAB2_LIB.BASEBOARD_FAB2(SCH_1):GND     I1 @BASEBOARD_FAB2_LIB.BASEBOARD_FAB2(SCH_1):PAGE69
  CB15    GND @BASEBOARD_FAB2_LIB.BASEBOARD_FAB2(SCH_1):GND     I1 @BASEBOARD_FAB2_LIB.BASEBOARD_FAB2(SCH_1):PAGE69
  CF17    GND @BASEBOARD_FAB2_LIB.BASEBOARD_FAB2(SCH_1):GND     I1 @BASEBOARD_FAB2_LIB.BASEBOARD_FAB2(SCH_1):PAGE69
  CD15    GND @BASEBOARD_FAB2_LIB.BASEBOARD_FAB2(SCH_1):GND     I1 @BASEBOARD_FAB2_LIB.BASEBOARD_FAB2(SCH_1):PAGE69
  CE16    GND @BASEBOARD_FAB2_LIB.BASEBOARD_FAB2(SCH_1):GND     I1 @BASEBOARD_FAB2_LIB.BASEBOARD_FAB2(SCH_1):PAGE69
  CH17    GND @BASEBOARD_FAB2_LIB.BASEBOARD_FAB2(SCH_1):GND     I1 @BASEBOARD_FAB2_LIB.BASEBOARD_FAB2(SCH_1):PAGE69
  CJ18    GND @BASEBOARD_FAB2_LIB.BASEBOARD_FAB2(SCH_1):GND     I1 @BASEBOARD_FAB2_LIB.BASEBOARD_FAB2(SCH_1):PAGE69
  CL16    GND @BASEBOARD_FAB2_LIB.BASEBOARD_FAB2(SCH_1):GND     I1 @BASEBOARD_FAB2_LIB.BASEBOARD_FAB2(SCH_1):PAGE69
  CP21    GND @BASEBOARD_FAB2_LIB.BASEBOARD_FAB2(SCH_1):GND     I1 @BASEBOARD_FAB2_LIB.BASEBOARD_FAB2(SCH_1):PAGE69
  CN20    GND @BASEBOARD_FAB2_LIB.BASEBOARD_FAB2(SCH_1):GND     I1 @BASEBOARD_FAB2_LIB.BASEBOARD_FAB2(SCH_1):PAGE69
  CR18    GND @BASEBOARD_FAB2_LIB.BASEBOARD_FAB2(SCH_1):GND     I1 @BASEBOARD_FAB2_LIB.BASEBOARD_FAB2(SCH_1):PAGE69
  CT21    GND @BASEBOARD_FAB2_LIB.BASEBOARD_FAB2(SCH_1):GND     I1 @BASEBOARD_FAB2_LIB.BASEBOARD_FAB2(SCH_1):PAGE69
  CV19    GND @BASEBOARD_FAB2_LIB.BASEBOARD_FAB2(SCH_1):GND     I1 @BASEBOARD_FAB2_LIB.BASEBOARD_FAB2(SCH_1):PAGE69
  CW20    GND @BASEBOARD_FAB2_LIB.BASEBOARD_FAB2(SCH_1):GND     I1 @BASEBOARD_FAB2_LIB.BASEBOARD_FAB2(SCH_1):PAGE69
  DA20    GND @BASEBOARD_FAB2_LIB.BASEBOARD_FAB2(SCH_1):GND     I1 @BASEBOARD_FAB2_LIB.BASEBOARD_FAB2(SCH_1):PAGE69
  DD19    GND @BASEBOARD_FAB2_LIB.BASEBOARD_FAB2(SCH_1):GND     I1 @BASEBOARD_FAB2_LIB.BASEBOARD_FAB2(SCH_1):PAGE69
  DB21    GND @BASEBOARD_FAB2_LIB.BASEBOARD_FAB2(SCH_1):GND     I1 @BASEBOARD_FAB2_LIB.BASEBOARD_FAB2(SCH_1):PAGE69
  DC22    GND @BASEBOARD_FAB2_LIB.BASEBOARD_FAB2(SCH_1):GND     I1 @BASEBOARD_FAB2_LIB.BASEBOARD_FAB2(SCH_1):PAGE69
  DE22    GND @BASEBOARD_FAB2_LIB.BASEBOARD_FAB2(SCH_1):GND     I1 @BASEBOARD_FAB2_LIB.BASEBOARD_FAB2(SCH_1):PAGE69
  DF23    GND @BASEBOARD_FAB2_LIB.BASEBOARD_FAB2(SCH_1):GND     I1 @BASEBOARD_FAB2_LIB.BASEBOARD_FAB2(SCH_1):PAGE69
  CA16    GND @BASEBOARD_FAB2_LIB.BASEBOARD_FAB2(SCH_1):GND     I1 @BASEBOARD_FAB2_LIB.BASEBOARD_FAB2(SCH_1):PAGE69
  BY15    GND @BASEBOARD_FAB2_LIB.BASEBOARD_FAB2(SCH_1):GND     I1 @BASEBOARD_FAB2_LIB.BASEBOARD_FAB2(SCH_1):PAGE69
  CD17    GND @BASEBOARD_FAB2_LIB.BASEBOARD_FAB2(SCH_1):GND     I1 @BASEBOARD_FAB2_LIB.BASEBOARD_FAB2(SCH_1):PAGE69
  CC14    GND @BASEBOARD_FAB2_LIB.BASEBOARD_FAB2(SCH_1):GND     I1 @BASEBOARD_FAB2_LIB.BASEBOARD_FAB2(SCH_1):PAGE69
  CF15    GND @BASEBOARD_FAB2_LIB.BASEBOARD_FAB2(SCH_1):GND     I1 @BASEBOARD_FAB2_LIB.BASEBOARD_FAB2(SCH_1):PAGE69
  CG16    GND @BASEBOARD_FAB2_LIB.BASEBOARD_FAB2(SCH_1):GND     I1 @BASEBOARD_FAB2_LIB.BASEBOARD_FAB2(SCH_1):PAGE69
  CK17    GND @BASEBOARD_FAB2_LIB.BASEBOARD_FAB2(SCH_1):GND     I1 @BASEBOARD_FAB2_LIB.BASEBOARD_FAB2(SCH_1):PAGE69
  CJ16    GND @BASEBOARD_FAB2_LIB.BASEBOARD_FAB2(SCH_1):GND     I1 @BASEBOARD_FAB2_LIB.BASEBOARD_FAB2(SCH_1):PAGE69
  CM21    GND @BASEBOARD_FAB2_LIB.BASEBOARD_FAB2(SCH_1):GND     I1 @BASEBOARD_FAB2_LIB.BASEBOARD_FAB2(SCH_1):PAGE69
  CP19    GND @BASEBOARD_FAB2_LIB.BASEBOARD_FAB2(SCH_1):GND     I1 @BASEBOARD_FAB2_LIB.BASEBOARD_FAB2(SCH_1):PAGE69
  CN18    GND @BASEBOARD_FAB2_LIB.BASEBOARD_FAB2(SCH_1):GND     I1 @BASEBOARD_FAB2_LIB.BASEBOARD_FAB2(SCH_1):PAGE69
  CR20    GND @BASEBOARD_FAB2_LIB.BASEBOARD_FAB2(SCH_1):GND     I1 @BASEBOARD_FAB2_LIB.BASEBOARD_FAB2(SCH_1):PAGE69
  CW18    GND @BASEBOARD_FAB2_LIB.BASEBOARD_FAB2(SCH_1):GND     I1 @BASEBOARD_FAB2_LIB.BASEBOARD_FAB2(SCH_1):PAGE69
  CU20    GND @BASEBOARD_FAB2_LIB.BASEBOARD_FAB2(SCH_1):GND     I1 @BASEBOARD_FAB2_LIB.BASEBOARD_FAB2(SCH_1):PAGE69
  CY19    GND @BASEBOARD_FAB2_LIB.BASEBOARD_FAB2(SCH_1):GND     I1 @BASEBOARD_FAB2_LIB.BASEBOARD_FAB2(SCH_1):PAGE69
  DB19    GND @BASEBOARD_FAB2_LIB.BASEBOARD_FAB2(SCH_1):GND     I1 @BASEBOARD_FAB2_LIB.BASEBOARD_FAB2(SCH_1):PAGE69
  DC20    GND @BASEBOARD_FAB2_LIB.BASEBOARD_FAB2(SCH_1):GND     I1 @BASEBOARD_FAB2_LIB.BASEBOARD_FAB2(SCH_1):PAGE69
  DA22    GND @BASEBOARD_FAB2_LIB.BASEBOARD_FAB2(SCH_1):GND     I1 @BASEBOARD_FAB2_LIB.BASEBOARD_FAB2(SCH_1):PAGE69
  DD21    GND @BASEBOARD_FAB2_LIB.BASEBOARD_FAB2(SCH_1):GND     I1 @BASEBOARD_FAB2_LIB.BASEBOARD_FAB2(SCH_1):PAGE69
  DG22    GND @BASEBOARD_FAB2_LIB.BASEBOARD_FAB2(SCH_1):GND     I1 @BASEBOARD_FAB2_LIB.BASEBOARD_FAB2(SCH_1):PAGE69
  CC12 TP_CPU1_UPI2_RSVD_DT21 @BASEBOARD_FAB2_LIB.BASEBOARD_FAB2(SCH_1):TP_CPU1_UPI2_RSVD_DT21     I1 @BASEBOARD_FAB2_LIB.BASEBOARD_FAB2(SCH_1):PAGE69
  CC10 TP_CPU1_UPI2_RSVD_DM21 @BASEBOARD_FAB2_LIB.BASEBOARD_FAB2(SCH_1):TP_CPU1_UPI2_RSVD_DM21     I1 @BASEBOARD_FAB2_LIB.BASEBOARD_FAB2(SCH_1):PAGE69
  CE12 TP_CPU1_UPI2_RSVD_DL20 @BASEBOARD_FAB2_LIB.BASEBOARD_FAB2(SCH_1):TP_CPU1_UPI2_RSVD_DL20     I1 @BASEBOARD_FAB2_LIB.BASEBOARD_FAB2(SCH_1):PAGE69
  CH11 TP_CPU1_UPI2_RSVD_DG20 @BASEBOARD_FAB2_LIB.BASEBOARD_FAB2(SCH_1):TP_CPU1_UPI2_RSVD_DG20     I1 @BASEBOARD_FAB2_LIB.BASEBOARD_FAB2(SCH_1):PAGE69
  CF13 TP_CPU1_UPI2_RSVD_DH19 @BASEBOARD_FAB2_LIB.BASEBOARD_FAB2(SCH_1):TP_CPU1_UPI2_RSVD_DH19     I1 @BASEBOARD_FAB2_LIB.BASEBOARD_FAB2(SCH_1):PAGE69
  CJ14 TP_CPU1_UPI2_RSVD_DK17 @BASEBOARD_FAB2_LIB.BASEBOARD_FAB2(SCH_1):TP_CPU1_UPI2_RSVD_DK17     I1 @BASEBOARD_FAB2_LIB.BASEBOARD_FAB2(SCH_1):PAGE69
  CM13 TP_CPU1_UPI2_RSVD_DG18 @BASEBOARD_FAB2_LIB.BASEBOARD_FAB2(SCH_1):TP_CPU1_UPI2_RSVD_DG18     I1 @BASEBOARD_FAB2_LIB.BASEBOARD_FAB2(SCH_1):PAGE69
  CU14 TP_CPU1_UPI2_RSVD_DD17 @BASEBOARD_FAB2_LIB.BASEBOARD_FAB2(SCH_1):TP_CPU1_UPI2_RSVD_DD17     I1 @BASEBOARD_FAB2_LIB.BASEBOARD_FAB2(SCH_1):PAGE69
  CW14 TP_CPU1_UPI2_RSVD_DF15 @BASEBOARD_FAB2_LIB.BASEBOARD_FAB2(SCH_1):TP_CPU1_UPI2_RSVD_DF15     I1 @BASEBOARD_FAB2_LIB.BASEBOARD_FAB2(SCH_1):PAGE69
  DA16 TP_CPU1_UPI2_RSVD_DC16 @BASEBOARD_FAB2_LIB.BASEBOARD_FAB2(SCH_1):TP_CPU1_UPI2_RSVD_DC16     I1 @BASEBOARD_FAB2_LIB.BASEBOARD_FAB2(SCH_1):PAGE69
  DC16 TP_CPU1_UPI2_RSVD_DA16 @BASEBOARD_FAB2_LIB.BASEBOARD_FAB2(SCH_1):TP_CPU1_UPI2_RSVD_DA16     I1 @BASEBOARD_FAB2_LIB.BASEBOARD_FAB2(SCH_1):PAGE69
  DF15 TP_CPU1_UPI2_RSVD_CW14 @BASEBOARD_FAB2_LIB.BASEBOARD_FAB2(SCH_1):TP_CPU1_UPI2_RSVD_CW14     I1 @BASEBOARD_FAB2_LIB.BASEBOARD_FAB2(SCH_1):PAGE69
  DD17 TP_CPU1_UPI2_RSVD_CU14 @BASEBOARD_FAB2_LIB.BASEBOARD_FAB2(SCH_1):TP_CPU1_UPI2_RSVD_CU14     I1 @BASEBOARD_FAB2_LIB.BASEBOARD_FAB2(SCH_1):PAGE69
  DG18 TP_CPU1_UPI2_RSVD_CM13 @BASEBOARD_FAB2_LIB.BASEBOARD_FAB2(SCH_1):TP_CPU1_UPI2_RSVD_CM13     I1 @BASEBOARD_FAB2_LIB.BASEBOARD_FAB2(SCH_1):PAGE69
  DK17 TP_CPU1_UPI2_RSVD_CJ14 @BASEBOARD_FAB2_LIB.BASEBOARD_FAB2(SCH_1):TP_CPU1_UPI2_RSVD_CJ14     I1 @BASEBOARD_FAB2_LIB.BASEBOARD_FAB2(SCH_1):PAGE69
  DH19 TP_CPU1_UPI2_RSVD_CF13 @BASEBOARD_FAB2_LIB.BASEBOARD_FAB2(SCH_1):TP_CPU1_UPI2_RSVD_CF13     I1 @BASEBOARD_FAB2_LIB.BASEBOARD_FAB2(SCH_1):PAGE69
  DG20 TP_CPU1_UPI2_RSVD_CH11 @BASEBOARD_FAB2_LIB.BASEBOARD_FAB2(SCH_1):TP_CPU1_UPI2_RSVD_CH11     I1 @BASEBOARD_FAB2_LIB.BASEBOARD_FAB2(SCH_1):PAGE69
  DL20 TP_CPU1_UPI2_RSVD_CE12 @BASEBOARD_FAB2_LIB.BASEBOARD_FAB2(SCH_1):TP_CPU1_UPI2_RSVD_CE12     I1 @BASEBOARD_FAB2_LIB.BASEBOARD_FAB2(SCH_1):PAGE69
  DM21 TP_CPU1_UPI2_RSVD_CC10 @BASEBOARD_FAB2_LIB.BASEBOARD_FAB2(SCH_1):TP_CPU1_UPI2_RSVD_CC10     I1 @BASEBOARD_FAB2_LIB.BASEBOARD_FAB2(SCH_1):PAGE69
  DT21 TP_CPU1_UPI2_RSVD_CC12 @BASEBOARD_FAB2_LIB.BASEBOARD_FAB2(SCH_1):TP_CPU1_UPI2_RSVD_CC12     I1 @BASEBOARD_FAB2_LIB.BASEBOARD_FAB2(SCH_1):PAGE69
  CA12 TP_CPU1_UPI2_RSVD_DP21 @BASEBOARD_FAB2_LIB.BASEBOARD_FAB2(SCH_1):TP_CPU1_UPI2_RSVD_DP21     I1 @BASEBOARD_FAB2_LIB.BASEBOARD_FAB2(SCH_1):PAGE69
  CB11 TP_CPU1_UPI2_RSVD_DN20 @BASEBOARD_FAB2_LIB.BASEBOARD_FAB2(SCH_1):TP_CPU1_UPI2_RSVD_DN20     I1 @BASEBOARD_FAB2_LIB.BASEBOARD_FAB2(SCH_1):PAGE69
  CD11 TP_CPU1_UPI2_RSVD_DK19 @BASEBOARD_FAB2_LIB.BASEBOARD_FAB2(SCH_1):TP_CPU1_UPI2_RSVD_DK19     I1 @BASEBOARD_FAB2_LIB.BASEBOARD_FAB2(SCH_1):PAGE69
  CF11 TP_CPU1_UPI2_RSVD_DJ20 @BASEBOARD_FAB2_LIB.BASEBOARD_FAB2(SCH_1):TP_CPU1_UPI2_RSVD_DJ20     I1 @BASEBOARD_FAB2_LIB.BASEBOARD_FAB2(SCH_1):PAGE69
  CG12 TP_CPU1_UPI2_RSVD_DJ18 @BASEBOARD_FAB2_LIB.BASEBOARD_FAB2(SCH_1):TP_CPU1_UPI2_RSVD_DJ18     I1 @BASEBOARD_FAB2_LIB.BASEBOARD_FAB2(SCH_1):PAGE69
  CH13 TP_CPU1_UPI2_RSVD_DH17 @BASEBOARD_FAB2_LIB.BASEBOARD_FAB2(SCH_1):TP_CPU1_UPI2_RSVD_DH17     I1 @BASEBOARD_FAB2_LIB.BASEBOARD_FAB2(SCH_1):PAGE69
  CK13 TP_CPU1_UPI2_RSVD_DF17 @BASEBOARD_FAB2_LIB.BASEBOARD_FAB2(SCH_1):TP_CPU1_UPI2_RSVD_DF17     I1 @BASEBOARD_FAB2_LIB.BASEBOARD_FAB2(SCH_1):PAGE69
  CR14 TP_CPU1_UPI2_RSVD_DE16 @BASEBOARD_FAB2_LIB.BASEBOARD_FAB2(SCH_1):TP_CPU1_UPI2_RSVD_DE16     I1 @BASEBOARD_FAB2_LIB.BASEBOARD_FAB2(SCH_1):PAGE69
  CV13 TP_CPU1_UPI2_RSVD_DD15 @BASEBOARD_FAB2_LIB.BASEBOARD_FAB2(SCH_1):TP_CPU1_UPI2_RSVD_DD15     I1 @BASEBOARD_FAB2_LIB.BASEBOARD_FAB2(SCH_1):PAGE69
  CW16 TP_CPU1_UPI2_RSVD_DB15 @BASEBOARD_FAB2_LIB.BASEBOARD_FAB2(SCH_1):TP_CPU1_UPI2_RSVD_DB15     I1 @BASEBOARD_FAB2_LIB.BASEBOARD_FAB2(SCH_1):PAGE69
  DB15 TP_CPU1_UPI2_RSVD_CW16 @BASEBOARD_FAB2_LIB.BASEBOARD_FAB2(SCH_1):TP_CPU1_UPI2_RSVD_CW16     I1 @BASEBOARD_FAB2_LIB.BASEBOARD_FAB2(SCH_1):PAGE69
  DD15 TP_CPU1_UPI2_RSVD_CV13 @BASEBOARD_FAB2_LIB.BASEBOARD_FAB2(SCH_1):TP_CPU1_UPI2_RSVD_CV13     I1 @BASEBOARD_FAB2_LIB.BASEBOARD_FAB2(SCH_1):PAGE69
  DE16 TP_CPU1_UPI2_RSVD_CR14 @BASEBOARD_FAB2_LIB.BASEBOARD_FAB2(SCH_1):TP_CPU1_UPI2_RSVD_CR14     I1 @BASEBOARD_FAB2_LIB.BASEBOARD_FAB2(SCH_1):PAGE69
  DF17 TP_CPU1_UPI2_RSVD_CK13 @BASEBOARD_FAB2_LIB.BASEBOARD_FAB2(SCH_1):TP_CPU1_UPI2_RSVD_CK13     I1 @BASEBOARD_FAB2_LIB.BASEBOARD_FAB2(SCH_1):PAGE69
  DH17 TP_CPU1_UPI2_RSVD_CH13 @BASEBOARD_FAB2_LIB.BASEBOARD_FAB2(SCH_1):TP_CPU1_UPI2_RSVD_CH13     I1 @BASEBOARD_FAB2_LIB.BASEBOARD_FAB2(SCH_1):PAGE69
  DJ18 TP_CPU1_UPI2_RSVD_CG12 @BASEBOARD_FAB2_LIB.BASEBOARD_FAB2(SCH_1):TP_CPU1_UPI2_RSVD_CG12     I1 @BASEBOARD_FAB2_LIB.BASEBOARD_FAB2(SCH_1):PAGE69
  DJ20 TP_CPU1_UPI2_RSVD_CF11 @BASEBOARD_FAB2_LIB.BASEBOARD_FAB2(SCH_1):TP_CPU1_UPI2_RSVD_CF11     I1 @BASEBOARD_FAB2_LIB.BASEBOARD_FAB2(SCH_1):PAGE69
  DK19 TP_CPU1_UPI2_RSVD_CD11 @BASEBOARD_FAB2_LIB.BASEBOARD_FAB2(SCH_1):TP_CPU1_UPI2_RSVD_CD11     I1 @BASEBOARD_FAB2_LIB.BASEBOARD_FAB2(SCH_1):PAGE69
  DN20 TP_CPU1_UPI2_RSVD_CB11 @BASEBOARD_FAB2_LIB.BASEBOARD_FAB2(SCH_1):TP_CPU1_UPI2_RSVD_CB11     I1 @BASEBOARD_FAB2_LIB.BASEBOARD_FAB2(SCH_1):PAGE69
  DP21 TP_CPU1_UPI2_RSVD_CA12 @BASEBOARD_FAB2_LIB.BASEBOARD_FAB2(SCH_1):TP_CPU1_UPI2_RSVD_CA12     I1 @BASEBOARD_FAB2_LIB.BASEBOARD_FAB2(SCH_1):PAGE69
  AY83 TP_CPU1_RSVD_255 @BASEBOARD_FAB2_LIB.BASEBOARD_FAB2(SCH_1):TP_CPU1_RSVD_255     I9 @BASEBOARD_FAB2_LIB.BASEBOARD_FAB2(SCH_1):PAGE70
  BA78 TP_CPU1_RSVD_171 @BASEBOARD_FAB2_LIB.BASEBOARD_FAB2(SCH_1):TP_CPU1_RSVD_171     I9 @BASEBOARD_FAB2_LIB.BASEBOARD_FAB2(SCH_1):PAGE70
  BA82 TP_CPU1_RSVD_170 @BASEBOARD_FAB2_LIB.BASEBOARD_FAB2(SCH_1):TP_CPU1_RSVD_170     I9 @BASEBOARD_FAB2_LIB.BASEBOARD_FAB2(SCH_1):PAGE70
  BB13 TP_CPU1_RSVD_169 @BASEBOARD_FAB2_LIB.BASEBOARD_FAB2(SCH_1):TP_CPU1_RSVD_169     I9 @BASEBOARD_FAB2_LIB.BASEBOARD_FAB2(SCH_1):PAGE70
  BB15 TP_CPU1_RSVD_168 @BASEBOARD_FAB2_LIB.BASEBOARD_FAB2(SCH_1):TP_CPU1_RSVD_168     I9 @BASEBOARD_FAB2_LIB.BASEBOARD_FAB2(SCH_1):PAGE70
  BB17 TP_CPU1_RSVD_167 @BASEBOARD_FAB2_LIB.BASEBOARD_FAB2(SCH_1):TP_CPU1_RSVD_167     I9 @BASEBOARD_FAB2_LIB.BASEBOARD_FAB2(SCH_1):PAGE70
  BB21 TP_CPU1_RSVD_166 @BASEBOARD_FAB2_LIB.BASEBOARD_FAB2(SCH_1):TP_CPU1_RSVD_166     I9 @BASEBOARD_FAB2_LIB.BASEBOARD_FAB2(SCH_1):PAGE70
  BB25 CLK_100M_CPU1_RC_REFCLK1_DN @BASEBOARD_FAB2_LIB.BASEBOARD_FAB2(SCH_1):CLK_100M_CPU1_RC_REFCLK1_DN     I9 @BASEBOARD_FAB2_LIB.BASEBOARD_FAB2(SCH_1):PAGE70
  BB65 TP_CPU1_RSVD_164 @BASEBOARD_FAB2_LIB.BASEBOARD_FAB2(SCH_1):TP_CPU1_RSVD_164     I9 @BASEBOARD_FAB2_LIB.BASEBOARD_FAB2(SCH_1):PAGE70
  BB67 TP_CPU1_RSVD_163 @BASEBOARD_FAB2_LIB.BASEBOARD_FAB2(SCH_1):TP_CPU1_RSVD_163     I9 @BASEBOARD_FAB2_LIB.BASEBOARD_FAB2(SCH_1):PAGE70
  BC14 TP_CPU1_RSVD_162 @BASEBOARD_FAB2_LIB.BASEBOARD_FAB2(SCH_1):TP_CPU1_RSVD_162     I9 @BASEBOARD_FAB2_LIB.BASEBOARD_FAB2(SCH_1):PAGE70
  BC18 TP_CPU1_RSVD_161 @BASEBOARD_FAB2_LIB.BASEBOARD_FAB2(SCH_1):TP_CPU1_RSVD_161     I9 @BASEBOARD_FAB2_LIB.BASEBOARD_FAB2(SCH_1):PAGE70
  BC20 TP_CPU1_RSVD_160 @BASEBOARD_FAB2_LIB.BASEBOARD_FAB2(SCH_1):TP_CPU1_RSVD_160     I9 @BASEBOARD_FAB2_LIB.BASEBOARD_FAB2(SCH_1):PAGE70
  BC22 TP_CPU1_RSVD_159 @BASEBOARD_FAB2_LIB.BASEBOARD_FAB2(SCH_1):TP_CPU1_RSVD_159     I9 @BASEBOARD_FAB2_LIB.BASEBOARD_FAB2(SCH_1):PAGE70
  BC64 TP_CPU1_RSVD_158 @BASEBOARD_FAB2_LIB.BASEBOARD_FAB2(SCH_1):TP_CPU1_RSVD_158     I9 @BASEBOARD_FAB2_LIB.BASEBOARD_FAB2(SCH_1):PAGE70
  BC66 TP_CPU1_RSVD_157 @BASEBOARD_FAB2_LIB.BASEBOARD_FAB2(SCH_1):TP_CPU1_RSVD_157     I9 @BASEBOARD_FAB2_LIB.BASEBOARD_FAB2(SCH_1):PAGE70
  BC68 TP_CPU1_RSVD_156 @BASEBOARD_FAB2_LIB.BASEBOARD_FAB2(SCH_1):TP_CPU1_RSVD_156     I9 @BASEBOARD_FAB2_LIB.BASEBOARD_FAB2(SCH_1):PAGE70
  BD17 TP_CPU1_RSVD_155 @BASEBOARD_FAB2_LIB.BASEBOARD_FAB2(SCH_1):TP_CPU1_RSVD_155     I9 @BASEBOARD_FAB2_LIB.BASEBOARD_FAB2(SCH_1):PAGE70
  BD19 TP_CPU1_RSVD_154 @BASEBOARD_FAB2_LIB.BASEBOARD_FAB2(SCH_1):TP_CPU1_RSVD_154     I9 @BASEBOARD_FAB2_LIB.BASEBOARD_FAB2(SCH_1):PAGE70
  BD25 CLK_100M_CPU1_RC_REFCLK1_DP @BASEBOARD_FAB2_LIB.BASEBOARD_FAB2(SCH_1):CLK_100M_CPU1_RC_REFCLK1_DP     I9 @BASEBOARD_FAB2_LIB.BASEBOARD_FAB2(SCH_1):PAGE70
  BD65 TP_CPU1_RSVD_152 @BASEBOARD_FAB2_LIB.BASEBOARD_FAB2(SCH_1):TP_CPU1_RSVD_152     I9 @BASEBOARD_FAB2_LIB.BASEBOARD_FAB2(SCH_1):PAGE70
  BD67 TP_CPU1_RSVD_151 @BASEBOARD_FAB2_LIB.BASEBOARD_FAB2(SCH_1):TP_CPU1_RSVD_151     I9 @BASEBOARD_FAB2_LIB.BASEBOARD_FAB2(SCH_1):PAGE70
  BD69 TP_CPU1_RSVD_150 @BASEBOARD_FAB2_LIB.BASEBOARD_FAB2(SCH_1):TP_CPU1_RSVD_150     I9 @BASEBOARD_FAB2_LIB.BASEBOARD_FAB2(SCH_1):PAGE70
  BE18 TP_CPU1_RSVD_149 @BASEBOARD_FAB2_LIB.BASEBOARD_FAB2(SCH_1):TP_CPU1_RSVD_149     I9 @BASEBOARD_FAB2_LIB.BASEBOARD_FAB2(SCH_1):PAGE70
  BE20 TP_CPU1_RSVD_148 @BASEBOARD_FAB2_LIB.BASEBOARD_FAB2(SCH_1):TP_CPU1_RSVD_148     I9 @BASEBOARD_FAB2_LIB.BASEBOARD_FAB2(SCH_1):PAGE70
  BE22 TP_CPU1_RSVD_147 @BASEBOARD_FAB2_LIB.BASEBOARD_FAB2(SCH_1):TP_CPU1_RSVD_147     I9 @BASEBOARD_FAB2_LIB.BASEBOARD_FAB2(SCH_1):PAGE70
  BF21 TP_CPU1_RSVD_146 @BASEBOARD_FAB2_LIB.BASEBOARD_FAB2(SCH_1):TP_CPU1_RSVD_146     I9 @BASEBOARD_FAB2_LIB.BASEBOARD_FAB2(SCH_1):PAGE70
  BG18 TP_CPU1_RSVD_145 @BASEBOARD_FAB2_LIB.BASEBOARD_FAB2(SCH_1):TP_CPU1_RSVD_145     I9 @BASEBOARD_FAB2_LIB.BASEBOARD_FAB2(SCH_1):PAGE70
  BG20 TP_CPU1_RSVD_144 @BASEBOARD_FAB2_LIB.BASEBOARD_FAB2(SCH_1):TP_CPU1_RSVD_144     I9 @BASEBOARD_FAB2_LIB.BASEBOARD_FAB2(SCH_1):PAGE70
  BH19 PVCCMCP_CPU1 @BASEBOARD_FAB2_LIB.BASEBOARD_FAB2(SCH_1):PVCCMCP_CPU1     I9 @BASEBOARD_FAB2_LIB.BASEBOARD_FAB2(SCH_1):PAGE70
  BJ16 PVCCMCP_CPU1 @BASEBOARD_FAB2_LIB.BASEBOARD_FAB2(SCH_1):PVCCMCP_CPU1     I9 @BASEBOARD_FAB2_LIB.BASEBOARD_FAB2(SCH_1):PAGE70
  BJ18 PVCCMCP_CPU1 @BASEBOARD_FAB2_LIB.BASEBOARD_FAB2(SCH_1):PVCCMCP_CPU1     I9 @BASEBOARD_FAB2_LIB.BASEBOARD_FAB2(SCH_1):PAGE70
  BJ20 PVCCMCP_CPU1 @BASEBOARD_FAB2_LIB.BASEBOARD_FAB2(SCH_1):PVCCMCP_CPU1     I9 @BASEBOARD_FAB2_LIB.BASEBOARD_FAB2(SCH_1):PAGE70
  BK17 PVCCMCP_CPU1 @BASEBOARD_FAB2_LIB.BASEBOARD_FAB2(SCH_1):PVCCMCP_CPU1     I9 @BASEBOARD_FAB2_LIB.BASEBOARD_FAB2(SCH_1):PAGE70
  BL18 PVCCIOMCP_CPU1 @BASEBOARD_FAB2_LIB.BASEBOARD_FAB2(SCH_1):PVCCIOMCP_CPU1     I9 @BASEBOARD_FAB2_LIB.BASEBOARD_FAB2(SCH_1):PAGE70
  BL20 PVCCMCP_CPU1 @BASEBOARD_FAB2_LIB.BASEBOARD_FAB2(SCH_1):PVCCMCP_CPU1     I9 @BASEBOARD_FAB2_LIB.BASEBOARD_FAB2(SCH_1):PAGE70
  BM17 PVCCIOMCP_CPU1 @BASEBOARD_FAB2_LIB.BASEBOARD_FAB2(SCH_1):PVCCIOMCP_CPU1     I9 @BASEBOARD_FAB2_LIB.BASEBOARD_FAB2(SCH_1):PAGE70
  BM19 PVCCMCP_CPU1 @BASEBOARD_FAB2_LIB.BASEBOARD_FAB2(SCH_1):PVCCMCP_CPU1     I9 @BASEBOARD_FAB2_LIB.BASEBOARD_FAB2(SCH_1):PAGE70
  BN18 PVCCIOMCP_CPU1 @BASEBOARD_FAB2_LIB.BASEBOARD_FAB2(SCH_1):PVCCIOMCP_CPU1     I9 @BASEBOARD_FAB2_LIB.BASEBOARD_FAB2(SCH_1):PAGE70
  BP17 PVCCIOMCP_CPU1 @BASEBOARD_FAB2_LIB.BASEBOARD_FAB2(SCH_1):PVCCIOMCP_CPU1     I9 @BASEBOARD_FAB2_LIB.BASEBOARD_FAB2(SCH_1):PAGE70
  BP21 PVCCMCP_CPU1 @BASEBOARD_FAB2_LIB.BASEBOARD_FAB2(SCH_1):PVCCMCP_CPU1     I9 @BASEBOARD_FAB2_LIB.BASEBOARD_FAB2(SCH_1):PAGE70
  BR22 PVCCMCP_CPU1 @BASEBOARD_FAB2_LIB.BASEBOARD_FAB2(SCH_1):PVCCMCP_CPU1     I9 @BASEBOARD_FAB2_LIB.BASEBOARD_FAB2(SCH_1):PAGE70
  BR24 PVCCMCP_CPU1 @BASEBOARD_FAB2_LIB.BASEBOARD_FAB2(SCH_1):PVCCMCP_CPU1     I9 @BASEBOARD_FAB2_LIB.BASEBOARD_FAB2(SCH_1):PAGE70
  BU18 PVCCIOMCP_CPU1 @BASEBOARD_FAB2_LIB.BASEBOARD_FAB2(SCH_1):PVCCIOMCP_CPU1     I9 @BASEBOARD_FAB2_LIB.BASEBOARD_FAB2(SCH_1):PAGE70
  BU20 PVCCMCP_CPU1 @BASEBOARD_FAB2_LIB.BASEBOARD_FAB2(SCH_1):PVCCMCP_CPU1     I9 @BASEBOARD_FAB2_LIB.BASEBOARD_FAB2(SCH_1):PAGE70
  BU22 PVCCMCP_CPU1 @BASEBOARD_FAB2_LIB.BASEBOARD_FAB2(SCH_1):PVCCMCP_CPU1     I9 @BASEBOARD_FAB2_LIB.BASEBOARD_FAB2(SCH_1):PAGE70
  BV19 PVCCMCP_CPU1 @BASEBOARD_FAB2_LIB.BASEBOARD_FAB2(SCH_1):PVCCMCP_CPU1     I9 @BASEBOARD_FAB2_LIB.BASEBOARD_FAB2(SCH_1):PAGE70
  BV21 PVCCMCP_CPU1 @BASEBOARD_FAB2_LIB.BASEBOARD_FAB2(SCH_1):PVCCMCP_CPU1     I9 @BASEBOARD_FAB2_LIB.BASEBOARD_FAB2(SCH_1):PAGE70
  BV23 TP_CPU1_RSVD_124 @BASEBOARD_FAB2_LIB.BASEBOARD_FAB2(SCH_1):TP_CPU1_RSVD_124     I9 @BASEBOARD_FAB2_LIB.BASEBOARD_FAB2(SCH_1):PAGE70
  BW10 TP_CPU1_RSVD_123 @BASEBOARD_FAB2_LIB.BASEBOARD_FAB2(SCH_1):TP_CPU1_RSVD_123     I9 @BASEBOARD_FAB2_LIB.BASEBOARD_FAB2(SCH_1):PAGE70
  BW20 PVCCMCP_CPU1 @BASEBOARD_FAB2_LIB.BASEBOARD_FAB2(SCH_1):PVCCMCP_CPU1     I9 @BASEBOARD_FAB2_LIB.BASEBOARD_FAB2(SCH_1):PAGE70
  BW22 TP_CPU1_RSVD_121 @BASEBOARD_FAB2_LIB.BASEBOARD_FAB2(SCH_1):TP_CPU1_RSVD_121     I9 @BASEBOARD_FAB2_LIB.BASEBOARD_FAB2(SCH_1):PAGE70
  BY19 PVCCMCP_CPU1 @BASEBOARD_FAB2_LIB.BASEBOARD_FAB2(SCH_1):PVCCMCP_CPU1     I9 @BASEBOARD_FAB2_LIB.BASEBOARD_FAB2(SCH_1):PAGE70
  BY25 TP_CPU1_RSVD_119 @BASEBOARD_FAB2_LIB.BASEBOARD_FAB2(SCH_1):TP_CPU1_RSVD_119     I9 @BASEBOARD_FAB2_LIB.BASEBOARD_FAB2(SCH_1):PAGE70
  CA22 PVCCMCP_CPU1 @BASEBOARD_FAB2_LIB.BASEBOARD_FAB2(SCH_1):PVCCMCP_CPU1     I9 @BASEBOARD_FAB2_LIB.BASEBOARD_FAB2(SCH_1):PAGE70
  CA24 TP_CPU1_RSVD_117 @BASEBOARD_FAB2_LIB.BASEBOARD_FAB2(SCH_1):TP_CPU1_RSVD_117     I9 @BASEBOARD_FAB2_LIB.BASEBOARD_FAB2(SCH_1):PAGE70
  CB19 PVCCMCP_CPU1 @BASEBOARD_FAB2_LIB.BASEBOARD_FAB2(SCH_1):PVCCMCP_CPU1     I9 @BASEBOARD_FAB2_LIB.BASEBOARD_FAB2(SCH_1):PAGE70
  CB21 PVCCMCP_CPU1 @BASEBOARD_FAB2_LIB.BASEBOARD_FAB2(SCH_1):PVCCMCP_CPU1     I9 @BASEBOARD_FAB2_LIB.BASEBOARD_FAB2(SCH_1):PAGE70
  CB25 TP_CPU1_RSVD_114 @BASEBOARD_FAB2_LIB.BASEBOARD_FAB2(SCH_1):TP_CPU1_RSVD_114     I9 @BASEBOARD_FAB2_LIB.BASEBOARD_FAB2(SCH_1):PAGE70
   CB5 TP_CPU1_RSVD_113 @BASEBOARD_FAB2_LIB.BASEBOARD_FAB2(SCH_1):TP_CPU1_RSVD_113     I9 @BASEBOARD_FAB2_LIB.BASEBOARD_FAB2(SCH_1):PAGE70
  CC20 PVCCMCP_CPU1 @BASEBOARD_FAB2_LIB.BASEBOARD_FAB2(SCH_1):PVCCMCP_CPU1     I9 @BASEBOARD_FAB2_LIB.BASEBOARD_FAB2(SCH_1):PAGE70
   CC6 TP_CPU1_RSVD_111 @BASEBOARD_FAB2_LIB.BASEBOARD_FAB2(SCH_1):TP_CPU1_RSVD_111     I9 @BASEBOARD_FAB2_LIB.BASEBOARD_FAB2(SCH_1):PAGE70
  CD19 PVCCMCP_CPU1 @BASEBOARD_FAB2_LIB.BASEBOARD_FAB2(SCH_1):PVCCMCP_CPU1     I9 @BASEBOARD_FAB2_LIB.BASEBOARD_FAB2(SCH_1):PAGE70
  CD21 PVCCMCP_CPU1 @BASEBOARD_FAB2_LIB.BASEBOARD_FAB2(SCH_1):PVCCMCP_CPU1     I9 @BASEBOARD_FAB2_LIB.BASEBOARD_FAB2(SCH_1):PAGE70
  CD25 TP_CPU1_RSVD_108 @BASEBOARD_FAB2_LIB.BASEBOARD_FAB2(SCH_1):TP_CPU1_RSVD_108     I9 @BASEBOARD_FAB2_LIB.BASEBOARD_FAB2(SCH_1):PAGE70
  CE22 PVCCMCP_CPU1 @BASEBOARD_FAB2_LIB.BASEBOARD_FAB2(SCH_1):PVCCMCP_CPU1     I9 @BASEBOARD_FAB2_LIB.BASEBOARD_FAB2(SCH_1):PAGE70
  CE78 TP_CPU1_RSVD_106 @BASEBOARD_FAB2_LIB.BASEBOARD_FAB2(SCH_1):TP_CPU1_RSVD_106     I9 @BASEBOARD_FAB2_LIB.BASEBOARD_FAB2(SCH_1):PAGE70
  CE80 TP_CPU1_RSVD_105 @BASEBOARD_FAB2_LIB.BASEBOARD_FAB2(SCH_1):TP_CPU1_RSVD_105     I9 @BASEBOARD_FAB2_LIB.BASEBOARD_FAB2(SCH_1):PAGE70
  CF19 PVCCMCP_CPU1 @BASEBOARD_FAB2_LIB.BASEBOARD_FAB2(SCH_1):PVCCMCP_CPU1     I9 @BASEBOARD_FAB2_LIB.BASEBOARD_FAB2(SCH_1):PAGE70
  CF21 PVCCMCP_CPU1 @BASEBOARD_FAB2_LIB.BASEBOARD_FAB2(SCH_1):PVCCMCP_CPU1     I9 @BASEBOARD_FAB2_LIB.BASEBOARD_FAB2(SCH_1):PAGE70
  CF23 PVCCMCP_CPU1 @BASEBOARD_FAB2_LIB.BASEBOARD_FAB2(SCH_1):PVCCMCP_CPU1     I9 @BASEBOARD_FAB2_LIB.BASEBOARD_FAB2(SCH_1):PAGE70
  CF79 TP_CPU1_RSVD_101 @BASEBOARD_FAB2_LIB.BASEBOARD_FAB2(SCH_1):TP_CPU1_RSVD_101     I9 @BASEBOARD_FAB2_LIB.BASEBOARD_FAB2(SCH_1):PAGE70
  CF81 TP_CPU1_RSVD_100 @BASEBOARD_FAB2_LIB.BASEBOARD_FAB2(SCH_1):TP_CPU1_RSVD_100     I9 @BASEBOARD_FAB2_LIB.BASEBOARD_FAB2(SCH_1):PAGE70
  CG10 TP_CPU1_RSVD_99 @BASEBOARD_FAB2_LIB.BASEBOARD_FAB2(SCH_1):TP_CPU1_RSVD_99     I9 @BASEBOARD_FAB2_LIB.BASEBOARD_FAB2(SCH_1):PAGE70
  CG20 PVCCMCP_CPU1 @BASEBOARD_FAB2_LIB.BASEBOARD_FAB2(SCH_1):PVCCMCP_CPU1     I9 @BASEBOARD_FAB2_LIB.BASEBOARD_FAB2(SCH_1):PAGE70
  CG24 TP_CPU1_RSVD_97 @BASEBOARD_FAB2_LIB.BASEBOARD_FAB2(SCH_1):TP_CPU1_RSVD_97     I9 @BASEBOARD_FAB2_LIB.BASEBOARD_FAB2(SCH_1):PAGE70
  CG26 PVCCMCP_CPU1 @BASEBOARD_FAB2_LIB.BASEBOARD_FAB2(SCH_1):PVCCMCP_CPU1     I9 @BASEBOARD_FAB2_LIB.BASEBOARD_FAB2(SCH_1):PAGE70
  CG78 TP_CPU1_RSVD_95 @BASEBOARD_FAB2_LIB.BASEBOARD_FAB2(SCH_1):TP_CPU1_RSVD_95     I9 @BASEBOARD_FAB2_LIB.BASEBOARD_FAB2(SCH_1):PAGE70
  CG82 TP_CPU1_RSVD_94 @BASEBOARD_FAB2_LIB.BASEBOARD_FAB2(SCH_1):TP_CPU1_RSVD_94     I9 @BASEBOARD_FAB2_LIB.BASEBOARD_FAB2(SCH_1):PAGE70
  CH21 PVCCMCP_CPU1 @BASEBOARD_FAB2_LIB.BASEBOARD_FAB2(SCH_1):PVCCMCP_CPU1     I9 @BASEBOARD_FAB2_LIB.BASEBOARD_FAB2(SCH_1):PAGE70
  CH23 PVCCMCP_CPU1 @BASEBOARD_FAB2_LIB.BASEBOARD_FAB2(SCH_1):PVCCMCP_CPU1     I9 @BASEBOARD_FAB2_LIB.BASEBOARD_FAB2(SCH_1):PAGE70
  CH25 TP_CPU1_RSVD_91 @BASEBOARD_FAB2_LIB.BASEBOARD_FAB2(SCH_1):TP_CPU1_RSVD_91    I10 @BASEBOARD_FAB2_LIB.BASEBOARD_FAB2(SCH_1):PAGE70
  CH77 TP_CPU1_RSVD_90 @BASEBOARD_FAB2_LIB.BASEBOARD_FAB2(SCH_1):TP_CPU1_RSVD_90    I10 @BASEBOARD_FAB2_LIB.BASEBOARD_FAB2(SCH_1):PAGE70
  CJ20 PVCCMCP_CPU1 @BASEBOARD_FAB2_LIB.BASEBOARD_FAB2(SCH_1):PVCCMCP_CPU1    I10 @BASEBOARD_FAB2_LIB.BASEBOARD_FAB2(SCH_1):PAGE70
  CJ22 PVCCMCP_CPU1 @BASEBOARD_FAB2_LIB.BASEBOARD_FAB2(SCH_1):PVCCMCP_CPU1    I10 @BASEBOARD_FAB2_LIB.BASEBOARD_FAB2(SCH_1):PAGE70
  CJ24 PVCCMCP_CPU1 @BASEBOARD_FAB2_LIB.BASEBOARD_FAB2(SCH_1):PVCCMCP_CPU1    I10 @BASEBOARD_FAB2_LIB.BASEBOARD_FAB2(SCH_1):PAGE70
  CJ26 PVCCMCP_CPU1 @BASEBOARD_FAB2_LIB.BASEBOARD_FAB2(SCH_1):PVCCMCP_CPU1    I10 @BASEBOARD_FAB2_LIB.BASEBOARD_FAB2(SCH_1):PAGE70
  CK19 TP_CPU1_RSVD_85 @BASEBOARD_FAB2_LIB.BASEBOARD_FAB2(SCH_1):TP_CPU1_RSVD_85    I10 @BASEBOARD_FAB2_LIB.BASEBOARD_FAB2(SCH_1):PAGE70
  CK23 PVCCMCP_CPU1 @BASEBOARD_FAB2_LIB.BASEBOARD_FAB2(SCH_1):PVCCMCP_CPU1    I10 @BASEBOARD_FAB2_LIB.BASEBOARD_FAB2(SCH_1):PAGE70
  CK25 PVCCMCP_CPU1 @BASEBOARD_FAB2_LIB.BASEBOARD_FAB2(SCH_1):PVCCMCP_CPU1    I10 @BASEBOARD_FAB2_LIB.BASEBOARD_FAB2(SCH_1):PAGE70
  CK77 TP_CPU1_RSVD_82 @BASEBOARD_FAB2_LIB.BASEBOARD_FAB2(SCH_1):TP_CPU1_RSVD_82    I10 @BASEBOARD_FAB2_LIB.BASEBOARD_FAB2(SCH_1):PAGE70
  CL24 PVCCMCP_CPU1 @BASEBOARD_FAB2_LIB.BASEBOARD_FAB2(SCH_1):PVCCMCP_CPU1    I10 @BASEBOARD_FAB2_LIB.BASEBOARD_FAB2(SCH_1):PAGE70
  AW22 TP_CPU1_TEST_10 @BASEBOARD_FAB2_LIB.BASEBOARD_FAB2(SCH_1):TP_CPU1_TEST_10    I10 @BASEBOARD_FAB2_LIB.BASEBOARD_FAB2(SCH_1):PAGE70
  AR16 TP_CPU1_TEST_6 @BASEBOARD_FAB2_LIB.BASEBOARD_FAB2(SCH_1):TP_CPU1_TEST_6    I10 @BASEBOARD_FAB2_LIB.BASEBOARD_FAB2(SCH_1):PAGE70
  AU18 TP_CPU1_TEST_7 @BASEBOARD_FAB2_LIB.BASEBOARD_FAB2(SCH_1):TP_CPU1_TEST_7    I10 @BASEBOARD_FAB2_LIB.BASEBOARD_FAB2(SCH_1):PAGE70
  AW16 TP_CPU1_TEST_8 @BASEBOARD_FAB2_LIB.BASEBOARD_FAB2(SCH_1):TP_CPU1_TEST_8    I10 @BASEBOARD_FAB2_LIB.BASEBOARD_FAB2(SCH_1):PAGE70
  AW20 TP_CPU1_TEST_9 @BASEBOARD_FAB2_LIB.BASEBOARD_FAB2(SCH_1):TP_CPU1_TEST_9    I10 @BASEBOARD_FAB2_LIB.BASEBOARD_FAB2(SCH_1):PAGE70
  AF43 PVCCIN_CPU1 @BASEBOARD_FAB2_LIB.BASEBOARD_FAB2(SCH_1):PVCCIN_CPU1    I50 @BASEBOARD_FAB2_LIB.BASEBOARD_FAB2(SCH_1):PAGE71
  AG38 PVCCIN_CPU1 @BASEBOARD_FAB2_LIB.BASEBOARD_FAB2(SCH_1):PVCCIN_CPU1    I50 @BASEBOARD_FAB2_LIB.BASEBOARD_FAB2(SCH_1):PAGE71
  AG40 PVCCIN_CPU1 @BASEBOARD_FAB2_LIB.BASEBOARD_FAB2(SCH_1):PVCCIN_CPU1    I50 @BASEBOARD_FAB2_LIB.BASEBOARD_FAB2(SCH_1):PAGE71
  AG42 PVCCIN_CPU1 @BASEBOARD_FAB2_LIB.BASEBOARD_FAB2(SCH_1):PVCCIN_CPU1    I50 @BASEBOARD_FAB2_LIB.BASEBOARD_FAB2(SCH_1):PAGE71
  AH37 PVCCIN_CPU1 @BASEBOARD_FAB2_LIB.BASEBOARD_FAB2(SCH_1):PVCCIN_CPU1    I50 @BASEBOARD_FAB2_LIB.BASEBOARD_FAB2(SCH_1):PAGE71
  AH39 PVCCIN_CPU1 @BASEBOARD_FAB2_LIB.BASEBOARD_FAB2(SCH_1):PVCCIN_CPU1    I50 @BASEBOARD_FAB2_LIB.BASEBOARD_FAB2(SCH_1):PAGE71
  AH41 PVCCIN_CPU1 @BASEBOARD_FAB2_LIB.BASEBOARD_FAB2(SCH_1):PVCCIN_CPU1    I50 @BASEBOARD_FAB2_LIB.BASEBOARD_FAB2(SCH_1):PAGE71
  AJ36 PVCCIN_CPU1 @BASEBOARD_FAB2_LIB.BASEBOARD_FAB2(SCH_1):PVCCIN_CPU1    I50 @BASEBOARD_FAB2_LIB.BASEBOARD_FAB2(SCH_1):PAGE71
  AK35 PVCCIN_CPU1 @BASEBOARD_FAB2_LIB.BASEBOARD_FAB2(SCH_1):PVCCIN_CPU1    I50 @BASEBOARD_FAB2_LIB.BASEBOARD_FAB2(SCH_1):PAGE71
  AK45 PVCCIN_CPU1 @BASEBOARD_FAB2_LIB.BASEBOARD_FAB2(SCH_1):PVCCIN_CPU1    I50 @BASEBOARD_FAB2_LIB.BASEBOARD_FAB2(SCH_1):PAGE71
  AK47 PVCCIN_CPU1 @BASEBOARD_FAB2_LIB.BASEBOARD_FAB2(SCH_1):PVCCIN_CPU1    I50 @BASEBOARD_FAB2_LIB.BASEBOARD_FAB2(SCH_1):PAGE71
  AK49 PVCCIN_CPU1 @BASEBOARD_FAB2_LIB.BASEBOARD_FAB2(SCH_1):PVCCIN_CPU1    I50 @BASEBOARD_FAB2_LIB.BASEBOARD_FAB2(SCH_1):PAGE71
  AK51 PVCCIN_CPU1 @BASEBOARD_FAB2_LIB.BASEBOARD_FAB2(SCH_1):PVCCIN_CPU1    I50 @BASEBOARD_FAB2_LIB.BASEBOARD_FAB2(SCH_1):PAGE71
  AK53 PVCCIN_CPU1 @BASEBOARD_FAB2_LIB.BASEBOARD_FAB2(SCH_1):PVCCIN_CPU1    I50 @BASEBOARD_FAB2_LIB.BASEBOARD_FAB2(SCH_1):PAGE71
  AL34 PVCCIN_CPU1 @BASEBOARD_FAB2_LIB.BASEBOARD_FAB2(SCH_1):PVCCIN_CPU1    I50 @BASEBOARD_FAB2_LIB.BASEBOARD_FAB2(SCH_1):PAGE71
  AL46 PVCCIN_CPU1 @BASEBOARD_FAB2_LIB.BASEBOARD_FAB2(SCH_1):PVCCIN_CPU1    I50 @BASEBOARD_FAB2_LIB.BASEBOARD_FAB2(SCH_1):PAGE71
  AL48 PVCCIN_CPU1 @BASEBOARD_FAB2_LIB.BASEBOARD_FAB2(SCH_1):PVCCIN_CPU1    I50 @BASEBOARD_FAB2_LIB.BASEBOARD_FAB2(SCH_1):PAGE71
  AL50 PVCCIN_CPU1 @BASEBOARD_FAB2_LIB.BASEBOARD_FAB2(SCH_1):PVCCIN_CPU1    I50 @BASEBOARD_FAB2_LIB.BASEBOARD_FAB2(SCH_1):PAGE71
  AL52 PVCCIN_CPU1 @BASEBOARD_FAB2_LIB.BASEBOARD_FAB2(SCH_1):PVCCIN_CPU1    I50 @BASEBOARD_FAB2_LIB.BASEBOARD_FAB2(SCH_1):PAGE71
  AL54 PVCCIN_CPU1 @BASEBOARD_FAB2_LIB.BASEBOARD_FAB2(SCH_1):PVCCIN_CPU1    I50 @BASEBOARD_FAB2_LIB.BASEBOARD_FAB2(SCH_1):PAGE71
  AM33 PVCCIN_CPU1 @BASEBOARD_FAB2_LIB.BASEBOARD_FAB2(SCH_1):PVCCIN_CPU1    I50 @BASEBOARD_FAB2_LIB.BASEBOARD_FAB2(SCH_1):PAGE71
  AM53 PVCCIN_CPU1 @BASEBOARD_FAB2_LIB.BASEBOARD_FAB2(SCH_1):PVCCIN_CPU1    I50 @BASEBOARD_FAB2_LIB.BASEBOARD_FAB2(SCH_1):PAGE71
  AM55 PVCCIN_CPU1 @BASEBOARD_FAB2_LIB.BASEBOARD_FAB2(SCH_1):PVCCIN_CPU1    I50 @BASEBOARD_FAB2_LIB.BASEBOARD_FAB2(SCH_1):PAGE71
  AN32 PVCCIN_CPU1 @BASEBOARD_FAB2_LIB.BASEBOARD_FAB2(SCH_1):PVCCIN_CPU1    I50 @BASEBOARD_FAB2_LIB.BASEBOARD_FAB2(SCH_1):PAGE71
  AN54 PVCCIN_CPU1 @BASEBOARD_FAB2_LIB.BASEBOARD_FAB2(SCH_1):PVCCIN_CPU1    I50 @BASEBOARD_FAB2_LIB.BASEBOARD_FAB2(SCH_1):PAGE71
  AN56 PVCCIN_CPU1 @BASEBOARD_FAB2_LIB.BASEBOARD_FAB2(SCH_1):PVCCIN_CPU1    I50 @BASEBOARD_FAB2_LIB.BASEBOARD_FAB2(SCH_1):PAGE71
  AP55 PVCCIN_CPU1 @BASEBOARD_FAB2_LIB.BASEBOARD_FAB2(SCH_1):PVCCIN_CPU1    I50 @BASEBOARD_FAB2_LIB.BASEBOARD_FAB2(SCH_1):PAGE71
  AP57 PVCCIN_CPU1 @BASEBOARD_FAB2_LIB.BASEBOARD_FAB2(SCH_1):PVCCIN_CPU1    I50 @BASEBOARD_FAB2_LIB.BASEBOARD_FAB2(SCH_1):PAGE71
  AR56 PVCCIN_CPU1 @BASEBOARD_FAB2_LIB.BASEBOARD_FAB2(SCH_1):PVCCIN_CPU1    I50 @BASEBOARD_FAB2_LIB.BASEBOARD_FAB2(SCH_1):PAGE71
  AR58 PVCCIN_CPU1 @BASEBOARD_FAB2_LIB.BASEBOARD_FAB2(SCH_1):PVCCIN_CPU1    I50 @BASEBOARD_FAB2_LIB.BASEBOARD_FAB2(SCH_1):PAGE71
  AT57 PVCCIN_CPU1 @BASEBOARD_FAB2_LIB.BASEBOARD_FAB2(SCH_1):PVCCIN_CPU1    I50 @BASEBOARD_FAB2_LIB.BASEBOARD_FAB2(SCH_1):PAGE71
  AT59 PVCCIN_CPU1 @BASEBOARD_FAB2_LIB.BASEBOARD_FAB2(SCH_1):PVCCIN_CPU1    I50 @BASEBOARD_FAB2_LIB.BASEBOARD_FAB2(SCH_1):PAGE71
  AU58 PVCCIN_CPU1 @BASEBOARD_FAB2_LIB.BASEBOARD_FAB2(SCH_1):PVCCIN_CPU1    I50 @BASEBOARD_FAB2_LIB.BASEBOARD_FAB2(SCH_1):PAGE71
  AU60 PVCCIN_CPU1 @BASEBOARD_FAB2_LIB.BASEBOARD_FAB2(SCH_1):PVCCIN_CPU1    I50 @BASEBOARD_FAB2_LIB.BASEBOARD_FAB2(SCH_1):PAGE71
  AV59 PVCCIN_CPU1 @BASEBOARD_FAB2_LIB.BASEBOARD_FAB2(SCH_1):PVCCIN_CPU1    I50 @BASEBOARD_FAB2_LIB.BASEBOARD_FAB2(SCH_1):PAGE71
  AV61 PVCCIN_CPU1 @BASEBOARD_FAB2_LIB.BASEBOARD_FAB2(SCH_1):PVCCIN_CPU1    I50 @BASEBOARD_FAB2_LIB.BASEBOARD_FAB2(SCH_1):PAGE71
  AW60 PVCCIN_CPU1 @BASEBOARD_FAB2_LIB.BASEBOARD_FAB2(SCH_1):PVCCIN_CPU1    I50 @BASEBOARD_FAB2_LIB.BASEBOARD_FAB2(SCH_1):PAGE71
  AY61 PVCCIN_CPU1 @BASEBOARD_FAB2_LIB.BASEBOARD_FAB2(SCH_1):PVCCIN_CPU1    I50 @BASEBOARD_FAB2_LIB.BASEBOARD_FAB2(SCH_1):PAGE71
  BA60 PVCCIN_CPU1 @BASEBOARD_FAB2_LIB.BASEBOARD_FAB2(SCH_1):PVCCIN_CPU1    I50 @BASEBOARD_FAB2_LIB.BASEBOARD_FAB2(SCH_1):PAGE71
  BB61 PVCCIN_CPU1 @BASEBOARD_FAB2_LIB.BASEBOARD_FAB2(SCH_1):PVCCIN_CPU1    I50 @BASEBOARD_FAB2_LIB.BASEBOARD_FAB2(SCH_1):PAGE71
  BB85 PVCCIN_CPU1 @BASEBOARD_FAB2_LIB.BASEBOARD_FAB2(SCH_1):PVCCIN_CPU1    I50 @BASEBOARD_FAB2_LIB.BASEBOARD_FAB2(SCH_1):PAGE71
  BC60 PVCCIN_CPU1 @BASEBOARD_FAB2_LIB.BASEBOARD_FAB2(SCH_1):PVCCIN_CPU1    I50 @BASEBOARD_FAB2_LIB.BASEBOARD_FAB2(SCH_1):PAGE71
  BC62 PVCCIN_CPU1 @BASEBOARD_FAB2_LIB.BASEBOARD_FAB2(SCH_1):PVCCIN_CPU1    I50 @BASEBOARD_FAB2_LIB.BASEBOARD_FAB2(SCH_1):PAGE71
  BC84 PVCCIN_CPU1 @BASEBOARD_FAB2_LIB.BASEBOARD_FAB2(SCH_1):PVCCIN_CPU1    I50 @BASEBOARD_FAB2_LIB.BASEBOARD_FAB2(SCH_1):PAGE71
  BD61 PVCCIN_CPU1 @BASEBOARD_FAB2_LIB.BASEBOARD_FAB2(SCH_1):PVCCIN_CPU1    I50 @BASEBOARD_FAB2_LIB.BASEBOARD_FAB2(SCH_1):PAGE71
  BD73 PVCCIN_CPU1 @BASEBOARD_FAB2_LIB.BASEBOARD_FAB2(SCH_1):PVCCIN_CPU1    I50 @BASEBOARD_FAB2_LIB.BASEBOARD_FAB2(SCH_1):PAGE71
  BD75 PVCCIN_CPU1 @BASEBOARD_FAB2_LIB.BASEBOARD_FAB2(SCH_1):PVCCIN_CPU1    I50 @BASEBOARD_FAB2_LIB.BASEBOARD_FAB2(SCH_1):PAGE71
  BD77 PVCCIN_CPU1 @BASEBOARD_FAB2_LIB.BASEBOARD_FAB2(SCH_1):PVCCIN_CPU1    I50 @BASEBOARD_FAB2_LIB.BASEBOARD_FAB2(SCH_1):PAGE71
  BD79 PVCCIN_CPU1 @BASEBOARD_FAB2_LIB.BASEBOARD_FAB2(SCH_1):PVCCIN_CPU1    I50 @BASEBOARD_FAB2_LIB.BASEBOARD_FAB2(SCH_1):PAGE71
  BD81 PVCCIN_CPU1 @BASEBOARD_FAB2_LIB.BASEBOARD_FAB2(SCH_1):PVCCIN_CPU1    I50 @BASEBOARD_FAB2_LIB.BASEBOARD_FAB2(SCH_1):PAGE71
  BD83 PVCCIN_CPU1 @BASEBOARD_FAB2_LIB.BASEBOARD_FAB2(SCH_1):PVCCIN_CPU1    I50 @BASEBOARD_FAB2_LIB.BASEBOARD_FAB2(SCH_1):PAGE71
  BD85 PVCCIN_CPU1 @BASEBOARD_FAB2_LIB.BASEBOARD_FAB2(SCH_1):PVCCIN_CPU1    I50 @BASEBOARD_FAB2_LIB.BASEBOARD_FAB2(SCH_1):PAGE71
  BE60 PVCCIN_CPU1 @BASEBOARD_FAB2_LIB.BASEBOARD_FAB2(SCH_1):PVCCIN_CPU1    I50 @BASEBOARD_FAB2_LIB.BASEBOARD_FAB2(SCH_1):PAGE71
  BE62 PVCCIN_CPU1 @BASEBOARD_FAB2_LIB.BASEBOARD_FAB2(SCH_1):PVCCIN_CPU1    I50 @BASEBOARD_FAB2_LIB.BASEBOARD_FAB2(SCH_1):PAGE71
  BE72 PVCCIN_CPU1 @BASEBOARD_FAB2_LIB.BASEBOARD_FAB2(SCH_1):PVCCIN_CPU1    I50 @BASEBOARD_FAB2_LIB.BASEBOARD_FAB2(SCH_1):PAGE71
  BE74 PVCCIN_CPU1 @BASEBOARD_FAB2_LIB.BASEBOARD_FAB2(SCH_1):PVCCIN_CPU1    I50 @BASEBOARD_FAB2_LIB.BASEBOARD_FAB2(SCH_1):PAGE71
  BE76 PVCCIN_CPU1 @BASEBOARD_FAB2_LIB.BASEBOARD_FAB2(SCH_1):PVCCIN_CPU1    I50 @BASEBOARD_FAB2_LIB.BASEBOARD_FAB2(SCH_1):PAGE71
  BE78 PVCCIN_CPU1 @BASEBOARD_FAB2_LIB.BASEBOARD_FAB2(SCH_1):PVCCIN_CPU1    I50 @BASEBOARD_FAB2_LIB.BASEBOARD_FAB2(SCH_1):PAGE71
  BE80 PVCCIN_CPU1 @BASEBOARD_FAB2_LIB.BASEBOARD_FAB2(SCH_1):PVCCIN_CPU1    I50 @BASEBOARD_FAB2_LIB.BASEBOARD_FAB2(SCH_1):PAGE71
  BE82 PVCCIN_CPU1 @BASEBOARD_FAB2_LIB.BASEBOARD_FAB2(SCH_1):PVCCIN_CPU1    I50 @BASEBOARD_FAB2_LIB.BASEBOARD_FAB2(SCH_1):PAGE71
  BE84 PVCCIN_CPU1 @BASEBOARD_FAB2_LIB.BASEBOARD_FAB2(SCH_1):PVCCIN_CPU1    I50 @BASEBOARD_FAB2_LIB.BASEBOARD_FAB2(SCH_1):PAGE71
  BF61 PVCCIN_CPU1 @BASEBOARD_FAB2_LIB.BASEBOARD_FAB2(SCH_1):PVCCIN_CPU1    I50 @BASEBOARD_FAB2_LIB.BASEBOARD_FAB2(SCH_1):PAGE71
  BF73 PVCCIN_CPU1 @BASEBOARD_FAB2_LIB.BASEBOARD_FAB2(SCH_1):PVCCIN_CPU1    I50 @BASEBOARD_FAB2_LIB.BASEBOARD_FAB2(SCH_1):PAGE71
  BF75 PVCCIN_CPU1 @BASEBOARD_FAB2_LIB.BASEBOARD_FAB2(SCH_1):PVCCIN_CPU1    I50 @BASEBOARD_FAB2_LIB.BASEBOARD_FAB2(SCH_1):PAGE71
  BF77 PVCCIN_CPU1 @BASEBOARD_FAB2_LIB.BASEBOARD_FAB2(SCH_1):PVCCIN_CPU1    I50 @BASEBOARD_FAB2_LIB.BASEBOARD_FAB2(SCH_1):PAGE71
  BF79 PVCCIN_CPU1 @BASEBOARD_FAB2_LIB.BASEBOARD_FAB2(SCH_1):PVCCIN_CPU1    I50 @BASEBOARD_FAB2_LIB.BASEBOARD_FAB2(SCH_1):PAGE71
  BF81 PVCCIN_CPU1 @BASEBOARD_FAB2_LIB.BASEBOARD_FAB2(SCH_1):PVCCIN_CPU1    I50 @BASEBOARD_FAB2_LIB.BASEBOARD_FAB2(SCH_1):PAGE71
  BF83 PVCCIN_CPU1 @BASEBOARD_FAB2_LIB.BASEBOARD_FAB2(SCH_1):PVCCIN_CPU1    I50 @BASEBOARD_FAB2_LIB.BASEBOARD_FAB2(SCH_1):PAGE71
  BF85 PVCCIN_CPU1 @BASEBOARD_FAB2_LIB.BASEBOARD_FAB2(SCH_1):PVCCIN_CPU1    I50 @BASEBOARD_FAB2_LIB.BASEBOARD_FAB2(SCH_1):PAGE71
  BG60 PVCCIN_CPU1 @BASEBOARD_FAB2_LIB.BASEBOARD_FAB2(SCH_1):PVCCIN_CPU1    I50 @BASEBOARD_FAB2_LIB.BASEBOARD_FAB2(SCH_1):PAGE71
  BG62 PVCCIN_CPU1 @BASEBOARD_FAB2_LIB.BASEBOARD_FAB2(SCH_1):PVCCIN_CPU1    I50 @BASEBOARD_FAB2_LIB.BASEBOARD_FAB2(SCH_1):PAGE71
  BG64 PVCCIN_CPU1 @BASEBOARD_FAB2_LIB.BASEBOARD_FAB2(SCH_1):PVCCIN_CPU1    I50 @BASEBOARD_FAB2_LIB.BASEBOARD_FAB2(SCH_1):PAGE71
  BG66 PVCCIN_CPU1 @BASEBOARD_FAB2_LIB.BASEBOARD_FAB2(SCH_1):PVCCIN_CPU1    I50 @BASEBOARD_FAB2_LIB.BASEBOARD_FAB2(SCH_1):PAGE71
  BG68 PVCCIN_CPU1 @BASEBOARD_FAB2_LIB.BASEBOARD_FAB2(SCH_1):PVCCIN_CPU1    I50 @BASEBOARD_FAB2_LIB.BASEBOARD_FAB2(SCH_1):PAGE71
  BG70 PVCCIN_CPU1 @BASEBOARD_FAB2_LIB.BASEBOARD_FAB2(SCH_1):PVCCIN_CPU1    I50 @BASEBOARD_FAB2_LIB.BASEBOARD_FAB2(SCH_1):PAGE71
  BG84 PVCCIN_CPU1 @BASEBOARD_FAB2_LIB.BASEBOARD_FAB2(SCH_1):PVCCIN_CPU1    I50 @BASEBOARD_FAB2_LIB.BASEBOARD_FAB2(SCH_1):PAGE71
  BH61 PVCCIN_CPU1 @BASEBOARD_FAB2_LIB.BASEBOARD_FAB2(SCH_1):PVCCIN_CPU1    I50 @BASEBOARD_FAB2_LIB.BASEBOARD_FAB2(SCH_1):PAGE71
  BH63 PVCCIN_CPU1 @BASEBOARD_FAB2_LIB.BASEBOARD_FAB2(SCH_1):PVCCIN_CPU1    I50 @BASEBOARD_FAB2_LIB.BASEBOARD_FAB2(SCH_1):PAGE71
  BH65 PVCCIN_CPU1 @BASEBOARD_FAB2_LIB.BASEBOARD_FAB2(SCH_1):PVCCIN_CPU1    I50 @BASEBOARD_FAB2_LIB.BASEBOARD_FAB2(SCH_1):PAGE71
  BH67 PVCCIN_CPU1 @BASEBOARD_FAB2_LIB.BASEBOARD_FAB2(SCH_1):PVCCIN_CPU1    I50 @BASEBOARD_FAB2_LIB.BASEBOARD_FAB2(SCH_1):PAGE71
  BH69 PVCCIN_CPU1 @BASEBOARD_FAB2_LIB.BASEBOARD_FAB2(SCH_1):PVCCIN_CPU1    I50 @BASEBOARD_FAB2_LIB.BASEBOARD_FAB2(SCH_1):PAGE71
  BH71 PVCCIN_CPU1 @BASEBOARD_FAB2_LIB.BASEBOARD_FAB2(SCH_1):PVCCIN_CPU1    I50 @BASEBOARD_FAB2_LIB.BASEBOARD_FAB2(SCH_1):PAGE71
  BH73 PVCCIN_CPU1 @BASEBOARD_FAB2_LIB.BASEBOARD_FAB2(SCH_1):PVCCIN_CPU1    I50 @BASEBOARD_FAB2_LIB.BASEBOARD_FAB2(SCH_1):PAGE71
  BH75 PVCCIN_CPU1 @BASEBOARD_FAB2_LIB.BASEBOARD_FAB2(SCH_1):PVCCIN_CPU1    I50 @BASEBOARD_FAB2_LIB.BASEBOARD_FAB2(SCH_1):PAGE71
  BH77 PVCCIN_CPU1 @BASEBOARD_FAB2_LIB.BASEBOARD_FAB2(SCH_1):PVCCIN_CPU1    I50 @BASEBOARD_FAB2_LIB.BASEBOARD_FAB2(SCH_1):PAGE71
  BH79 PVCCIN_CPU1 @BASEBOARD_FAB2_LIB.BASEBOARD_FAB2(SCH_1):PVCCIN_CPU1    I50 @BASEBOARD_FAB2_LIB.BASEBOARD_FAB2(SCH_1):PAGE71
  BH81 PVCCIN_CPU1 @BASEBOARD_FAB2_LIB.BASEBOARD_FAB2(SCH_1):PVCCIN_CPU1    I50 @BASEBOARD_FAB2_LIB.BASEBOARD_FAB2(SCH_1):PAGE71
  BH83 PVCCIN_CPU1 @BASEBOARD_FAB2_LIB.BASEBOARD_FAB2(SCH_1):PVCCIN_CPU1    I50 @BASEBOARD_FAB2_LIB.BASEBOARD_FAB2(SCH_1):PAGE71
  BJ60 PVCCIN_CPU1 @BASEBOARD_FAB2_LIB.BASEBOARD_FAB2(SCH_1):PVCCIN_CPU1    I50 @BASEBOARD_FAB2_LIB.BASEBOARD_FAB2(SCH_1):PAGE71
  BJ62 PVCCIN_CPU1 @BASEBOARD_FAB2_LIB.BASEBOARD_FAB2(SCH_1):PVCCIN_CPU1    I50 @BASEBOARD_FAB2_LIB.BASEBOARD_FAB2(SCH_1):PAGE71
  BJ64 PVCCIN_CPU1 @BASEBOARD_FAB2_LIB.BASEBOARD_FAB2(SCH_1):PVCCIN_CPU1    I50 @BASEBOARD_FAB2_LIB.BASEBOARD_FAB2(SCH_1):PAGE71
  BJ66 PVCCIN_CPU1 @BASEBOARD_FAB2_LIB.BASEBOARD_FAB2(SCH_1):PVCCIN_CPU1    I50 @BASEBOARD_FAB2_LIB.BASEBOARD_FAB2(SCH_1):PAGE71
  BJ68 PVCCIN_CPU1 @BASEBOARD_FAB2_LIB.BASEBOARD_FAB2(SCH_1):PVCCIN_CPU1    I50 @BASEBOARD_FAB2_LIB.BASEBOARD_FAB2(SCH_1):PAGE71
  BJ70 PVCCIN_CPU1 @BASEBOARD_FAB2_LIB.BASEBOARD_FAB2(SCH_1):PVCCIN_CPU1    I50 @BASEBOARD_FAB2_LIB.BASEBOARD_FAB2(SCH_1):PAGE71
  BJ72 PVCCIN_CPU1 @BASEBOARD_FAB2_LIB.BASEBOARD_FAB2(SCH_1):PVCCIN_CPU1    I50 @BASEBOARD_FAB2_LIB.BASEBOARD_FAB2(SCH_1):PAGE71
  BJ74 PVCCIN_CPU1 @BASEBOARD_FAB2_LIB.BASEBOARD_FAB2(SCH_1):PVCCIN_CPU1    I50 @BASEBOARD_FAB2_LIB.BASEBOARD_FAB2(SCH_1):PAGE71
  BJ76 PVCCIN_CPU1 @BASEBOARD_FAB2_LIB.BASEBOARD_FAB2(SCH_1):PVCCIN_CPU1    I50 @BASEBOARD_FAB2_LIB.BASEBOARD_FAB2(SCH_1):PAGE71
  BJ78 PVCCIN_CPU1 @BASEBOARD_FAB2_LIB.BASEBOARD_FAB2(SCH_1):PVCCIN_CPU1    I50 @BASEBOARD_FAB2_LIB.BASEBOARD_FAB2(SCH_1):PAGE71
  BJ80 PVCCIN_CPU1 @BASEBOARD_FAB2_LIB.BASEBOARD_FAB2(SCH_1):PVCCIN_CPU1    I50 @BASEBOARD_FAB2_LIB.BASEBOARD_FAB2(SCH_1):PAGE71
  BJ82 PVCCIN_CPU1 @BASEBOARD_FAB2_LIB.BASEBOARD_FAB2(SCH_1):PVCCIN_CPU1    I50 @BASEBOARD_FAB2_LIB.BASEBOARD_FAB2(SCH_1):PAGE71
  BJ84 PVCCIN_CPU1 @BASEBOARD_FAB2_LIB.BASEBOARD_FAB2(SCH_1):PVCCIN_CPU1    I50 @BASEBOARD_FAB2_LIB.BASEBOARD_FAB2(SCH_1):PAGE71
  BK61 PVCCIN_CPU1 @BASEBOARD_FAB2_LIB.BASEBOARD_FAB2(SCH_1):PVCCIN_CPU1    I50 @BASEBOARD_FAB2_LIB.BASEBOARD_FAB2(SCH_1):PAGE71
  BK63 PVCCIN_CPU1 @BASEBOARD_FAB2_LIB.BASEBOARD_FAB2(SCH_1):PVCCIN_CPU1    I50 @BASEBOARD_FAB2_LIB.BASEBOARD_FAB2(SCH_1):PAGE71
  BK65 PVCCIN_CPU1 @BASEBOARD_FAB2_LIB.BASEBOARD_FAB2(SCH_1):PVCCIN_CPU1    I50 @BASEBOARD_FAB2_LIB.BASEBOARD_FAB2(SCH_1):PAGE71
  BK67 PVCCIN_CPU1 @BASEBOARD_FAB2_LIB.BASEBOARD_FAB2(SCH_1):PVCCIN_CPU1    I50 @BASEBOARD_FAB2_LIB.BASEBOARD_FAB2(SCH_1):PAGE71
  BK69 PVCCIN_CPU1 @BASEBOARD_FAB2_LIB.BASEBOARD_FAB2(SCH_1):PVCCIN_CPU1    I50 @BASEBOARD_FAB2_LIB.BASEBOARD_FAB2(SCH_1):PAGE71
  BK71 PVCCIN_CPU1 @BASEBOARD_FAB2_LIB.BASEBOARD_FAB2(SCH_1):PVCCIN_CPU1    I50 @BASEBOARD_FAB2_LIB.BASEBOARD_FAB2(SCH_1):PAGE71
  BK73 PVCCIN_CPU1 @BASEBOARD_FAB2_LIB.BASEBOARD_FAB2(SCH_1):PVCCIN_CPU1    I50 @BASEBOARD_FAB2_LIB.BASEBOARD_FAB2(SCH_1):PAGE71
  BK75 PVCCIN_CPU1 @BASEBOARD_FAB2_LIB.BASEBOARD_FAB2(SCH_1):PVCCIN_CPU1    I50 @BASEBOARD_FAB2_LIB.BASEBOARD_FAB2(SCH_1):PAGE71
  BK77 PVCCIN_CPU1 @BASEBOARD_FAB2_LIB.BASEBOARD_FAB2(SCH_1):PVCCIN_CPU1    I50 @BASEBOARD_FAB2_LIB.BASEBOARD_FAB2(SCH_1):PAGE71
  BK79 PVCCIN_CPU1 @BASEBOARD_FAB2_LIB.BASEBOARD_FAB2(SCH_1):PVCCIN_CPU1    I50 @BASEBOARD_FAB2_LIB.BASEBOARD_FAB2(SCH_1):PAGE71
  BK81 PVCCIN_CPU1 @BASEBOARD_FAB2_LIB.BASEBOARD_FAB2(SCH_1):PVCCIN_CPU1    I50 @BASEBOARD_FAB2_LIB.BASEBOARD_FAB2(SCH_1):PAGE71
  BK83 PVCCIN_CPU1 @BASEBOARD_FAB2_LIB.BASEBOARD_FAB2(SCH_1):PVCCIN_CPU1    I50 @BASEBOARD_FAB2_LIB.BASEBOARD_FAB2(SCH_1):PAGE71
  BL60 PVCCIN_CPU1 @BASEBOARD_FAB2_LIB.BASEBOARD_FAB2(SCH_1):PVCCIN_CPU1    I50 @BASEBOARD_FAB2_LIB.BASEBOARD_FAB2(SCH_1):PAGE71
  BL62 PVCCIN_CPU1 @BASEBOARD_FAB2_LIB.BASEBOARD_FAB2(SCH_1):PVCCIN_CPU1    I50 @BASEBOARD_FAB2_LIB.BASEBOARD_FAB2(SCH_1):PAGE71
  BL84 PVCCIN_CPU1 @BASEBOARD_FAB2_LIB.BASEBOARD_FAB2(SCH_1):PVCCIN_CPU1    I50 @BASEBOARD_FAB2_LIB.BASEBOARD_FAB2(SCH_1):PAGE71
  BM61 PVCCIN_CPU1 @BASEBOARD_FAB2_LIB.BASEBOARD_FAB2(SCH_1):PVCCIN_CPU1    I50 @BASEBOARD_FAB2_LIB.BASEBOARD_FAB2(SCH_1):PAGE71
  BM63 PVCCIN_CPU1 @BASEBOARD_FAB2_LIB.BASEBOARD_FAB2(SCH_1):PVCCIN_CPU1    I50 @BASEBOARD_FAB2_LIB.BASEBOARD_FAB2(SCH_1):PAGE71
  BM65 PVCCIN_CPU1 @BASEBOARD_FAB2_LIB.BASEBOARD_FAB2(SCH_1):PVCCIN_CPU1    I50 @BASEBOARD_FAB2_LIB.BASEBOARD_FAB2(SCH_1):PAGE71
  BM67 PVCCIN_CPU1 @BASEBOARD_FAB2_LIB.BASEBOARD_FAB2(SCH_1):PVCCIN_CPU1    I50 @BASEBOARD_FAB2_LIB.BASEBOARD_FAB2(SCH_1):PAGE71
  BM69 PVCCIN_CPU1 @BASEBOARD_FAB2_LIB.BASEBOARD_FAB2(SCH_1):PVCCIN_CPU1    I50 @BASEBOARD_FAB2_LIB.BASEBOARD_FAB2(SCH_1):PAGE71
  BM71 PVCCIN_CPU1 @BASEBOARD_FAB2_LIB.BASEBOARD_FAB2(SCH_1):PVCCIN_CPU1    I50 @BASEBOARD_FAB2_LIB.BASEBOARD_FAB2(SCH_1):PAGE71
  BM73 PVCCIN_CPU1 @BASEBOARD_FAB2_LIB.BASEBOARD_FAB2(SCH_1):PVCCIN_CPU1    I50 @BASEBOARD_FAB2_LIB.BASEBOARD_FAB2(SCH_1):PAGE71
  BM75 PVCCIN_CPU1 @BASEBOARD_FAB2_LIB.BASEBOARD_FAB2(SCH_1):PVCCIN_CPU1    I50 @BASEBOARD_FAB2_LIB.BASEBOARD_FAB2(SCH_1):PAGE71
  BM77 PVCCIN_CPU1 @BASEBOARD_FAB2_LIB.BASEBOARD_FAB2(SCH_1):PVCCIN_CPU1    I50 @BASEBOARD_FAB2_LIB.BASEBOARD_FAB2(SCH_1):PAGE71
  BM79 PVCCIN_CPU1 @BASEBOARD_FAB2_LIB.BASEBOARD_FAB2(SCH_1):PVCCIN_CPU1    I50 @BASEBOARD_FAB2_LIB.BASEBOARD_FAB2(SCH_1):PAGE71
  BM81 PVCCIN_CPU1 @BASEBOARD_FAB2_LIB.BASEBOARD_FAB2(SCH_1):PVCCIN_CPU1    I50 @BASEBOARD_FAB2_LIB.BASEBOARD_FAB2(SCH_1):PAGE71
  BM83 PVCCIN_CPU1 @BASEBOARD_FAB2_LIB.BASEBOARD_FAB2(SCH_1):PVCCIN_CPU1    I50 @BASEBOARD_FAB2_LIB.BASEBOARD_FAB2(SCH_1):PAGE71
  BN60 PVCCIN_CPU1 @BASEBOARD_FAB2_LIB.BASEBOARD_FAB2(SCH_1):PVCCIN_CPU1    I50 @BASEBOARD_FAB2_LIB.BASEBOARD_FAB2(SCH_1):PAGE71
  BN62 PVCCIN_CPU1 @BASEBOARD_FAB2_LIB.BASEBOARD_FAB2(SCH_1):PVCCIN_CPU1    I50 @BASEBOARD_FAB2_LIB.BASEBOARD_FAB2(SCH_1):PAGE71
  BN64 PVCCIN_CPU1 @BASEBOARD_FAB2_LIB.BASEBOARD_FAB2(SCH_1):PVCCIN_CPU1    I50 @BASEBOARD_FAB2_LIB.BASEBOARD_FAB2(SCH_1):PAGE71
  BN66 PVCCIN_CPU1 @BASEBOARD_FAB2_LIB.BASEBOARD_FAB2(SCH_1):PVCCIN_CPU1    I50 @BASEBOARD_FAB2_LIB.BASEBOARD_FAB2(SCH_1):PAGE71
  BN68 PVCCIN_CPU1 @BASEBOARD_FAB2_LIB.BASEBOARD_FAB2(SCH_1):PVCCIN_CPU1    I50 @BASEBOARD_FAB2_LIB.BASEBOARD_FAB2(SCH_1):PAGE71
  BN70 PVCCIN_CPU1 @BASEBOARD_FAB2_LIB.BASEBOARD_FAB2(SCH_1):PVCCIN_CPU1    I50 @BASEBOARD_FAB2_LIB.BASEBOARD_FAB2(SCH_1):PAGE71
  BN72 PVCCIN_CPU1 @BASEBOARD_FAB2_LIB.BASEBOARD_FAB2(SCH_1):PVCCIN_CPU1    I50 @BASEBOARD_FAB2_LIB.BASEBOARD_FAB2(SCH_1):PAGE71
  BN74 PVCCIN_CPU1 @BASEBOARD_FAB2_LIB.BASEBOARD_FAB2(SCH_1):PVCCIN_CPU1    I50 @BASEBOARD_FAB2_LIB.BASEBOARD_FAB2(SCH_1):PAGE71
  BN76 PVCCIN_CPU1 @BASEBOARD_FAB2_LIB.BASEBOARD_FAB2(SCH_1):PVCCIN_CPU1    I50 @BASEBOARD_FAB2_LIB.BASEBOARD_FAB2(SCH_1):PAGE71
  BN78 PVCCIN_CPU1 @BASEBOARD_FAB2_LIB.BASEBOARD_FAB2(SCH_1):PVCCIN_CPU1    I50 @BASEBOARD_FAB2_LIB.BASEBOARD_FAB2(SCH_1):PAGE71
  BN80 PVCCIN_CPU1 @BASEBOARD_FAB2_LIB.BASEBOARD_FAB2(SCH_1):PVCCIN_CPU1    I51 @BASEBOARD_FAB2_LIB.BASEBOARD_FAB2(SCH_1):PAGE71
  BN82 PVCCIN_CPU1 @BASEBOARD_FAB2_LIB.BASEBOARD_FAB2(SCH_1):PVCCIN_CPU1    I51 @BASEBOARD_FAB2_LIB.BASEBOARD_FAB2(SCH_1):PAGE71
  BN84 PVCCIN_CPU1 @BASEBOARD_FAB2_LIB.BASEBOARD_FAB2(SCH_1):PVCCIN_CPU1    I51 @BASEBOARD_FAB2_LIB.BASEBOARD_FAB2(SCH_1):PAGE71
  BP61 PVCCIN_CPU1 @BASEBOARD_FAB2_LIB.BASEBOARD_FAB2(SCH_1):PVCCIN_CPU1    I51 @BASEBOARD_FAB2_LIB.BASEBOARD_FAB2(SCH_1):PAGE71
  BP63 PVCCIN_CPU1 @BASEBOARD_FAB2_LIB.BASEBOARD_FAB2(SCH_1):PVCCIN_CPU1    I51 @BASEBOARD_FAB2_LIB.BASEBOARD_FAB2(SCH_1):PAGE71
  BP65 PVCCIN_CPU1 @BASEBOARD_FAB2_LIB.BASEBOARD_FAB2(SCH_1):PVCCIN_CPU1    I51 @BASEBOARD_FAB2_LIB.BASEBOARD_FAB2(SCH_1):PAGE71
  BP67 PVCCIN_CPU1 @BASEBOARD_FAB2_LIB.BASEBOARD_FAB2(SCH_1):PVCCIN_CPU1    I51 @BASEBOARD_FAB2_LIB.BASEBOARD_FAB2(SCH_1):PAGE71
  BP69 PVCCIN_CPU1 @BASEBOARD_FAB2_LIB.BASEBOARD_FAB2(SCH_1):PVCCIN_CPU1    I51 @BASEBOARD_FAB2_LIB.BASEBOARD_FAB2(SCH_1):PAGE71
  BP71 PVCCIN_CPU1 @BASEBOARD_FAB2_LIB.BASEBOARD_FAB2(SCH_1):PVCCIN_CPU1    I51 @BASEBOARD_FAB2_LIB.BASEBOARD_FAB2(SCH_1):PAGE71
  BP73 PVCCIN_CPU1 @BASEBOARD_FAB2_LIB.BASEBOARD_FAB2(SCH_1):PVCCIN_CPU1    I51 @BASEBOARD_FAB2_LIB.BASEBOARD_FAB2(SCH_1):PAGE71
  BP75 PVCCIN_CPU1 @BASEBOARD_FAB2_LIB.BASEBOARD_FAB2(SCH_1):PVCCIN_CPU1    I51 @BASEBOARD_FAB2_LIB.BASEBOARD_FAB2(SCH_1):PAGE71
  BP77 PVCCIN_CPU1 @BASEBOARD_FAB2_LIB.BASEBOARD_FAB2(SCH_1):PVCCIN_CPU1    I51 @BASEBOARD_FAB2_LIB.BASEBOARD_FAB2(SCH_1):PAGE71
  BP79 PVCCIN_CPU1 @BASEBOARD_FAB2_LIB.BASEBOARD_FAB2(SCH_1):PVCCIN_CPU1    I51 @BASEBOARD_FAB2_LIB.BASEBOARD_FAB2(SCH_1):PAGE71
  BP81 PVCCIN_CPU1 @BASEBOARD_FAB2_LIB.BASEBOARD_FAB2(SCH_1):PVCCIN_CPU1    I51 @BASEBOARD_FAB2_LIB.BASEBOARD_FAB2(SCH_1):PAGE71
  BP83 PVCCIN_CPU1 @BASEBOARD_FAB2_LIB.BASEBOARD_FAB2(SCH_1):PVCCIN_CPU1    I51 @BASEBOARD_FAB2_LIB.BASEBOARD_FAB2(SCH_1):PAGE71
  BR60 PVCCIN_CPU1 @BASEBOARD_FAB2_LIB.BASEBOARD_FAB2(SCH_1):PVCCIN_CPU1    I51 @BASEBOARD_FAB2_LIB.BASEBOARD_FAB2(SCH_1):PAGE71
  BR62 PVCCIN_CPU1 @BASEBOARD_FAB2_LIB.BASEBOARD_FAB2(SCH_1):PVCCIN_CPU1    I51 @BASEBOARD_FAB2_LIB.BASEBOARD_FAB2(SCH_1):PAGE71
  BR84 PVCCIN_CPU1 @BASEBOARD_FAB2_LIB.BASEBOARD_FAB2(SCH_1):PVCCIN_CPU1    I51 @BASEBOARD_FAB2_LIB.BASEBOARD_FAB2(SCH_1):PAGE71
  BT61 PVCCIN_CPU1 @BASEBOARD_FAB2_LIB.BASEBOARD_FAB2(SCH_1):PVCCIN_CPU1    I51 @BASEBOARD_FAB2_LIB.BASEBOARD_FAB2(SCH_1):PAGE71
  BT63 PVCCIN_CPU1 @BASEBOARD_FAB2_LIB.BASEBOARD_FAB2(SCH_1):PVCCIN_CPU1    I51 @BASEBOARD_FAB2_LIB.BASEBOARD_FAB2(SCH_1):PAGE71
  BT65 PVCCIN_CPU1 @BASEBOARD_FAB2_LIB.BASEBOARD_FAB2(SCH_1):PVCCIN_CPU1    I51 @BASEBOARD_FAB2_LIB.BASEBOARD_FAB2(SCH_1):PAGE71
  BT67 PVCCIN_CPU1 @BASEBOARD_FAB2_LIB.BASEBOARD_FAB2(SCH_1):PVCCIN_CPU1    I51 @BASEBOARD_FAB2_LIB.BASEBOARD_FAB2(SCH_1):PAGE71
  BT69 PVCCIN_CPU1 @BASEBOARD_FAB2_LIB.BASEBOARD_FAB2(SCH_1):PVCCIN_CPU1    I51 @BASEBOARD_FAB2_LIB.BASEBOARD_FAB2(SCH_1):PAGE71
  BT71 PVCCIN_CPU1 @BASEBOARD_FAB2_LIB.BASEBOARD_FAB2(SCH_1):PVCCIN_CPU1    I51 @BASEBOARD_FAB2_LIB.BASEBOARD_FAB2(SCH_1):PAGE71
  BT73 PVCCIN_CPU1 @BASEBOARD_FAB2_LIB.BASEBOARD_FAB2(SCH_1):PVCCIN_CPU1    I51 @BASEBOARD_FAB2_LIB.BASEBOARD_FAB2(SCH_1):PAGE71
  BT75 PVCCIN_CPU1 @BASEBOARD_FAB2_LIB.BASEBOARD_FAB2(SCH_1):PVCCIN_CPU1    I51 @BASEBOARD_FAB2_LIB.BASEBOARD_FAB2(SCH_1):PAGE71
  BT77 PVCCIN_CPU1 @BASEBOARD_FAB2_LIB.BASEBOARD_FAB2(SCH_1):PVCCIN_CPU1    I51 @BASEBOARD_FAB2_LIB.BASEBOARD_FAB2(SCH_1):PAGE71
  BT79 PVCCIN_CPU1 @BASEBOARD_FAB2_LIB.BASEBOARD_FAB2(SCH_1):PVCCIN_CPU1    I51 @BASEBOARD_FAB2_LIB.BASEBOARD_FAB2(SCH_1):PAGE71
  BT81 PVCCIN_CPU1 @BASEBOARD_FAB2_LIB.BASEBOARD_FAB2(SCH_1):PVCCIN_CPU1    I51 @BASEBOARD_FAB2_LIB.BASEBOARD_FAB2(SCH_1):PAGE71
  BT83 PVCCIN_CPU1 @BASEBOARD_FAB2_LIB.BASEBOARD_FAB2(SCH_1):PVCCIN_CPU1    I51 @BASEBOARD_FAB2_LIB.BASEBOARD_FAB2(SCH_1):PAGE71
  BU60 PVCCIN_CPU1 @BASEBOARD_FAB2_LIB.BASEBOARD_FAB2(SCH_1):PVCCIN_CPU1    I51 @BASEBOARD_FAB2_LIB.BASEBOARD_FAB2(SCH_1):PAGE71
  BU62 PVCCIN_CPU1 @BASEBOARD_FAB2_LIB.BASEBOARD_FAB2(SCH_1):PVCCIN_CPU1    I51 @BASEBOARD_FAB2_LIB.BASEBOARD_FAB2(SCH_1):PAGE71
  BU64 PVCCIN_CPU1 @BASEBOARD_FAB2_LIB.BASEBOARD_FAB2(SCH_1):PVCCIN_CPU1    I51 @BASEBOARD_FAB2_LIB.BASEBOARD_FAB2(SCH_1):PAGE71
  BU66 PVCCIN_CPU1 @BASEBOARD_FAB2_LIB.BASEBOARD_FAB2(SCH_1):PVCCIN_CPU1    I51 @BASEBOARD_FAB2_LIB.BASEBOARD_FAB2(SCH_1):PAGE71
  BU68 PVCCIN_CPU1 @BASEBOARD_FAB2_LIB.BASEBOARD_FAB2(SCH_1):PVCCIN_CPU1    I51 @BASEBOARD_FAB2_LIB.BASEBOARD_FAB2(SCH_1):PAGE71
  BU70 PVCCIN_CPU1 @BASEBOARD_FAB2_LIB.BASEBOARD_FAB2(SCH_1):PVCCIN_CPU1    I51 @BASEBOARD_FAB2_LIB.BASEBOARD_FAB2(SCH_1):PAGE71
  BU72 PVCCIN_CPU1 @BASEBOARD_FAB2_LIB.BASEBOARD_FAB2(SCH_1):PVCCIN_CPU1    I51 @BASEBOARD_FAB2_LIB.BASEBOARD_FAB2(SCH_1):PAGE71
  BU74 PVCCIN_CPU1 @BASEBOARD_FAB2_LIB.BASEBOARD_FAB2(SCH_1):PVCCIN_CPU1    I51 @BASEBOARD_FAB2_LIB.BASEBOARD_FAB2(SCH_1):PAGE71
  BU76 PVCCIN_CPU1 @BASEBOARD_FAB2_LIB.BASEBOARD_FAB2(SCH_1):PVCCIN_CPU1    I51 @BASEBOARD_FAB2_LIB.BASEBOARD_FAB2(SCH_1):PAGE71
  BU78 PVCCIN_CPU1 @BASEBOARD_FAB2_LIB.BASEBOARD_FAB2(SCH_1):PVCCIN_CPU1    I51 @BASEBOARD_FAB2_LIB.BASEBOARD_FAB2(SCH_1):PAGE71
  BU80 PVCCIN_CPU1 @BASEBOARD_FAB2_LIB.BASEBOARD_FAB2(SCH_1):PVCCIN_CPU1    I51 @BASEBOARD_FAB2_LIB.BASEBOARD_FAB2(SCH_1):PAGE71
  BU82 PVCCIN_CPU1 @BASEBOARD_FAB2_LIB.BASEBOARD_FAB2(SCH_1):PVCCIN_CPU1    I51 @BASEBOARD_FAB2_LIB.BASEBOARD_FAB2(SCH_1):PAGE71
  BU84 PVCCIN_CPU1 @BASEBOARD_FAB2_LIB.BASEBOARD_FAB2(SCH_1):PVCCIN_CPU1    I51 @BASEBOARD_FAB2_LIB.BASEBOARD_FAB2(SCH_1):PAGE71
  BV61 PVCCIN_CPU1 @BASEBOARD_FAB2_LIB.BASEBOARD_FAB2(SCH_1):PVCCIN_CPU1    I51 @BASEBOARD_FAB2_LIB.BASEBOARD_FAB2(SCH_1):PAGE71
  BV63 PVCCIN_CPU1 @BASEBOARD_FAB2_LIB.BASEBOARD_FAB2(SCH_1):PVCCIN_CPU1    I51 @BASEBOARD_FAB2_LIB.BASEBOARD_FAB2(SCH_1):PAGE71
  BV65 PVCCIN_CPU1 @BASEBOARD_FAB2_LIB.BASEBOARD_FAB2(SCH_1):PVCCIN_CPU1    I51 @BASEBOARD_FAB2_LIB.BASEBOARD_FAB2(SCH_1):PAGE71
  BV67 PVCCIN_CPU1 @BASEBOARD_FAB2_LIB.BASEBOARD_FAB2(SCH_1):PVCCIN_CPU1    I51 @BASEBOARD_FAB2_LIB.BASEBOARD_FAB2(SCH_1):PAGE71
  BV69 PVCCIN_CPU1 @BASEBOARD_FAB2_LIB.BASEBOARD_FAB2(SCH_1):PVCCIN_CPU1    I51 @BASEBOARD_FAB2_LIB.BASEBOARD_FAB2(SCH_1):PAGE71
  BV71 PVCCIN_CPU1 @BASEBOARD_FAB2_LIB.BASEBOARD_FAB2(SCH_1):PVCCIN_CPU1    I51 @BASEBOARD_FAB2_LIB.BASEBOARD_FAB2(SCH_1):PAGE71
  BV73 PVCCIN_CPU1 @BASEBOARD_FAB2_LIB.BASEBOARD_FAB2(SCH_1):PVCCIN_CPU1    I51 @BASEBOARD_FAB2_LIB.BASEBOARD_FAB2(SCH_1):PAGE71
  BV75 PVCCIN_CPU1 @BASEBOARD_FAB2_LIB.BASEBOARD_FAB2(SCH_1):PVCCIN_CPU1    I51 @BASEBOARD_FAB2_LIB.BASEBOARD_FAB2(SCH_1):PAGE71
  BV77 PVCCIN_CPU1 @BASEBOARD_FAB2_LIB.BASEBOARD_FAB2(SCH_1):PVCCIN_CPU1    I51 @BASEBOARD_FAB2_LIB.BASEBOARD_FAB2(SCH_1):PAGE71
  BV79 PVCCIN_CPU1 @BASEBOARD_FAB2_LIB.BASEBOARD_FAB2(SCH_1):PVCCIN_CPU1    I51 @BASEBOARD_FAB2_LIB.BASEBOARD_FAB2(SCH_1):PAGE71
  BV81 PVCCIN_CPU1 @BASEBOARD_FAB2_LIB.BASEBOARD_FAB2(SCH_1):PVCCIN_CPU1    I51 @BASEBOARD_FAB2_LIB.BASEBOARD_FAB2(SCH_1):PAGE71
  BV83 PVCCIN_CPU1 @BASEBOARD_FAB2_LIB.BASEBOARD_FAB2(SCH_1):PVCCIN_CPU1    I51 @BASEBOARD_FAB2_LIB.BASEBOARD_FAB2(SCH_1):PAGE71
  BW60 PVCCIN_CPU1 @BASEBOARD_FAB2_LIB.BASEBOARD_FAB2(SCH_1):PVCCIN_CPU1    I51 @BASEBOARD_FAB2_LIB.BASEBOARD_FAB2(SCH_1):PAGE71
  BW62 PVCCIN_CPU1 @BASEBOARD_FAB2_LIB.BASEBOARD_FAB2(SCH_1):PVCCIN_CPU1    I51 @BASEBOARD_FAB2_LIB.BASEBOARD_FAB2(SCH_1):PAGE71
  BW64 PVCCIN_CPU1 @BASEBOARD_FAB2_LIB.BASEBOARD_FAB2(SCH_1):PVCCIN_CPU1    I51 @BASEBOARD_FAB2_LIB.BASEBOARD_FAB2(SCH_1):PAGE71
  BW66 PVCCIN_CPU1 @BASEBOARD_FAB2_LIB.BASEBOARD_FAB2(SCH_1):PVCCIN_CPU1    I51 @BASEBOARD_FAB2_LIB.BASEBOARD_FAB2(SCH_1):PAGE71
  BW68 PVCCIN_CPU1 @BASEBOARD_FAB2_LIB.BASEBOARD_FAB2(SCH_1):PVCCIN_CPU1    I51 @BASEBOARD_FAB2_LIB.BASEBOARD_FAB2(SCH_1):PAGE71
  BW70 PVCCIN_CPU1 @BASEBOARD_FAB2_LIB.BASEBOARD_FAB2(SCH_1):PVCCIN_CPU1    I51 @BASEBOARD_FAB2_LIB.BASEBOARD_FAB2(SCH_1):PAGE71
  BW84 PVCCIN_CPU1 @BASEBOARD_FAB2_LIB.BASEBOARD_FAB2(SCH_1):PVCCIN_CPU1    I51 @BASEBOARD_FAB2_LIB.BASEBOARD_FAB2(SCH_1):PAGE71
  BY61 PVCCIN_CPU1 @BASEBOARD_FAB2_LIB.BASEBOARD_FAB2(SCH_1):PVCCIN_CPU1    I51 @BASEBOARD_FAB2_LIB.BASEBOARD_FAB2(SCH_1):PAGE71
  BY73 PVCCIN_CPU1 @BASEBOARD_FAB2_LIB.BASEBOARD_FAB2(SCH_1):PVCCIN_CPU1    I51 @BASEBOARD_FAB2_LIB.BASEBOARD_FAB2(SCH_1):PAGE71
  BY75 PVCCIN_CPU1 @BASEBOARD_FAB2_LIB.BASEBOARD_FAB2(SCH_1):PVCCIN_CPU1    I51 @BASEBOARD_FAB2_LIB.BASEBOARD_FAB2(SCH_1):PAGE71
  BY77 PVCCIN_CPU1 @BASEBOARD_FAB2_LIB.BASEBOARD_FAB2(SCH_1):PVCCIN_CPU1    I51 @BASEBOARD_FAB2_LIB.BASEBOARD_FAB2(SCH_1):PAGE71
  BY79 PVCCIN_CPU1 @BASEBOARD_FAB2_LIB.BASEBOARD_FAB2(SCH_1):PVCCIN_CPU1    I51 @BASEBOARD_FAB2_LIB.BASEBOARD_FAB2(SCH_1):PAGE71
  BY81 PVCCIN_CPU1 @BASEBOARD_FAB2_LIB.BASEBOARD_FAB2(SCH_1):PVCCIN_CPU1    I51 @BASEBOARD_FAB2_LIB.BASEBOARD_FAB2(SCH_1):PAGE71
  BY83 PVCCIN_CPU1 @BASEBOARD_FAB2_LIB.BASEBOARD_FAB2(SCH_1):PVCCIN_CPU1    I51 @BASEBOARD_FAB2_LIB.BASEBOARD_FAB2(SCH_1):PAGE71
  CA60 PVCCIN_CPU1 @BASEBOARD_FAB2_LIB.BASEBOARD_FAB2(SCH_1):PVCCIN_CPU1    I51 @BASEBOARD_FAB2_LIB.BASEBOARD_FAB2(SCH_1):PAGE71
  CA62 PVCCIN_CPU1 @BASEBOARD_FAB2_LIB.BASEBOARD_FAB2(SCH_1):PVCCIN_CPU1    I51 @BASEBOARD_FAB2_LIB.BASEBOARD_FAB2(SCH_1):PAGE71
  CA72 PVCCIN_CPU1 @BASEBOARD_FAB2_LIB.BASEBOARD_FAB2(SCH_1):PVCCIN_CPU1    I51 @BASEBOARD_FAB2_LIB.BASEBOARD_FAB2(SCH_1):PAGE71
  CA74 PVCCIN_CPU1 @BASEBOARD_FAB2_LIB.BASEBOARD_FAB2(SCH_1):PVCCIN_CPU1    I51 @BASEBOARD_FAB2_LIB.BASEBOARD_FAB2(SCH_1):PAGE71
  CA76 PVCCIN_CPU1 @BASEBOARD_FAB2_LIB.BASEBOARD_FAB2(SCH_1):PVCCIN_CPU1    I51 @BASEBOARD_FAB2_LIB.BASEBOARD_FAB2(SCH_1):PAGE71
  CA78 PVCCIN_CPU1 @BASEBOARD_FAB2_LIB.BASEBOARD_FAB2(SCH_1):PVCCIN_CPU1    I51 @BASEBOARD_FAB2_LIB.BASEBOARD_FAB2(SCH_1):PAGE71
  CA80 PVCCIN_CPU1 @BASEBOARD_FAB2_LIB.BASEBOARD_FAB2(SCH_1):PVCCIN_CPU1    I51 @BASEBOARD_FAB2_LIB.BASEBOARD_FAB2(SCH_1):PAGE71
  CA82 PVCCIN_CPU1 @BASEBOARD_FAB2_LIB.BASEBOARD_FAB2(SCH_1):PVCCIN_CPU1    I51 @BASEBOARD_FAB2_LIB.BASEBOARD_FAB2(SCH_1):PAGE71
  CA84 PVCCIN_CPU1 @BASEBOARD_FAB2_LIB.BASEBOARD_FAB2(SCH_1):PVCCIN_CPU1    I51 @BASEBOARD_FAB2_LIB.BASEBOARD_FAB2(SCH_1):PAGE71
  CB61 PVCCIN_CPU1 @BASEBOARD_FAB2_LIB.BASEBOARD_FAB2(SCH_1):PVCCIN_CPU1    I51 @BASEBOARD_FAB2_LIB.BASEBOARD_FAB2(SCH_1):PAGE71
  CB73 PVCCIN_CPU1 @BASEBOARD_FAB2_LIB.BASEBOARD_FAB2(SCH_1):PVCCIN_CPU1    I51 @BASEBOARD_FAB2_LIB.BASEBOARD_FAB2(SCH_1):PAGE71
  CB75 PVCCIN_CPU1 @BASEBOARD_FAB2_LIB.BASEBOARD_FAB2(SCH_1):PVCCIN_CPU1    I51 @BASEBOARD_FAB2_LIB.BASEBOARD_FAB2(SCH_1):PAGE71
  CB77 PVCCIN_CPU1 @BASEBOARD_FAB2_LIB.BASEBOARD_FAB2(SCH_1):PVCCIN_CPU1    I51 @BASEBOARD_FAB2_LIB.BASEBOARD_FAB2(SCH_1):PAGE71
  CB79 PVCCIN_CPU1 @BASEBOARD_FAB2_LIB.BASEBOARD_FAB2(SCH_1):PVCCIN_CPU1    I51 @BASEBOARD_FAB2_LIB.BASEBOARD_FAB2(SCH_1):PAGE71
  CB81 PVCCIN_CPU1 @BASEBOARD_FAB2_LIB.BASEBOARD_FAB2(SCH_1):PVCCIN_CPU1    I51 @BASEBOARD_FAB2_LIB.BASEBOARD_FAB2(SCH_1):PAGE71
  CB83 PVCCIN_CPU1 @BASEBOARD_FAB2_LIB.BASEBOARD_FAB2(SCH_1):PVCCIN_CPU1    I51 @BASEBOARD_FAB2_LIB.BASEBOARD_FAB2(SCH_1):PAGE71
  CC60 PVCCIN_CPU1 @BASEBOARD_FAB2_LIB.BASEBOARD_FAB2(SCH_1):PVCCIN_CPU1    I51 @BASEBOARD_FAB2_LIB.BASEBOARD_FAB2(SCH_1):PAGE71
  CC62 PVCCIN_CPU1 @BASEBOARD_FAB2_LIB.BASEBOARD_FAB2(SCH_1):PVCCIN_CPU1    I51 @BASEBOARD_FAB2_LIB.BASEBOARD_FAB2(SCH_1):PAGE71
  CC84 PVCCIN_CPU1 @BASEBOARD_FAB2_LIB.BASEBOARD_FAB2(SCH_1):PVCCIN_CPU1    I51 @BASEBOARD_FAB2_LIB.BASEBOARD_FAB2(SCH_1):PAGE71
  CD61 PVCCIN_CPU1 @BASEBOARD_FAB2_LIB.BASEBOARD_FAB2(SCH_1):PVCCIN_CPU1    I51 @BASEBOARD_FAB2_LIB.BASEBOARD_FAB2(SCH_1):PAGE71
  CD83 PVCCIN_CPU1 @BASEBOARD_FAB2_LIB.BASEBOARD_FAB2(SCH_1):PVCCIN_CPU1    I51 @BASEBOARD_FAB2_LIB.BASEBOARD_FAB2(SCH_1):PAGE71
  CD85 PVCCIN_CPU1 @BASEBOARD_FAB2_LIB.BASEBOARD_FAB2(SCH_1):PVCCIN_CPU1    I51 @BASEBOARD_FAB2_LIB.BASEBOARD_FAB2(SCH_1):PAGE71
  CE60 PVCCIN_CPU1 @BASEBOARD_FAB2_LIB.BASEBOARD_FAB2(SCH_1):PVCCIN_CPU1    I51 @BASEBOARD_FAB2_LIB.BASEBOARD_FAB2(SCH_1):PAGE71
  CE84 PVCCIN_CPU1 @BASEBOARD_FAB2_LIB.BASEBOARD_FAB2(SCH_1):PVCCIN_CPU1    I51 @BASEBOARD_FAB2_LIB.BASEBOARD_FAB2(SCH_1):PAGE71
  CF61 PVCCIN_CPU1 @BASEBOARD_FAB2_LIB.BASEBOARD_FAB2(SCH_1):PVCCIN_CPU1    I51 @BASEBOARD_FAB2_LIB.BASEBOARD_FAB2(SCH_1):PAGE71
  CF85 PVCCIN_CPU1 @BASEBOARD_FAB2_LIB.BASEBOARD_FAB2(SCH_1):PVCCIN_CPU1    I51 @BASEBOARD_FAB2_LIB.BASEBOARD_FAB2(SCH_1):PAGE71
  CG60 PVCCIN_CPU1 @BASEBOARD_FAB2_LIB.BASEBOARD_FAB2(SCH_1):PVCCIN_CPU1    I51 @BASEBOARD_FAB2_LIB.BASEBOARD_FAB2(SCH_1):PAGE71
  CG84 PVCCIN_CPU1 @BASEBOARD_FAB2_LIB.BASEBOARD_FAB2(SCH_1):PVCCIN_CPU1    I51 @BASEBOARD_FAB2_LIB.BASEBOARD_FAB2(SCH_1):PAGE71
  CH61 PVCCIN_CPU1 @BASEBOARD_FAB2_LIB.BASEBOARD_FAB2(SCH_1):PVCCIN_CPU1    I51 @BASEBOARD_FAB2_LIB.BASEBOARD_FAB2(SCH_1):PAGE71
  CH85 PVCCIN_CPU1 @BASEBOARD_FAB2_LIB.BASEBOARD_FAB2(SCH_1):PVCCIN_CPU1    I51 @BASEBOARD_FAB2_LIB.BASEBOARD_FAB2(SCH_1):PAGE71
  CJ60 PVCCIN_CPU1 @BASEBOARD_FAB2_LIB.BASEBOARD_FAB2(SCH_1):PVCCIN_CPU1    I51 @BASEBOARD_FAB2_LIB.BASEBOARD_FAB2(SCH_1):PAGE71
  CK59 PVCCIN_CPU1 @BASEBOARD_FAB2_LIB.BASEBOARD_FAB2(SCH_1):PVCCIN_CPU1    I51 @BASEBOARD_FAB2_LIB.BASEBOARD_FAB2(SCH_1):PAGE71
  CK61 PVCCIN_CPU1 @BASEBOARD_FAB2_LIB.BASEBOARD_FAB2(SCH_1):PVCCIN_CPU1    I51 @BASEBOARD_FAB2_LIB.BASEBOARD_FAB2(SCH_1):PAGE71
  CL58 PVCCIN_CPU1 @BASEBOARD_FAB2_LIB.BASEBOARD_FAB2(SCH_1):PVCCIN_CPU1    I51 @BASEBOARD_FAB2_LIB.BASEBOARD_FAB2(SCH_1):PAGE71
  CL60 PVCCIN_CPU1 @BASEBOARD_FAB2_LIB.BASEBOARD_FAB2(SCH_1):PVCCIN_CPU1    I51 @BASEBOARD_FAB2_LIB.BASEBOARD_FAB2(SCH_1):PAGE71
  CM57 PVCCIN_CPU1 @BASEBOARD_FAB2_LIB.BASEBOARD_FAB2(SCH_1):PVCCIN_CPU1    I51 @BASEBOARD_FAB2_LIB.BASEBOARD_FAB2(SCH_1):PAGE71
  CM59 PVCCIN_CPU1 @BASEBOARD_FAB2_LIB.BASEBOARD_FAB2(SCH_1):PVCCIN_CPU1    I51 @BASEBOARD_FAB2_LIB.BASEBOARD_FAB2(SCH_1):PAGE71
  CN56 PVCCIN_CPU1 @BASEBOARD_FAB2_LIB.BASEBOARD_FAB2(SCH_1):PVCCIN_CPU1    I51 @BASEBOARD_FAB2_LIB.BASEBOARD_FAB2(SCH_1):PAGE71
  CN58 PVCCIN_CPU1 @BASEBOARD_FAB2_LIB.BASEBOARD_FAB2(SCH_1):PVCCIN_CPU1    I51 @BASEBOARD_FAB2_LIB.BASEBOARD_FAB2(SCH_1):PAGE71
  CP33 PVCCIN_CPU1 @BASEBOARD_FAB2_LIB.BASEBOARD_FAB2(SCH_1):PVCCIN_CPU1    I51 @BASEBOARD_FAB2_LIB.BASEBOARD_FAB2(SCH_1):PAGE71
  CP55 PVCCIN_CPU1 @BASEBOARD_FAB2_LIB.BASEBOARD_FAB2(SCH_1):PVCCIN_CPU1    I51 @BASEBOARD_FAB2_LIB.BASEBOARD_FAB2(SCH_1):PAGE71
  CP57 PVCCIN_CPU1 @BASEBOARD_FAB2_LIB.BASEBOARD_FAB2(SCH_1):PVCCIN_CPU1    I51 @BASEBOARD_FAB2_LIB.BASEBOARD_FAB2(SCH_1):PAGE71
  CR34 PVCCIN_CPU1 @BASEBOARD_FAB2_LIB.BASEBOARD_FAB2(SCH_1):PVCCIN_CPU1    I51 @BASEBOARD_FAB2_LIB.BASEBOARD_FAB2(SCH_1):PAGE71
  CR54 PVCCIN_CPU1 @BASEBOARD_FAB2_LIB.BASEBOARD_FAB2(SCH_1):PVCCIN_CPU1    I51 @BASEBOARD_FAB2_LIB.BASEBOARD_FAB2(SCH_1):PAGE71
  CR56 PVCCIN_CPU1 @BASEBOARD_FAB2_LIB.BASEBOARD_FAB2(SCH_1):PVCCIN_CPU1    I51 @BASEBOARD_FAB2_LIB.BASEBOARD_FAB2(SCH_1):PAGE71
  CT37 PVCCIN_CPU1 @BASEBOARD_FAB2_LIB.BASEBOARD_FAB2(SCH_1):PVCCIN_CPU1    I51 @BASEBOARD_FAB2_LIB.BASEBOARD_FAB2(SCH_1):PAGE71
  CT39 PVCCIN_CPU1 @BASEBOARD_FAB2_LIB.BASEBOARD_FAB2(SCH_1):PVCCIN_CPU1    I51 @BASEBOARD_FAB2_LIB.BASEBOARD_FAB2(SCH_1):PAGE71
  CT41 PVCCIN_CPU1 @BASEBOARD_FAB2_LIB.BASEBOARD_FAB2(SCH_1):PVCCIN_CPU1    I51 @BASEBOARD_FAB2_LIB.BASEBOARD_FAB2(SCH_1):PAGE71
  CT53 PVCCIN_CPU1 @BASEBOARD_FAB2_LIB.BASEBOARD_FAB2(SCH_1):PVCCIN_CPU1    I51 @BASEBOARD_FAB2_LIB.BASEBOARD_FAB2(SCH_1):PAGE71
  CT55 PVCCIN_CPU1 @BASEBOARD_FAB2_LIB.BASEBOARD_FAB2(SCH_1):PVCCIN_CPU1    I51 @BASEBOARD_FAB2_LIB.BASEBOARD_FAB2(SCH_1):PAGE71
  CU38 PVCCIN_CPU1 @BASEBOARD_FAB2_LIB.BASEBOARD_FAB2(SCH_1):PVCCIN_CPU1    I51 @BASEBOARD_FAB2_LIB.BASEBOARD_FAB2(SCH_1):PAGE71
  CU40 PVCCIN_CPU1 @BASEBOARD_FAB2_LIB.BASEBOARD_FAB2(SCH_1):PVCCIN_CPU1    I51 @BASEBOARD_FAB2_LIB.BASEBOARD_FAB2(SCH_1):PAGE71
  CU42 PVCCIN_CPU1 @BASEBOARD_FAB2_LIB.BASEBOARD_FAB2(SCH_1):PVCCIN_CPU1    I51 @BASEBOARD_FAB2_LIB.BASEBOARD_FAB2(SCH_1):PAGE71
  CU52 PVCCIN_CPU1 @BASEBOARD_FAB2_LIB.BASEBOARD_FAB2(SCH_1):PVCCIN_CPU1    I51 @BASEBOARD_FAB2_LIB.BASEBOARD_FAB2(SCH_1):PAGE71
  CU54 PVCCIN_CPU1 @BASEBOARD_FAB2_LIB.BASEBOARD_FAB2(SCH_1):PVCCIN_CPU1    I51 @BASEBOARD_FAB2_LIB.BASEBOARD_FAB2(SCH_1):PAGE71
  CV51 PVCCIN_CPU1 @BASEBOARD_FAB2_LIB.BASEBOARD_FAB2(SCH_1):PVCCIN_CPU1    I51 @BASEBOARD_FAB2_LIB.BASEBOARD_FAB2(SCH_1):PAGE71
  CW46 PVCCIN_CPU1 @BASEBOARD_FAB2_LIB.BASEBOARD_FAB2(SCH_1):PVCCIN_CPU1    I51 @BASEBOARD_FAB2_LIB.BASEBOARD_FAB2(SCH_1):PAGE71
  CW48 PVCCIN_CPU1 @BASEBOARD_FAB2_LIB.BASEBOARD_FAB2(SCH_1):PVCCIN_CPU1    I51 @BASEBOARD_FAB2_LIB.BASEBOARD_FAB2(SCH_1):PAGE71
  CW50 PVCCIN_CPU1 @BASEBOARD_FAB2_LIB.BASEBOARD_FAB2(SCH_1):PVCCIN_CPU1    I51 @BASEBOARD_FAB2_LIB.BASEBOARD_FAB2(SCH_1):PAGE71
  CY47 PVCCIN_CPU1 @BASEBOARD_FAB2_LIB.BASEBOARD_FAB2(SCH_1):PVCCIN_CPU1    I51 @BASEBOARD_FAB2_LIB.BASEBOARD_FAB2(SCH_1):PAGE71
  CY49 PVCCIN_CPU1 @BASEBOARD_FAB2_LIB.BASEBOARD_FAB2(SCH_1):PVCCIN_CPU1    I51 @BASEBOARD_FAB2_LIB.BASEBOARD_FAB2(SCH_1):PAGE71
  AV85 VSENSE_VCCINR2PMAX_CPU1 @BASEBOARD_FAB2_LIB.BASEBOARD_FAB2(SCH_1):VSENSE_VCCINR2PMAX_CPU1    I51 @BASEBOARD_FAB2_LIB.BASEBOARD_FAB2(SCH_1):PAGE71
  AW86 VSENSE_VCCINR2PMAX_CPU1 @BASEBOARD_FAB2_LIB.BASEBOARD_FAB2(SCH_1):VSENSE_VCCINR2PMAX_CPU1    I51 @BASEBOARD_FAB2_LIB.BASEBOARD_FAB2(SCH_1):PAGE71
  BA86 VSENSE_PVCCIN_CPU1_SKT_VSEN @BASEBOARD_FAB2_LIB.BASEBOARD_FAB2(SCH_1):VSENSE_PVCCIN_CPU1_SKT_VSEN    I51 @BASEBOARD_FAB2_LIB.BASEBOARD_FAB2(SCH_1):PAGE71
  AD41 VSENSE_PMAX_CPU1 @BASEBOARD_FAB2_LIB.BASEBOARD_FAB2(SCH_1):VSENSE_PMAX_CPU1    I51 @BASEBOARD_FAB2_LIB.BASEBOARD_FAB2(SCH_1):PAGE71
  AY85 VSENSE_PVCCIN_CPU1_SKT_VRTN @BASEBOARD_FAB2_LIB.BASEBOARD_FAB2(SCH_1):VSENSE_PVCCIN_CPU1_SKT_VRTN    I51 @BASEBOARD_FAB2_LIB.BASEBOARD_FAB2(SCH_1):PAGE71
   B47 PVDDQ_GHJ @BASEBOARD_FAB2_LIB.BASEBOARD_FAB2(SCH_1):PVDDQ_GHJ    I32 @BASEBOARD_FAB2_LIB.BASEBOARD_FAB2(SCH_1):PAGE72
   C46 PVDDQ_GHJ @BASEBOARD_FAB2_LIB.BASEBOARD_FAB2(SCH_1):PVDDQ_GHJ    I32 @BASEBOARD_FAB2_LIB.BASEBOARD_FAB2(SCH_1):PAGE72
   D45 PVDDQ_GHJ @BASEBOARD_FAB2_LIB.BASEBOARD_FAB2(SCH_1):PVDDQ_GHJ    I32 @BASEBOARD_FAB2_LIB.BASEBOARD_FAB2(SCH_1):PAGE72
  AF63 PVDDQ_GHJ @BASEBOARD_FAB2_LIB.BASEBOARD_FAB2(SCH_1):PVDDQ_GHJ    I32 @BASEBOARD_FAB2_LIB.BASEBOARD_FAB2(SCH_1):PAGE72
  AF61 PVDDQ_GHJ @BASEBOARD_FAB2_LIB.BASEBOARD_FAB2(SCH_1):PVDDQ_GHJ    I32 @BASEBOARD_FAB2_LIB.BASEBOARD_FAB2(SCH_1):PAGE72
  AF59 PVDDQ_GHJ @BASEBOARD_FAB2_LIB.BASEBOARD_FAB2(SCH_1):PVDDQ_GHJ    I32 @BASEBOARD_FAB2_LIB.BASEBOARD_FAB2(SCH_1):PAGE72
  AF57 PVDDQ_GHJ @BASEBOARD_FAB2_LIB.BASEBOARD_FAB2(SCH_1):PVDDQ_GHJ    I32 @BASEBOARD_FAB2_LIB.BASEBOARD_FAB2(SCH_1):PAGE72
  AF55 PVDDQ_GHJ @BASEBOARD_FAB2_LIB.BASEBOARD_FAB2(SCH_1):PVDDQ_GHJ    I32 @BASEBOARD_FAB2_LIB.BASEBOARD_FAB2(SCH_1):PAGE72
  AD45 PVDDQ_GHJ @BASEBOARD_FAB2_LIB.BASEBOARD_FAB2(SCH_1):PVDDQ_GHJ    I32 @BASEBOARD_FAB2_LIB.BASEBOARD_FAB2(SCH_1):PAGE72
   Y63 PVDDQ_GHJ @BASEBOARD_FAB2_LIB.BASEBOARD_FAB2(SCH_1):PVDDQ_GHJ    I32 @BASEBOARD_FAB2_LIB.BASEBOARD_FAB2(SCH_1):PAGE72
   Y61 PVDDQ_GHJ @BASEBOARD_FAB2_LIB.BASEBOARD_FAB2(SCH_1):PVDDQ_GHJ    I32 @BASEBOARD_FAB2_LIB.BASEBOARD_FAB2(SCH_1):PAGE72
   Y59 PVDDQ_GHJ @BASEBOARD_FAB2_LIB.BASEBOARD_FAB2(SCH_1):PVDDQ_GHJ    I32 @BASEBOARD_FAB2_LIB.BASEBOARD_FAB2(SCH_1):PAGE72
   Y57 PVDDQ_GHJ @BASEBOARD_FAB2_LIB.BASEBOARD_FAB2(SCH_1):PVDDQ_GHJ    I32 @BASEBOARD_FAB2_LIB.BASEBOARD_FAB2(SCH_1):PAGE72
   Y55 PVDDQ_GHJ @BASEBOARD_FAB2_LIB.BASEBOARD_FAB2(SCH_1):PVDDQ_GHJ    I32 @BASEBOARD_FAB2_LIB.BASEBOARD_FAB2(SCH_1):PAGE72
   Y53 PVDDQ_GHJ @BASEBOARD_FAB2_LIB.BASEBOARD_FAB2(SCH_1):PVDDQ_GHJ    I32 @BASEBOARD_FAB2_LIB.BASEBOARD_FAB2(SCH_1):PAGE72
   Y51 PVDDQ_GHJ @BASEBOARD_FAB2_LIB.BASEBOARD_FAB2(SCH_1):PVDDQ_GHJ    I32 @BASEBOARD_FAB2_LIB.BASEBOARD_FAB2(SCH_1):PAGE72
   Y49 PVDDQ_GHJ @BASEBOARD_FAB2_LIB.BASEBOARD_FAB2(SCH_1):PVDDQ_GHJ    I32 @BASEBOARD_FAB2_LIB.BASEBOARD_FAB2(SCH_1):PAGE72
   Y47 PVDDQ_GHJ @BASEBOARD_FAB2_LIB.BASEBOARD_FAB2(SCH_1):PVDDQ_GHJ    I32 @BASEBOARD_FAB2_LIB.BASEBOARD_FAB2(SCH_1):PAGE72
   Y45 PVDDQ_GHJ @BASEBOARD_FAB2_LIB.BASEBOARD_FAB2(SCH_1):PVDDQ_GHJ    I32 @BASEBOARD_FAB2_LIB.BASEBOARD_FAB2(SCH_1):PAGE72
   W64 PVDDQ_GHJ @BASEBOARD_FAB2_LIB.BASEBOARD_FAB2(SCH_1):PVDDQ_GHJ    I32 @BASEBOARD_FAB2_LIB.BASEBOARD_FAB2(SCH_1):PAGE72
   U62 PVDDQ_GHJ @BASEBOARD_FAB2_LIB.BASEBOARD_FAB2(SCH_1):PVDDQ_GHJ    I32 @BASEBOARD_FAB2_LIB.BASEBOARD_FAB2(SCH_1):PAGE72
   U60 PVDDQ_GHJ @BASEBOARD_FAB2_LIB.BASEBOARD_FAB2(SCH_1):PVDDQ_GHJ    I32 @BASEBOARD_FAB2_LIB.BASEBOARD_FAB2(SCH_1):PAGE72
   U58 PVDDQ_GHJ @BASEBOARD_FAB2_LIB.BASEBOARD_FAB2(SCH_1):PVDDQ_GHJ    I32 @BASEBOARD_FAB2_LIB.BASEBOARD_FAB2(SCH_1):PAGE72
   U56 PVDDQ_GHJ @BASEBOARD_FAB2_LIB.BASEBOARD_FAB2(SCH_1):PVDDQ_GHJ    I32 @BASEBOARD_FAB2_LIB.BASEBOARD_FAB2(SCH_1):PAGE72
   U54 PVDDQ_GHJ @BASEBOARD_FAB2_LIB.BASEBOARD_FAB2(SCH_1):PVDDQ_GHJ    I32 @BASEBOARD_FAB2_LIB.BASEBOARD_FAB2(SCH_1):PAGE72
   U52 PVDDQ_GHJ @BASEBOARD_FAB2_LIB.BASEBOARD_FAB2(SCH_1):PVDDQ_GHJ    I32 @BASEBOARD_FAB2_LIB.BASEBOARD_FAB2(SCH_1):PAGE72
   U50 PVDDQ_GHJ @BASEBOARD_FAB2_LIB.BASEBOARD_FAB2(SCH_1):PVDDQ_GHJ    I32 @BASEBOARD_FAB2_LIB.BASEBOARD_FAB2(SCH_1):PAGE72
   U48 PVDDQ_GHJ @BASEBOARD_FAB2_LIB.BASEBOARD_FAB2(SCH_1):PVDDQ_GHJ    I32 @BASEBOARD_FAB2_LIB.BASEBOARD_FAB2(SCH_1):PAGE72
   U46 PVDDQ_GHJ @BASEBOARD_FAB2_LIB.BASEBOARD_FAB2(SCH_1):PVDDQ_GHJ    I32 @BASEBOARD_FAB2_LIB.BASEBOARD_FAB2(SCH_1):PAGE72
   N64 PVDDQ_GHJ @BASEBOARD_FAB2_LIB.BASEBOARD_FAB2(SCH_1):PVDDQ_GHJ    I32 @BASEBOARD_FAB2_LIB.BASEBOARD_FAB2(SCH_1):PAGE72
   L62 PVDDQ_GHJ @BASEBOARD_FAB2_LIB.BASEBOARD_FAB2(SCH_1):PVDDQ_GHJ    I32 @BASEBOARD_FAB2_LIB.BASEBOARD_FAB2(SCH_1):PAGE72
   L60 PVDDQ_GHJ @BASEBOARD_FAB2_LIB.BASEBOARD_FAB2(SCH_1):PVDDQ_GHJ    I32 @BASEBOARD_FAB2_LIB.BASEBOARD_FAB2(SCH_1):PAGE72
   L58 PVDDQ_GHJ @BASEBOARD_FAB2_LIB.BASEBOARD_FAB2(SCH_1):PVDDQ_GHJ    I32 @BASEBOARD_FAB2_LIB.BASEBOARD_FAB2(SCH_1):PAGE72
   L56 PVDDQ_GHJ @BASEBOARD_FAB2_LIB.BASEBOARD_FAB2(SCH_1):PVDDQ_GHJ    I32 @BASEBOARD_FAB2_LIB.BASEBOARD_FAB2(SCH_1):PAGE72
   L54 PVDDQ_GHJ @BASEBOARD_FAB2_LIB.BASEBOARD_FAB2(SCH_1):PVDDQ_GHJ    I32 @BASEBOARD_FAB2_LIB.BASEBOARD_FAB2(SCH_1):PAGE72
   L52 PVDDQ_GHJ @BASEBOARD_FAB2_LIB.BASEBOARD_FAB2(SCH_1):PVDDQ_GHJ    I32 @BASEBOARD_FAB2_LIB.BASEBOARD_FAB2(SCH_1):PAGE72
   L50 PVDDQ_GHJ @BASEBOARD_FAB2_LIB.BASEBOARD_FAB2(SCH_1):PVDDQ_GHJ    I32 @BASEBOARD_FAB2_LIB.BASEBOARD_FAB2(SCH_1):PAGE72
   L48 PVDDQ_GHJ @BASEBOARD_FAB2_LIB.BASEBOARD_FAB2(SCH_1):PVDDQ_GHJ    I32 @BASEBOARD_FAB2_LIB.BASEBOARD_FAB2(SCH_1):PAGE72
   L46 PVDDQ_GHJ @BASEBOARD_FAB2_LIB.BASEBOARD_FAB2(SCH_1):PVDDQ_GHJ    I32 @BASEBOARD_FAB2_LIB.BASEBOARD_FAB2(SCH_1):PAGE72
   E64 PVDDQ_GHJ @BASEBOARD_FAB2_LIB.BASEBOARD_FAB2(SCH_1):PVDDQ_GHJ    I32 @BASEBOARD_FAB2_LIB.BASEBOARD_FAB2(SCH_1):PAGE72
   E62 PVDDQ_GHJ @BASEBOARD_FAB2_LIB.BASEBOARD_FAB2(SCH_1):PVDDQ_GHJ    I32 @BASEBOARD_FAB2_LIB.BASEBOARD_FAB2(SCH_1):PAGE72
   E60 PVDDQ_GHJ @BASEBOARD_FAB2_LIB.BASEBOARD_FAB2(SCH_1):PVDDQ_GHJ    I32 @BASEBOARD_FAB2_LIB.BASEBOARD_FAB2(SCH_1):PAGE72
   E58 PVDDQ_GHJ @BASEBOARD_FAB2_LIB.BASEBOARD_FAB2(SCH_1):PVDDQ_GHJ    I32 @BASEBOARD_FAB2_LIB.BASEBOARD_FAB2(SCH_1):PAGE72
   E56 PVDDQ_GHJ @BASEBOARD_FAB2_LIB.BASEBOARD_FAB2(SCH_1):PVDDQ_GHJ    I32 @BASEBOARD_FAB2_LIB.BASEBOARD_FAB2(SCH_1):PAGE72
   E54 PVDDQ_GHJ @BASEBOARD_FAB2_LIB.BASEBOARD_FAB2(SCH_1):PVDDQ_GHJ    I32 @BASEBOARD_FAB2_LIB.BASEBOARD_FAB2(SCH_1):PAGE72
   E52 PVDDQ_GHJ @BASEBOARD_FAB2_LIB.BASEBOARD_FAB2(SCH_1):PVDDQ_GHJ    I32 @BASEBOARD_FAB2_LIB.BASEBOARD_FAB2(SCH_1):PAGE72
   E50 PVDDQ_GHJ @BASEBOARD_FAB2_LIB.BASEBOARD_FAB2(SCH_1):PVDDQ_GHJ    I32 @BASEBOARD_FAB2_LIB.BASEBOARD_FAB2(SCH_1):PAGE72
   E48 PVDDQ_GHJ @BASEBOARD_FAB2_LIB.BASEBOARD_FAB2(SCH_1):PVDDQ_GHJ    I32 @BASEBOARD_FAB2_LIB.BASEBOARD_FAB2(SCH_1):PAGE72
   E46 PVDDQ_GHJ @BASEBOARD_FAB2_LIB.BASEBOARD_FAB2(SCH_1):PVDDQ_GHJ    I32 @BASEBOARD_FAB2_LIB.BASEBOARD_FAB2(SCH_1):PAGE72
   B59 PVDDQ_GHJ @BASEBOARD_FAB2_LIB.BASEBOARD_FAB2(SCH_1):PVDDQ_GHJ    I32 @BASEBOARD_FAB2_LIB.BASEBOARD_FAB2(SCH_1):PAGE72
   B53 PVDDQ_GHJ @BASEBOARD_FAB2_LIB.BASEBOARD_FAB2(SCH_1):PVDDQ_GHJ    I32 @BASEBOARD_FAB2_LIB.BASEBOARD_FAB2(SCH_1):PAGE72
   B49 PVDDQ_GHJ @BASEBOARD_FAB2_LIB.BASEBOARD_FAB2(SCH_1):PVDDQ_GHJ    I32 @BASEBOARD_FAB2_LIB.BASEBOARD_FAB2(SCH_1):PAGE72
  EE44 PVDDQ_KLM @BASEBOARD_FAB2_LIB.BASEBOARD_FAB2(SCH_1):PVDDQ_KLM    I32 @BASEBOARD_FAB2_LIB.BASEBOARD_FAB2(SCH_1):PAGE72
  EF45 PVDDQ_KLM @BASEBOARD_FAB2_LIB.BASEBOARD_FAB2(SCH_1):PVDDQ_KLM    I32 @BASEBOARD_FAB2_LIB.BASEBOARD_FAB2(SCH_1):PAGE72
  DB53 PVDDQ_KLM @BASEBOARD_FAB2_LIB.BASEBOARD_FAB2(SCH_1):PVDDQ_KLM    I32 @BASEBOARD_FAB2_LIB.BASEBOARD_FAB2(SCH_1):PAGE72
  DB55 PVDDQ_KLM @BASEBOARD_FAB2_LIB.BASEBOARD_FAB2(SCH_1):PVDDQ_KLM    I32 @BASEBOARD_FAB2_LIB.BASEBOARD_FAB2(SCH_1):PAGE72
  DB57 PVDDQ_KLM @BASEBOARD_FAB2_LIB.BASEBOARD_FAB2(SCH_1):PVDDQ_KLM    I32 @BASEBOARD_FAB2_LIB.BASEBOARD_FAB2(SCH_1):PAGE72
  DB59 PVDDQ_KLM @BASEBOARD_FAB2_LIB.BASEBOARD_FAB2(SCH_1):PVDDQ_KLM    I32 @BASEBOARD_FAB2_LIB.BASEBOARD_FAB2(SCH_1):PAGE72
  DB61 PVDDQ_KLM @BASEBOARD_FAB2_LIB.BASEBOARD_FAB2(SCH_1):PVDDQ_KLM    I32 @BASEBOARD_FAB2_LIB.BASEBOARD_FAB2(SCH_1):PAGE72
  DB63 PVDDQ_KLM @BASEBOARD_FAB2_LIB.BASEBOARD_FAB2(SCH_1):PVDDQ_KLM    I32 @BASEBOARD_FAB2_LIB.BASEBOARD_FAB2(SCH_1):PAGE72
  DD45 PVDDQ_KLM @BASEBOARD_FAB2_LIB.BASEBOARD_FAB2(SCH_1):PVDDQ_KLM    I32 @BASEBOARD_FAB2_LIB.BASEBOARD_FAB2(SCH_1):PAGE72
  DH45 PVDDQ_KLM @BASEBOARD_FAB2_LIB.BASEBOARD_FAB2(SCH_1):PVDDQ_KLM    I32 @BASEBOARD_FAB2_LIB.BASEBOARD_FAB2(SCH_1):PAGE72
  DH47 PVDDQ_KLM @BASEBOARD_FAB2_LIB.BASEBOARD_FAB2(SCH_1):PVDDQ_KLM    I32 @BASEBOARD_FAB2_LIB.BASEBOARD_FAB2(SCH_1):PAGE72
  DH49 PVDDQ_KLM @BASEBOARD_FAB2_LIB.BASEBOARD_FAB2(SCH_1):PVDDQ_KLM    I32 @BASEBOARD_FAB2_LIB.BASEBOARD_FAB2(SCH_1):PAGE72
  DH51 PVDDQ_KLM @BASEBOARD_FAB2_LIB.BASEBOARD_FAB2(SCH_1):PVDDQ_KLM    I32 @BASEBOARD_FAB2_LIB.BASEBOARD_FAB2(SCH_1):PAGE72
  DH53 PVDDQ_KLM @BASEBOARD_FAB2_LIB.BASEBOARD_FAB2(SCH_1):PVDDQ_KLM    I32 @BASEBOARD_FAB2_LIB.BASEBOARD_FAB2(SCH_1):PAGE72
  DH55 PVDDQ_KLM @BASEBOARD_FAB2_LIB.BASEBOARD_FAB2(SCH_1):PVDDQ_KLM    I32 @BASEBOARD_FAB2_LIB.BASEBOARD_FAB2(SCH_1):PAGE72
  DH57 PVDDQ_KLM @BASEBOARD_FAB2_LIB.BASEBOARD_FAB2(SCH_1):PVDDQ_KLM    I32 @BASEBOARD_FAB2_LIB.BASEBOARD_FAB2(SCH_1):PAGE72
  DH59 PVDDQ_KLM @BASEBOARD_FAB2_LIB.BASEBOARD_FAB2(SCH_1):PVDDQ_KLM    I32 @BASEBOARD_FAB2_LIB.BASEBOARD_FAB2(SCH_1):PAGE72
  DH61 PVDDQ_KLM @BASEBOARD_FAB2_LIB.BASEBOARD_FAB2(SCH_1):PVDDQ_KLM    I32 @BASEBOARD_FAB2_LIB.BASEBOARD_FAB2(SCH_1):PAGE72
  DH63 PVDDQ_KLM @BASEBOARD_FAB2_LIB.BASEBOARD_FAB2(SCH_1):PVDDQ_KLM    I32 @BASEBOARD_FAB2_LIB.BASEBOARD_FAB2(SCH_1):PAGE72
  DJ64 PVDDQ_KLM @BASEBOARD_FAB2_LIB.BASEBOARD_FAB2(SCH_1):PVDDQ_KLM    I32 @BASEBOARD_FAB2_LIB.BASEBOARD_FAB2(SCH_1):PAGE72
  DL46 PVDDQ_KLM @BASEBOARD_FAB2_LIB.BASEBOARD_FAB2(SCH_1):PVDDQ_KLM    I32 @BASEBOARD_FAB2_LIB.BASEBOARD_FAB2(SCH_1):PAGE72
  DL48 PVDDQ_KLM @BASEBOARD_FAB2_LIB.BASEBOARD_FAB2(SCH_1):PVDDQ_KLM    I32 @BASEBOARD_FAB2_LIB.BASEBOARD_FAB2(SCH_1):PAGE72
  DL50 PVDDQ_KLM @BASEBOARD_FAB2_LIB.BASEBOARD_FAB2(SCH_1):PVDDQ_KLM    I32 @BASEBOARD_FAB2_LIB.BASEBOARD_FAB2(SCH_1):PAGE72
  DL52 PVDDQ_KLM @BASEBOARD_FAB2_LIB.BASEBOARD_FAB2(SCH_1):PVDDQ_KLM    I32 @BASEBOARD_FAB2_LIB.BASEBOARD_FAB2(SCH_1):PAGE72
  DL54 PVDDQ_KLM @BASEBOARD_FAB2_LIB.BASEBOARD_FAB2(SCH_1):PVDDQ_KLM    I32 @BASEBOARD_FAB2_LIB.BASEBOARD_FAB2(SCH_1):PAGE72
  DL56 PVDDQ_KLM @BASEBOARD_FAB2_LIB.BASEBOARD_FAB2(SCH_1):PVDDQ_KLM    I32 @BASEBOARD_FAB2_LIB.BASEBOARD_FAB2(SCH_1):PAGE72
  DL58 PVDDQ_KLM @BASEBOARD_FAB2_LIB.BASEBOARD_FAB2(SCH_1):PVDDQ_KLM    I32 @BASEBOARD_FAB2_LIB.BASEBOARD_FAB2(SCH_1):PAGE72
  DL60 PVDDQ_KLM @BASEBOARD_FAB2_LIB.BASEBOARD_FAB2(SCH_1):PVDDQ_KLM    I32 @BASEBOARD_FAB2_LIB.BASEBOARD_FAB2(SCH_1):PAGE72
  DL62 PVDDQ_KLM @BASEBOARD_FAB2_LIB.BASEBOARD_FAB2(SCH_1):PVDDQ_KLM    I32 @BASEBOARD_FAB2_LIB.BASEBOARD_FAB2(SCH_1):PAGE72
  DU46 PVDDQ_KLM @BASEBOARD_FAB2_LIB.BASEBOARD_FAB2(SCH_1):PVDDQ_KLM    I32 @BASEBOARD_FAB2_LIB.BASEBOARD_FAB2(SCH_1):PAGE72
  DU48 PVDDQ_KLM @BASEBOARD_FAB2_LIB.BASEBOARD_FAB2(SCH_1):PVDDQ_KLM    I32 @BASEBOARD_FAB2_LIB.BASEBOARD_FAB2(SCH_1):PAGE72
  DU50 PVDDQ_KLM @BASEBOARD_FAB2_LIB.BASEBOARD_FAB2(SCH_1):PVDDQ_KLM    I32 @BASEBOARD_FAB2_LIB.BASEBOARD_FAB2(SCH_1):PAGE72
  DU52 PVDDQ_KLM @BASEBOARD_FAB2_LIB.BASEBOARD_FAB2(SCH_1):PVDDQ_KLM    I32 @BASEBOARD_FAB2_LIB.BASEBOARD_FAB2(SCH_1):PAGE72
  DU54 PVDDQ_KLM @BASEBOARD_FAB2_LIB.BASEBOARD_FAB2(SCH_1):PVDDQ_KLM    I32 @BASEBOARD_FAB2_LIB.BASEBOARD_FAB2(SCH_1):PAGE72
  DU56 PVDDQ_KLM @BASEBOARD_FAB2_LIB.BASEBOARD_FAB2(SCH_1):PVDDQ_KLM    I32 @BASEBOARD_FAB2_LIB.BASEBOARD_FAB2(SCH_1):PAGE72
  DU58 PVDDQ_KLM @BASEBOARD_FAB2_LIB.BASEBOARD_FAB2(SCH_1):PVDDQ_KLM    I32 @BASEBOARD_FAB2_LIB.BASEBOARD_FAB2(SCH_1):PAGE72
  DU60 PVDDQ_KLM @BASEBOARD_FAB2_LIB.BASEBOARD_FAB2(SCH_1):PVDDQ_KLM    I32 @BASEBOARD_FAB2_LIB.BASEBOARD_FAB2(SCH_1):PAGE72
  DU62 PVDDQ_KLM @BASEBOARD_FAB2_LIB.BASEBOARD_FAB2(SCH_1):PVDDQ_KLM    I32 @BASEBOARD_FAB2_LIB.BASEBOARD_FAB2(SCH_1):PAGE72
  DU64 PVDDQ_KLM @BASEBOARD_FAB2_LIB.BASEBOARD_FAB2(SCH_1):PVDDQ_KLM    I32 @BASEBOARD_FAB2_LIB.BASEBOARD_FAB2(SCH_1):PAGE72
  EC46 PVDDQ_KLM @BASEBOARD_FAB2_LIB.BASEBOARD_FAB2(SCH_1):PVDDQ_KLM    I32 @BASEBOARD_FAB2_LIB.BASEBOARD_FAB2(SCH_1):PAGE72
  EC48 PVDDQ_KLM @BASEBOARD_FAB2_LIB.BASEBOARD_FAB2(SCH_1):PVDDQ_KLM    I32 @BASEBOARD_FAB2_LIB.BASEBOARD_FAB2(SCH_1):PAGE72
  EC50 PVDDQ_KLM @BASEBOARD_FAB2_LIB.BASEBOARD_FAB2(SCH_1):PVDDQ_KLM    I32 @BASEBOARD_FAB2_LIB.BASEBOARD_FAB2(SCH_1):PAGE72
  EC52 PVDDQ_KLM @BASEBOARD_FAB2_LIB.BASEBOARD_FAB2(SCH_1):PVDDQ_KLM    I32 @BASEBOARD_FAB2_LIB.BASEBOARD_FAB2(SCH_1):PAGE72
  EC54 PVDDQ_KLM @BASEBOARD_FAB2_LIB.BASEBOARD_FAB2(SCH_1):PVDDQ_KLM    I32 @BASEBOARD_FAB2_LIB.BASEBOARD_FAB2(SCH_1):PAGE72
  EC56 PVDDQ_KLM @BASEBOARD_FAB2_LIB.BASEBOARD_FAB2(SCH_1):PVDDQ_KLM    I32 @BASEBOARD_FAB2_LIB.BASEBOARD_FAB2(SCH_1):PAGE72
  EC58 PVDDQ_KLM @BASEBOARD_FAB2_LIB.BASEBOARD_FAB2(SCH_1):PVDDQ_KLM    I32 @BASEBOARD_FAB2_LIB.BASEBOARD_FAB2(SCH_1):PAGE72
  EC60 PVDDQ_KLM @BASEBOARD_FAB2_LIB.BASEBOARD_FAB2(SCH_1):PVDDQ_KLM    I32 @BASEBOARD_FAB2_LIB.BASEBOARD_FAB2(SCH_1):PAGE72
  EC62 PVDDQ_KLM @BASEBOARD_FAB2_LIB.BASEBOARD_FAB2(SCH_1):PVDDQ_KLM    I32 @BASEBOARD_FAB2_LIB.BASEBOARD_FAB2(SCH_1):PAGE72
  EF49 PVDDQ_KLM @BASEBOARD_FAB2_LIB.BASEBOARD_FAB2(SCH_1):PVDDQ_KLM    I32 @BASEBOARD_FAB2_LIB.BASEBOARD_FAB2(SCH_1):PAGE72
  EF53 PVDDQ_KLM @BASEBOARD_FAB2_LIB.BASEBOARD_FAB2(SCH_1):PVDDQ_KLM    I32 @BASEBOARD_FAB2_LIB.BASEBOARD_FAB2(SCH_1):PAGE72
  EF59 PVDDQ_KLM @BASEBOARD_FAB2_LIB.BASEBOARD_FAB2(SCH_1):PVDDQ_KLM    I32 @BASEBOARD_FAB2_LIB.BASEBOARD_FAB2(SCH_1):PAGE72
  BY27 P1V8_MCP_CPU1 @BASEBOARD_FAB2_LIB.BASEBOARD_FAB2(SCH_1):P1V8_MCP_CPU1    I33 @BASEBOARD_FAB2_LIB.BASEBOARD_FAB2(SCH_1):PAGE72
  BV27 P1V8_MCP_CPU1 @BASEBOARD_FAB2_LIB.BASEBOARD_FAB2(SCH_1):P1V8_MCP_CPU1    I33 @BASEBOARD_FAB2_LIB.BASEBOARD_FAB2(SCH_1):PAGE72
  BU26 P1V8_MCP_CPU1 @BASEBOARD_FAB2_LIB.BASEBOARD_FAB2(SCH_1):P1V8_MCP_CPU1    I33 @BASEBOARD_FAB2_LIB.BASEBOARD_FAB2(SCH_1):PAGE72
  BT27 P1V8_MCP_CPU1 @BASEBOARD_FAB2_LIB.BASEBOARD_FAB2(SCH_1):P1V8_MCP_CPU1    I33 @BASEBOARD_FAB2_LIB.BASEBOARD_FAB2(SCH_1):PAGE72
  BM11 PVCCIOMCP_CPU1 @BASEBOARD_FAB2_LIB.BASEBOARD_FAB2(SCH_1):PVCCIOMCP_CPU1    I33 @BASEBOARD_FAB2_LIB.BASEBOARD_FAB2(SCH_1):PAGE72
  BN12 PVCCIOMCP_CPU1 @BASEBOARD_FAB2_LIB.BASEBOARD_FAB2(SCH_1):PVCCIOMCP_CPU1    I33 @BASEBOARD_FAB2_LIB.BASEBOARD_FAB2(SCH_1):PAGE72
  BN14 PVCCIOMCP_CPU1 @BASEBOARD_FAB2_LIB.BASEBOARD_FAB2(SCH_1):PVCCIOMCP_CPU1    I33 @BASEBOARD_FAB2_LIB.BASEBOARD_FAB2(SCH_1):PAGE72
  BP11 PVCCIOMCP_CPU1 @BASEBOARD_FAB2_LIB.BASEBOARD_FAB2(SCH_1):PVCCIOMCP_CPU1    I33 @BASEBOARD_FAB2_LIB.BASEBOARD_FAB2(SCH_1):PAGE72
  BP13 PVCCIOMCP_CPU1 @BASEBOARD_FAB2_LIB.BASEBOARD_FAB2(SCH_1):PVCCIOMCP_CPU1    I33 @BASEBOARD_FAB2_LIB.BASEBOARD_FAB2(SCH_1):PAGE72
  BP15 PVCCIOMCP_CPU1 @BASEBOARD_FAB2_LIB.BASEBOARD_FAB2(SCH_1):PVCCIOMCP_CPU1    I33 @BASEBOARD_FAB2_LIB.BASEBOARD_FAB2(SCH_1):PAGE72
  BR12 PVCCIOMCP_CPU1 @BASEBOARD_FAB2_LIB.BASEBOARD_FAB2(SCH_1):PVCCIOMCP_CPU1    I33 @BASEBOARD_FAB2_LIB.BASEBOARD_FAB2(SCH_1):PAGE72
  BR14 PVCCIOMCP_CPU1 @BASEBOARD_FAB2_LIB.BASEBOARD_FAB2(SCH_1):PVCCIOMCP_CPU1    I33 @BASEBOARD_FAB2_LIB.BASEBOARD_FAB2(SCH_1):PAGE72
  BT11 PVCCIOMCP_CPU1 @BASEBOARD_FAB2_LIB.BASEBOARD_FAB2(SCH_1):PVCCIOMCP_CPU1    I33 @BASEBOARD_FAB2_LIB.BASEBOARD_FAB2(SCH_1):PAGE72
  BT13 PVCCIOMCP_CPU1 @BASEBOARD_FAB2_LIB.BASEBOARD_FAB2(SCH_1):PVCCIOMCP_CPU1    I33 @BASEBOARD_FAB2_LIB.BASEBOARD_FAB2(SCH_1):PAGE72
  BT15 PVCCIOMCP_CPU1 @BASEBOARD_FAB2_LIB.BASEBOARD_FAB2(SCH_1):PVCCIOMCP_CPU1    I33 @BASEBOARD_FAB2_LIB.BASEBOARD_FAB2(SCH_1):PAGE72
  BU12 PVCCIOMCP_CPU1 @BASEBOARD_FAB2_LIB.BASEBOARD_FAB2(SCH_1):PVCCIOMCP_CPU1    I33 @BASEBOARD_FAB2_LIB.BASEBOARD_FAB2(SCH_1):PAGE72
  BU14 PVCCIOMCP_CPU1 @BASEBOARD_FAB2_LIB.BASEBOARD_FAB2(SCH_1):PVCCIOMCP_CPU1    I33 @BASEBOARD_FAB2_LIB.BASEBOARD_FAB2(SCH_1):PAGE72
  BV11 PVCCIOMCP_CPU1 @BASEBOARD_FAB2_LIB.BASEBOARD_FAB2(SCH_1):PVCCIOMCP_CPU1    I33 @BASEBOARD_FAB2_LIB.BASEBOARD_FAB2(SCH_1):PAGE72
  BV13 PVCCIOMCP_CPU1 @BASEBOARD_FAB2_LIB.BASEBOARD_FAB2(SCH_1):PVCCIOMCP_CPU1    I33 @BASEBOARD_FAB2_LIB.BASEBOARD_FAB2(SCH_1):PAGE72
  BV15 PVCCIOMCP_CPU1 @BASEBOARD_FAB2_LIB.BASEBOARD_FAB2(SCH_1):PVCCIOMCP_CPU1    I33 @BASEBOARD_FAB2_LIB.BASEBOARD_FAB2(SCH_1):PAGE72
  BD13 PVCCMCP_CPU1 @BASEBOARD_FAB2_LIB.BASEBOARD_FAB2(SCH_1):PVCCMCP_CPU1    I33 @BASEBOARD_FAB2_LIB.BASEBOARD_FAB2(SCH_1):PAGE72
  BE12 PVCCMCP_CPU1 @BASEBOARD_FAB2_LIB.BASEBOARD_FAB2(SCH_1):PVCCMCP_CPU1    I33 @BASEBOARD_FAB2_LIB.BASEBOARD_FAB2(SCH_1):PAGE72
  BE14 PVCCMCP_CPU1 @BASEBOARD_FAB2_LIB.BASEBOARD_FAB2(SCH_1):PVCCMCP_CPU1    I33 @BASEBOARD_FAB2_LIB.BASEBOARD_FAB2(SCH_1):PAGE72
  BF11 PVCCMCP_CPU1 @BASEBOARD_FAB2_LIB.BASEBOARD_FAB2(SCH_1):PVCCMCP_CPU1    I33 @BASEBOARD_FAB2_LIB.BASEBOARD_FAB2(SCH_1):PAGE72
  BF13 PVCCMCP_CPU1 @BASEBOARD_FAB2_LIB.BASEBOARD_FAB2(SCH_1):PVCCMCP_CPU1    I33 @BASEBOARD_FAB2_LIB.BASEBOARD_FAB2(SCH_1):PAGE72
  BG12 PVCCMCP_CPU1 @BASEBOARD_FAB2_LIB.BASEBOARD_FAB2(SCH_1):PVCCMCP_CPU1    I33 @BASEBOARD_FAB2_LIB.BASEBOARD_FAB2(SCH_1):PAGE72
  BG14 PVCCMCP_CPU1 @BASEBOARD_FAB2_LIB.BASEBOARD_FAB2(SCH_1):PVCCMCP_CPU1    I33 @BASEBOARD_FAB2_LIB.BASEBOARD_FAB2(SCH_1):PAGE72
  BH13 PVCCMCP_CPU1 @BASEBOARD_FAB2_LIB.BASEBOARD_FAB2(SCH_1):PVCCMCP_CPU1    I33 @BASEBOARD_FAB2_LIB.BASEBOARD_FAB2(SCH_1):PAGE72
  BJ12 PVCCMCP_CPU1 @BASEBOARD_FAB2_LIB.BASEBOARD_FAB2(SCH_1):PVCCMCP_CPU1    I33 @BASEBOARD_FAB2_LIB.BASEBOARD_FAB2(SCH_1):PAGE72
  BJ14 PVCCMCP_CPU1 @BASEBOARD_FAB2_LIB.BASEBOARD_FAB2(SCH_1):PVCCMCP_CPU1    I33 @BASEBOARD_FAB2_LIB.BASEBOARD_FAB2(SCH_1):PAGE72
  BK13 PVCCMCP_CPU1 @BASEBOARD_FAB2_LIB.BASEBOARD_FAB2(SCH_1):PVCCMCP_CPU1    I33 @BASEBOARD_FAB2_LIB.BASEBOARD_FAB2(SCH_1):PAGE72
  BK15 PVCCMCP_CPU1 @BASEBOARD_FAB2_LIB.BASEBOARD_FAB2(SCH_1):PVCCMCP_CPU1    I33 @BASEBOARD_FAB2_LIB.BASEBOARD_FAB2(SCH_1):PAGE72
  BL14 PVCCMCP_CPU1 @BASEBOARD_FAB2_LIB.BASEBOARD_FAB2(SCH_1):PVCCMCP_CPU1    I33 @BASEBOARD_FAB2_LIB.BASEBOARD_FAB2(SCH_1):PAGE72
    A8 PVPP_GHJ @BASEBOARD_FAB2_LIB.BASEBOARD_FAB2(SCH_1):PVPP_GHJ    I33 @BASEBOARD_FAB2_LIB.BASEBOARD_FAB2(SCH_1):PAGE72
   A10 PVPP_GHJ @BASEBOARD_FAB2_LIB.BASEBOARD_FAB2(SCH_1):PVPP_GHJ    I33 @BASEBOARD_FAB2_LIB.BASEBOARD_FAB2(SCH_1):PAGE72
   A12 PVPP_GHJ @BASEBOARD_FAB2_LIB.BASEBOARD_FAB2(SCH_1):PVPP_GHJ    I33 @BASEBOARD_FAB2_LIB.BASEBOARD_FAB2(SCH_1):PAGE72
   B11 PVPP_GHJ @BASEBOARD_FAB2_LIB.BASEBOARD_FAB2(SCH_1):PVPP_GHJ    I33 @BASEBOARD_FAB2_LIB.BASEBOARD_FAB2(SCH_1):PAGE72
  CY55 P3V3_STBY @BASEBOARD_FAB2_LIB.BASEBOARD_FAB2(SCH_1):P3V3_STBY    I33 @BASEBOARD_FAB2_LIB.BASEBOARD_FAB2(SCH_1):PAGE72
  AR28 PVCCIO_CPU1 @BASEBOARD_FAB2_LIB.BASEBOARD_FAB2(SCH_1):PVCCIO_CPU1    I33 @BASEBOARD_FAB2_LIB.BASEBOARD_FAB2(SCH_1):PAGE72
  AL28 PVCCIO_CPU1 @BASEBOARD_FAB2_LIB.BASEBOARD_FAB2(SCH_1):PVCCIO_CPU1    I33 @BASEBOARD_FAB2_LIB.BASEBOARD_FAB2(SCH_1):PAGE72
  AM29 PVCCIO_CPU1 @BASEBOARD_FAB2_LIB.BASEBOARD_FAB2(SCH_1):PVCCIO_CPU1    I33 @BASEBOARD_FAB2_LIB.BASEBOARD_FAB2(SCH_1):PAGE72
  AG34 PVCCIO_CPU1 @BASEBOARD_FAB2_LIB.BASEBOARD_FAB2(SCH_1):PVCCIO_CPU1    I33 @BASEBOARD_FAB2_LIB.BASEBOARD_FAB2(SCH_1):PAGE72
  AE34 PVCCIO_CPU1 @BASEBOARD_FAB2_LIB.BASEBOARD_FAB2(SCH_1):PVCCIO_CPU1    I33 @BASEBOARD_FAB2_LIB.BASEBOARD_FAB2(SCH_1):PAGE72
  AD35 PVCCIO_CPU1 @BASEBOARD_FAB2_LIB.BASEBOARD_FAB2(SCH_1):PVCCIO_CPU1    I33 @BASEBOARD_FAB2_LIB.BASEBOARD_FAB2(SCH_1):PAGE72
  AF35 PVCCIO_CPU1 @BASEBOARD_FAB2_LIB.BASEBOARD_FAB2(SCH_1):PVCCIO_CPU1    I33 @BASEBOARD_FAB2_LIB.BASEBOARD_FAB2(SCH_1):PAGE72
  AC36 PVCCIO_CPU1 @BASEBOARD_FAB2_LIB.BASEBOARD_FAB2(SCH_1):PVCCIO_CPU1    I33 @BASEBOARD_FAB2_LIB.BASEBOARD_FAB2(SCH_1):PAGE72
  AD37 PVCCIO_CPU1 @BASEBOARD_FAB2_LIB.BASEBOARD_FAB2(SCH_1):PVCCIO_CPU1    I33 @BASEBOARD_FAB2_LIB.BASEBOARD_FAB2(SCH_1):PAGE72
  AE36 PVCCIO_CPU1 @BASEBOARD_FAB2_LIB.BASEBOARD_FAB2(SCH_1):PVCCIO_CPU1    I33 @BASEBOARD_FAB2_LIB.BASEBOARD_FAB2(SCH_1):PAGE72
  BF27 PVCCIO_CPU1 @BASEBOARD_FAB2_LIB.BASEBOARD_FAB2(SCH_1):PVCCIO_CPU1    I33 @BASEBOARD_FAB2_LIB.BASEBOARD_FAB2(SCH_1):PAGE72
  BG26 PVCCIO_CPU1 @BASEBOARD_FAB2_LIB.BASEBOARD_FAB2(SCH_1):PVCCIO_CPU1    I33 @BASEBOARD_FAB2_LIB.BASEBOARD_FAB2(SCH_1):PAGE72
  BH25 PVCCIO_CPU1 @BASEBOARD_FAB2_LIB.BASEBOARD_FAB2(SCH_1):PVCCIO_CPU1    I33 @BASEBOARD_FAB2_LIB.BASEBOARD_FAB2(SCH_1):PAGE72
  BH27 PVCCIO_CPU1 @BASEBOARD_FAB2_LIB.BASEBOARD_FAB2(SCH_1):PVCCIO_CPU1    I33 @BASEBOARD_FAB2_LIB.BASEBOARD_FAB2(SCH_1):PAGE72
  BJ26 PVCCIO_CPU1 @BASEBOARD_FAB2_LIB.BASEBOARD_FAB2(SCH_1):PVCCIO_CPU1    I33 @BASEBOARD_FAB2_LIB.BASEBOARD_FAB2(SCH_1):PAGE72
  BK25 PVCCIO_CPU1 @BASEBOARD_FAB2_LIB.BASEBOARD_FAB2(SCH_1):PVCCIO_CPU1    I33 @BASEBOARD_FAB2_LIB.BASEBOARD_FAB2(SCH_1):PAGE72
  BK27 PVCCIO_CPU1 @BASEBOARD_FAB2_LIB.BASEBOARD_FAB2(SCH_1):PVCCIO_CPU1    I33 @BASEBOARD_FAB2_LIB.BASEBOARD_FAB2(SCH_1):PAGE72
  BL26 PVCCIO_CPU1 @BASEBOARD_FAB2_LIB.BASEBOARD_FAB2(SCH_1):PVCCIO_CPU1    I33 @BASEBOARD_FAB2_LIB.BASEBOARD_FAB2(SCH_1):PAGE72
  BM27 PVCCIO_CPU1 @BASEBOARD_FAB2_LIB.BASEBOARD_FAB2(SCH_1):PVCCIO_CPU1    I33 @BASEBOARD_FAB2_LIB.BASEBOARD_FAB2(SCH_1):PAGE72
  CH27 PVCCIO_CPU1 @BASEBOARD_FAB2_LIB.BASEBOARD_FAB2(SCH_1):PVCCIO_CPU1    I33 @BASEBOARD_FAB2_LIB.BASEBOARD_FAB2(SCH_1):PAGE72
  CJ28 PVCCIO_CPU1 @BASEBOARD_FAB2_LIB.BASEBOARD_FAB2(SCH_1):PVCCIO_CPU1    I33 @BASEBOARD_FAB2_LIB.BASEBOARD_FAB2(SCH_1):PAGE72
  CC26 PVCCIO_CPU1 @BASEBOARD_FAB2_LIB.BASEBOARD_FAB2(SCH_1):PVCCIO_CPU1    I33 @BASEBOARD_FAB2_LIB.BASEBOARD_FAB2(SCH_1):PAGE72
  CD27 PVCCIO_CPU1 @BASEBOARD_FAB2_LIB.BASEBOARD_FAB2(SCH_1):PVCCIO_CPU1    I33 @BASEBOARD_FAB2_LIB.BASEBOARD_FAB2(SCH_1):PAGE72
  CF27 PVCCIO_CPU1 @BASEBOARD_FAB2_LIB.BASEBOARD_FAB2(SCH_1):PVCCIO_CPU1    I33 @BASEBOARD_FAB2_LIB.BASEBOARD_FAB2(SCH_1):PAGE72
  AV27 PVCCIO_CPU1 @BASEBOARD_FAB2_LIB.BASEBOARD_FAB2(SCH_1):PVCCIO_CPU1    I33 @BASEBOARD_FAB2_LIB.BASEBOARD_FAB2(SCH_1):PAGE72
  AW26 PVCCIO_CPU1 @BASEBOARD_FAB2_LIB.BASEBOARD_FAB2(SCH_1):PVCCIO_CPU1    I33 @BASEBOARD_FAB2_LIB.BASEBOARD_FAB2(SCH_1):PAGE72
  AY27 PVCCIO_CPU1 @BASEBOARD_FAB2_LIB.BASEBOARD_FAB2(SCH_1):PVCCIO_CPU1    I33 @BASEBOARD_FAB2_LIB.BASEBOARD_FAB2(SCH_1):PAGE72
  BA26 PVCCIO_CPU1 @BASEBOARD_FAB2_LIB.BASEBOARD_FAB2(SCH_1):PVCCIO_CPU1    I33 @BASEBOARD_FAB2_LIB.BASEBOARD_FAB2(SCH_1):PAGE72
  BB27 PVCCIO_CPU1 @BASEBOARD_FAB2_LIB.BASEBOARD_FAB2(SCH_1):PVCCIO_CPU1    I33 @BASEBOARD_FAB2_LIB.BASEBOARD_FAB2(SCH_1):PAGE72
  BC26 PVCCIO_CPU1 @BASEBOARD_FAB2_LIB.BASEBOARD_FAB2(SCH_1):PVCCIO_CPU1    I33 @BASEBOARD_FAB2_LIB.BASEBOARD_FAB2(SCH_1):PAGE72
   W10 PVCCIO_CPU1 @BASEBOARD_FAB2_LIB.BASEBOARD_FAB2(SCH_1):PVCCIO_CPU1    I33 @BASEBOARD_FAB2_LIB.BASEBOARD_FAB2(SCH_1):PAGE72
   N18 PVCCIO_CPU1 @BASEBOARD_FAB2_LIB.BASEBOARD_FAB2(SCH_1):PVCCIO_CPU1    I33 @BASEBOARD_FAB2_LIB.BASEBOARD_FAB2(SCH_1):PAGE72
    M9 PVCCIO_CPU1 @BASEBOARD_FAB2_LIB.BASEBOARD_FAB2(SCH_1):PVCCIO_CPU1    I33 @BASEBOARD_FAB2_LIB.BASEBOARD_FAB2(SCH_1):PAGE72
    M7 PVCCIO_CPU1 @BASEBOARD_FAB2_LIB.BASEBOARD_FAB2(SCH_1):PVCCIO_CPU1    I33 @BASEBOARD_FAB2_LIB.BASEBOARD_FAB2(SCH_1):PAGE72
   K15 PVCCIO_CPU1 @BASEBOARD_FAB2_LIB.BASEBOARD_FAB2(SCH_1):PVCCIO_CPU1    I33 @BASEBOARD_FAB2_LIB.BASEBOARD_FAB2(SCH_1):PAGE72
    J2 PVCCIO_CPU1 @BASEBOARD_FAB2_LIB.BASEBOARD_FAB2(SCH_1):PVCCIO_CPU1    I33 @BASEBOARD_FAB2_LIB.BASEBOARD_FAB2(SCH_1):PAGE72
  EB15 PVCCIO_CPU1 @BASEBOARD_FAB2_LIB.BASEBOARD_FAB2(SCH_1):PVCCIO_CPU1    I33 @BASEBOARD_FAB2_LIB.BASEBOARD_FAB2(SCH_1):PAGE72
  EA12 PVCCIO_CPU1 @BASEBOARD_FAB2_LIB.BASEBOARD_FAB2(SCH_1):PVCCIO_CPU1    I33 @BASEBOARD_FAB2_LIB.BASEBOARD_FAB2(SCH_1):PAGE72
  DU20 PVCCIO_CPU1 @BASEBOARD_FAB2_LIB.BASEBOARD_FAB2(SCH_1):PVCCIO_CPU1    I33 @BASEBOARD_FAB2_LIB.BASEBOARD_FAB2(SCH_1):PAGE72
   DR2 PVCCIO_CPU1 @BASEBOARD_FAB2_LIB.BASEBOARD_FAB2(SCH_1):PVCCIO_CPU1    I33 @BASEBOARD_FAB2_LIB.BASEBOARD_FAB2(SCH_1):PAGE72
  DR10 PVCCIO_CPU1 @BASEBOARD_FAB2_LIB.BASEBOARD_FAB2(SCH_1):PVCCIO_CPU1    I33 @BASEBOARD_FAB2_LIB.BASEBOARD_FAB2(SCH_1):PAGE72
  DP19 PVCCIO_CPU1 @BASEBOARD_FAB2_LIB.BASEBOARD_FAB2(SCH_1):PVCCIO_CPU1    I33 @BASEBOARD_FAB2_LIB.BASEBOARD_FAB2(SCH_1):PAGE72
   DN8 PVCCIO_CPU1 @BASEBOARD_FAB2_LIB.BASEBOARD_FAB2(SCH_1):PVCCIO_CPU1    I33 @BASEBOARD_FAB2_LIB.BASEBOARD_FAB2(SCH_1):PAGE72
  DM17 PVCCIO_CPU1 @BASEBOARD_FAB2_LIB.BASEBOARD_FAB2(SCH_1):PVCCIO_CPU1    I33 @BASEBOARD_FAB2_LIB.BASEBOARD_FAB2(SCH_1):PAGE72
  DJ16 PVCCIO_CPU1 @BASEBOARD_FAB2_LIB.BASEBOARD_FAB2(SCH_1):PVCCIO_CPU1    I33 @BASEBOARD_FAB2_LIB.BASEBOARD_FAB2(SCH_1):PAGE72
   H13 PVCCIO_CPU1 @BASEBOARD_FAB2_LIB.BASEBOARD_FAB2(SCH_1):PVCCIO_CPU1    I33 @BASEBOARD_FAB2_LIB.BASEBOARD_FAB2(SCH_1):PAGE72
   J10 PVCCIO_CPU1 @BASEBOARD_FAB2_LIB.BASEBOARD_FAB2(SCH_1):PVCCIO_CPU1    I33 @BASEBOARD_FAB2_LIB.BASEBOARD_FAB2(SCH_1):PAGE72
   L14 PVCCIO_CPU1 @BASEBOARD_FAB2_LIB.BASEBOARD_FAB2(SCH_1):PVCCIO_CPU1    I33 @BASEBOARD_FAB2_LIB.BASEBOARD_FAB2(SCH_1):PAGE72
   L16 PVCCIO_CPU1 @BASEBOARD_FAB2_LIB.BASEBOARD_FAB2(SCH_1):PVCCIO_CPU1    I33 @BASEBOARD_FAB2_LIB.BASEBOARD_FAB2(SCH_1):PAGE72
   DH7 PVCCIO_CPU1 @BASEBOARD_FAB2_LIB.BASEBOARD_FAB2(SCH_1):PVCCIO_CPU1    I33 @BASEBOARD_FAB2_LIB.BASEBOARD_FAB2(SCH_1):PAGE72
   DG8 PVCCIO_CPU1 @BASEBOARD_FAB2_LIB.BASEBOARD_FAB2(SCH_1):PVCCIO_CPU1    I33 @BASEBOARD_FAB2_LIB.BASEBOARD_FAB2(SCH_1):PAGE72
   M11 PVCCIO_CPU1 @BASEBOARD_FAB2_LIB.BASEBOARD_FAB2(SCH_1):PVCCIO_CPU1    I33 @BASEBOARD_FAB2_LIB.BASEBOARD_FAB2(SCH_1):PAGE72
   M21 PVCCIO_CPU1 @BASEBOARD_FAB2_LIB.BASEBOARD_FAB2(SCH_1):PVCCIO_CPU1    I33 @BASEBOARD_FAB2_LIB.BASEBOARD_FAB2(SCH_1):PAGE72
    P5 PVCCIO_CPU1 @BASEBOARD_FAB2_LIB.BASEBOARD_FAB2(SCH_1):PVCCIO_CPU1    I33 @BASEBOARD_FAB2_LIB.BASEBOARD_FAB2(SCH_1):PAGE72
    T3 PVCCIO_CPU1 @BASEBOARD_FAB2_LIB.BASEBOARD_FAB2(SCH_1):PVCCIO_CPU1    I33 @BASEBOARD_FAB2_LIB.BASEBOARD_FAB2(SCH_1):PAGE72
   U14 PVCCIO_CPU1 @BASEBOARD_FAB2_LIB.BASEBOARD_FAB2(SCH_1):PVCCIO_CPU1    I33 @BASEBOARD_FAB2_LIB.BASEBOARD_FAB2(SCH_1):PAGE72
  DF21 PVCCIO_CPU1 @BASEBOARD_FAB2_LIB.BASEBOARD_FAB2(SCH_1):PVCCIO_CPU1    I33 @BASEBOARD_FAB2_LIB.BASEBOARD_FAB2(SCH_1):PAGE72
    W4 PVCCIO_CPU1 @BASEBOARD_FAB2_LIB.BASEBOARD_FAB2(SCH_1):PVCCIO_CPU1    I33 @BASEBOARD_FAB2_LIB.BASEBOARD_FAB2(SCH_1):PAGE72
    W6 PVCCIO_CPU1 @BASEBOARD_FAB2_LIB.BASEBOARD_FAB2(SCH_1):PVCCIO_CPU1    I33 @BASEBOARD_FAB2_LIB.BASEBOARD_FAB2(SCH_1):PAGE72
  AA10 PVCCIO_CPU1 @BASEBOARD_FAB2_LIB.BASEBOARD_FAB2(SCH_1):PVCCIO_CPU1    I33 @BASEBOARD_FAB2_LIB.BASEBOARD_FAB2(SCH_1):PAGE72
  AC20 PVCCIO_CPU1 @BASEBOARD_FAB2_LIB.BASEBOARD_FAB2(SCH_1):PVCCIO_CPU1    I33 @BASEBOARD_FAB2_LIB.BASEBOARD_FAB2(SCH_1):PAGE72
   AC4 PVCCIO_CPU1 @BASEBOARD_FAB2_LIB.BASEBOARD_FAB2(SCH_1):PVCCIO_CPU1    I33 @BASEBOARD_FAB2_LIB.BASEBOARD_FAB2(SCH_1):PAGE72
   AH9 PVCCIO_CPU1 @BASEBOARD_FAB2_LIB.BASEBOARD_FAB2(SCH_1):PVCCIO_CPU1    I33 @BASEBOARD_FAB2_LIB.BASEBOARD_FAB2(SCH_1):PAGE72
  DF13 PVCCIO_CPU1 @BASEBOARD_FAB2_LIB.BASEBOARD_FAB2(SCH_1):PVCCIO_CPU1    I33 @BASEBOARD_FAB2_LIB.BASEBOARD_FAB2(SCH_1):PAGE72
  AN10 PVCCIO_CPU1 @BASEBOARD_FAB2_LIB.BASEBOARD_FAB2(SCH_1):PVCCIO_CPU1    I33 @BASEBOARD_FAB2_LIB.BASEBOARD_FAB2(SCH_1):PAGE72
   DD7 PVCCIO_CPU1 @BASEBOARD_FAB2_LIB.BASEBOARD_FAB2(SCH_1):PVCCIO_CPU1    I33 @BASEBOARD_FAB2_LIB.BASEBOARD_FAB2(SCH_1):PAGE72
  AT11 PVCCIO_CPU1 @BASEBOARD_FAB2_LIB.BASEBOARD_FAB2(SCH_1):PVCCIO_CPU1    I33 @BASEBOARD_FAB2_LIB.BASEBOARD_FAB2(SCH_1):PAGE72
   AW6 PVCCIO_CPU1 @BASEBOARD_FAB2_LIB.BASEBOARD_FAB2(SCH_1):PVCCIO_CPU1    I33 @BASEBOARD_FAB2_LIB.BASEBOARD_FAB2(SCH_1):PAGE72
  AY11 PVCCIO_CPU1 @BASEBOARD_FAB2_LIB.BASEBOARD_FAB2(SCH_1):PVCCIO_CPU1    I33 @BASEBOARD_FAB2_LIB.BASEBOARD_FAB2(SCH_1):PAGE72
  BA24 PVCCIO_CPU1 @BASEBOARD_FAB2_LIB.BASEBOARD_FAB2(SCH_1):PVCCIO_CPU1    I33 @BASEBOARD_FAB2_LIB.BASEBOARD_FAB2(SCH_1):PAGE72
   BB5 PVCCIO_CPU1 @BASEBOARD_FAB2_LIB.BASEBOARD_FAB2(SCH_1):PVCCIO_CPU1    I33 @BASEBOARD_FAB2_LIB.BASEBOARD_FAB2(SCH_1):PAGE72
  DA14 PVCCIO_CPU1 @BASEBOARD_FAB2_LIB.BASEBOARD_FAB2(SCH_1):PVCCIO_CPU1    I33 @BASEBOARD_FAB2_LIB.BASEBOARD_FAB2(SCH_1):PAGE72
  BF23 PVCCIO_CPU1 @BASEBOARD_FAB2_LIB.BASEBOARD_FAB2(SCH_1):PVCCIO_CPU1    I33 @BASEBOARD_FAB2_LIB.BASEBOARD_FAB2(SCH_1):PAGE72
  BJ24 PVCCIO_CPU1 @BASEBOARD_FAB2_LIB.BASEBOARD_FAB2(SCH_1):PVCCIO_CPU1    I33 @BASEBOARD_FAB2_LIB.BASEBOARD_FAB2(SCH_1):PAGE72
  BP25 PVCCIO_CPU1 @BASEBOARD_FAB2_LIB.BASEBOARD_FAB2(SCH_1):PVCCIO_CPU1    I33 @BASEBOARD_FAB2_LIB.BASEBOARD_FAB2(SCH_1):PAGE72
  CB13 PVCCIO_CPU1 @BASEBOARD_FAB2_LIB.BASEBOARD_FAB2(SCH_1):PVCCIO_CPU1    I33 @BASEBOARD_FAB2_LIB.BASEBOARD_FAB2(SCH_1):PAGE72
  CB17 PVCCIO_CPU1 @BASEBOARD_FAB2_LIB.BASEBOARD_FAB2(SCH_1):PVCCIO_CPU1    I33 @BASEBOARD_FAB2_LIB.BASEBOARD_FAB2(SCH_1):PAGE72
   CD9 PVCCIO_CPU1 @BASEBOARD_FAB2_LIB.BASEBOARD_FAB2(SCH_1):PVCCIO_CPU1    I33 @BASEBOARD_FAB2_LIB.BASEBOARD_FAB2(SCH_1):PAGE72
  CE18 PVCCIO_CPU1 @BASEBOARD_FAB2_LIB.BASEBOARD_FAB2(SCH_1):PVCCIO_CPU1    I33 @BASEBOARD_FAB2_LIB.BASEBOARD_FAB2(SCH_1):PAGE72
    D7 PVCCIO_CPU1 @BASEBOARD_FAB2_LIB.BASEBOARD_FAB2(SCH_1):PVCCIO_CPU1    I33 @BASEBOARD_FAB2_LIB.BASEBOARD_FAB2(SCH_1):PAGE72
   CH9 PVCCIO_CPU1 @BASEBOARD_FAB2_LIB.BASEBOARD_FAB2(SCH_1):PVCCIO_CPU1    I33 @BASEBOARD_FAB2_LIB.BASEBOARD_FAB2(SCH_1):PAGE72
   CV7 PVCCIO_CPU1 @BASEBOARD_FAB2_LIB.BASEBOARD_FAB2(SCH_1):PVCCIO_CPU1    I33 @BASEBOARD_FAB2_LIB.BASEBOARD_FAB2(SCH_1):PAGE72
   CK5 PVCCIO_CPU1 @BASEBOARD_FAB2_LIB.BASEBOARD_FAB2(SCH_1):PVCCIO_CPU1    I33 @BASEBOARD_FAB2_LIB.BASEBOARD_FAB2(SCH_1):PAGE72
  CL12 PVCCIO_CPU1 @BASEBOARD_FAB2_LIB.BASEBOARD_FAB2(SCH_1):PVCCIO_CPU1    I33 @BASEBOARD_FAB2_LIB.BASEBOARD_FAB2(SCH_1):PAGE72
  CM15 PVCCIO_CPU1 @BASEBOARD_FAB2_LIB.BASEBOARD_FAB2(SCH_1):PVCCIO_CPU1    I33 @BASEBOARD_FAB2_LIB.BASEBOARD_FAB2(SCH_1):PAGE72
  CB65 PVSA_CPU1 @BASEBOARD_FAB2_LIB.BASEBOARD_FAB2(SCH_1):PVSA_CPU1    I33 @BASEBOARD_FAB2_LIB.BASEBOARD_FAB2(SCH_1):PAGE72
  CB67 PVSA_CPU1 @BASEBOARD_FAB2_LIB.BASEBOARD_FAB2(SCH_1):PVSA_CPU1    I33 @BASEBOARD_FAB2_LIB.BASEBOARD_FAB2(SCH_1):PAGE72
  CB69 PVSA_CPU1 @BASEBOARD_FAB2_LIB.BASEBOARD_FAB2(SCH_1):PVSA_CPU1    I33 @BASEBOARD_FAB2_LIB.BASEBOARD_FAB2(SCH_1):PAGE72
  CC66 PVSA_CPU1 @BASEBOARD_FAB2_LIB.BASEBOARD_FAB2(SCH_1):PVSA_CPU1    I33 @BASEBOARD_FAB2_LIB.BASEBOARD_FAB2(SCH_1):PAGE72
  CC68 PVSA_CPU1 @BASEBOARD_FAB2_LIB.BASEBOARD_FAB2(SCH_1):PVSA_CPU1    I33 @BASEBOARD_FAB2_LIB.BASEBOARD_FAB2(SCH_1):PAGE72
  CC70 PVSA_CPU1 @BASEBOARD_FAB2_LIB.BASEBOARD_FAB2(SCH_1):PVSA_CPU1    I33 @BASEBOARD_FAB2_LIB.BASEBOARD_FAB2(SCH_1):PAGE72
  CD65 PVSA_CPU1 @BASEBOARD_FAB2_LIB.BASEBOARD_FAB2(SCH_1):PVSA_CPU1    I33 @BASEBOARD_FAB2_LIB.BASEBOARD_FAB2(SCH_1):PAGE72
  CD67 PVSA_CPU1 @BASEBOARD_FAB2_LIB.BASEBOARD_FAB2(SCH_1):PVSA_CPU1    I33 @BASEBOARD_FAB2_LIB.BASEBOARD_FAB2(SCH_1):PAGE72
  CD69 PVSA_CPU1 @BASEBOARD_FAB2_LIB.BASEBOARD_FAB2(SCH_1):PVSA_CPU1    I33 @BASEBOARD_FAB2_LIB.BASEBOARD_FAB2(SCH_1):PAGE72
  CD71 PVSA_CPU1 @BASEBOARD_FAB2_LIB.BASEBOARD_FAB2(SCH_1):PVSA_CPU1    I33 @BASEBOARD_FAB2_LIB.BASEBOARD_FAB2(SCH_1):PAGE72
  CE64 PVSA_CPU1 @BASEBOARD_FAB2_LIB.BASEBOARD_FAB2(SCH_1):PVSA_CPU1    I33 @BASEBOARD_FAB2_LIB.BASEBOARD_FAB2(SCH_1):PAGE72
  CE66 PVSA_CPU1 @BASEBOARD_FAB2_LIB.BASEBOARD_FAB2(SCH_1):PVSA_CPU1    I33 @BASEBOARD_FAB2_LIB.BASEBOARD_FAB2(SCH_1):PAGE72
  CE68 PVSA_CPU1 @BASEBOARD_FAB2_LIB.BASEBOARD_FAB2(SCH_1):PVSA_CPU1    I33 @BASEBOARD_FAB2_LIB.BASEBOARD_FAB2(SCH_1):PAGE72
  CE72 PVSA_CPU1 @BASEBOARD_FAB2_LIB.BASEBOARD_FAB2(SCH_1):PVSA_CPU1    I33 @BASEBOARD_FAB2_LIB.BASEBOARD_FAB2(SCH_1):PAGE72
  CE74 PVSA_CPU1 @BASEBOARD_FAB2_LIB.BASEBOARD_FAB2(SCH_1):PVSA_CPU1    I33 @BASEBOARD_FAB2_LIB.BASEBOARD_FAB2(SCH_1):PAGE72
  CF65 PVSA_CPU1 @BASEBOARD_FAB2_LIB.BASEBOARD_FAB2(SCH_1):PVSA_CPU1    I33 @BASEBOARD_FAB2_LIB.BASEBOARD_FAB2(SCH_1):PAGE72
  CF67 PVSA_CPU1 @BASEBOARD_FAB2_LIB.BASEBOARD_FAB2(SCH_1):PVSA_CPU1    I33 @BASEBOARD_FAB2_LIB.BASEBOARD_FAB2(SCH_1):PAGE72
  CF73 PVSA_CPU1 @BASEBOARD_FAB2_LIB.BASEBOARD_FAB2(SCH_1):PVSA_CPU1    I33 @BASEBOARD_FAB2_LIB.BASEBOARD_FAB2(SCH_1):PAGE72
  CF75 PVSA_CPU1 @BASEBOARD_FAB2_LIB.BASEBOARD_FAB2(SCH_1):PVSA_CPU1    I33 @BASEBOARD_FAB2_LIB.BASEBOARD_FAB2(SCH_1):PAGE72
  CG64 PVSA_CPU1 @BASEBOARD_FAB2_LIB.BASEBOARD_FAB2(SCH_1):PVSA_CPU1    I33 @BASEBOARD_FAB2_LIB.BASEBOARD_FAB2(SCH_1):PAGE72
  CG66 PVSA_CPU1 @BASEBOARD_FAB2_LIB.BASEBOARD_FAB2(SCH_1):PVSA_CPU1    I33 @BASEBOARD_FAB2_LIB.BASEBOARD_FAB2(SCH_1):PAGE72
  CG74 PVSA_CPU1 @BASEBOARD_FAB2_LIB.BASEBOARD_FAB2(SCH_1):PVSA_CPU1    I33 @BASEBOARD_FAB2_LIB.BASEBOARD_FAB2(SCH_1):PAGE72
  CH65 PVSA_CPU1 @BASEBOARD_FAB2_LIB.BASEBOARD_FAB2(SCH_1):PVSA_CPU1    I33 @BASEBOARD_FAB2_LIB.BASEBOARD_FAB2(SCH_1):PAGE72
  CH75 PVSA_CPU1 @BASEBOARD_FAB2_LIB.BASEBOARD_FAB2(SCH_1):PVSA_CPU1    I33 @BASEBOARD_FAB2_LIB.BASEBOARD_FAB2(SCH_1):PAGE72
  CJ64 PVSA_CPU1 @BASEBOARD_FAB2_LIB.BASEBOARD_FAB2(SCH_1):PVSA_CPU1    I33 @BASEBOARD_FAB2_LIB.BASEBOARD_FAB2(SCH_1):PAGE72
  CJ66 PVSA_CPU1 @BASEBOARD_FAB2_LIB.BASEBOARD_FAB2(SCH_1):PVSA_CPU1    I33 @BASEBOARD_FAB2_LIB.BASEBOARD_FAB2(SCH_1):PAGE72
  BT17 VSENSE_PVCCIOMCP_CPU1_SKT_VSEN @BASEBOARD_FAB2_LIB.BASEBOARD_FAB2(SCH_1):VSENSE_PVCCIOMCP_CPU1_SKT_VSEN   I107 @BASEBOARD_FAB2_LIB.BASEBOARD_FAB2(SCH_1):PAGE73
  BU16 VSENSE_PVCCIOMCP_CPU1_SKT_VRTN @BASEBOARD_FAB2_LIB.BASEBOARD_FAB2(SCH_1):VSENSE_PVCCIOMCP_CPU1_SKT_VRTN   I107 @BASEBOARD_FAB2_LIB.BASEBOARD_FAB2(SCH_1):PAGE73
  BN16 VSENSE_PVCCMCP_CPU1_SKT_VSEN @BASEBOARD_FAB2_LIB.BASEBOARD_FAB2(SCH_1):VSENSE_PVCCMCP_CPU1_SKT_VSEN   I107 @BASEBOARD_FAB2_LIB.BASEBOARD_FAB2(SCH_1):PAGE73
  BL16 VSENSE_PVCCMCP_CPU1_SKT_VRTN @BASEBOARD_FAB2_LIB.BASEBOARD_FAB2(SCH_1):VSENSE_PVCCMCP_CPU1_SKT_VRTN   I107 @BASEBOARD_FAB2_LIB.BASEBOARD_FAB2(SCH_1):PAGE73
  CL26 PVCCMCP_CPU1 @BASEBOARD_FAB2_LIB.BASEBOARD_FAB2(SCH_1):PVCCMCP_CPU1   I107 @BASEBOARD_FAB2_LIB.BASEBOARD_FAB2(SCH_1):PAGE73
  CM23 PVCCMCP_CPU1 @BASEBOARD_FAB2_LIB.BASEBOARD_FAB2(SCH_1):PVCCMCP_CPU1   I107 @BASEBOARD_FAB2_LIB.BASEBOARD_FAB2(SCH_1):PAGE73
  CM25 PVCCMCP_CPU1 @BASEBOARD_FAB2_LIB.BASEBOARD_FAB2(SCH_1):PVCCMCP_CPU1   I107 @BASEBOARD_FAB2_LIB.BASEBOARD_FAB2(SCH_1):PAGE73
  CN22 TP_CPU1_KTI2_AMONV @BASEBOARD_FAB2_LIB.BASEBOARD_FAB2(SCH_1):TP_CPU1_KTI2_AMONV   I107 @BASEBOARD_FAB2_LIB.BASEBOARD_FAB2(SCH_1):PAGE73
  CN24 PVCCMCP_CPU1 @BASEBOARD_FAB2_LIB.BASEBOARD_FAB2(SCH_1):PVCCMCP_CPU1   I107 @BASEBOARD_FAB2_LIB.BASEBOARD_FAB2(SCH_1):PAGE73
  CN28 PD_CPU1_MCP01_DMON @BASEBOARD_FAB2_LIB.BASEBOARD_FAB2(SCH_1):PD_CPU1_MCP01_DMON   I107 @BASEBOARD_FAB2_LIB.BASEBOARD_FAB2(SCH_1):PAGE73
  CP23 PVCCMCP_CPU1 @BASEBOARD_FAB2_LIB.BASEBOARD_FAB2(SCH_1):PVCCMCP_CPU1   I107 @BASEBOARD_FAB2_LIB.BASEBOARD_FAB2(SCH_1):PAGE73
  CP31 TP_CPU1_RSVD_73 @BASEBOARD_FAB2_LIB.BASEBOARD_FAB2(SCH_1):TP_CPU1_RSVD_73   I107 @BASEBOARD_FAB2_LIB.BASEBOARD_FAB2(SCH_1):PAGE73
  CR60 TP_CPU1_RSVD_72 @BASEBOARD_FAB2_LIB.BASEBOARD_FAB2(SCH_1):TP_CPU1_RSVD_72   I107 @BASEBOARD_FAB2_LIB.BASEBOARD_FAB2(SCH_1):PAGE73
  CT23 PVCCMCP_CPU1 @BASEBOARD_FAB2_LIB.BASEBOARD_FAB2(SCH_1):PVCCMCP_CPU1   I107 @BASEBOARD_FAB2_LIB.BASEBOARD_FAB2(SCH_1):PAGE73
   CT5 TP_CPU1_RSVD_70 @BASEBOARD_FAB2_LIB.BASEBOARD_FAB2(SCH_1):TP_CPU1_RSVD_70   I107 @BASEBOARD_FAB2_LIB.BASEBOARD_FAB2(SCH_1):PAGE73
  CT69 TP_CPU1_RSVD_69 @BASEBOARD_FAB2_LIB.BASEBOARD_FAB2(SCH_1):TP_CPU1_RSVD_69   I107 @BASEBOARD_FAB2_LIB.BASEBOARD_FAB2(SCH_1):PAGE73
  CU24 PVCCMCP_CPU1 @BASEBOARD_FAB2_LIB.BASEBOARD_FAB2(SCH_1):PVCCMCP_CPU1   I107 @BASEBOARD_FAB2_LIB.BASEBOARD_FAB2(SCH_1):PAGE73
   CU6 TP_CPU1_RSVD_67 @BASEBOARD_FAB2_LIB.BASEBOARD_FAB2(SCH_1):TP_CPU1_RSVD_67   I107 @BASEBOARD_FAB2_LIB.BASEBOARD_FAB2(SCH_1):PAGE73
  CU60 TP_CPU1_RSVD_66 @BASEBOARD_FAB2_LIB.BASEBOARD_FAB2(SCH_1):TP_CPU1_RSVD_66   I107 @BASEBOARD_FAB2_LIB.BASEBOARD_FAB2(SCH_1):PAGE73
  CV23 PVCCMCP_CPU1 @BASEBOARD_FAB2_LIB.BASEBOARD_FAB2(SCH_1):PVCCMCP_CPU1   I107 @BASEBOARD_FAB2_LIB.BASEBOARD_FAB2(SCH_1):PAGE73
  CV69 TP_CPU1_RSVD_64 @BASEBOARD_FAB2_LIB.BASEBOARD_FAB2(SCH_1):TP_CPU1_RSVD_64   I107 @BASEBOARD_FAB2_LIB.BASEBOARD_FAB2(SCH_1):PAGE73
  CW22 TP_CPU1_KTI2_DFX_DN @BASEBOARD_FAB2_LIB.BASEBOARD_FAB2(SCH_1):TP_CPU1_KTI2_DFX_DN   I107 @BASEBOARD_FAB2_LIB.BASEBOARD_FAB2(SCH_1):PAGE73
  CW24 PVCCMCP_CPU1 @BASEBOARD_FAB2_LIB.BASEBOARD_FAB2(SCH_1):PVCCMCP_CPU1   I107 @BASEBOARD_FAB2_LIB.BASEBOARD_FAB2(SCH_1):PAGE73
  CW60 TP_CPU1_RSVD_61 @BASEBOARD_FAB2_LIB.BASEBOARD_FAB2(SCH_1):TP_CPU1_RSVD_61   I107 @BASEBOARD_FAB2_LIB.BASEBOARD_FAB2(SCH_1):PAGE73
  CW62 TP_CPU1_RSVD_60 @BASEBOARD_FAB2_LIB.BASEBOARD_FAB2(SCH_1):TP_CPU1_RSVD_60   I107 @BASEBOARD_FAB2_LIB.BASEBOARD_FAB2(SCH_1):PAGE73
  CY23 TP_CPU1_RSVD_59 @BASEBOARD_FAB2_LIB.BASEBOARD_FAB2(SCH_1):TP_CPU1_RSVD_59   I107 @BASEBOARD_FAB2_LIB.BASEBOARD_FAB2(SCH_1):PAGE73
  CY25 PVCCMCP_CPU1 @BASEBOARD_FAB2_LIB.BASEBOARD_FAB2(SCH_1):PVCCMCP_CPU1   I107 @BASEBOARD_FAB2_LIB.BASEBOARD_FAB2(SCH_1):PAGE73
  CY39 TP_CPU1_RSVD_57 @BASEBOARD_FAB2_LIB.BASEBOARD_FAB2(SCH_1):TP_CPU1_RSVD_57   I107 @BASEBOARD_FAB2_LIB.BASEBOARD_FAB2(SCH_1):PAGE73
  CY53 TP_CPU1_RSVD_56 @BASEBOARD_FAB2_LIB.BASEBOARD_FAB2(SCH_1):TP_CPU1_RSVD_56   I107 @BASEBOARD_FAB2_LIB.BASEBOARD_FAB2(SCH_1):PAGE73
  CY57 TP_CPU1_RSVD_55 @BASEBOARD_FAB2_LIB.BASEBOARD_FAB2(SCH_1):TP_CPU1_RSVD_55   I107 @BASEBOARD_FAB2_LIB.BASEBOARD_FAB2(SCH_1):PAGE73
  CY63 TP_CPU1_RSVD_54 @BASEBOARD_FAB2_LIB.BASEBOARD_FAB2(SCH_1):TP_CPU1_RSVD_54   I107 @BASEBOARD_FAB2_LIB.BASEBOARD_FAB2(SCH_1):PAGE73
  CY73 TP_CPU1_RSVD_53 @BASEBOARD_FAB2_LIB.BASEBOARD_FAB2(SCH_1):TP_CPU1_RSVD_53   I107 @BASEBOARD_FAB2_LIB.BASEBOARD_FAB2(SCH_1):PAGE73
  DA24 PVCCMCP_CPU1 @BASEBOARD_FAB2_LIB.BASEBOARD_FAB2(SCH_1):PVCCMCP_CPU1   I107 @BASEBOARD_FAB2_LIB.BASEBOARD_FAB2(SCH_1):PAGE73
  DA40 TP_CPU1_RSVD_51 @BASEBOARD_FAB2_LIB.BASEBOARD_FAB2(SCH_1):TP_CPU1_RSVD_51   I107 @BASEBOARD_FAB2_LIB.BASEBOARD_FAB2(SCH_1):PAGE73
  DA52 TP_CPU1_RSVD_50 @BASEBOARD_FAB2_LIB.BASEBOARD_FAB2(SCH_1):TP_CPU1_RSVD_50   I107 @BASEBOARD_FAB2_LIB.BASEBOARD_FAB2(SCH_1):PAGE73
  DA54 TP_CPU1_RSVD_49 @BASEBOARD_FAB2_LIB.BASEBOARD_FAB2(SCH_1):TP_CPU1_RSVD_49   I107 @BASEBOARD_FAB2_LIB.BASEBOARD_FAB2(SCH_1):PAGE73
  DA56 TP_CPU1_RSVD_48 @BASEBOARD_FAB2_LIB.BASEBOARD_FAB2(SCH_1):TP_CPU1_RSVD_48   I107 @BASEBOARD_FAB2_LIB.BASEBOARD_FAB2(SCH_1):PAGE73
  DC46 TP_CPU1_RSVD_47 @BASEBOARD_FAB2_LIB.BASEBOARD_FAB2(SCH_1):TP_CPU1_RSVD_47   I107 @BASEBOARD_FAB2_LIB.BASEBOARD_FAB2(SCH_1):PAGE73
  DC52 TP_CPU1_RSVD_46 @BASEBOARD_FAB2_LIB.BASEBOARD_FAB2(SCH_1):TP_CPU1_RSVD_46   I107 @BASEBOARD_FAB2_LIB.BASEBOARD_FAB2(SCH_1):PAGE73
  DD51 TP_CPU1_RSVD_45 @BASEBOARD_FAB2_LIB.BASEBOARD_FAB2(SCH_1):TP_CPU1_RSVD_45   I107 @BASEBOARD_FAB2_LIB.BASEBOARD_FAB2(SCH_1):PAGE73
  DG36 TP_CPU1_RSVD_44 @BASEBOARD_FAB2_LIB.BASEBOARD_FAB2(SCH_1):TP_CPU1_RSVD_44   I107 @BASEBOARD_FAB2_LIB.BASEBOARD_FAB2(SCH_1):PAGE73
  DG64 TP_CPU1_RSVD_43 @BASEBOARD_FAB2_LIB.BASEBOARD_FAB2(SCH_1):TP_CPU1_RSVD_43   I107 @BASEBOARD_FAB2_LIB.BASEBOARD_FAB2(SCH_1):PAGE73
  DH65 TP_CPU1_RSVD_42 @BASEBOARD_FAB2_LIB.BASEBOARD_FAB2(SCH_1):TP_CPU1_RSVD_42   I107 @BASEBOARD_FAB2_LIB.BASEBOARD_FAB2(SCH_1):PAGE73
  DJ36 TP_CPU1_RSVD_41 @BASEBOARD_FAB2_LIB.BASEBOARD_FAB2(SCH_1):TP_CPU1_RSVD_41   I107 @BASEBOARD_FAB2_LIB.BASEBOARD_FAB2(SCH_1):PAGE73
  DJ66 TP_CPU1_RSVD_40 @BASEBOARD_FAB2_LIB.BASEBOARD_FAB2(SCH_1):TP_CPU1_RSVD_40   I107 @BASEBOARD_FAB2_LIB.BASEBOARD_FAB2(SCH_1):PAGE73
  DK15 TP_CPU1_RSVD_39 @BASEBOARD_FAB2_LIB.BASEBOARD_FAB2(SCH_1):TP_CPU1_RSVD_39   I107 @BASEBOARD_FAB2_LIB.BASEBOARD_FAB2(SCH_1):PAGE73
  DK37 TP_CPU1_RSVD_38 @BASEBOARD_FAB2_LIB.BASEBOARD_FAB2(SCH_1):TP_CPU1_RSVD_38   I107 @BASEBOARD_FAB2_LIB.BASEBOARD_FAB2(SCH_1):PAGE73
  DK65 TP_CPU1_RSVD_37 @BASEBOARD_FAB2_LIB.BASEBOARD_FAB2(SCH_1):TP_CPU1_RSVD_37   I107 @BASEBOARD_FAB2_LIB.BASEBOARD_FAB2(SCH_1):PAGE73
  DK67 TP_CPU1_RSVD_36 @BASEBOARD_FAB2_LIB.BASEBOARD_FAB2(SCH_1):TP_CPU1_RSVD_36   I107 @BASEBOARD_FAB2_LIB.BASEBOARD_FAB2(SCH_1):PAGE73
  DL38 TP_CPU1_RSVD_35 @BASEBOARD_FAB2_LIB.BASEBOARD_FAB2(SCH_1):TP_CPU1_RSVD_35   I107 @BASEBOARD_FAB2_LIB.BASEBOARD_FAB2(SCH_1):PAGE73
  DL66 TP_CPU1_RSVD_34 @BASEBOARD_FAB2_LIB.BASEBOARD_FAB2(SCH_1):TP_CPU1_RSVD_34   I107 @BASEBOARD_FAB2_LIB.BASEBOARD_FAB2(SCH_1):PAGE73
  DM67 TP_CPU1_RSVD_33 @BASEBOARD_FAB2_LIB.BASEBOARD_FAB2(SCH_1):TP_CPU1_RSVD_33   I107 @BASEBOARD_FAB2_LIB.BASEBOARD_FAB2(SCH_1):PAGE73
  DN62 TP_CPU1_RSVD_32 @BASEBOARD_FAB2_LIB.BASEBOARD_FAB2(SCH_1):TP_CPU1_RSVD_32   I107 @BASEBOARD_FAB2_LIB.BASEBOARD_FAB2(SCH_1):PAGE73
  DN66 TP_CPU1_RSVD_31 @BASEBOARD_FAB2_LIB.BASEBOARD_FAB2(SCH_1):TP_CPU1_RSVD_31   I107 @BASEBOARD_FAB2_LIB.BASEBOARD_FAB2(SCH_1):PAGE73
  DP17 TP_CPU1_RSVD_30 @BASEBOARD_FAB2_LIB.BASEBOARD_FAB2(SCH_1):TP_CPU1_RSVD_30   I107 @BASEBOARD_FAB2_LIB.BASEBOARD_FAB2(SCH_1):PAGE73
  DP65 TP_CPU1_RSVD_29 @BASEBOARD_FAB2_LIB.BASEBOARD_FAB2(SCH_1):TP_CPU1_RSVD_29   I107 @BASEBOARD_FAB2_LIB.BASEBOARD_FAB2(SCH_1):PAGE73
  DR44 TP_CPU1_RSVD_28 @BASEBOARD_FAB2_LIB.BASEBOARD_FAB2(SCH_1):TP_CPU1_RSVD_28   I107 @BASEBOARD_FAB2_LIB.BASEBOARD_FAB2(SCH_1):PAGE73
  DT71 TP_CPU1_RSVD_27 @BASEBOARD_FAB2_LIB.BASEBOARD_FAB2(SCH_1):TP_CPU1_RSVD_27   I107 @BASEBOARD_FAB2_LIB.BASEBOARD_FAB2(SCH_1):PAGE73
  DU44 TP_CPU1_RSVD_26 @BASEBOARD_FAB2_LIB.BASEBOARD_FAB2(SCH_1):TP_CPU1_RSVD_26   I107 @BASEBOARD_FAB2_LIB.BASEBOARD_FAB2(SCH_1):PAGE73
  DV61 TP_CPU1_RSVD_25 @BASEBOARD_FAB2_LIB.BASEBOARD_FAB2(SCH_1):TP_CPU1_RSVD_25   I107 @BASEBOARD_FAB2_LIB.BASEBOARD_FAB2(SCH_1):PAGE73
  DV71 TP_CPU1_RSVD_24 @BASEBOARD_FAB2_LIB.BASEBOARD_FAB2(SCH_1):TP_CPU1_RSVD_24   I107 @BASEBOARD_FAB2_LIB.BASEBOARD_FAB2(SCH_1):PAGE73
  DW44 TP_CPU1_RSVD_23 @BASEBOARD_FAB2_LIB.BASEBOARD_FAB2(SCH_1):TP_CPU1_RSVD_23   I107 @BASEBOARD_FAB2_LIB.BASEBOARD_FAB2(SCH_1):PAGE73
  DW46 TP_CPU1_RSVD_22 @BASEBOARD_FAB2_LIB.BASEBOARD_FAB2(SCH_1):TP_CPU1_RSVD_22   I107 @BASEBOARD_FAB2_LIB.BASEBOARD_FAB2(SCH_1):PAGE73
   DY3 TP_CPU1_RSVD_21 @BASEBOARD_FAB2_LIB.BASEBOARD_FAB2(SCH_1):TP_CPU1_RSVD_21   I107 @BASEBOARD_FAB2_LIB.BASEBOARD_FAB2(SCH_1):PAGE73
   EA4 TP_CPU1_RSVD_20 @BASEBOARD_FAB2_LIB.BASEBOARD_FAB2(SCH_1):TP_CPU1_RSVD_20   I107 @BASEBOARD_FAB2_LIB.BASEBOARD_FAB2(SCH_1):PAGE73
  EA44 TP_CPU1_RSVD_19 @BASEBOARD_FAB2_LIB.BASEBOARD_FAB2(SCH_1):TP_CPU1_RSVD_19   I107 @BASEBOARD_FAB2_LIB.BASEBOARD_FAB2(SCH_1):PAGE73
   EB3 TP_CPU1_RSVD_18 @BASEBOARD_FAB2_LIB.BASEBOARD_FAB2(SCH_1):TP_CPU1_RSVD_18   I107 @BASEBOARD_FAB2_LIB.BASEBOARD_FAB2(SCH_1):PAGE73
   EB5 TP_CPU1_RSVD_17 @BASEBOARD_FAB2_LIB.BASEBOARD_FAB2(SCH_1):TP_CPU1_RSVD_17   I107 @BASEBOARD_FAB2_LIB.BASEBOARD_FAB2(SCH_1):PAGE73
  EB85 TP_CPU1_RSVD_16 @BASEBOARD_FAB2_LIB.BASEBOARD_FAB2(SCH_1):TP_CPU1_RSVD_16   I107 @BASEBOARD_FAB2_LIB.BASEBOARD_FAB2(SCH_1):PAGE73
  EC16 TP_CPU1_RSVD_15 @BASEBOARD_FAB2_LIB.BASEBOARD_FAB2(SCH_1):TP_CPU1_RSVD_15   I107 @BASEBOARD_FAB2_LIB.BASEBOARD_FAB2(SCH_1):PAGE73
   EC4 TP_CPU1_RSVD_14 @BASEBOARD_FAB2_LIB.BASEBOARD_FAB2(SCH_1):TP_CPU1_RSVD_14   I107 @BASEBOARD_FAB2_LIB.BASEBOARD_FAB2(SCH_1):PAGE73
  EC44 TP_CPU1_RSVD_13 @BASEBOARD_FAB2_LIB.BASEBOARD_FAB2(SCH_1):TP_CPU1_RSVD_13   I107 @BASEBOARD_FAB2_LIB.BASEBOARD_FAB2(SCH_1):PAGE73
  EC84 TP_CPU1_RSVD_12 @BASEBOARD_FAB2_LIB.BASEBOARD_FAB2(SCH_1):TP_CPU1_RSVD_12   I107 @BASEBOARD_FAB2_LIB.BASEBOARD_FAB2(SCH_1):PAGE73
  ED45 TP_CPU1_RSVD_11 @BASEBOARD_FAB2_LIB.BASEBOARD_FAB2(SCH_1):TP_CPU1_RSVD_11   I107 @BASEBOARD_FAB2_LIB.BASEBOARD_FAB2(SCH_1):PAGE73
   ED5 TP_CPU1_RSVD_10 @BASEBOARD_FAB2_LIB.BASEBOARD_FAB2(SCH_1):TP_CPU1_RSVD_10   I107 @BASEBOARD_FAB2_LIB.BASEBOARD_FAB2(SCH_1):PAGE73
  ED83 TP_CPU1_RSVD_9 @BASEBOARD_FAB2_LIB.BASEBOARD_FAB2(SCH_1):TP_CPU1_RSVD_9   I107 @BASEBOARD_FAB2_LIB.BASEBOARD_FAB2(SCH_1):PAGE73
  EE16 TP_CPU1_RSVD_8 @BASEBOARD_FAB2_LIB.BASEBOARD_FAB2(SCH_1):TP_CPU1_RSVD_8   I107 @BASEBOARD_FAB2_LIB.BASEBOARD_FAB2(SCH_1):PAGE73
  EE46 TP_CPU1_RSVD_7 @BASEBOARD_FAB2_LIB.BASEBOARD_FAB2(SCH_1):TP_CPU1_RSVD_7   I107 @BASEBOARD_FAB2_LIB.BASEBOARD_FAB2(SCH_1):PAGE73
   EE6 TP_CPU1_RSVD_6 @BASEBOARD_FAB2_LIB.BASEBOARD_FAB2(SCH_1):TP_CPU1_RSVD_6   I107 @BASEBOARD_FAB2_LIB.BASEBOARD_FAB2(SCH_1):PAGE73
  EE82 TP_CPU1_RSVD_5 @BASEBOARD_FAB2_LIB.BASEBOARD_FAB2(SCH_1):TP_CPU1_RSVD_5   I107 @BASEBOARD_FAB2_LIB.BASEBOARD_FAB2(SCH_1):PAGE73
  EE84 TP_CPU1_RSVD_4 @BASEBOARD_FAB2_LIB.BASEBOARD_FAB2(SCH_1):TP_CPU1_RSVD_4   I107 @BASEBOARD_FAB2_LIB.BASEBOARD_FAB2(SCH_1):PAGE73
  EF47 TP_CPU1_RSVD_3 @BASEBOARD_FAB2_LIB.BASEBOARD_FAB2(SCH_1):TP_CPU1_RSVD_3   I107 @BASEBOARD_FAB2_LIB.BASEBOARD_FAB2(SCH_1):PAGE73
  EF77 TP_CPU1_RSVD_2 @BASEBOARD_FAB2_LIB.BASEBOARD_FAB2(SCH_1):TP_CPU1_RSVD_2   I107 @BASEBOARD_FAB2_LIB.BASEBOARD_FAB2(SCH_1):PAGE73
  EF81 TP_CPU1_RSVD_1 @BASEBOARD_FAB2_LIB.BASEBOARD_FAB2(SCH_1):TP_CPU1_RSVD_1   I107 @BASEBOARD_FAB2_LIB.BASEBOARD_FAB2(SCH_1):PAGE73
  EF83 TP_CPU1_RSVD_0 @BASEBOARD_FAB2_LIB.BASEBOARD_FAB2(SCH_1):TP_CPU1_RSVD_0   I107 @BASEBOARD_FAB2_LIB.BASEBOARD_FAB2(SCH_1):PAGE73
   CN6 PVCCIO_CPU1 @BASEBOARD_FAB2_LIB.BASEBOARD_FAB2(SCH_1):PVCCIO_CPU1   I107 @BASEBOARD_FAB2_LIB.BASEBOARD_FAB2(SCH_1):PAGE73
  CU12 PVCCIO_CPU1 @BASEBOARD_FAB2_LIB.BASEBOARD_FAB2(SCH_1):PVCCIO_CPU1   I107 @BASEBOARD_FAB2_LIB.BASEBOARD_FAB2(SCH_1):PAGE73
  CV21 PVCCIO_CPU1 @BASEBOARD_FAB2_LIB.BASEBOARD_FAB2(SCH_1):PVCCIO_CPU1   I107 @BASEBOARD_FAB2_LIB.BASEBOARD_FAB2(SCH_1):PAGE73
  CU18 PVCCIO_CPU1 @BASEBOARD_FAB2_LIB.BASEBOARD_FAB2(SCH_1):PVCCIO_CPU1   I107 @BASEBOARD_FAB2_LIB.BASEBOARD_FAB2(SCH_1):PAGE73
  CY17 PVCCIO_CPU1 @BASEBOARD_FAB2_LIB.BASEBOARD_FAB2(SCH_1):PVCCIO_CPU1   I107 @BASEBOARD_FAB2_LIB.BASEBOARD_FAB2(SCH_1):PAGE73
  DC18 PVCCIO_CPU1 @BASEBOARD_FAB2_LIB.BASEBOARD_FAB2(SCH_1):PVCCIO_CPU1   I107 @BASEBOARD_FAB2_LIB.BASEBOARD_FAB2(SCH_1):PAGE73
  DE14 PVCCIO_CPU1 @BASEBOARD_FAB2_LIB.BASEBOARD_FAB2(SCH_1):PVCCIO_CPU1   I107 @BASEBOARD_FAB2_LIB.BASEBOARD_FAB2(SCH_1):PAGE73
  CP13 PVCCIO_CPU1 @BASEBOARD_FAB2_LIB.BASEBOARD_FAB2(SCH_1):PVCCIO_CPU1   I107 @BASEBOARD_FAB2_LIB.BASEBOARD_FAB2(SCH_1):PAGE73
  CL20 PVCCIO_CPU1 @BASEBOARD_FAB2_LIB.BASEBOARD_FAB2(SCH_1):PVCCIO_CPU1   I107 @BASEBOARD_FAB2_LIB.BASEBOARD_FAB2(SCH_1):PAGE73
  CG14 PVCCIO_CPU1 @BASEBOARD_FAB2_LIB.BASEBOARD_FAB2(SCH_1):PVCCIO_CPU1   I107 @BASEBOARD_FAB2_LIB.BASEBOARD_FAB2(SCH_1):PAGE73
   CF5 PVCCIO_CPU1 @BASEBOARD_FAB2_LIB.BASEBOARD_FAB2(SCH_1):PVCCIO_CPU1   I107 @BASEBOARD_FAB2_LIB.BASEBOARD_FAB2(SCH_1):PAGE73
  DK21 PVCCIO_CPU1 @BASEBOARD_FAB2_LIB.BASEBOARD_FAB2(SCH_1):PVCCIO_CPU1   I107 @BASEBOARD_FAB2_LIB.BASEBOARD_FAB2(SCH_1):PAGE73
  BE24 PVCCIO_CPU1 @BASEBOARD_FAB2_LIB.BASEBOARD_FAB2(SCH_1):PVCCIO_CPU1   I107 @BASEBOARD_FAB2_LIB.BASEBOARD_FAB2(SCH_1):PAGE73
   AT7 PVCCIO_CPU1 @BASEBOARD_FAB2_LIB.BASEBOARD_FAB2(SCH_1):PVCCIO_CPU1   I107 @BASEBOARD_FAB2_LIB.BASEBOARD_FAB2(SCH_1):PAGE73
   AT5 PVCCIO_CPU1 @BASEBOARD_FAB2_LIB.BASEBOARD_FAB2(SCH_1):PVCCIO_CPU1   I107 @BASEBOARD_FAB2_LIB.BASEBOARD_FAB2(SCH_1):PAGE73
   AM5 PVCCIO_CPU1 @BASEBOARD_FAB2_LIB.BASEBOARD_FAB2(SCH_1):PVCCIO_CPU1   I107 @BASEBOARD_FAB2_LIB.BASEBOARD_FAB2(SCH_1):PAGE73
  DV11 PVCCIO_CPU1 @BASEBOARD_FAB2_LIB.BASEBOARD_FAB2(SCH_1):PVCCIO_CPU1   I107 @BASEBOARD_FAB2_LIB.BASEBOARD_FAB2(SCH_1):PAGE73
   AF5 PVCCIO_CPU1 @BASEBOARD_FAB2_LIB.BASEBOARD_FAB2(SCH_1):PVCCIO_CPU1   I107 @BASEBOARD_FAB2_LIB.BASEBOARD_FAB2(SCH_1):PAGE73
  AE10 PVCCIO_CPU1 @BASEBOARD_FAB2_LIB.BASEBOARD_FAB2(SCH_1):PVCCIO_CPU1   I107 @BASEBOARD_FAB2_LIB.BASEBOARD_FAB2(SCH_1):PAGE73
  EE10 PVCCIO_CPU1 @BASEBOARD_FAB2_LIB.BASEBOARD_FAB2(SCH_1):PVCCIO_CPU1   I107 @BASEBOARD_FAB2_LIB.BASEBOARD_FAB2(SCH_1):PAGE73
   BH5 VSENSE_PVCCIO_CPU1_SKT_VSEN @BASEBOARD_FAB2_LIB.BASEBOARD_FAB2(SCH_1):VSENSE_PVCCIO_CPU1_SKT_VSEN   I107 @BASEBOARD_FAB2_LIB.BASEBOARD_FAB2(SCH_1):PAGE73
  CE76 VSENSE_PVSA_CPU1_SKT_VSEN @BASEBOARD_FAB2_LIB.BASEBOARD_FAB2(SCH_1):VSENSE_PVSA_CPU1_SKT_VSEN   I107 @BASEBOARD_FAB2_LIB.BASEBOARD_FAB2(SCH_1):PAGE73
   BF5 VSENSE_PVCCIO_CPU1_SKT_VRTN @BASEBOARD_FAB2_LIB.BASEBOARD_FAB2(SCH_1):VSENSE_PVCCIO_CPU1_SKT_VRTN   I107 @BASEBOARD_FAB2_LIB.BASEBOARD_FAB2(SCH_1):PAGE73
  CG76 VSENSE_PVSA_CPU1_SKT_VRTN @BASEBOARD_FAB2_LIB.BASEBOARD_FAB2(SCH_1):VSENSE_PVSA_CPU1_SKT_VRTN   I107 @BASEBOARD_FAB2_LIB.BASEBOARD_FAB2(SCH_1):PAGE73
    B9    GND @BASEBOARD_FAB2_LIB.BASEBOARD_FAB2(SCH_1):GND    I20 @BASEBOARD_FAB2_LIB.BASEBOARD_FAB2(SCH_1):PAGE74
   A42    GND @BASEBOARD_FAB2_LIB.BASEBOARD_FAB2(SCH_1):GND    I20 @BASEBOARD_FAB2_LIB.BASEBOARD_FAB2(SCH_1):PAGE74
   B43    GND @BASEBOARD_FAB2_LIB.BASEBOARD_FAB2(SCH_1):GND    I20 @BASEBOARD_FAB2_LIB.BASEBOARD_FAB2(SCH_1):PAGE74
    B5    GND @BASEBOARD_FAB2_LIB.BASEBOARD_FAB2(SCH_1):GND    I20 @BASEBOARD_FAB2_LIB.BASEBOARD_FAB2(SCH_1):PAGE74
   B79    GND @BASEBOARD_FAB2_LIB.BASEBOARD_FAB2(SCH_1):GND    I20 @BASEBOARD_FAB2_LIB.BASEBOARD_FAB2(SCH_1):PAGE74
    C4    GND @BASEBOARD_FAB2_LIB.BASEBOARD_FAB2(SCH_1):GND    I20 @BASEBOARD_FAB2_LIB.BASEBOARD_FAB2(SCH_1):PAGE74
   C80    GND @BASEBOARD_FAB2_LIB.BASEBOARD_FAB2(SCH_1):GND    I20 @BASEBOARD_FAB2_LIB.BASEBOARD_FAB2(SCH_1):PAGE74
    D3    GND @BASEBOARD_FAB2_LIB.BASEBOARD_FAB2(SCH_1):GND    I20 @BASEBOARD_FAB2_LIB.BASEBOARD_FAB2(SCH_1):PAGE74
   D81    GND @BASEBOARD_FAB2_LIB.BASEBOARD_FAB2(SCH_1):GND    I20 @BASEBOARD_FAB2_LIB.BASEBOARD_FAB2(SCH_1):PAGE74
   E82    GND @BASEBOARD_FAB2_LIB.BASEBOARD_FAB2(SCH_1):GND    I20 @BASEBOARD_FAB2_LIB.BASEBOARD_FAB2(SCH_1):PAGE74
   J86    GND @BASEBOARD_FAB2_LIB.BASEBOARD_FAB2(SCH_1):GND    I20 @BASEBOARD_FAB2_LIB.BASEBOARD_FAB2(SCH_1):PAGE74
  DY85    GND @BASEBOARD_FAB2_LIB.BASEBOARD_FAB2(SCH_1):GND    I20 @BASEBOARD_FAB2_LIB.BASEBOARD_FAB2(SCH_1):PAGE74
  EA84    GND @BASEBOARD_FAB2_LIB.BASEBOARD_FAB2(SCH_1):GND    I20 @BASEBOARD_FAB2_LIB.BASEBOARD_FAB2(SCH_1):PAGE74
  EB83    GND @BASEBOARD_FAB2_LIB.BASEBOARD_FAB2(SCH_1):GND    I20 @BASEBOARD_FAB2_LIB.BASEBOARD_FAB2(SCH_1):PAGE74
   DW2    GND @BASEBOARD_FAB2_LIB.BASEBOARD_FAB2(SCH_1):GND    I20 @BASEBOARD_FAB2_LIB.BASEBOARD_FAB2(SCH_1):PAGE74
  EC42    GND @BASEBOARD_FAB2_LIB.BASEBOARD_FAB2(SCH_1):GND    I20 @BASEBOARD_FAB2_LIB.BASEBOARD_FAB2(SCH_1):PAGE74
   EC6    GND @BASEBOARD_FAB2_LIB.BASEBOARD_FAB2(SCH_1):GND    I20 @BASEBOARD_FAB2_LIB.BASEBOARD_FAB2(SCH_1):PAGE74
  EC82    GND @BASEBOARD_FAB2_LIB.BASEBOARD_FAB2(SCH_1):GND    I20 @BASEBOARD_FAB2_LIB.BASEBOARD_FAB2(SCH_1):PAGE74
  ED41    GND @BASEBOARD_FAB2_LIB.BASEBOARD_FAB2(SCH_1):GND    I20 @BASEBOARD_FAB2_LIB.BASEBOARD_FAB2(SCH_1):PAGE74
   ED7    GND @BASEBOARD_FAB2_LIB.BASEBOARD_FAB2(SCH_1):GND    I20 @BASEBOARD_FAB2_LIB.BASEBOARD_FAB2(SCH_1):PAGE74
  ED81    GND @BASEBOARD_FAB2_LIB.BASEBOARD_FAB2(SCH_1):GND    I20 @BASEBOARD_FAB2_LIB.BASEBOARD_FAB2(SCH_1):PAGE74
  EE40    GND @BASEBOARD_FAB2_LIB.BASEBOARD_FAB2(SCH_1):GND    I20 @BASEBOARD_FAB2_LIB.BASEBOARD_FAB2(SCH_1):PAGE74
   EE8    GND @BASEBOARD_FAB2_LIB.BASEBOARD_FAB2(SCH_1):GND    I20 @BASEBOARD_FAB2_LIB.BASEBOARD_FAB2(SCH_1):PAGE74
  EE80    GND @BASEBOARD_FAB2_LIB.BASEBOARD_FAB2(SCH_1):GND    I20 @BASEBOARD_FAB2_LIB.BASEBOARD_FAB2(SCH_1):PAGE74
  ED69    GND @BASEBOARD_FAB2_LIB.BASEBOARD_FAB2(SCH_1):GND    I20 @BASEBOARD_FAB2_LIB.BASEBOARD_FAB2(SCH_1):PAGE74
   E66    GND @BASEBOARD_FAB2_LIB.BASEBOARD_FAB2(SCH_1):GND    I20 @BASEBOARD_FAB2_LIB.BASEBOARD_FAB2(SCH_1):PAGE74
   V11    GND @BASEBOARD_FAB2_LIB.BASEBOARD_FAB2(SCH_1):GND    I20 @BASEBOARD_FAB2_LIB.BASEBOARD_FAB2(SCH_1):PAGE74
    L8    GND @BASEBOARD_FAB2_LIB.BASEBOARD_FAB2(SCH_1):GND    I20 @BASEBOARD_FAB2_LIB.BASEBOARD_FAB2(SCH_1):PAGE74
  EA14    GND @BASEBOARD_FAB2_LIB.BASEBOARD_FAB2(SCH_1):GND    I20 @BASEBOARD_FAB2_LIB.BASEBOARD_FAB2(SCH_1):PAGE74
  DY63    GND @BASEBOARD_FAB2_LIB.BASEBOARD_FAB2(SCH_1):GND    I20 @BASEBOARD_FAB2_LIB.BASEBOARD_FAB2(SCH_1):PAGE74
  DY61    GND @BASEBOARD_FAB2_LIB.BASEBOARD_FAB2(SCH_1):GND    I20 @BASEBOARD_FAB2_LIB.BASEBOARD_FAB2(SCH_1):PAGE74
  DY59    GND @BASEBOARD_FAB2_LIB.BASEBOARD_FAB2(SCH_1):GND    I20 @BASEBOARD_FAB2_LIB.BASEBOARD_FAB2(SCH_1):PAGE74
  DY57    GND @BASEBOARD_FAB2_LIB.BASEBOARD_FAB2(SCH_1):GND    I20 @BASEBOARD_FAB2_LIB.BASEBOARD_FAB2(SCH_1):PAGE74
  DY55    GND @BASEBOARD_FAB2_LIB.BASEBOARD_FAB2(SCH_1):GND    I20 @BASEBOARD_FAB2_LIB.BASEBOARD_FAB2(SCH_1):PAGE74
  DY53    GND @BASEBOARD_FAB2_LIB.BASEBOARD_FAB2(SCH_1):GND    I20 @BASEBOARD_FAB2_LIB.BASEBOARD_FAB2(SCH_1):PAGE74
  DY51    GND @BASEBOARD_FAB2_LIB.BASEBOARD_FAB2(SCH_1):GND    I20 @BASEBOARD_FAB2_LIB.BASEBOARD_FAB2(SCH_1):PAGE74
  DY49    GND @BASEBOARD_FAB2_LIB.BASEBOARD_FAB2(SCH_1):GND    I20 @BASEBOARD_FAB2_LIB.BASEBOARD_FAB2(SCH_1):PAGE74
  DY47    GND @BASEBOARD_FAB2_LIB.BASEBOARD_FAB2(SCH_1):GND    I20 @BASEBOARD_FAB2_LIB.BASEBOARD_FAB2(SCH_1):PAGE74
  DY45    GND @BASEBOARD_FAB2_LIB.BASEBOARD_FAB2(SCH_1):GND    I20 @BASEBOARD_FAB2_LIB.BASEBOARD_FAB2(SCH_1):PAGE74
  DV19    GND @BASEBOARD_FAB2_LIB.BASEBOARD_FAB2(SCH_1):GND    I20 @BASEBOARD_FAB2_LIB.BASEBOARD_FAB2(SCH_1):PAGE74
   DP9    GND @BASEBOARD_FAB2_LIB.BASEBOARD_FAB2(SCH_1):GND    I20 @BASEBOARD_FAB2_LIB.BASEBOARD_FAB2(SCH_1):PAGE74
  DP63    GND @BASEBOARD_FAB2_LIB.BASEBOARD_FAB2(SCH_1):GND    I20 @BASEBOARD_FAB2_LIB.BASEBOARD_FAB2(SCH_1):PAGE74
  DP61    GND @BASEBOARD_FAB2_LIB.BASEBOARD_FAB2(SCH_1):GND    I20 @BASEBOARD_FAB2_LIB.BASEBOARD_FAB2(SCH_1):PAGE74
  DP59    GND @BASEBOARD_FAB2_LIB.BASEBOARD_FAB2(SCH_1):GND    I20 @BASEBOARD_FAB2_LIB.BASEBOARD_FAB2(SCH_1):PAGE74
  DP57    GND @BASEBOARD_FAB2_LIB.BASEBOARD_FAB2(SCH_1):GND    I20 @BASEBOARD_FAB2_LIB.BASEBOARD_FAB2(SCH_1):PAGE74
  DP55    GND @BASEBOARD_FAB2_LIB.BASEBOARD_FAB2(SCH_1):GND    I20 @BASEBOARD_FAB2_LIB.BASEBOARD_FAB2(SCH_1):PAGE74
  DP53    GND @BASEBOARD_FAB2_LIB.BASEBOARD_FAB2(SCH_1):GND    I20 @BASEBOARD_FAB2_LIB.BASEBOARD_FAB2(SCH_1):PAGE74
  DP51    GND @BASEBOARD_FAB2_LIB.BASEBOARD_FAB2(SCH_1):GND    I20 @BASEBOARD_FAB2_LIB.BASEBOARD_FAB2(SCH_1):PAGE74
  DP49    GND @BASEBOARD_FAB2_LIB.BASEBOARD_FAB2(SCH_1):GND    I20 @BASEBOARD_FAB2_LIB.BASEBOARD_FAB2(SCH_1):PAGE74
  DP47    GND @BASEBOARD_FAB2_LIB.BASEBOARD_FAB2(SCH_1):GND    I20 @BASEBOARD_FAB2_LIB.BASEBOARD_FAB2(SCH_1):PAGE74
  DP45    GND @BASEBOARD_FAB2_LIB.BASEBOARD_FAB2(SCH_1):GND    I20 @BASEBOARD_FAB2_LIB.BASEBOARD_FAB2(SCH_1):PAGE74
  DN18    GND @BASEBOARD_FAB2_LIB.BASEBOARD_FAB2(SCH_1):GND    I20 @BASEBOARD_FAB2_LIB.BASEBOARD_FAB2(SCH_1):PAGE74
   DL8    GND @BASEBOARD_FAB2_LIB.BASEBOARD_FAB2(SCH_1):GND    I20 @BASEBOARD_FAB2_LIB.BASEBOARD_FAB2(SCH_1):PAGE74
  DE62    GND @BASEBOARD_FAB2_LIB.BASEBOARD_FAB2(SCH_1):GND    I20 @BASEBOARD_FAB2_LIB.BASEBOARD_FAB2(SCH_1):PAGE74
  DE60    GND @BASEBOARD_FAB2_LIB.BASEBOARD_FAB2(SCH_1):GND    I20 @BASEBOARD_FAB2_LIB.BASEBOARD_FAB2(SCH_1):PAGE74
  DE58    GND @BASEBOARD_FAB2_LIB.BASEBOARD_FAB2(SCH_1):GND    I20 @BASEBOARD_FAB2_LIB.BASEBOARD_FAB2(SCH_1):PAGE74
  DE56    GND @BASEBOARD_FAB2_LIB.BASEBOARD_FAB2(SCH_1):GND    I20 @BASEBOARD_FAB2_LIB.BASEBOARD_FAB2(SCH_1):PAGE74
  DE54    GND @BASEBOARD_FAB2_LIB.BASEBOARD_FAB2(SCH_1):GND    I20 @BASEBOARD_FAB2_LIB.BASEBOARD_FAB2(SCH_1):PAGE74
  DE52    GND @BASEBOARD_FAB2_LIB.BASEBOARD_FAB2(SCH_1):GND    I20 @BASEBOARD_FAB2_LIB.BASEBOARD_FAB2(SCH_1):PAGE74
  DE50    GND @BASEBOARD_FAB2_LIB.BASEBOARD_FAB2(SCH_1):GND    I20 @BASEBOARD_FAB2_LIB.BASEBOARD_FAB2(SCH_1):PAGE74
  DE48    GND @BASEBOARD_FAB2_LIB.BASEBOARD_FAB2(SCH_1):GND    I20 @BASEBOARD_FAB2_LIB.BASEBOARD_FAB2(SCH_1):PAGE74
   CW6    GND @BASEBOARD_FAB2_LIB.BASEBOARD_FAB2(SCH_1):GND    I20 @BASEBOARD_FAB2_LIB.BASEBOARD_FAB2(SCH_1):PAGE74
   CG6    GND @BASEBOARD_FAB2_LIB.BASEBOARD_FAB2(SCH_1):GND    I20 @BASEBOARD_FAB2_LIB.BASEBOARD_FAB2(SCH_1):PAGE74
   AR6    GND @BASEBOARD_FAB2_LIB.BASEBOARD_FAB2(SCH_1):GND    I20 @BASEBOARD_FAB2_LIB.BASEBOARD_FAB2(SCH_1):PAGE74
   AJ4    GND @BASEBOARD_FAB2_LIB.BASEBOARD_FAB2(SCH_1):GND    I20 @BASEBOARD_FAB2_LIB.BASEBOARD_FAB2(SCH_1):PAGE74
  AC62    GND @BASEBOARD_FAB2_LIB.BASEBOARD_FAB2(SCH_1):GND    I20 @BASEBOARD_FAB2_LIB.BASEBOARD_FAB2(SCH_1):PAGE74
  AC60    GND @BASEBOARD_FAB2_LIB.BASEBOARD_FAB2(SCH_1):GND    I20 @BASEBOARD_FAB2_LIB.BASEBOARD_FAB2(SCH_1):PAGE74
  AC58    GND @BASEBOARD_FAB2_LIB.BASEBOARD_FAB2(SCH_1):GND    I20 @BASEBOARD_FAB2_LIB.BASEBOARD_FAB2(SCH_1):PAGE74
   A26    GND @BASEBOARD_FAB2_LIB.BASEBOARD_FAB2(SCH_1):GND    I20 @BASEBOARD_FAB2_LIB.BASEBOARD_FAB2(SCH_1):PAGE74
   A30    GND @BASEBOARD_FAB2_LIB.BASEBOARD_FAB2(SCH_1):GND    I20 @BASEBOARD_FAB2_LIB.BASEBOARD_FAB2(SCH_1):PAGE74
   A32    GND @BASEBOARD_FAB2_LIB.BASEBOARD_FAB2(SCH_1):GND    I20 @BASEBOARD_FAB2_LIB.BASEBOARD_FAB2(SCH_1):PAGE74
   A36    GND @BASEBOARD_FAB2_LIB.BASEBOARD_FAB2(SCH_1):GND    I20 @BASEBOARD_FAB2_LIB.BASEBOARD_FAB2(SCH_1):PAGE74
   A38    GND @BASEBOARD_FAB2_LIB.BASEBOARD_FAB2(SCH_1):GND    I20 @BASEBOARD_FAB2_LIB.BASEBOARD_FAB2(SCH_1):PAGE74
   B25    GND @BASEBOARD_FAB2_LIB.BASEBOARD_FAB2(SCH_1):GND    I20 @BASEBOARD_FAB2_LIB.BASEBOARD_FAB2(SCH_1):PAGE74
   B31    GND @BASEBOARD_FAB2_LIB.BASEBOARD_FAB2(SCH_1):GND    I20 @BASEBOARD_FAB2_LIB.BASEBOARD_FAB2(SCH_1):PAGE74
   B37    GND @BASEBOARD_FAB2_LIB.BASEBOARD_FAB2(SCH_1):GND    I20 @BASEBOARD_FAB2_LIB.BASEBOARD_FAB2(SCH_1):PAGE74
   B71    GND @BASEBOARD_FAB2_LIB.BASEBOARD_FAB2(SCH_1):GND    I20 @BASEBOARD_FAB2_LIB.BASEBOARD_FAB2(SCH_1):PAGE74
   B75    GND @BASEBOARD_FAB2_LIB.BASEBOARD_FAB2(SCH_1):GND    I20 @BASEBOARD_FAB2_LIB.BASEBOARD_FAB2(SCH_1):PAGE74
    C8    GND @BASEBOARD_FAB2_LIB.BASEBOARD_FAB2(SCH_1):GND    I20 @BASEBOARD_FAB2_LIB.BASEBOARD_FAB2(SCH_1):PAGE74
   C10    GND @BASEBOARD_FAB2_LIB.BASEBOARD_FAB2(SCH_1):GND    I20 @BASEBOARD_FAB2_LIB.BASEBOARD_FAB2(SCH_1):PAGE74
   C12    GND @BASEBOARD_FAB2_LIB.BASEBOARD_FAB2(SCH_1):GND    I20 @BASEBOARD_FAB2_LIB.BASEBOARD_FAB2(SCH_1):PAGE74
   C14    GND @BASEBOARD_FAB2_LIB.BASEBOARD_FAB2(SCH_1):GND    I20 @BASEBOARD_FAB2_LIB.BASEBOARD_FAB2(SCH_1):PAGE74
   C16    GND @BASEBOARD_FAB2_LIB.BASEBOARD_FAB2(SCH_1):GND    I20 @BASEBOARD_FAB2_LIB.BASEBOARD_FAB2(SCH_1):PAGE74
   C76    GND @BASEBOARD_FAB2_LIB.BASEBOARD_FAB2(SCH_1):GND    I20 @BASEBOARD_FAB2_LIB.BASEBOARD_FAB2(SCH_1):PAGE74
   C78    GND @BASEBOARD_FAB2_LIB.BASEBOARD_FAB2(SCH_1):GND    I20 @BASEBOARD_FAB2_LIB.BASEBOARD_FAB2(SCH_1):PAGE74
  CM27    GND @BASEBOARD_FAB2_LIB.BASEBOARD_FAB2(SCH_1):GND    I20 @BASEBOARD_FAB2_LIB.BASEBOARD_FAB2(SCH_1):PAGE74
   D11    GND @BASEBOARD_FAB2_LIB.BASEBOARD_FAB2(SCH_1):GND    I20 @BASEBOARD_FAB2_LIB.BASEBOARD_FAB2(SCH_1):PAGE74
   D13    GND @BASEBOARD_FAB2_LIB.BASEBOARD_FAB2(SCH_1):GND    I20 @BASEBOARD_FAB2_LIB.BASEBOARD_FAB2(SCH_1):PAGE74
   D25    GND @BASEBOARD_FAB2_LIB.BASEBOARD_FAB2(SCH_1):GND    I20 @BASEBOARD_FAB2_LIB.BASEBOARD_FAB2(SCH_1):PAGE74
   D27    GND @BASEBOARD_FAB2_LIB.BASEBOARD_FAB2(SCH_1):GND    I20 @BASEBOARD_FAB2_LIB.BASEBOARD_FAB2(SCH_1):PAGE74
   D29    GND @BASEBOARD_FAB2_LIB.BASEBOARD_FAB2(SCH_1):GND    I20 @BASEBOARD_FAB2_LIB.BASEBOARD_FAB2(SCH_1):PAGE74
   D31    GND @BASEBOARD_FAB2_LIB.BASEBOARD_FAB2(SCH_1):GND    I20 @BASEBOARD_FAB2_LIB.BASEBOARD_FAB2(SCH_1):PAGE74
   D33    GND @BASEBOARD_FAB2_LIB.BASEBOARD_FAB2(SCH_1):GND    I20 @BASEBOARD_FAB2_LIB.BASEBOARD_FAB2(SCH_1):PAGE74
   D35    GND @BASEBOARD_FAB2_LIB.BASEBOARD_FAB2(SCH_1):GND    I20 @BASEBOARD_FAB2_LIB.BASEBOARD_FAB2(SCH_1):PAGE74
   D37    GND @BASEBOARD_FAB2_LIB.BASEBOARD_FAB2(SCH_1):GND    I20 @BASEBOARD_FAB2_LIB.BASEBOARD_FAB2(SCH_1):PAGE74
   D39    GND @BASEBOARD_FAB2_LIB.BASEBOARD_FAB2(SCH_1):GND    I20 @BASEBOARD_FAB2_LIB.BASEBOARD_FAB2(SCH_1):PAGE74
   D41    GND @BASEBOARD_FAB2_LIB.BASEBOARD_FAB2(SCH_1):GND    I20 @BASEBOARD_FAB2_LIB.BASEBOARD_FAB2(SCH_1):PAGE74
   D43    GND @BASEBOARD_FAB2_LIB.BASEBOARD_FAB2(SCH_1):GND    I20 @BASEBOARD_FAB2_LIB.BASEBOARD_FAB2(SCH_1):PAGE74
   D77    GND @BASEBOARD_FAB2_LIB.BASEBOARD_FAB2(SCH_1):GND    I20 @BASEBOARD_FAB2_LIB.BASEBOARD_FAB2(SCH_1):PAGE74
    E6    GND @BASEBOARD_FAB2_LIB.BASEBOARD_FAB2(SCH_1):GND    I20 @BASEBOARD_FAB2_LIB.BASEBOARD_FAB2(SCH_1):PAGE74
    E8    GND @BASEBOARD_FAB2_LIB.BASEBOARD_FAB2(SCH_1):GND    I20 @BASEBOARD_FAB2_LIB.BASEBOARD_FAB2(SCH_1):PAGE74
   E16    GND @BASEBOARD_FAB2_LIB.BASEBOARD_FAB2(SCH_1):GND    I20 @BASEBOARD_FAB2_LIB.BASEBOARD_FAB2(SCH_1):PAGE74
   E18    GND @BASEBOARD_FAB2_LIB.BASEBOARD_FAB2(SCH_1):GND    I20 @BASEBOARD_FAB2_LIB.BASEBOARD_FAB2(SCH_1):PAGE74
   E20    GND @BASEBOARD_FAB2_LIB.BASEBOARD_FAB2(SCH_1):GND    I20 @BASEBOARD_FAB2_LIB.BASEBOARD_FAB2(SCH_1):PAGE74
   E22    GND @BASEBOARD_FAB2_LIB.BASEBOARD_FAB2(SCH_1):GND    I20 @BASEBOARD_FAB2_LIB.BASEBOARD_FAB2(SCH_1):PAGE74
   E72    GND @BASEBOARD_FAB2_LIB.BASEBOARD_FAB2(SCH_1):GND    I20 @BASEBOARD_FAB2_LIB.BASEBOARD_FAB2(SCH_1):PAGE74
   E74    GND @BASEBOARD_FAB2_LIB.BASEBOARD_FAB2(SCH_1):GND    I20 @BASEBOARD_FAB2_LIB.BASEBOARD_FAB2(SCH_1):PAGE74
   E76    GND @BASEBOARD_FAB2_LIB.BASEBOARD_FAB2(SCH_1):GND    I20 @BASEBOARD_FAB2_LIB.BASEBOARD_FAB2(SCH_1):PAGE74
    F5    GND @BASEBOARD_FAB2_LIB.BASEBOARD_FAB2(SCH_1):GND    I20 @BASEBOARD_FAB2_LIB.BASEBOARD_FAB2(SCH_1):PAGE74
   F17    GND @BASEBOARD_FAB2_LIB.BASEBOARD_FAB2(SCH_1):GND    I20 @BASEBOARD_FAB2_LIB.BASEBOARD_FAB2(SCH_1):PAGE74
   F19    GND @BASEBOARD_FAB2_LIB.BASEBOARD_FAB2(SCH_1):GND    I20 @BASEBOARD_FAB2_LIB.BASEBOARD_FAB2(SCH_1):PAGE74
   F25    GND @BASEBOARD_FAB2_LIB.BASEBOARD_FAB2(SCH_1):GND    I20 @BASEBOARD_FAB2_LIB.BASEBOARD_FAB2(SCH_1):PAGE74
   F31    GND @BASEBOARD_FAB2_LIB.BASEBOARD_FAB2(SCH_1):GND    I20 @BASEBOARD_FAB2_LIB.BASEBOARD_FAB2(SCH_1):PAGE74
   F37    GND @BASEBOARD_FAB2_LIB.BASEBOARD_FAB2(SCH_1):GND    I20 @BASEBOARD_FAB2_LIB.BASEBOARD_FAB2(SCH_1):PAGE74
   F43    GND @BASEBOARD_FAB2_LIB.BASEBOARD_FAB2(SCH_1):GND    I20 @BASEBOARD_FAB2_LIB.BASEBOARD_FAB2(SCH_1):PAGE74
   F67    GND @BASEBOARD_FAB2_LIB.BASEBOARD_FAB2(SCH_1):GND    I20 @BASEBOARD_FAB2_LIB.BASEBOARD_FAB2(SCH_1):PAGE74
   F69    GND @BASEBOARD_FAB2_LIB.BASEBOARD_FAB2(SCH_1):GND    I20 @BASEBOARD_FAB2_LIB.BASEBOARD_FAB2(SCH_1):PAGE74
    G4    GND @BASEBOARD_FAB2_LIB.BASEBOARD_FAB2(SCH_1):GND    I20 @BASEBOARD_FAB2_LIB.BASEBOARD_FAB2(SCH_1):PAGE74
    G8    GND @BASEBOARD_FAB2_LIB.BASEBOARD_FAB2(SCH_1):GND    I20 @BASEBOARD_FAB2_LIB.BASEBOARD_FAB2(SCH_1):PAGE74
   G22    GND @BASEBOARD_FAB2_LIB.BASEBOARD_FAB2(SCH_1):GND    I20 @BASEBOARD_FAB2_LIB.BASEBOARD_FAB2(SCH_1):PAGE74
   G24    GND @BASEBOARD_FAB2_LIB.BASEBOARD_FAB2(SCH_1):GND    I20 @BASEBOARD_FAB2_LIB.BASEBOARD_FAB2(SCH_1):PAGE74
   G26    GND @BASEBOARD_FAB2_LIB.BASEBOARD_FAB2(SCH_1):GND    I20 @BASEBOARD_FAB2_LIB.BASEBOARD_FAB2(SCH_1):PAGE74
   G30    GND @BASEBOARD_FAB2_LIB.BASEBOARD_FAB2(SCH_1):GND    I20 @BASEBOARD_FAB2_LIB.BASEBOARD_FAB2(SCH_1):PAGE74
   G32    GND @BASEBOARD_FAB2_LIB.BASEBOARD_FAB2(SCH_1):GND    I20 @BASEBOARD_FAB2_LIB.BASEBOARD_FAB2(SCH_1):PAGE74
   G36    GND @BASEBOARD_FAB2_LIB.BASEBOARD_FAB2(SCH_1):GND    I20 @BASEBOARD_FAB2_LIB.BASEBOARD_FAB2(SCH_1):PAGE74
   G38    GND @BASEBOARD_FAB2_LIB.BASEBOARD_FAB2(SCH_1):GND    I20 @BASEBOARD_FAB2_LIB.BASEBOARD_FAB2(SCH_1):PAGE74
   G42    GND @BASEBOARD_FAB2_LIB.BASEBOARD_FAB2(SCH_1):GND    I20 @BASEBOARD_FAB2_LIB.BASEBOARD_FAB2(SCH_1):PAGE74
   G66    GND @BASEBOARD_FAB2_LIB.BASEBOARD_FAB2(SCH_1):GND    I20 @BASEBOARD_FAB2_LIB.BASEBOARD_FAB2(SCH_1):PAGE74
   G70    GND @BASEBOARD_FAB2_LIB.BASEBOARD_FAB2(SCH_1):GND    I20 @BASEBOARD_FAB2_LIB.BASEBOARD_FAB2(SCH_1):PAGE74
   G76    GND @BASEBOARD_FAB2_LIB.BASEBOARD_FAB2(SCH_1):GND    I20 @BASEBOARD_FAB2_LIB.BASEBOARD_FAB2(SCH_1):PAGE74
   G78    GND @BASEBOARD_FAB2_LIB.BASEBOARD_FAB2(SCH_1):GND    I20 @BASEBOARD_FAB2_LIB.BASEBOARD_FAB2(SCH_1):PAGE74
   G80    GND @BASEBOARD_FAB2_LIB.BASEBOARD_FAB2(SCH_1):GND    I20 @BASEBOARD_FAB2_LIB.BASEBOARD_FAB2(SCH_1):PAGE74
   G82    GND @BASEBOARD_FAB2_LIB.BASEBOARD_FAB2(SCH_1):GND    I20 @BASEBOARD_FAB2_LIB.BASEBOARD_FAB2(SCH_1):PAGE74
    H3    GND @BASEBOARD_FAB2_LIB.BASEBOARD_FAB2(SCH_1):GND    I20 @BASEBOARD_FAB2_LIB.BASEBOARD_FAB2(SCH_1):PAGE74
   H11    GND @BASEBOARD_FAB2_LIB.BASEBOARD_FAB2(SCH_1):GND    I20 @BASEBOARD_FAB2_LIB.BASEBOARD_FAB2(SCH_1):PAGE74
   H25    GND @BASEBOARD_FAB2_LIB.BASEBOARD_FAB2(SCH_1):GND    I20 @BASEBOARD_FAB2_LIB.BASEBOARD_FAB2(SCH_1):PAGE74
   H27    GND @BASEBOARD_FAB2_LIB.BASEBOARD_FAB2(SCH_1):GND    I20 @BASEBOARD_FAB2_LIB.BASEBOARD_FAB2(SCH_1):PAGE74
   H29    GND @BASEBOARD_FAB2_LIB.BASEBOARD_FAB2(SCH_1):GND    I20 @BASEBOARD_FAB2_LIB.BASEBOARD_FAB2(SCH_1):PAGE74
   H31    GND @BASEBOARD_FAB2_LIB.BASEBOARD_FAB2(SCH_1):GND    I20 @BASEBOARD_FAB2_LIB.BASEBOARD_FAB2(SCH_1):PAGE74
   H33    GND @BASEBOARD_FAB2_LIB.BASEBOARD_FAB2(SCH_1):GND    I20 @BASEBOARD_FAB2_LIB.BASEBOARD_FAB2(SCH_1):PAGE74
   H35    GND @BASEBOARD_FAB2_LIB.BASEBOARD_FAB2(SCH_1):GND    I20 @BASEBOARD_FAB2_LIB.BASEBOARD_FAB2(SCH_1):PAGE74
   H37    GND @BASEBOARD_FAB2_LIB.BASEBOARD_FAB2(SCH_1):GND    I20 @BASEBOARD_FAB2_LIB.BASEBOARD_FAB2(SCH_1):PAGE74
   H39    GND @BASEBOARD_FAB2_LIB.BASEBOARD_FAB2(SCH_1):GND    I20 @BASEBOARD_FAB2_LIB.BASEBOARD_FAB2(SCH_1):PAGE74
   H41    GND @BASEBOARD_FAB2_LIB.BASEBOARD_FAB2(SCH_1):GND    I20 @BASEBOARD_FAB2_LIB.BASEBOARD_FAB2(SCH_1):PAGE74
   H65    GND @BASEBOARD_FAB2_LIB.BASEBOARD_FAB2(SCH_1):GND    I20 @BASEBOARD_FAB2_LIB.BASEBOARD_FAB2(SCH_1):PAGE74
   H71    GND @BASEBOARD_FAB2_LIB.BASEBOARD_FAB2(SCH_1):GND    I20 @BASEBOARD_FAB2_LIB.BASEBOARD_FAB2(SCH_1):PAGE74
   H75    GND @BASEBOARD_FAB2_LIB.BASEBOARD_FAB2(SCH_1):GND    I20 @BASEBOARD_FAB2_LIB.BASEBOARD_FAB2(SCH_1):PAGE74
  DN44    GND @BASEBOARD_FAB2_LIB.BASEBOARD_FAB2(SCH_1):GND    I20 @BASEBOARD_FAB2_LIB.BASEBOARD_FAB2(SCH_1):PAGE74
    J4    GND @BASEBOARD_FAB2_LIB.BASEBOARD_FAB2(SCH_1):GND    I20 @BASEBOARD_FAB2_LIB.BASEBOARD_FAB2(SCH_1):PAGE74
   J12    GND @BASEBOARD_FAB2_LIB.BASEBOARD_FAB2(SCH_1):GND    I20 @BASEBOARD_FAB2_LIB.BASEBOARD_FAB2(SCH_1):PAGE74
   J14    GND @BASEBOARD_FAB2_LIB.BASEBOARD_FAB2(SCH_1):GND    I20 @BASEBOARD_FAB2_LIB.BASEBOARD_FAB2(SCH_1):PAGE74
   J22    GND @BASEBOARD_FAB2_LIB.BASEBOARD_FAB2(SCH_1):GND    I20 @BASEBOARD_FAB2_LIB.BASEBOARD_FAB2(SCH_1):PAGE74
   J26    GND @BASEBOARD_FAB2_LIB.BASEBOARD_FAB2(SCH_1):GND    I20 @BASEBOARD_FAB2_LIB.BASEBOARD_FAB2(SCH_1):PAGE74
   J28    GND @BASEBOARD_FAB2_LIB.BASEBOARD_FAB2(SCH_1):GND    I20 @BASEBOARD_FAB2_LIB.BASEBOARD_FAB2(SCH_1):PAGE74
   J32    GND @BASEBOARD_FAB2_LIB.BASEBOARD_FAB2(SCH_1):GND    I20 @BASEBOARD_FAB2_LIB.BASEBOARD_FAB2(SCH_1):PAGE74
   J34    GND @BASEBOARD_FAB2_LIB.BASEBOARD_FAB2(SCH_1):GND    I20 @BASEBOARD_FAB2_LIB.BASEBOARD_FAB2(SCH_1):PAGE74
   J38    GND @BASEBOARD_FAB2_LIB.BASEBOARD_FAB2(SCH_1):GND    I20 @BASEBOARD_FAB2_LIB.BASEBOARD_FAB2(SCH_1):PAGE74
   J40    GND @BASEBOARD_FAB2_LIB.BASEBOARD_FAB2(SCH_1):GND    I20 @BASEBOARD_FAB2_LIB.BASEBOARD_FAB2(SCH_1):PAGE74
   J72    GND @BASEBOARD_FAB2_LIB.BASEBOARD_FAB2(SCH_1):GND    I20 @BASEBOARD_FAB2_LIB.BASEBOARD_FAB2(SCH_1):PAGE74
   J74    GND @BASEBOARD_FAB2_LIB.BASEBOARD_FAB2(SCH_1):GND    I20 @BASEBOARD_FAB2_LIB.BASEBOARD_FAB2(SCH_1):PAGE74
   J76    GND @BASEBOARD_FAB2_LIB.BASEBOARD_FAB2(SCH_1):GND    I21 @BASEBOARD_FAB2_LIB.BASEBOARD_FAB2(SCH_1):PAGE74
   J82    GND @BASEBOARD_FAB2_LIB.BASEBOARD_FAB2(SCH_1):GND    I21 @BASEBOARD_FAB2_LIB.BASEBOARD_FAB2(SCH_1):PAGE74
   J84    GND @BASEBOARD_FAB2_LIB.BASEBOARD_FAB2(SCH_1):GND    I21 @BASEBOARD_FAB2_LIB.BASEBOARD_FAB2(SCH_1):PAGE74
    K1    GND @BASEBOARD_FAB2_LIB.BASEBOARD_FAB2(SCH_1):GND    I21 @BASEBOARD_FAB2_LIB.BASEBOARD_FAB2(SCH_1):PAGE74
   K11    GND @BASEBOARD_FAB2_LIB.BASEBOARD_FAB2(SCH_1):GND    I21 @BASEBOARD_FAB2_LIB.BASEBOARD_FAB2(SCH_1):PAGE74
   K13    GND @BASEBOARD_FAB2_LIB.BASEBOARD_FAB2(SCH_1):GND    I21 @BASEBOARD_FAB2_LIB.BASEBOARD_FAB2(SCH_1):PAGE74
   K17    GND @BASEBOARD_FAB2_LIB.BASEBOARD_FAB2(SCH_1):GND    I21 @BASEBOARD_FAB2_LIB.BASEBOARD_FAB2(SCH_1):PAGE74
   DB7    GND @BASEBOARD_FAB2_LIB.BASEBOARD_FAB2(SCH_1):GND    I21 @BASEBOARD_FAB2_LIB.BASEBOARD_FAB2(SCH_1):PAGE74
   K27    GND @BASEBOARD_FAB2_LIB.BASEBOARD_FAB2(SCH_1):GND    I21 @BASEBOARD_FAB2_LIB.BASEBOARD_FAB2(SCH_1):PAGE74
   K33    GND @BASEBOARD_FAB2_LIB.BASEBOARD_FAB2(SCH_1):GND    I21 @BASEBOARD_FAB2_LIB.BASEBOARD_FAB2(SCH_1):PAGE74
   K39    GND @BASEBOARD_FAB2_LIB.BASEBOARD_FAB2(SCH_1):GND    I21 @BASEBOARD_FAB2_LIB.BASEBOARD_FAB2(SCH_1):PAGE74
   K65    GND @BASEBOARD_FAB2_LIB.BASEBOARD_FAB2(SCH_1):GND    I21 @BASEBOARD_FAB2_LIB.BASEBOARD_FAB2(SCH_1):PAGE74
   K67    GND @BASEBOARD_FAB2_LIB.BASEBOARD_FAB2(SCH_1):GND    I21 @BASEBOARD_FAB2_LIB.BASEBOARD_FAB2(SCH_1):PAGE74
   K69    GND @BASEBOARD_FAB2_LIB.BASEBOARD_FAB2(SCH_1):GND    I21 @BASEBOARD_FAB2_LIB.BASEBOARD_FAB2(SCH_1):PAGE74
   K71    GND @BASEBOARD_FAB2_LIB.BASEBOARD_FAB2(SCH_1):GND    I21 @BASEBOARD_FAB2_LIB.BASEBOARD_FAB2(SCH_1):PAGE74
   K73    GND @BASEBOARD_FAB2_LIB.BASEBOARD_FAB2(SCH_1):GND    I21 @BASEBOARD_FAB2_LIB.BASEBOARD_FAB2(SCH_1):PAGE74
   K77    GND @BASEBOARD_FAB2_LIB.BASEBOARD_FAB2(SCH_1):GND    I21 @BASEBOARD_FAB2_LIB.BASEBOARD_FAB2(SCH_1):PAGE74
   K81    GND @BASEBOARD_FAB2_LIB.BASEBOARD_FAB2(SCH_1):GND    I21 @BASEBOARD_FAB2_LIB.BASEBOARD_FAB2(SCH_1):PAGE74
   K83    GND @BASEBOARD_FAB2_LIB.BASEBOARD_FAB2(SCH_1):GND    I21 @BASEBOARD_FAB2_LIB.BASEBOARD_FAB2(SCH_1):PAGE74
   K85    GND @BASEBOARD_FAB2_LIB.BASEBOARD_FAB2(SCH_1):GND    I21 @BASEBOARD_FAB2_LIB.BASEBOARD_FAB2(SCH_1):PAGE74
   L10    GND @BASEBOARD_FAB2_LIB.BASEBOARD_FAB2(SCH_1):GND    I21 @BASEBOARD_FAB2_LIB.BASEBOARD_FAB2(SCH_1):PAGE74
    L2    GND @BASEBOARD_FAB2_LIB.BASEBOARD_FAB2(SCH_1):GND    I21 @BASEBOARD_FAB2_LIB.BASEBOARD_FAB2(SCH_1):PAGE74
    L6    GND @BASEBOARD_FAB2_LIB.BASEBOARD_FAB2(SCH_1):GND    I21 @BASEBOARD_FAB2_LIB.BASEBOARD_FAB2(SCH_1):PAGE74
   L20    GND @BASEBOARD_FAB2_LIB.BASEBOARD_FAB2(SCH_1):GND    I21 @BASEBOARD_FAB2_LIB.BASEBOARD_FAB2(SCH_1):PAGE74
   L22    GND @BASEBOARD_FAB2_LIB.BASEBOARD_FAB2(SCH_1):GND    I21 @BASEBOARD_FAB2_LIB.BASEBOARD_FAB2(SCH_1):PAGE74
   L72    GND @BASEBOARD_FAB2_LIB.BASEBOARD_FAB2(SCH_1):GND    I21 @BASEBOARD_FAB2_LIB.BASEBOARD_FAB2(SCH_1):PAGE74
   L78    GND @BASEBOARD_FAB2_LIB.BASEBOARD_FAB2(SCH_1):GND    I21 @BASEBOARD_FAB2_LIB.BASEBOARD_FAB2(SCH_1):PAGE74
   L80    GND @BASEBOARD_FAB2_LIB.BASEBOARD_FAB2(SCH_1):GND    I21 @BASEBOARD_FAB2_LIB.BASEBOARD_FAB2(SCH_1):PAGE74
   L82    GND @BASEBOARD_FAB2_LIB.BASEBOARD_FAB2(SCH_1):GND    I21 @BASEBOARD_FAB2_LIB.BASEBOARD_FAB2(SCH_1):PAGE74
   BT9    GND @BASEBOARD_FAB2_LIB.BASEBOARD_FAB2(SCH_1):GND    I21 @BASEBOARD_FAB2_LIB.BASEBOARD_FAB2(SCH_1):PAGE74
   CT7    GND @BASEBOARD_FAB2_LIB.BASEBOARD_FAB2(SCH_1):GND    I21 @BASEBOARD_FAB2_LIB.BASEBOARD_FAB2(SCH_1):PAGE74
   M15    GND @BASEBOARD_FAB2_LIB.BASEBOARD_FAB2(SCH_1):GND    I21 @BASEBOARD_FAB2_LIB.BASEBOARD_FAB2(SCH_1):PAGE74
   M17    GND @BASEBOARD_FAB2_LIB.BASEBOARD_FAB2(SCH_1):GND    I21 @BASEBOARD_FAB2_LIB.BASEBOARD_FAB2(SCH_1):PAGE74
   M19    GND @BASEBOARD_FAB2_LIB.BASEBOARD_FAB2(SCH_1):GND    I21 @BASEBOARD_FAB2_LIB.BASEBOARD_FAB2(SCH_1):PAGE74
   M23    GND @BASEBOARD_FAB2_LIB.BASEBOARD_FAB2(SCH_1):GND    I21 @BASEBOARD_FAB2_LIB.BASEBOARD_FAB2(SCH_1):PAGE74
   M25    GND @BASEBOARD_FAB2_LIB.BASEBOARD_FAB2(SCH_1):GND    I21 @BASEBOARD_FAB2_LIB.BASEBOARD_FAB2(SCH_1):PAGE74
   M27    GND @BASEBOARD_FAB2_LIB.BASEBOARD_FAB2(SCH_1):GND    I21 @BASEBOARD_FAB2_LIB.BASEBOARD_FAB2(SCH_1):PAGE74
   M29    GND @BASEBOARD_FAB2_LIB.BASEBOARD_FAB2(SCH_1):GND    I21 @BASEBOARD_FAB2_LIB.BASEBOARD_FAB2(SCH_1):PAGE74
   M31    GND @BASEBOARD_FAB2_LIB.BASEBOARD_FAB2(SCH_1):GND    I21 @BASEBOARD_FAB2_LIB.BASEBOARD_FAB2(SCH_1):PAGE74
   M33    GND @BASEBOARD_FAB2_LIB.BASEBOARD_FAB2(SCH_1):GND    I21 @BASEBOARD_FAB2_LIB.BASEBOARD_FAB2(SCH_1):PAGE74
   M35    GND @BASEBOARD_FAB2_LIB.BASEBOARD_FAB2(SCH_1):GND    I21 @BASEBOARD_FAB2_LIB.BASEBOARD_FAB2(SCH_1):PAGE74
   M37    GND @BASEBOARD_FAB2_LIB.BASEBOARD_FAB2(SCH_1):GND    I21 @BASEBOARD_FAB2_LIB.BASEBOARD_FAB2(SCH_1):PAGE74
   M39    GND @BASEBOARD_FAB2_LIB.BASEBOARD_FAB2(SCH_1):GND    I21 @BASEBOARD_FAB2_LIB.BASEBOARD_FAB2(SCH_1):PAGE74
   M41    GND @BASEBOARD_FAB2_LIB.BASEBOARD_FAB2(SCH_1):GND    I21 @BASEBOARD_FAB2_LIB.BASEBOARD_FAB2(SCH_1):PAGE74
   M43    GND @BASEBOARD_FAB2_LIB.BASEBOARD_FAB2(SCH_1):GND    I21 @BASEBOARD_FAB2_LIB.BASEBOARD_FAB2(SCH_1):PAGE74
   M65    GND @BASEBOARD_FAB2_LIB.BASEBOARD_FAB2(SCH_1):GND    I21 @BASEBOARD_FAB2_LIB.BASEBOARD_FAB2(SCH_1):PAGE74
   M71    GND @BASEBOARD_FAB2_LIB.BASEBOARD_FAB2(SCH_1):GND    I21 @BASEBOARD_FAB2_LIB.BASEBOARD_FAB2(SCH_1):PAGE74
   M79    GND @BASEBOARD_FAB2_LIB.BASEBOARD_FAB2(SCH_1):GND    I21 @BASEBOARD_FAB2_LIB.BASEBOARD_FAB2(SCH_1):PAGE74
   M83    GND @BASEBOARD_FAB2_LIB.BASEBOARD_FAB2(SCH_1):GND    I21 @BASEBOARD_FAB2_LIB.BASEBOARD_FAB2(SCH_1):PAGE74
   M85    GND @BASEBOARD_FAB2_LIB.BASEBOARD_FAB2(SCH_1):GND    I21 @BASEBOARD_FAB2_LIB.BASEBOARD_FAB2(SCH_1):PAGE74
  DM19    GND @BASEBOARD_FAB2_LIB.BASEBOARD_FAB2(SCH_1):GND    I21 @BASEBOARD_FAB2_LIB.BASEBOARD_FAB2(SCH_1):PAGE74
   N20    GND @BASEBOARD_FAB2_LIB.BASEBOARD_FAB2(SCH_1):GND    I21 @BASEBOARD_FAB2_LIB.BASEBOARD_FAB2(SCH_1):PAGE74
   N22    GND @BASEBOARD_FAB2_LIB.BASEBOARD_FAB2(SCH_1):GND    I21 @BASEBOARD_FAB2_LIB.BASEBOARD_FAB2(SCH_1):PAGE74
    N6    GND @BASEBOARD_FAB2_LIB.BASEBOARD_FAB2(SCH_1):GND    I21 @BASEBOARD_FAB2_LIB.BASEBOARD_FAB2(SCH_1):PAGE74
   N66    GND @BASEBOARD_FAB2_LIB.BASEBOARD_FAB2(SCH_1):GND    I21 @BASEBOARD_FAB2_LIB.BASEBOARD_FAB2(SCH_1):PAGE74
   N70    GND @BASEBOARD_FAB2_LIB.BASEBOARD_FAB2(SCH_1):GND    I21 @BASEBOARD_FAB2_LIB.BASEBOARD_FAB2(SCH_1):PAGE74
   N72    GND @BASEBOARD_FAB2_LIB.BASEBOARD_FAB2(SCH_1):GND    I21 @BASEBOARD_FAB2_LIB.BASEBOARD_FAB2(SCH_1):PAGE74
   N74    GND @BASEBOARD_FAB2_LIB.BASEBOARD_FAB2(SCH_1):GND    I21 @BASEBOARD_FAB2_LIB.BASEBOARD_FAB2(SCH_1):PAGE74
   N76    GND @BASEBOARD_FAB2_LIB.BASEBOARD_FAB2(SCH_1):GND    I21 @BASEBOARD_FAB2_LIB.BASEBOARD_FAB2(SCH_1):PAGE74
   N78    GND @BASEBOARD_FAB2_LIB.BASEBOARD_FAB2(SCH_1):GND    I21 @BASEBOARD_FAB2_LIB.BASEBOARD_FAB2(SCH_1):PAGE74
    N4    GND @BASEBOARD_FAB2_LIB.BASEBOARD_FAB2(SCH_1):GND    I21 @BASEBOARD_FAB2_LIB.BASEBOARD_FAB2(SCH_1):PAGE74
    N8    GND @BASEBOARD_FAB2_LIB.BASEBOARD_FAB2(SCH_1):GND    I21 @BASEBOARD_FAB2_LIB.BASEBOARD_FAB2(SCH_1):PAGE74
   P11    GND @BASEBOARD_FAB2_LIB.BASEBOARD_FAB2(SCH_1):GND    I21 @BASEBOARD_FAB2_LIB.BASEBOARD_FAB2(SCH_1):PAGE74
   P15    GND @BASEBOARD_FAB2_LIB.BASEBOARD_FAB2(SCH_1):GND    I21 @BASEBOARD_FAB2_LIB.BASEBOARD_FAB2(SCH_1):PAGE74
   P27    GND @BASEBOARD_FAB2_LIB.BASEBOARD_FAB2(SCH_1):GND    I21 @BASEBOARD_FAB2_LIB.BASEBOARD_FAB2(SCH_1):PAGE74
   P33    GND @BASEBOARD_FAB2_LIB.BASEBOARD_FAB2(SCH_1):GND    I21 @BASEBOARD_FAB2_LIB.BASEBOARD_FAB2(SCH_1):PAGE74
   P39    GND @BASEBOARD_FAB2_LIB.BASEBOARD_FAB2(SCH_1):GND    I21 @BASEBOARD_FAB2_LIB.BASEBOARD_FAB2(SCH_1):PAGE74
   P67    GND @BASEBOARD_FAB2_LIB.BASEBOARD_FAB2(SCH_1):GND    I21 @BASEBOARD_FAB2_LIB.BASEBOARD_FAB2(SCH_1):PAGE74
   P69    GND @BASEBOARD_FAB2_LIB.BASEBOARD_FAB2(SCH_1):GND    I21 @BASEBOARD_FAB2_LIB.BASEBOARD_FAB2(SCH_1):PAGE74
   P71    GND @BASEBOARD_FAB2_LIB.BASEBOARD_FAB2(SCH_1):GND    I21 @BASEBOARD_FAB2_LIB.BASEBOARD_FAB2(SCH_1):PAGE74
   P81    GND @BASEBOARD_FAB2_LIB.BASEBOARD_FAB2(SCH_1):GND    I21 @BASEBOARD_FAB2_LIB.BASEBOARD_FAB2(SCH_1):PAGE74
   P83    GND @BASEBOARD_FAB2_LIB.BASEBOARD_FAB2(SCH_1):GND    I21 @BASEBOARD_FAB2_LIB.BASEBOARD_FAB2(SCH_1):PAGE74
   R14    GND @BASEBOARD_FAB2_LIB.BASEBOARD_FAB2(SCH_1):GND    I21 @BASEBOARD_FAB2_LIB.BASEBOARD_FAB2(SCH_1):PAGE74
   R18    GND @BASEBOARD_FAB2_LIB.BASEBOARD_FAB2(SCH_1):GND    I21 @BASEBOARD_FAB2_LIB.BASEBOARD_FAB2(SCH_1):PAGE74
    R2    GND @BASEBOARD_FAB2_LIB.BASEBOARD_FAB2(SCH_1):GND    I21 @BASEBOARD_FAB2_LIB.BASEBOARD_FAB2(SCH_1):PAGE74
    R4    GND @BASEBOARD_FAB2_LIB.BASEBOARD_FAB2(SCH_1):GND    I21 @BASEBOARD_FAB2_LIB.BASEBOARD_FAB2(SCH_1):PAGE74
   R22    GND @BASEBOARD_FAB2_LIB.BASEBOARD_FAB2(SCH_1):GND    I21 @BASEBOARD_FAB2_LIB.BASEBOARD_FAB2(SCH_1):PAGE74
   R26    GND @BASEBOARD_FAB2_LIB.BASEBOARD_FAB2(SCH_1):GND    I21 @BASEBOARD_FAB2_LIB.BASEBOARD_FAB2(SCH_1):PAGE74
   R28    GND @BASEBOARD_FAB2_LIB.BASEBOARD_FAB2(SCH_1):GND    I21 @BASEBOARD_FAB2_LIB.BASEBOARD_FAB2(SCH_1):PAGE74
   R32    GND @BASEBOARD_FAB2_LIB.BASEBOARD_FAB2(SCH_1):GND    I21 @BASEBOARD_FAB2_LIB.BASEBOARD_FAB2(SCH_1):PAGE74
   R34    GND @BASEBOARD_FAB2_LIB.BASEBOARD_FAB2(SCH_1):GND    I21 @BASEBOARD_FAB2_LIB.BASEBOARD_FAB2(SCH_1):PAGE74
   R38    GND @BASEBOARD_FAB2_LIB.BASEBOARD_FAB2(SCH_1):GND    I21 @BASEBOARD_FAB2_LIB.BASEBOARD_FAB2(SCH_1):PAGE74
   R40    GND @BASEBOARD_FAB2_LIB.BASEBOARD_FAB2(SCH_1):GND    I21 @BASEBOARD_FAB2_LIB.BASEBOARD_FAB2(SCH_1):PAGE74
   R68    GND @BASEBOARD_FAB2_LIB.BASEBOARD_FAB2(SCH_1):GND    I21 @BASEBOARD_FAB2_LIB.BASEBOARD_FAB2(SCH_1):PAGE74
   R72    GND @BASEBOARD_FAB2_LIB.BASEBOARD_FAB2(SCH_1):GND    I21 @BASEBOARD_FAB2_LIB.BASEBOARD_FAB2(SCH_1):PAGE74
   R78    GND @BASEBOARD_FAB2_LIB.BASEBOARD_FAB2(SCH_1):GND    I21 @BASEBOARD_FAB2_LIB.BASEBOARD_FAB2(SCH_1):PAGE74
   R86    GND @BASEBOARD_FAB2_LIB.BASEBOARD_FAB2(SCH_1):GND    I21 @BASEBOARD_FAB2_LIB.BASEBOARD_FAB2(SCH_1):PAGE74
   T13    GND @BASEBOARD_FAB2_LIB.BASEBOARD_FAB2(SCH_1):GND    I21 @BASEBOARD_FAB2_LIB.BASEBOARD_FAB2(SCH_1):PAGE74
   T17    GND @BASEBOARD_FAB2_LIB.BASEBOARD_FAB2(SCH_1):GND    I21 @BASEBOARD_FAB2_LIB.BASEBOARD_FAB2(SCH_1):PAGE74
   T25    GND @BASEBOARD_FAB2_LIB.BASEBOARD_FAB2(SCH_1):GND    I21 @BASEBOARD_FAB2_LIB.BASEBOARD_FAB2(SCH_1):PAGE74
   T29    GND @BASEBOARD_FAB2_LIB.BASEBOARD_FAB2(SCH_1):GND    I21 @BASEBOARD_FAB2_LIB.BASEBOARD_FAB2(SCH_1):PAGE74
   T31    GND @BASEBOARD_FAB2_LIB.BASEBOARD_FAB2(SCH_1):GND    I21 @BASEBOARD_FAB2_LIB.BASEBOARD_FAB2(SCH_1):PAGE74
   T35    GND @BASEBOARD_FAB2_LIB.BASEBOARD_FAB2(SCH_1):GND    I21 @BASEBOARD_FAB2_LIB.BASEBOARD_FAB2(SCH_1):PAGE74
   T37    GND @BASEBOARD_FAB2_LIB.BASEBOARD_FAB2(SCH_1):GND    I21 @BASEBOARD_FAB2_LIB.BASEBOARD_FAB2(SCH_1):PAGE74
   T41    GND @BASEBOARD_FAB2_LIB.BASEBOARD_FAB2(SCH_1):GND    I21 @BASEBOARD_FAB2_LIB.BASEBOARD_FAB2(SCH_1):PAGE74
   T65    GND @BASEBOARD_FAB2_LIB.BASEBOARD_FAB2(SCH_1):GND    I21 @BASEBOARD_FAB2_LIB.BASEBOARD_FAB2(SCH_1):PAGE74
   T73    GND @BASEBOARD_FAB2_LIB.BASEBOARD_FAB2(SCH_1):GND    I21 @BASEBOARD_FAB2_LIB.BASEBOARD_FAB2(SCH_1):PAGE74
   T77    GND @BASEBOARD_FAB2_LIB.BASEBOARD_FAB2(SCH_1):GND    I21 @BASEBOARD_FAB2_LIB.BASEBOARD_FAB2(SCH_1):PAGE74
   T83    GND @BASEBOARD_FAB2_LIB.BASEBOARD_FAB2(SCH_1):GND    I21 @BASEBOARD_FAB2_LIB.BASEBOARD_FAB2(SCH_1):PAGE74
   T85    GND @BASEBOARD_FAB2_LIB.BASEBOARD_FAB2(SCH_1):GND    I21 @BASEBOARD_FAB2_LIB.BASEBOARD_FAB2(SCH_1):PAGE74
    U2    GND @BASEBOARD_FAB2_LIB.BASEBOARD_FAB2(SCH_1):GND    I21 @BASEBOARD_FAB2_LIB.BASEBOARD_FAB2(SCH_1):PAGE74
    U4    GND @BASEBOARD_FAB2_LIB.BASEBOARD_FAB2(SCH_1):GND    I21 @BASEBOARD_FAB2_LIB.BASEBOARD_FAB2(SCH_1):PAGE74
    U6    GND @BASEBOARD_FAB2_LIB.BASEBOARD_FAB2(SCH_1):GND    I21 @BASEBOARD_FAB2_LIB.BASEBOARD_FAB2(SCH_1):PAGE74
   U20    GND @BASEBOARD_FAB2_LIB.BASEBOARD_FAB2(SCH_1):GND    I21 @BASEBOARD_FAB2_LIB.BASEBOARD_FAB2(SCH_1):PAGE74
   U22    GND @BASEBOARD_FAB2_LIB.BASEBOARD_FAB2(SCH_1):GND    I21 @BASEBOARD_FAB2_LIB.BASEBOARD_FAB2(SCH_1):PAGE74
   U24    GND @BASEBOARD_FAB2_LIB.BASEBOARD_FAB2(SCH_1):GND    I21 @BASEBOARD_FAB2_LIB.BASEBOARD_FAB2(SCH_1):PAGE74
   U30    GND @BASEBOARD_FAB2_LIB.BASEBOARD_FAB2(SCH_1):GND    I21 @BASEBOARD_FAB2_LIB.BASEBOARD_FAB2(SCH_1):PAGE74
   U36    GND @BASEBOARD_FAB2_LIB.BASEBOARD_FAB2(SCH_1):GND    I21 @BASEBOARD_FAB2_LIB.BASEBOARD_FAB2(SCH_1):PAGE74
   U42    GND @BASEBOARD_FAB2_LIB.BASEBOARD_FAB2(SCH_1):GND    I21 @BASEBOARD_FAB2_LIB.BASEBOARD_FAB2(SCH_1):PAGE74
   U68    GND @BASEBOARD_FAB2_LIB.BASEBOARD_FAB2(SCH_1):GND    I21 @BASEBOARD_FAB2_LIB.BASEBOARD_FAB2(SCH_1):PAGE74
   U70    GND @BASEBOARD_FAB2_LIB.BASEBOARD_FAB2(SCH_1):GND    I21 @BASEBOARD_FAB2_LIB.BASEBOARD_FAB2(SCH_1):PAGE74
   U74    GND @BASEBOARD_FAB2_LIB.BASEBOARD_FAB2(SCH_1):GND    I21 @BASEBOARD_FAB2_LIB.BASEBOARD_FAB2(SCH_1):PAGE74
   U76    GND @BASEBOARD_FAB2_LIB.BASEBOARD_FAB2(SCH_1):GND    I21 @BASEBOARD_FAB2_LIB.BASEBOARD_FAB2(SCH_1):PAGE74
   U78    GND @BASEBOARD_FAB2_LIB.BASEBOARD_FAB2(SCH_1):GND    I21 @BASEBOARD_FAB2_LIB.BASEBOARD_FAB2(SCH_1):PAGE74
   U80    GND @BASEBOARD_FAB2_LIB.BASEBOARD_FAB2(SCH_1):GND    I21 @BASEBOARD_FAB2_LIB.BASEBOARD_FAB2(SCH_1):PAGE74
   U86    GND @BASEBOARD_FAB2_LIB.BASEBOARD_FAB2(SCH_1):GND    I21 @BASEBOARD_FAB2_LIB.BASEBOARD_FAB2(SCH_1):PAGE74
    V1    GND @BASEBOARD_FAB2_LIB.BASEBOARD_FAB2(SCH_1):GND    I21 @BASEBOARD_FAB2_LIB.BASEBOARD_FAB2(SCH_1):PAGE74
    V5    GND @BASEBOARD_FAB2_LIB.BASEBOARD_FAB2(SCH_1):GND    I21 @BASEBOARD_FAB2_LIB.BASEBOARD_FAB2(SCH_1):PAGE74
    V9    GND @BASEBOARD_FAB2_LIB.BASEBOARD_FAB2(SCH_1):GND    I21 @BASEBOARD_FAB2_LIB.BASEBOARD_FAB2(SCH_1):PAGE74
   V13    GND @BASEBOARD_FAB2_LIB.BASEBOARD_FAB2(SCH_1):GND    I21 @BASEBOARD_FAB2_LIB.BASEBOARD_FAB2(SCH_1):PAGE74
   V15    GND @BASEBOARD_FAB2_LIB.BASEBOARD_FAB2(SCH_1):GND    I21 @BASEBOARD_FAB2_LIB.BASEBOARD_FAB2(SCH_1):PAGE74
   V21    GND @BASEBOARD_FAB2_LIB.BASEBOARD_FAB2(SCH_1):GND    I21 @BASEBOARD_FAB2_LIB.BASEBOARD_FAB2(SCH_1):PAGE74
   V23    GND @BASEBOARD_FAB2_LIB.BASEBOARD_FAB2(SCH_1):GND    I21 @BASEBOARD_FAB2_LIB.BASEBOARD_FAB2(SCH_1):PAGE74
   V43    GND @BASEBOARD_FAB2_LIB.BASEBOARD_FAB2(SCH_1):GND    I21 @BASEBOARD_FAB2_LIB.BASEBOARD_FAB2(SCH_1):PAGE74
   V73    GND @BASEBOARD_FAB2_LIB.BASEBOARD_FAB2(SCH_1):GND    I21 @BASEBOARD_FAB2_LIB.BASEBOARD_FAB2(SCH_1):PAGE74
   V75    GND @BASEBOARD_FAB2_LIB.BASEBOARD_FAB2(SCH_1):GND    I21 @BASEBOARD_FAB2_LIB.BASEBOARD_FAB2(SCH_1):PAGE74
   V77    GND @BASEBOARD_FAB2_LIB.BASEBOARD_FAB2(SCH_1):GND    I21 @BASEBOARD_FAB2_LIB.BASEBOARD_FAB2(SCH_1):PAGE74
   V83    GND @BASEBOARD_FAB2_LIB.BASEBOARD_FAB2(SCH_1):GND    I21 @BASEBOARD_FAB2_LIB.BASEBOARD_FAB2(SCH_1):PAGE74
    W8    GND @BASEBOARD_FAB2_LIB.BASEBOARD_FAB2(SCH_1):GND    I21 @BASEBOARD_FAB2_LIB.BASEBOARD_FAB2(SCH_1):PAGE74
  AC56    GND @BASEBOARD_FAB2_LIB.BASEBOARD_FAB2(SCH_1):GND    I21 @BASEBOARD_FAB2_LIB.BASEBOARD_FAB2(SCH_1):PAGE74
   W12    GND @BASEBOARD_FAB2_LIB.BASEBOARD_FAB2(SCH_1):GND    I21 @BASEBOARD_FAB2_LIB.BASEBOARD_FAB2(SCH_1):PAGE74
   W22    GND @BASEBOARD_FAB2_LIB.BASEBOARD_FAB2(SCH_1):GND    I21 @BASEBOARD_FAB2_LIB.BASEBOARD_FAB2(SCH_1):PAGE74
   W24    GND @BASEBOARD_FAB2_LIB.BASEBOARD_FAB2(SCH_1):GND    I21 @BASEBOARD_FAB2_LIB.BASEBOARD_FAB2(SCH_1):PAGE74
   W26    GND @BASEBOARD_FAB2_LIB.BASEBOARD_FAB2(SCH_1):GND    I21 @BASEBOARD_FAB2_LIB.BASEBOARD_FAB2(SCH_1):PAGE74
   W28    GND @BASEBOARD_FAB2_LIB.BASEBOARD_FAB2(SCH_1):GND    I21 @BASEBOARD_FAB2_LIB.BASEBOARD_FAB2(SCH_1):PAGE74
   W30    GND @BASEBOARD_FAB2_LIB.BASEBOARD_FAB2(SCH_1):GND    I21 @BASEBOARD_FAB2_LIB.BASEBOARD_FAB2(SCH_1):PAGE74
   W32    GND @BASEBOARD_FAB2_LIB.BASEBOARD_FAB2(SCH_1):GND    I21 @BASEBOARD_FAB2_LIB.BASEBOARD_FAB2(SCH_1):PAGE74
   W34    GND @BASEBOARD_FAB2_LIB.BASEBOARD_FAB2(SCH_1):GND    I21 @BASEBOARD_FAB2_LIB.BASEBOARD_FAB2(SCH_1):PAGE74
   W36    GND @BASEBOARD_FAB2_LIB.BASEBOARD_FAB2(SCH_1):GND    I21 @BASEBOARD_FAB2_LIB.BASEBOARD_FAB2(SCH_1):PAGE74
   W38    GND @BASEBOARD_FAB2_LIB.BASEBOARD_FAB2(SCH_1):GND    I21 @BASEBOARD_FAB2_LIB.BASEBOARD_FAB2(SCH_1):PAGE74
   W40    GND @BASEBOARD_FAB2_LIB.BASEBOARD_FAB2(SCH_1):GND    I21 @BASEBOARD_FAB2_LIB.BASEBOARD_FAB2(SCH_1):PAGE74
   W42    GND @BASEBOARD_FAB2_LIB.BASEBOARD_FAB2(SCH_1):GND    I21 @BASEBOARD_FAB2_LIB.BASEBOARD_FAB2(SCH_1):PAGE74
   W68    GND @BASEBOARD_FAB2_LIB.BASEBOARD_FAB2(SCH_1):GND    I21 @BASEBOARD_FAB2_LIB.BASEBOARD_FAB2(SCH_1):PAGE74
   W74    GND @BASEBOARD_FAB2_LIB.BASEBOARD_FAB2(SCH_1):GND    I21 @BASEBOARD_FAB2_LIB.BASEBOARD_FAB2(SCH_1):PAGE74
   W78    GND @BASEBOARD_FAB2_LIB.BASEBOARD_FAB2(SCH_1):GND    I21 @BASEBOARD_FAB2_LIB.BASEBOARD_FAB2(SCH_1):PAGE74
   W82    GND @BASEBOARD_FAB2_LIB.BASEBOARD_FAB2(SCH_1):GND    I21 @BASEBOARD_FAB2_LIB.BASEBOARD_FAB2(SCH_1):PAGE74
   Y15    GND @BASEBOARD_FAB2_LIB.BASEBOARD_FAB2(SCH_1):GND    I21 @BASEBOARD_FAB2_LIB.BASEBOARD_FAB2(SCH_1):PAGE74
   Y17    GND @BASEBOARD_FAB2_LIB.BASEBOARD_FAB2(SCH_1):GND    I21 @BASEBOARD_FAB2_LIB.BASEBOARD_FAB2(SCH_1):PAGE74
    Y5    GND @BASEBOARD_FAB2_LIB.BASEBOARD_FAB2(SCH_1):GND    I21 @BASEBOARD_FAB2_LIB.BASEBOARD_FAB2(SCH_1):PAGE74
   Y67    GND @BASEBOARD_FAB2_LIB.BASEBOARD_FAB2(SCH_1):GND    I21 @BASEBOARD_FAB2_LIB.BASEBOARD_FAB2(SCH_1):PAGE74
    Y7    GND @BASEBOARD_FAB2_LIB.BASEBOARD_FAB2(SCH_1):GND    I21 @BASEBOARD_FAB2_LIB.BASEBOARD_FAB2(SCH_1):PAGE74
    Y9    GND @BASEBOARD_FAB2_LIB.BASEBOARD_FAB2(SCH_1):GND    I21 @BASEBOARD_FAB2_LIB.BASEBOARD_FAB2(SCH_1):PAGE74
   Y71    GND @BASEBOARD_FAB2_LIB.BASEBOARD_FAB2(SCH_1):GND    I21 @BASEBOARD_FAB2_LIB.BASEBOARD_FAB2(SCH_1):PAGE74
   Y73    GND @BASEBOARD_FAB2_LIB.BASEBOARD_FAB2(SCH_1):GND    I21 @BASEBOARD_FAB2_LIB.BASEBOARD_FAB2(SCH_1):PAGE74
   Y79    GND @BASEBOARD_FAB2_LIB.BASEBOARD_FAB2(SCH_1):GND    I21 @BASEBOARD_FAB2_LIB.BASEBOARD_FAB2(SCH_1):PAGE74
   Y81    GND @BASEBOARD_FAB2_LIB.BASEBOARD_FAB2(SCH_1):GND    I21 @BASEBOARD_FAB2_LIB.BASEBOARD_FAB2(SCH_1):PAGE74
   Y83    GND @BASEBOARD_FAB2_LIB.BASEBOARD_FAB2(SCH_1):GND    I21 @BASEBOARD_FAB2_LIB.BASEBOARD_FAB2(SCH_1):PAGE74
   Y85    GND @BASEBOARD_FAB2_LIB.BASEBOARD_FAB2(SCH_1):GND    I21 @BASEBOARD_FAB2_LIB.BASEBOARD_FAB2(SCH_1):PAGE74
   AA4    GND @BASEBOARD_FAB2_LIB.BASEBOARD_FAB2(SCH_1):GND    I21 @BASEBOARD_FAB2_LIB.BASEBOARD_FAB2(SCH_1):PAGE74
  AA16    GND @BASEBOARD_FAB2_LIB.BASEBOARD_FAB2(SCH_1):GND    I21 @BASEBOARD_FAB2_LIB.BASEBOARD_FAB2(SCH_1):PAGE74
  AA18    GND @BASEBOARD_FAB2_LIB.BASEBOARD_FAB2(SCH_1):GND    I22 @BASEBOARD_FAB2_LIB.BASEBOARD_FAB2(SCH_1):PAGE74
  AA22    GND @BASEBOARD_FAB2_LIB.BASEBOARD_FAB2(SCH_1):GND    I22 @BASEBOARD_FAB2_LIB.BASEBOARD_FAB2(SCH_1):PAGE74
  AA24    GND @BASEBOARD_FAB2_LIB.BASEBOARD_FAB2(SCH_1):GND    I22 @BASEBOARD_FAB2_LIB.BASEBOARD_FAB2(SCH_1):PAGE74
  AA30    GND @BASEBOARD_FAB2_LIB.BASEBOARD_FAB2(SCH_1):GND    I22 @BASEBOARD_FAB2_LIB.BASEBOARD_FAB2(SCH_1):PAGE74
  AA36    GND @BASEBOARD_FAB2_LIB.BASEBOARD_FAB2(SCH_1):GND    I22 @BASEBOARD_FAB2_LIB.BASEBOARD_FAB2(SCH_1):PAGE74
  AA42    GND @BASEBOARD_FAB2_LIB.BASEBOARD_FAB2(SCH_1):GND    I22 @BASEBOARD_FAB2_LIB.BASEBOARD_FAB2(SCH_1):PAGE74
  AA64    GND @BASEBOARD_FAB2_LIB.BASEBOARD_FAB2(SCH_1):GND    I22 @BASEBOARD_FAB2_LIB.BASEBOARD_FAB2(SCH_1):PAGE74
  AA66    GND @BASEBOARD_FAB2_LIB.BASEBOARD_FAB2(SCH_1):GND    I22 @BASEBOARD_FAB2_LIB.BASEBOARD_FAB2(SCH_1):PAGE74
  AA68    GND @BASEBOARD_FAB2_LIB.BASEBOARD_FAB2(SCH_1):GND    I22 @BASEBOARD_FAB2_LIB.BASEBOARD_FAB2(SCH_1):PAGE74
  AA76    GND @BASEBOARD_FAB2_LIB.BASEBOARD_FAB2(SCH_1):GND    I22 @BASEBOARD_FAB2_LIB.BASEBOARD_FAB2(SCH_1):PAGE74
  AA78    GND @BASEBOARD_FAB2_LIB.BASEBOARD_FAB2(SCH_1):GND    I22 @BASEBOARD_FAB2_LIB.BASEBOARD_FAB2(SCH_1):PAGE74
  AA80    GND @BASEBOARD_FAB2_LIB.BASEBOARD_FAB2(SCH_1):GND    I22 @BASEBOARD_FAB2_LIB.BASEBOARD_FAB2(SCH_1):PAGE74
  AA82    GND @BASEBOARD_FAB2_LIB.BASEBOARD_FAB2(SCH_1):GND    I22 @BASEBOARD_FAB2_LIB.BASEBOARD_FAB2(SCH_1):PAGE74
   AB1    GND @BASEBOARD_FAB2_LIB.BASEBOARD_FAB2(SCH_1):GND    I22 @BASEBOARD_FAB2_LIB.BASEBOARD_FAB2(SCH_1):PAGE74
   AB5    GND @BASEBOARD_FAB2_LIB.BASEBOARD_FAB2(SCH_1):GND    I22 @BASEBOARD_FAB2_LIB.BASEBOARD_FAB2(SCH_1):PAGE74
  AB11    GND @BASEBOARD_FAB2_LIB.BASEBOARD_FAB2(SCH_1):GND    I22 @BASEBOARD_FAB2_LIB.BASEBOARD_FAB2(SCH_1):PAGE74
  AB21    GND @BASEBOARD_FAB2_LIB.BASEBOARD_FAB2(SCH_1):GND    I22 @BASEBOARD_FAB2_LIB.BASEBOARD_FAB2(SCH_1):PAGE74
  AB23    GND @BASEBOARD_FAB2_LIB.BASEBOARD_FAB2(SCH_1):GND    I22 @BASEBOARD_FAB2_LIB.BASEBOARD_FAB2(SCH_1):PAGE74
  AB25    GND @BASEBOARD_FAB2_LIB.BASEBOARD_FAB2(SCH_1):GND    I22 @BASEBOARD_FAB2_LIB.BASEBOARD_FAB2(SCH_1):PAGE74
  AB29    GND @BASEBOARD_FAB2_LIB.BASEBOARD_FAB2(SCH_1):GND    I22 @BASEBOARD_FAB2_LIB.BASEBOARD_FAB2(SCH_1):PAGE74
  AB31    GND @BASEBOARD_FAB2_LIB.BASEBOARD_FAB2(SCH_1):GND    I22 @BASEBOARD_FAB2_LIB.BASEBOARD_FAB2(SCH_1):PAGE74
  AB35    GND @BASEBOARD_FAB2_LIB.BASEBOARD_FAB2(SCH_1):GND    I22 @BASEBOARD_FAB2_LIB.BASEBOARD_FAB2(SCH_1):PAGE74
  AB37    GND @BASEBOARD_FAB2_LIB.BASEBOARD_FAB2(SCH_1):GND    I22 @BASEBOARD_FAB2_LIB.BASEBOARD_FAB2(SCH_1):PAGE74
  AB41    GND @BASEBOARD_FAB2_LIB.BASEBOARD_FAB2(SCH_1):GND    I22 @BASEBOARD_FAB2_LIB.BASEBOARD_FAB2(SCH_1):PAGE74
  AB65    GND @BASEBOARD_FAB2_LIB.BASEBOARD_FAB2(SCH_1):GND    I22 @BASEBOARD_FAB2_LIB.BASEBOARD_FAB2(SCH_1):PAGE74
  AB69    GND @BASEBOARD_FAB2_LIB.BASEBOARD_FAB2(SCH_1):GND    I22 @BASEBOARD_FAB2_LIB.BASEBOARD_FAB2(SCH_1):PAGE74
  AB73    GND @BASEBOARD_FAB2_LIB.BASEBOARD_FAB2(SCH_1):GND    I22 @BASEBOARD_FAB2_LIB.BASEBOARD_FAB2(SCH_1):PAGE74
  AB79    GND @BASEBOARD_FAB2_LIB.BASEBOARD_FAB2(SCH_1):GND    I22 @BASEBOARD_FAB2_LIB.BASEBOARD_FAB2(SCH_1):PAGE74
  AB83    GND @BASEBOARD_FAB2_LIB.BASEBOARD_FAB2(SCH_1):GND    I22 @BASEBOARD_FAB2_LIB.BASEBOARD_FAB2(SCH_1):PAGE74
  AB85    GND @BASEBOARD_FAB2_LIB.BASEBOARD_FAB2(SCH_1):GND    I22 @BASEBOARD_FAB2_LIB.BASEBOARD_FAB2(SCH_1):PAGE74
  AC18    GND @BASEBOARD_FAB2_LIB.BASEBOARD_FAB2(SCH_1):GND    I22 @BASEBOARD_FAB2_LIB.BASEBOARD_FAB2(SCH_1):PAGE74
  AC22    GND @BASEBOARD_FAB2_LIB.BASEBOARD_FAB2(SCH_1):GND    I22 @BASEBOARD_FAB2_LIB.BASEBOARD_FAB2(SCH_1):PAGE74
  AC26    GND @BASEBOARD_FAB2_LIB.BASEBOARD_FAB2(SCH_1):GND    I22 @BASEBOARD_FAB2_LIB.BASEBOARD_FAB2(SCH_1):PAGE74
  AC28    GND @BASEBOARD_FAB2_LIB.BASEBOARD_FAB2(SCH_1):GND    I22 @BASEBOARD_FAB2_LIB.BASEBOARD_FAB2(SCH_1):PAGE74
  AC32    GND @BASEBOARD_FAB2_LIB.BASEBOARD_FAB2(SCH_1):GND    I22 @BASEBOARD_FAB2_LIB.BASEBOARD_FAB2(SCH_1):PAGE74
  AC34    GND @BASEBOARD_FAB2_LIB.BASEBOARD_FAB2(SCH_1):GND    I22 @BASEBOARD_FAB2_LIB.BASEBOARD_FAB2(SCH_1):PAGE74
  AC38    GND @BASEBOARD_FAB2_LIB.BASEBOARD_FAB2(SCH_1):GND    I22 @BASEBOARD_FAB2_LIB.BASEBOARD_FAB2(SCH_1):PAGE74
  AC40    GND @BASEBOARD_FAB2_LIB.BASEBOARD_FAB2(SCH_1):GND    I22 @BASEBOARD_FAB2_LIB.BASEBOARD_FAB2(SCH_1):PAGE74
  AC64    GND @BASEBOARD_FAB2_LIB.BASEBOARD_FAB2(SCH_1):GND    I22 @BASEBOARD_FAB2_LIB.BASEBOARD_FAB2(SCH_1):PAGE74
  AC70    GND @BASEBOARD_FAB2_LIB.BASEBOARD_FAB2(SCH_1):GND    I22 @BASEBOARD_FAB2_LIB.BASEBOARD_FAB2(SCH_1):PAGE74
  AC72    GND @BASEBOARD_FAB2_LIB.BASEBOARD_FAB2(SCH_1):GND    I22 @BASEBOARD_FAB2_LIB.BASEBOARD_FAB2(SCH_1):PAGE74
  AC78    GND @BASEBOARD_FAB2_LIB.BASEBOARD_FAB2(SCH_1):GND    I22 @BASEBOARD_FAB2_LIB.BASEBOARD_FAB2(SCH_1):PAGE74
  AC84    GND @BASEBOARD_FAB2_LIB.BASEBOARD_FAB2(SCH_1):GND    I22 @BASEBOARD_FAB2_LIB.BASEBOARD_FAB2(SCH_1):PAGE74
  AC86    GND @BASEBOARD_FAB2_LIB.BASEBOARD_FAB2(SCH_1):GND    I22 @BASEBOARD_FAB2_LIB.BASEBOARD_FAB2(SCH_1):PAGE74
   AD3    GND @BASEBOARD_FAB2_LIB.BASEBOARD_FAB2(SCH_1):GND    I22 @BASEBOARD_FAB2_LIB.BASEBOARD_FAB2(SCH_1):PAGE74
   AD7    GND @BASEBOARD_FAB2_LIB.BASEBOARD_FAB2(SCH_1):GND    I22 @BASEBOARD_FAB2_LIB.BASEBOARD_FAB2(SCH_1):PAGE74
   AD9    GND @BASEBOARD_FAB2_LIB.BASEBOARD_FAB2(SCH_1):GND    I22 @BASEBOARD_FAB2_LIB.BASEBOARD_FAB2(SCH_1):PAGE74
  AD11    GND @BASEBOARD_FAB2_LIB.BASEBOARD_FAB2(SCH_1):GND    I22 @BASEBOARD_FAB2_LIB.BASEBOARD_FAB2(SCH_1):PAGE74
  AD13    GND @BASEBOARD_FAB2_LIB.BASEBOARD_FAB2(SCH_1):GND    I22 @BASEBOARD_FAB2_LIB.BASEBOARD_FAB2(SCH_1):PAGE74
  AD15    GND @BASEBOARD_FAB2_LIB.BASEBOARD_FAB2(SCH_1):GND    I22 @BASEBOARD_FAB2_LIB.BASEBOARD_FAB2(SCH_1):PAGE74
  AD19    GND @BASEBOARD_FAB2_LIB.BASEBOARD_FAB2(SCH_1):GND    I22 @BASEBOARD_FAB2_LIB.BASEBOARD_FAB2(SCH_1):PAGE74
  AD21    GND @BASEBOARD_FAB2_LIB.BASEBOARD_FAB2(SCH_1):GND    I22 @BASEBOARD_FAB2_LIB.BASEBOARD_FAB2(SCH_1):PAGE74
  AD27    GND @BASEBOARD_FAB2_LIB.BASEBOARD_FAB2(SCH_1):GND    I22 @BASEBOARD_FAB2_LIB.BASEBOARD_FAB2(SCH_1):PAGE74
  AD33    GND @BASEBOARD_FAB2_LIB.BASEBOARD_FAB2(SCH_1):GND    I22 @BASEBOARD_FAB2_LIB.BASEBOARD_FAB2(SCH_1):PAGE74
  AD39    GND @BASEBOARD_FAB2_LIB.BASEBOARD_FAB2(SCH_1):GND    I22 @BASEBOARD_FAB2_LIB.BASEBOARD_FAB2(SCH_1):PAGE74
  AD43    GND @BASEBOARD_FAB2_LIB.BASEBOARD_FAB2(SCH_1):GND    I22 @BASEBOARD_FAB2_LIB.BASEBOARD_FAB2(SCH_1):PAGE74
  AD71    GND @BASEBOARD_FAB2_LIB.BASEBOARD_FAB2(SCH_1):GND    I22 @BASEBOARD_FAB2_LIB.BASEBOARD_FAB2(SCH_1):PAGE74
  AD73    GND @BASEBOARD_FAB2_LIB.BASEBOARD_FAB2(SCH_1):GND    I22 @BASEBOARD_FAB2_LIB.BASEBOARD_FAB2(SCH_1):PAGE74
  AD75    GND @BASEBOARD_FAB2_LIB.BASEBOARD_FAB2(SCH_1):GND    I22 @BASEBOARD_FAB2_LIB.BASEBOARD_FAB2(SCH_1):PAGE74
  AD81    GND @BASEBOARD_FAB2_LIB.BASEBOARD_FAB2(SCH_1):GND    I22 @BASEBOARD_FAB2_LIB.BASEBOARD_FAB2(SCH_1):PAGE74
  AD83    GND @BASEBOARD_FAB2_LIB.BASEBOARD_FAB2(SCH_1):GND    I22 @BASEBOARD_FAB2_LIB.BASEBOARD_FAB2(SCH_1):PAGE74
  AD85    GND @BASEBOARD_FAB2_LIB.BASEBOARD_FAB2(SCH_1):GND    I22 @BASEBOARD_FAB2_LIB.BASEBOARD_FAB2(SCH_1):PAGE74
   AE4    GND @BASEBOARD_FAB2_LIB.BASEBOARD_FAB2(SCH_1):GND    I22 @BASEBOARD_FAB2_LIB.BASEBOARD_FAB2(SCH_1):PAGE74
   AE8    GND @BASEBOARD_FAB2_LIB.BASEBOARD_FAB2(SCH_1):GND    I22 @BASEBOARD_FAB2_LIB.BASEBOARD_FAB2(SCH_1):PAGE74
  AC54    GND @BASEBOARD_FAB2_LIB.BASEBOARD_FAB2(SCH_1):GND    I22 @BASEBOARD_FAB2_LIB.BASEBOARD_FAB2(SCH_1):PAGE74
  AE16    GND @BASEBOARD_FAB2_LIB.BASEBOARD_FAB2(SCH_1):GND    I22 @BASEBOARD_FAB2_LIB.BASEBOARD_FAB2(SCH_1):PAGE74
  AE38    GND @BASEBOARD_FAB2_LIB.BASEBOARD_FAB2(SCH_1):GND    I22 @BASEBOARD_FAB2_LIB.BASEBOARD_FAB2(SCH_1):PAGE74
  AE40    GND @BASEBOARD_FAB2_LIB.BASEBOARD_FAB2(SCH_1):GND    I22 @BASEBOARD_FAB2_LIB.BASEBOARD_FAB2(SCH_1):PAGE74
  AE42    GND @BASEBOARD_FAB2_LIB.BASEBOARD_FAB2(SCH_1):GND    I22 @BASEBOARD_FAB2_LIB.BASEBOARD_FAB2(SCH_1):PAGE74
  AE64    GND @BASEBOARD_FAB2_LIB.BASEBOARD_FAB2(SCH_1):GND    I22 @BASEBOARD_FAB2_LIB.BASEBOARD_FAB2(SCH_1):PAGE74
  AE66    GND @BASEBOARD_FAB2_LIB.BASEBOARD_FAB2(SCH_1):GND    I22 @BASEBOARD_FAB2_LIB.BASEBOARD_FAB2(SCH_1):PAGE74
  AE68    GND @BASEBOARD_FAB2_LIB.BASEBOARD_FAB2(SCH_1):GND    I22 @BASEBOARD_FAB2_LIB.BASEBOARD_FAB2(SCH_1):PAGE74
  AE70    GND @BASEBOARD_FAB2_LIB.BASEBOARD_FAB2(SCH_1):GND    I22 @BASEBOARD_FAB2_LIB.BASEBOARD_FAB2(SCH_1):PAGE74
  AE78    GND @BASEBOARD_FAB2_LIB.BASEBOARD_FAB2(SCH_1):GND    I22 @BASEBOARD_FAB2_LIB.BASEBOARD_FAB2(SCH_1):PAGE74
   AF1    GND @BASEBOARD_FAB2_LIB.BASEBOARD_FAB2(SCH_1):GND    I22 @BASEBOARD_FAB2_LIB.BASEBOARD_FAB2(SCH_1):PAGE74
  AC52    GND @BASEBOARD_FAB2_LIB.BASEBOARD_FAB2(SCH_1):GND    I22 @BASEBOARD_FAB2_LIB.BASEBOARD_FAB2(SCH_1):PAGE74
   AF9    GND @BASEBOARD_FAB2_LIB.BASEBOARD_FAB2(SCH_1):GND    I22 @BASEBOARD_FAB2_LIB.BASEBOARD_FAB2(SCH_1):PAGE74
  AF21    GND @BASEBOARD_FAB2_LIB.BASEBOARD_FAB2(SCH_1):GND    I22 @BASEBOARD_FAB2_LIB.BASEBOARD_FAB2(SCH_1):PAGE74
  AF23    GND @BASEBOARD_FAB2_LIB.BASEBOARD_FAB2(SCH_1):GND    I22 @BASEBOARD_FAB2_LIB.BASEBOARD_FAB2(SCH_1):PAGE74
  AF25    GND @BASEBOARD_FAB2_LIB.BASEBOARD_FAB2(SCH_1):GND    I22 @BASEBOARD_FAB2_LIB.BASEBOARD_FAB2(SCH_1):PAGE74
  AF27    GND @BASEBOARD_FAB2_LIB.BASEBOARD_FAB2(SCH_1):GND    I22 @BASEBOARD_FAB2_LIB.BASEBOARD_FAB2(SCH_1):PAGE74
  AF29    GND @BASEBOARD_FAB2_LIB.BASEBOARD_FAB2(SCH_1):GND    I22 @BASEBOARD_FAB2_LIB.BASEBOARD_FAB2(SCH_1):PAGE74
  AF31    GND @BASEBOARD_FAB2_LIB.BASEBOARD_FAB2(SCH_1):GND    I22 @BASEBOARD_FAB2_LIB.BASEBOARD_FAB2(SCH_1):PAGE74
  AF33    GND @BASEBOARD_FAB2_LIB.BASEBOARD_FAB2(SCH_1):GND    I22 @BASEBOARD_FAB2_LIB.BASEBOARD_FAB2(SCH_1):PAGE74
  AF37    GND @BASEBOARD_FAB2_LIB.BASEBOARD_FAB2(SCH_1):GND    I22 @BASEBOARD_FAB2_LIB.BASEBOARD_FAB2(SCH_1):PAGE74
  AF39    GND @BASEBOARD_FAB2_LIB.BASEBOARD_FAB2(SCH_1):GND    I22 @BASEBOARD_FAB2_LIB.BASEBOARD_FAB2(SCH_1):PAGE74
  AF41    GND @BASEBOARD_FAB2_LIB.BASEBOARD_FAB2(SCH_1):GND    I22 @BASEBOARD_FAB2_LIB.BASEBOARD_FAB2(SCH_1):PAGE74
  AF73    GND @BASEBOARD_FAB2_LIB.BASEBOARD_FAB2(SCH_1):GND    I22 @BASEBOARD_FAB2_LIB.BASEBOARD_FAB2(SCH_1):PAGE74
  AF77    GND @BASEBOARD_FAB2_LIB.BASEBOARD_FAB2(SCH_1):GND    I22 @BASEBOARD_FAB2_LIB.BASEBOARD_FAB2(SCH_1):PAGE74
  AF83    GND @BASEBOARD_FAB2_LIB.BASEBOARD_FAB2(SCH_1):GND    I22 @BASEBOARD_FAB2_LIB.BASEBOARD_FAB2(SCH_1):PAGE74
  AF85    GND @BASEBOARD_FAB2_LIB.BASEBOARD_FAB2(SCH_1):GND    I22 @BASEBOARD_FAB2_LIB.BASEBOARD_FAB2(SCH_1):PAGE74
  AG12    GND @BASEBOARD_FAB2_LIB.BASEBOARD_FAB2(SCH_1):GND    I22 @BASEBOARD_FAB2_LIB.BASEBOARD_FAB2(SCH_1):PAGE74
  AG14    GND @BASEBOARD_FAB2_LIB.BASEBOARD_FAB2(SCH_1):GND    I22 @BASEBOARD_FAB2_LIB.BASEBOARD_FAB2(SCH_1):PAGE74
  AG18    GND @BASEBOARD_FAB2_LIB.BASEBOARD_FAB2(SCH_1):GND    I22 @BASEBOARD_FAB2_LIB.BASEBOARD_FAB2(SCH_1):PAGE74
  AG36    GND @BASEBOARD_FAB2_LIB.BASEBOARD_FAB2(SCH_1):GND    I22 @BASEBOARD_FAB2_LIB.BASEBOARD_FAB2(SCH_1):PAGE74
  AG64    GND @BASEBOARD_FAB2_LIB.BASEBOARD_FAB2(SCH_1):GND    I22 @BASEBOARD_FAB2_LIB.BASEBOARD_FAB2(SCH_1):PAGE74
  AG70    GND @BASEBOARD_FAB2_LIB.BASEBOARD_FAB2(SCH_1):GND    I22 @BASEBOARD_FAB2_LIB.BASEBOARD_FAB2(SCH_1):PAGE74
  AG74    GND @BASEBOARD_FAB2_LIB.BASEBOARD_FAB2(SCH_1):GND    I22 @BASEBOARD_FAB2_LIB.BASEBOARD_FAB2(SCH_1):PAGE74
  AG76    GND @BASEBOARD_FAB2_LIB.BASEBOARD_FAB2(SCH_1):GND    I22 @BASEBOARD_FAB2_LIB.BASEBOARD_FAB2(SCH_1):PAGE74
  AG78    GND @BASEBOARD_FAB2_LIB.BASEBOARD_FAB2(SCH_1):GND    I22 @BASEBOARD_FAB2_LIB.BASEBOARD_FAB2(SCH_1):PAGE74
  AG80    GND @BASEBOARD_FAB2_LIB.BASEBOARD_FAB2(SCH_1):GND    I22 @BASEBOARD_FAB2_LIB.BASEBOARD_FAB2(SCH_1):PAGE74
   AH1    GND @BASEBOARD_FAB2_LIB.BASEBOARD_FAB2(SCH_1):GND    I22 @BASEBOARD_FAB2_LIB.BASEBOARD_FAB2(SCH_1):PAGE74
   AH5    GND @BASEBOARD_FAB2_LIB.BASEBOARD_FAB2(SCH_1):GND    I22 @BASEBOARD_FAB2_LIB.BASEBOARD_FAB2(SCH_1):PAGE74
  AH21    GND @BASEBOARD_FAB2_LIB.BASEBOARD_FAB2(SCH_1):GND    I22 @BASEBOARD_FAB2_LIB.BASEBOARD_FAB2(SCH_1):PAGE74
  AH27    GND @BASEBOARD_FAB2_LIB.BASEBOARD_FAB2(SCH_1):GND    I22 @BASEBOARD_FAB2_LIB.BASEBOARD_FAB2(SCH_1):PAGE74
  AH33    GND @BASEBOARD_FAB2_LIB.BASEBOARD_FAB2(SCH_1):GND    I22 @BASEBOARD_FAB2_LIB.BASEBOARD_FAB2(SCH_1):PAGE74
  AH35    GND @BASEBOARD_FAB2_LIB.BASEBOARD_FAB2(SCH_1):GND    I22 @BASEBOARD_FAB2_LIB.BASEBOARD_FAB2(SCH_1):PAGE74
  AH45    GND @BASEBOARD_FAB2_LIB.BASEBOARD_FAB2(SCH_1):GND    I22 @BASEBOARD_FAB2_LIB.BASEBOARD_FAB2(SCH_1):PAGE74
  AH47    GND @BASEBOARD_FAB2_LIB.BASEBOARD_FAB2(SCH_1):GND    I22 @BASEBOARD_FAB2_LIB.BASEBOARD_FAB2(SCH_1):PAGE74
  AH49    GND @BASEBOARD_FAB2_LIB.BASEBOARD_FAB2(SCH_1):GND    I22 @BASEBOARD_FAB2_LIB.BASEBOARD_FAB2(SCH_1):PAGE74
  AH51    GND @BASEBOARD_FAB2_LIB.BASEBOARD_FAB2(SCH_1):GND    I22 @BASEBOARD_FAB2_LIB.BASEBOARD_FAB2(SCH_1):PAGE74
  AH53    GND @BASEBOARD_FAB2_LIB.BASEBOARD_FAB2(SCH_1):GND    I22 @BASEBOARD_FAB2_LIB.BASEBOARD_FAB2(SCH_1):PAGE74
  AH59    GND @BASEBOARD_FAB2_LIB.BASEBOARD_FAB2(SCH_1):GND    I22 @BASEBOARD_FAB2_LIB.BASEBOARD_FAB2(SCH_1):PAGE74
  AH61    GND @BASEBOARD_FAB2_LIB.BASEBOARD_FAB2(SCH_1):GND    I22 @BASEBOARD_FAB2_LIB.BASEBOARD_FAB2(SCH_1):PAGE74
  AH65    GND @BASEBOARD_FAB2_LIB.BASEBOARD_FAB2(SCH_1):GND    I22 @BASEBOARD_FAB2_LIB.BASEBOARD_FAB2(SCH_1):PAGE74
  AH69    GND @BASEBOARD_FAB2_LIB.BASEBOARD_FAB2(SCH_1):GND    I22 @BASEBOARD_FAB2_LIB.BASEBOARD_FAB2(SCH_1):PAGE74
  AH75    GND @BASEBOARD_FAB2_LIB.BASEBOARD_FAB2(SCH_1):GND    I22 @BASEBOARD_FAB2_LIB.BASEBOARD_FAB2(SCH_1):PAGE74
  AH77    GND @BASEBOARD_FAB2_LIB.BASEBOARD_FAB2(SCH_1):GND    I22 @BASEBOARD_FAB2_LIB.BASEBOARD_FAB2(SCH_1):PAGE74
  AH83    GND @BASEBOARD_FAB2_LIB.BASEBOARD_FAB2(SCH_1):GND    I22 @BASEBOARD_FAB2_LIB.BASEBOARD_FAB2(SCH_1):PAGE74
   AJ8    GND @BASEBOARD_FAB2_LIB.BASEBOARD_FAB2(SCH_1):GND    I22 @BASEBOARD_FAB2_LIB.BASEBOARD_FAB2(SCH_1):PAGE74
  AJ22    GND @BASEBOARD_FAB2_LIB.BASEBOARD_FAB2(SCH_1):GND    I22 @BASEBOARD_FAB2_LIB.BASEBOARD_FAB2(SCH_1):PAGE74
  AJ26    GND @BASEBOARD_FAB2_LIB.BASEBOARD_FAB2(SCH_1):GND    I22 @BASEBOARD_FAB2_LIB.BASEBOARD_FAB2(SCH_1):PAGE74
  AJ28    GND @BASEBOARD_FAB2_LIB.BASEBOARD_FAB2(SCH_1):GND    I22 @BASEBOARD_FAB2_LIB.BASEBOARD_FAB2(SCH_1):PAGE74
  AJ32    GND @BASEBOARD_FAB2_LIB.BASEBOARD_FAB2(SCH_1):GND    I22 @BASEBOARD_FAB2_LIB.BASEBOARD_FAB2(SCH_1):PAGE74
  AJ34    GND @BASEBOARD_FAB2_LIB.BASEBOARD_FAB2(SCH_1):GND    I22 @BASEBOARD_FAB2_LIB.BASEBOARD_FAB2(SCH_1):PAGE74
  AJ46    GND @BASEBOARD_FAB2_LIB.BASEBOARD_FAB2(SCH_1):GND    I22 @BASEBOARD_FAB2_LIB.BASEBOARD_FAB2(SCH_1):PAGE74
  AJ48    GND @BASEBOARD_FAB2_LIB.BASEBOARD_FAB2(SCH_1):GND    I22 @BASEBOARD_FAB2_LIB.BASEBOARD_FAB2(SCH_1):PAGE74
  AJ50    GND @BASEBOARD_FAB2_LIB.BASEBOARD_FAB2(SCH_1):GND    I22 @BASEBOARD_FAB2_LIB.BASEBOARD_FAB2(SCH_1):PAGE74
  AJ52    GND @BASEBOARD_FAB2_LIB.BASEBOARD_FAB2(SCH_1):GND    I22 @BASEBOARD_FAB2_LIB.BASEBOARD_FAB2(SCH_1):PAGE74
  AJ54    GND @BASEBOARD_FAB2_LIB.BASEBOARD_FAB2(SCH_1):GND    I22 @BASEBOARD_FAB2_LIB.BASEBOARD_FAB2(SCH_1):PAGE74
  AJ66    GND @BASEBOARD_FAB2_LIB.BASEBOARD_FAB2(SCH_1):GND    I22 @BASEBOARD_FAB2_LIB.BASEBOARD_FAB2(SCH_1):PAGE74
  AJ68    GND @BASEBOARD_FAB2_LIB.BASEBOARD_FAB2(SCH_1):GND    I22 @BASEBOARD_FAB2_LIB.BASEBOARD_FAB2(SCH_1):PAGE74
  AJ74    GND @BASEBOARD_FAB2_LIB.BASEBOARD_FAB2(SCH_1):GND    I22 @BASEBOARD_FAB2_LIB.BASEBOARD_FAB2(SCH_1):PAGE74
  AJ78    GND @BASEBOARD_FAB2_LIB.BASEBOARD_FAB2(SCH_1):GND    I22 @BASEBOARD_FAB2_LIB.BASEBOARD_FAB2(SCH_1):PAGE74
  AJ82    GND @BASEBOARD_FAB2_LIB.BASEBOARD_FAB2(SCH_1):GND    I22 @BASEBOARD_FAB2_LIB.BASEBOARD_FAB2(SCH_1):PAGE74
  AJ86    GND @BASEBOARD_FAB2_LIB.BASEBOARD_FAB2(SCH_1):GND    I22 @BASEBOARD_FAB2_LIB.BASEBOARD_FAB2(SCH_1):PAGE74
   AK9    GND @BASEBOARD_FAB2_LIB.BASEBOARD_FAB2(SCH_1):GND    I22 @BASEBOARD_FAB2_LIB.BASEBOARD_FAB2(SCH_1):PAGE74
  AK13    GND @BASEBOARD_FAB2_LIB.BASEBOARD_FAB2(SCH_1):GND    I22 @BASEBOARD_FAB2_LIB.BASEBOARD_FAB2(SCH_1):PAGE74
  AK19    GND @BASEBOARD_FAB2_LIB.BASEBOARD_FAB2(SCH_1):GND    I22 @BASEBOARD_FAB2_LIB.BASEBOARD_FAB2(SCH_1):PAGE74
  AK23    GND @BASEBOARD_FAB2_LIB.BASEBOARD_FAB2(SCH_1):GND    I22 @BASEBOARD_FAB2_LIB.BASEBOARD_FAB2(SCH_1):PAGE74
  AK25    GND @BASEBOARD_FAB2_LIB.BASEBOARD_FAB2(SCH_1):GND    I22 @BASEBOARD_FAB2_LIB.BASEBOARD_FAB2(SCH_1):PAGE74
  AK29    GND @BASEBOARD_FAB2_LIB.BASEBOARD_FAB2(SCH_1):GND    I22 @BASEBOARD_FAB2_LIB.BASEBOARD_FAB2(SCH_1):PAGE74
  AK31    GND @BASEBOARD_FAB2_LIB.BASEBOARD_FAB2(SCH_1):GND    I22 @BASEBOARD_FAB2_LIB.BASEBOARD_FAB2(SCH_1):PAGE74
  AK33    GND @BASEBOARD_FAB2_LIB.BASEBOARD_FAB2(SCH_1):GND    I22 @BASEBOARD_FAB2_LIB.BASEBOARD_FAB2(SCH_1):PAGE74
  AK55    GND @BASEBOARD_FAB2_LIB.BASEBOARD_FAB2(SCH_1):GND    I22 @BASEBOARD_FAB2_LIB.BASEBOARD_FAB2(SCH_1):PAGE74
  AK65    GND @BASEBOARD_FAB2_LIB.BASEBOARD_FAB2(SCH_1):GND    I22 @BASEBOARD_FAB2_LIB.BASEBOARD_FAB2(SCH_1):PAGE74
  AK67    GND @BASEBOARD_FAB2_LIB.BASEBOARD_FAB2(SCH_1):GND    I22 @BASEBOARD_FAB2_LIB.BASEBOARD_FAB2(SCH_1):PAGE74
  AK73    GND @BASEBOARD_FAB2_LIB.BASEBOARD_FAB2(SCH_1):GND    I22 @BASEBOARD_FAB2_LIB.BASEBOARD_FAB2(SCH_1):PAGE74
  AK79    GND @BASEBOARD_FAB2_LIB.BASEBOARD_FAB2(SCH_1):GND    I22 @BASEBOARD_FAB2_LIB.BASEBOARD_FAB2(SCH_1):PAGE74
  AK81    GND @BASEBOARD_FAB2_LIB.BASEBOARD_FAB2(SCH_1):GND    I22 @BASEBOARD_FAB2_LIB.BASEBOARD_FAB2(SCH_1):PAGE74
  AK83    GND @BASEBOARD_FAB2_LIB.BASEBOARD_FAB2(SCH_1):GND    I22 @BASEBOARD_FAB2_LIB.BASEBOARD_FAB2(SCH_1):PAGE74
  AK85    GND @BASEBOARD_FAB2_LIB.BASEBOARD_FAB2(SCH_1):GND    I22 @BASEBOARD_FAB2_LIB.BASEBOARD_FAB2(SCH_1):PAGE74
   AL4    GND @BASEBOARD_FAB2_LIB.BASEBOARD_FAB2(SCH_1):GND    I22 @BASEBOARD_FAB2_LIB.BASEBOARD_FAB2(SCH_1):PAGE74
  AL10    GND @BASEBOARD_FAB2_LIB.BASEBOARD_FAB2(SCH_1):GND    I22 @BASEBOARD_FAB2_LIB.BASEBOARD_FAB2(SCH_1):PAGE74
  AL24    GND @BASEBOARD_FAB2_LIB.BASEBOARD_FAB2(SCH_1):GND    I22 @BASEBOARD_FAB2_LIB.BASEBOARD_FAB2(SCH_1):PAGE74
  AL30    GND @BASEBOARD_FAB2_LIB.BASEBOARD_FAB2(SCH_1):GND    I22 @BASEBOARD_FAB2_LIB.BASEBOARD_FAB2(SCH_1):PAGE74
  AL32    GND @BASEBOARD_FAB2_LIB.BASEBOARD_FAB2(SCH_1):GND    I22 @BASEBOARD_FAB2_LIB.BASEBOARD_FAB2(SCH_1):PAGE74
  AL56    GND @BASEBOARD_FAB2_LIB.BASEBOARD_FAB2(SCH_1):GND    I22 @BASEBOARD_FAB2_LIB.BASEBOARD_FAB2(SCH_1):PAGE74
  AL64    GND @BASEBOARD_FAB2_LIB.BASEBOARD_FAB2(SCH_1):GND    I22 @BASEBOARD_FAB2_LIB.BASEBOARD_FAB2(SCH_1):PAGE74
  AL68    GND @BASEBOARD_FAB2_LIB.BASEBOARD_FAB2(SCH_1):GND    I22 @BASEBOARD_FAB2_LIB.BASEBOARD_FAB2(SCH_1):PAGE74
  AL76    GND @BASEBOARD_FAB2_LIB.BASEBOARD_FAB2(SCH_1):GND    I23 @BASEBOARD_FAB2_LIB.BASEBOARD_FAB2(SCH_1):PAGE74
  AL78    GND @BASEBOARD_FAB2_LIB.BASEBOARD_FAB2(SCH_1):GND    I23 @BASEBOARD_FAB2_LIB.BASEBOARD_FAB2(SCH_1):PAGE74
  AL80    GND @BASEBOARD_FAB2_LIB.BASEBOARD_FAB2(SCH_1):GND    I23 @BASEBOARD_FAB2_LIB.BASEBOARD_FAB2(SCH_1):PAGE74
  AL82    GND @BASEBOARD_FAB2_LIB.BASEBOARD_FAB2(SCH_1):GND    I23 @BASEBOARD_FAB2_LIB.BASEBOARD_FAB2(SCH_1):PAGE74
  AL86    GND @BASEBOARD_FAB2_LIB.BASEBOARD_FAB2(SCH_1):GND    I23 @BASEBOARD_FAB2_LIB.BASEBOARD_FAB2(SCH_1):PAGE74
   AM1    GND @BASEBOARD_FAB2_LIB.BASEBOARD_FAB2(SCH_1):GND    I23 @BASEBOARD_FAB2_LIB.BASEBOARD_FAB2(SCH_1):PAGE74
  AC50    GND @BASEBOARD_FAB2_LIB.BASEBOARD_FAB2(SCH_1):GND    I23 @BASEBOARD_FAB2_LIB.BASEBOARD_FAB2(SCH_1):PAGE74
  AM31    GND @BASEBOARD_FAB2_LIB.BASEBOARD_FAB2(SCH_1):GND    I23 @BASEBOARD_FAB2_LIB.BASEBOARD_FAB2(SCH_1):PAGE74
  AM57    GND @BASEBOARD_FAB2_LIB.BASEBOARD_FAB2(SCH_1):GND    I23 @BASEBOARD_FAB2_LIB.BASEBOARD_FAB2(SCH_1):PAGE74
  AM63    GND @BASEBOARD_FAB2_LIB.BASEBOARD_FAB2(SCH_1):GND    I23 @BASEBOARD_FAB2_LIB.BASEBOARD_FAB2(SCH_1):PAGE74
  AM69    GND @BASEBOARD_FAB2_LIB.BASEBOARD_FAB2(SCH_1):GND    I23 @BASEBOARD_FAB2_LIB.BASEBOARD_FAB2(SCH_1):PAGE74
  AM73    GND @BASEBOARD_FAB2_LIB.BASEBOARD_FAB2(SCH_1):GND    I23 @BASEBOARD_FAB2_LIB.BASEBOARD_FAB2(SCH_1):PAGE74
  AM79    GND @BASEBOARD_FAB2_LIB.BASEBOARD_FAB2(SCH_1):GND    I23 @BASEBOARD_FAB2_LIB.BASEBOARD_FAB2(SCH_1):PAGE74
  AM83    GND @BASEBOARD_FAB2_LIB.BASEBOARD_FAB2(SCH_1):GND    I23 @BASEBOARD_FAB2_LIB.BASEBOARD_FAB2(SCH_1):PAGE74
   AN2    GND @BASEBOARD_FAB2_LIB.BASEBOARD_FAB2(SCH_1):GND    I23 @BASEBOARD_FAB2_LIB.BASEBOARD_FAB2(SCH_1):PAGE74
   AN6    GND @BASEBOARD_FAB2_LIB.BASEBOARD_FAB2(SCH_1):GND    I23 @BASEBOARD_FAB2_LIB.BASEBOARD_FAB2(SCH_1):PAGE74
  AN28    GND @BASEBOARD_FAB2_LIB.BASEBOARD_FAB2(SCH_1):GND    I23 @BASEBOARD_FAB2_LIB.BASEBOARD_FAB2(SCH_1):PAGE74
  AN58    GND @BASEBOARD_FAB2_LIB.BASEBOARD_FAB2(SCH_1):GND    I23 @BASEBOARD_FAB2_LIB.BASEBOARD_FAB2(SCH_1):PAGE74
  AN78    GND @BASEBOARD_FAB2_LIB.BASEBOARD_FAB2(SCH_1):GND    I23 @BASEBOARD_FAB2_LIB.BASEBOARD_FAB2(SCH_1):PAGE74
   AP5    GND @BASEBOARD_FAB2_LIB.BASEBOARD_FAB2(SCH_1):GND    I23 @BASEBOARD_FAB2_LIB.BASEBOARD_FAB2(SCH_1):PAGE74
   AP9    GND @BASEBOARD_FAB2_LIB.BASEBOARD_FAB2(SCH_1):GND    I23 @BASEBOARD_FAB2_LIB.BASEBOARD_FAB2(SCH_1):PAGE74
  AP13    GND @BASEBOARD_FAB2_LIB.BASEBOARD_FAB2(SCH_1):GND    I23 @BASEBOARD_FAB2_LIB.BASEBOARD_FAB2(SCH_1):PAGE74
  AP19    GND @BASEBOARD_FAB2_LIB.BASEBOARD_FAB2(SCH_1):GND    I23 @BASEBOARD_FAB2_LIB.BASEBOARD_FAB2(SCH_1):PAGE74
  AP31    GND @BASEBOARD_FAB2_LIB.BASEBOARD_FAB2(SCH_1):GND    I23 @BASEBOARD_FAB2_LIB.BASEBOARD_FAB2(SCH_1):PAGE74
  AP59    GND @BASEBOARD_FAB2_LIB.BASEBOARD_FAB2(SCH_1):GND    I23 @BASEBOARD_FAB2_LIB.BASEBOARD_FAB2(SCH_1):PAGE74
  AP63    GND @BASEBOARD_FAB2_LIB.BASEBOARD_FAB2(SCH_1):GND    I23 @BASEBOARD_FAB2_LIB.BASEBOARD_FAB2(SCH_1):PAGE74
  AP65    GND @BASEBOARD_FAB2_LIB.BASEBOARD_FAB2(SCH_1):GND    I23 @BASEBOARD_FAB2_LIB.BASEBOARD_FAB2(SCH_1):PAGE74
  AP67    GND @BASEBOARD_FAB2_LIB.BASEBOARD_FAB2(SCH_1):GND    I23 @BASEBOARD_FAB2_LIB.BASEBOARD_FAB2(SCH_1):PAGE74
  AP69    GND @BASEBOARD_FAB2_LIB.BASEBOARD_FAB2(SCH_1):GND    I23 @BASEBOARD_FAB2_LIB.BASEBOARD_FAB2(SCH_1):PAGE74
  AP73    GND @BASEBOARD_FAB2_LIB.BASEBOARD_FAB2(SCH_1):GND    I23 @BASEBOARD_FAB2_LIB.BASEBOARD_FAB2(SCH_1):PAGE74
  AP75    GND @BASEBOARD_FAB2_LIB.BASEBOARD_FAB2(SCH_1):GND    I23 @BASEBOARD_FAB2_LIB.BASEBOARD_FAB2(SCH_1):PAGE74
  AP81    GND @BASEBOARD_FAB2_LIB.BASEBOARD_FAB2(SCH_1):GND    I23 @BASEBOARD_FAB2_LIB.BASEBOARD_FAB2(SCH_1):PAGE74
  AP83    GND @BASEBOARD_FAB2_LIB.BASEBOARD_FAB2(SCH_1):GND    I23 @BASEBOARD_FAB2_LIB.BASEBOARD_FAB2(SCH_1):PAGE74
  AP85    GND @BASEBOARD_FAB2_LIB.BASEBOARD_FAB2(SCH_1):GND    I23 @BASEBOARD_FAB2_LIB.BASEBOARD_FAB2(SCH_1):PAGE74
  AR10    GND @BASEBOARD_FAB2_LIB.BASEBOARD_FAB2(SCH_1):GND    I23 @BASEBOARD_FAB2_LIB.BASEBOARD_FAB2(SCH_1):PAGE74
  AR24    GND @BASEBOARD_FAB2_LIB.BASEBOARD_FAB2(SCH_1):GND    I23 @BASEBOARD_FAB2_LIB.BASEBOARD_FAB2(SCH_1):PAGE74
  AR30    GND @BASEBOARD_FAB2_LIB.BASEBOARD_FAB2(SCH_1):GND    I23 @BASEBOARD_FAB2_LIB.BASEBOARD_FAB2(SCH_1):PAGE74
  AR60    GND @BASEBOARD_FAB2_LIB.BASEBOARD_FAB2(SCH_1):GND    I23 @BASEBOARD_FAB2_LIB.BASEBOARD_FAB2(SCH_1):PAGE74
  AR72    GND @BASEBOARD_FAB2_LIB.BASEBOARD_FAB2(SCH_1):GND    I23 @BASEBOARD_FAB2_LIB.BASEBOARD_FAB2(SCH_1):PAGE74
  AR78    GND @BASEBOARD_FAB2_LIB.BASEBOARD_FAB2(SCH_1):GND    I23 @BASEBOARD_FAB2_LIB.BASEBOARD_FAB2(SCH_1):PAGE74
  AC48    GND @BASEBOARD_FAB2_LIB.BASEBOARD_FAB2(SCH_1):GND    I23 @BASEBOARD_FAB2_LIB.BASEBOARD_FAB2(SCH_1):PAGE74
   P63    GND @BASEBOARD_FAB2_LIB.BASEBOARD_FAB2(SCH_1):GND    I23 @BASEBOARD_FAB2_LIB.BASEBOARD_FAB2(SCH_1):PAGE74
  AT15    GND @BASEBOARD_FAB2_LIB.BASEBOARD_FAB2(SCH_1):GND    I23 @BASEBOARD_FAB2_LIB.BASEBOARD_FAB2(SCH_1):PAGE74
  AT17    GND @BASEBOARD_FAB2_LIB.BASEBOARD_FAB2(SCH_1):GND    I23 @BASEBOARD_FAB2_LIB.BASEBOARD_FAB2(SCH_1):PAGE74
  AT21    GND @BASEBOARD_FAB2_LIB.BASEBOARD_FAB2(SCH_1):GND    I23 @BASEBOARD_FAB2_LIB.BASEBOARD_FAB2(SCH_1):PAGE74
  AT27    GND @BASEBOARD_FAB2_LIB.BASEBOARD_FAB2(SCH_1):GND    I23 @BASEBOARD_FAB2_LIB.BASEBOARD_FAB2(SCH_1):PAGE74
  AT61    GND @BASEBOARD_FAB2_LIB.BASEBOARD_FAB2(SCH_1):GND    I23 @BASEBOARD_FAB2_LIB.BASEBOARD_FAB2(SCH_1):PAGE74
  AT63    GND @BASEBOARD_FAB2_LIB.BASEBOARD_FAB2(SCH_1):GND    I23 @BASEBOARD_FAB2_LIB.BASEBOARD_FAB2(SCH_1):PAGE74
  AT69    GND @BASEBOARD_FAB2_LIB.BASEBOARD_FAB2(SCH_1):GND    I23 @BASEBOARD_FAB2_LIB.BASEBOARD_FAB2(SCH_1):PAGE74
  AT73    GND @BASEBOARD_FAB2_LIB.BASEBOARD_FAB2(SCH_1):GND    I23 @BASEBOARD_FAB2_LIB.BASEBOARD_FAB2(SCH_1):PAGE74
  AT77    GND @BASEBOARD_FAB2_LIB.BASEBOARD_FAB2(SCH_1):GND    I23 @BASEBOARD_FAB2_LIB.BASEBOARD_FAB2(SCH_1):PAGE74
  AT83    GND @BASEBOARD_FAB2_LIB.BASEBOARD_FAB2(SCH_1):GND    I23 @BASEBOARD_FAB2_LIB.BASEBOARD_FAB2(SCH_1):PAGE74
  AT85    GND @BASEBOARD_FAB2_LIB.BASEBOARD_FAB2(SCH_1):GND    I23 @BASEBOARD_FAB2_LIB.BASEBOARD_FAB2(SCH_1):PAGE74
   AU2    GND @BASEBOARD_FAB2_LIB.BASEBOARD_FAB2(SCH_1):GND    I23 @BASEBOARD_FAB2_LIB.BASEBOARD_FAB2(SCH_1):PAGE74
   AU6    GND @BASEBOARD_FAB2_LIB.BASEBOARD_FAB2(SCH_1):GND    I23 @BASEBOARD_FAB2_LIB.BASEBOARD_FAB2(SCH_1):PAGE74
  AU26    GND @BASEBOARD_FAB2_LIB.BASEBOARD_FAB2(SCH_1):GND    I23 @BASEBOARD_FAB2_LIB.BASEBOARD_FAB2(SCH_1):PAGE74
  AU28    GND @BASEBOARD_FAB2_LIB.BASEBOARD_FAB2(SCH_1):GND    I23 @BASEBOARD_FAB2_LIB.BASEBOARD_FAB2(SCH_1):PAGE74
  AU62    GND @BASEBOARD_FAB2_LIB.BASEBOARD_FAB2(SCH_1):GND    I23 @BASEBOARD_FAB2_LIB.BASEBOARD_FAB2(SCH_1):PAGE74
  AU64    GND @BASEBOARD_FAB2_LIB.BASEBOARD_FAB2(SCH_1):GND    I23 @BASEBOARD_FAB2_LIB.BASEBOARD_FAB2(SCH_1):PAGE74
  AU68    GND @BASEBOARD_FAB2_LIB.BASEBOARD_FAB2(SCH_1):GND    I23 @BASEBOARD_FAB2_LIB.BASEBOARD_FAB2(SCH_1):PAGE74
  AU74    GND @BASEBOARD_FAB2_LIB.BASEBOARD_FAB2(SCH_1):GND    I23 @BASEBOARD_FAB2_LIB.BASEBOARD_FAB2(SCH_1):PAGE74
  AU76    GND @BASEBOARD_FAB2_LIB.BASEBOARD_FAB2(SCH_1):GND    I23 @BASEBOARD_FAB2_LIB.BASEBOARD_FAB2(SCH_1):PAGE74
  AU78    GND @BASEBOARD_FAB2_LIB.BASEBOARD_FAB2(SCH_1):GND    I23 @BASEBOARD_FAB2_LIB.BASEBOARD_FAB2(SCH_1):PAGE74
  AU80    GND @BASEBOARD_FAB2_LIB.BASEBOARD_FAB2(SCH_1):GND    I23 @BASEBOARD_FAB2_LIB.BASEBOARD_FAB2(SCH_1):PAGE74
  AU84    GND @BASEBOARD_FAB2_LIB.BASEBOARD_FAB2(SCH_1):GND    I23 @BASEBOARD_FAB2_LIB.BASEBOARD_FAB2(SCH_1):PAGE74
  AU86    GND @BASEBOARD_FAB2_LIB.BASEBOARD_FAB2(SCH_1):GND    I23 @BASEBOARD_FAB2_LIB.BASEBOARD_FAB2(SCH_1):PAGE74
   AV1    GND @BASEBOARD_FAB2_LIB.BASEBOARD_FAB2(SCH_1):GND    I23 @BASEBOARD_FAB2_LIB.BASEBOARD_FAB2(SCH_1):PAGE74
   AV3    GND @BASEBOARD_FAB2_LIB.BASEBOARD_FAB2(SCH_1):GND    I23 @BASEBOARD_FAB2_LIB.BASEBOARD_FAB2(SCH_1):PAGE74
   AV7    GND @BASEBOARD_FAB2_LIB.BASEBOARD_FAB2(SCH_1):GND    I23 @BASEBOARD_FAB2_LIB.BASEBOARD_FAB2(SCH_1):PAGE74
  AV11    GND @BASEBOARD_FAB2_LIB.BASEBOARD_FAB2(SCH_1):GND    I23 @BASEBOARD_FAB2_LIB.BASEBOARD_FAB2(SCH_1):PAGE74
  AV13    GND @BASEBOARD_FAB2_LIB.BASEBOARD_FAB2(SCH_1):GND    I23 @BASEBOARD_FAB2_LIB.BASEBOARD_FAB2(SCH_1):PAGE74
  AV19    GND @BASEBOARD_FAB2_LIB.BASEBOARD_FAB2(SCH_1):GND    I23 @BASEBOARD_FAB2_LIB.BASEBOARD_FAB2(SCH_1):PAGE74
  AV23    GND @BASEBOARD_FAB2_LIB.BASEBOARD_FAB2(SCH_1):GND    I23 @BASEBOARD_FAB2_LIB.BASEBOARD_FAB2(SCH_1):PAGE74
  AV25    GND @BASEBOARD_FAB2_LIB.BASEBOARD_FAB2(SCH_1):GND    I23 @BASEBOARD_FAB2_LIB.BASEBOARD_FAB2(SCH_1):PAGE74
  AV63    GND @BASEBOARD_FAB2_LIB.BASEBOARD_FAB2(SCH_1):GND    I23 @BASEBOARD_FAB2_LIB.BASEBOARD_FAB2(SCH_1):PAGE74
  AV65    GND @BASEBOARD_FAB2_LIB.BASEBOARD_FAB2(SCH_1):GND    I23 @BASEBOARD_FAB2_LIB.BASEBOARD_FAB2(SCH_1):PAGE74
  AV67    GND @BASEBOARD_FAB2_LIB.BASEBOARD_FAB2(SCH_1):GND    I23 @BASEBOARD_FAB2_LIB.BASEBOARD_FAB2(SCH_1):PAGE74
  AV75    GND @BASEBOARD_FAB2_LIB.BASEBOARD_FAB2(SCH_1):GND    I23 @BASEBOARD_FAB2_LIB.BASEBOARD_FAB2(SCH_1):PAGE74
  AV83    GND @BASEBOARD_FAB2_LIB.BASEBOARD_FAB2(SCH_1):GND    I23 @BASEBOARD_FAB2_LIB.BASEBOARD_FAB2(SCH_1):PAGE74
   AW2    GND @BASEBOARD_FAB2_LIB.BASEBOARD_FAB2(SCH_1):GND    I23 @BASEBOARD_FAB2_LIB.BASEBOARD_FAB2(SCH_1):PAGE74
  AW10    GND @BASEBOARD_FAB2_LIB.BASEBOARD_FAB2(SCH_1):GND    I23 @BASEBOARD_FAB2_LIB.BASEBOARD_FAB2(SCH_1):PAGE74
  AW62    GND @BASEBOARD_FAB2_LIB.BASEBOARD_FAB2(SCH_1):GND    I23 @BASEBOARD_FAB2_LIB.BASEBOARD_FAB2(SCH_1):PAGE74
  AW66    GND @BASEBOARD_FAB2_LIB.BASEBOARD_FAB2(SCH_1):GND    I23 @BASEBOARD_FAB2_LIB.BASEBOARD_FAB2(SCH_1):PAGE74
  AW68    GND @BASEBOARD_FAB2_LIB.BASEBOARD_FAB2(SCH_1):GND    I23 @BASEBOARD_FAB2_LIB.BASEBOARD_FAB2(SCH_1):PAGE74
  AW70    GND @BASEBOARD_FAB2_LIB.BASEBOARD_FAB2(SCH_1):GND    I23 @BASEBOARD_FAB2_LIB.BASEBOARD_FAB2(SCH_1):PAGE74
  AW72    GND @BASEBOARD_FAB2_LIB.BASEBOARD_FAB2(SCH_1):GND    I23 @BASEBOARD_FAB2_LIB.BASEBOARD_FAB2(SCH_1):PAGE74
  AW74    GND @BASEBOARD_FAB2_LIB.BASEBOARD_FAB2(SCH_1):GND    I23 @BASEBOARD_FAB2_LIB.BASEBOARD_FAB2(SCH_1):PAGE74
  AW78    GND @BASEBOARD_FAB2_LIB.BASEBOARD_FAB2(SCH_1):GND    I23 @BASEBOARD_FAB2_LIB.BASEBOARD_FAB2(SCH_1):PAGE74
  AW82    GND @BASEBOARD_FAB2_LIB.BASEBOARD_FAB2(SCH_1):GND    I23 @BASEBOARD_FAB2_LIB.BASEBOARD_FAB2(SCH_1):PAGE74
  AW84    GND @BASEBOARD_FAB2_LIB.BASEBOARD_FAB2(SCH_1):GND    I23 @BASEBOARD_FAB2_LIB.BASEBOARD_FAB2(SCH_1):PAGE74
   AY5    GND @BASEBOARD_FAB2_LIB.BASEBOARD_FAB2(SCH_1):GND    I23 @BASEBOARD_FAB2_LIB.BASEBOARD_FAB2(SCH_1):PAGE74
  AY15    GND @BASEBOARD_FAB2_LIB.BASEBOARD_FAB2(SCH_1):GND    I23 @BASEBOARD_FAB2_LIB.BASEBOARD_FAB2(SCH_1):PAGE74
  AY17    GND @BASEBOARD_FAB2_LIB.BASEBOARD_FAB2(SCH_1):GND    I23 @BASEBOARD_FAB2_LIB.BASEBOARD_FAB2(SCH_1):PAGE74
  AY21    GND @BASEBOARD_FAB2_LIB.BASEBOARD_FAB2(SCH_1):GND    I23 @BASEBOARD_FAB2_LIB.BASEBOARD_FAB2(SCH_1):PAGE74
  AY23    GND @BASEBOARD_FAB2_LIB.BASEBOARD_FAB2(SCH_1):GND    I23 @BASEBOARD_FAB2_LIB.BASEBOARD_FAB2(SCH_1):PAGE74
  AY25    GND @BASEBOARD_FAB2_LIB.BASEBOARD_FAB2(SCH_1):GND    I23 @BASEBOARD_FAB2_LIB.BASEBOARD_FAB2(SCH_1):PAGE74
  AY63    GND @BASEBOARD_FAB2_LIB.BASEBOARD_FAB2(SCH_1):GND    I23 @BASEBOARD_FAB2_LIB.BASEBOARD_FAB2(SCH_1):PAGE74
  AY79    GND @BASEBOARD_FAB2_LIB.BASEBOARD_FAB2(SCH_1):GND    I23 @BASEBOARD_FAB2_LIB.BASEBOARD_FAB2(SCH_1):PAGE74
  AY81    GND @BASEBOARD_FAB2_LIB.BASEBOARD_FAB2(SCH_1):GND    I23 @BASEBOARD_FAB2_LIB.BASEBOARD_FAB2(SCH_1):PAGE74
   BA2    GND @BASEBOARD_FAB2_LIB.BASEBOARD_FAB2(SCH_1):GND    I23 @BASEBOARD_FAB2_LIB.BASEBOARD_FAB2(SCH_1):PAGE74
   BA6    GND @BASEBOARD_FAB2_LIB.BASEBOARD_FAB2(SCH_1):GND    I23 @BASEBOARD_FAB2_LIB.BASEBOARD_FAB2(SCH_1):PAGE74
  BA12    GND @BASEBOARD_FAB2_LIB.BASEBOARD_FAB2(SCH_1):GND    I23 @BASEBOARD_FAB2_LIB.BASEBOARD_FAB2(SCH_1):PAGE74
  BA62    GND @BASEBOARD_FAB2_LIB.BASEBOARD_FAB2(SCH_1):GND    I23 @BASEBOARD_FAB2_LIB.BASEBOARD_FAB2(SCH_1):PAGE74
  BA68    GND @BASEBOARD_FAB2_LIB.BASEBOARD_FAB2(SCH_1):GND    I23 @BASEBOARD_FAB2_LIB.BASEBOARD_FAB2(SCH_1):PAGE74
  BA74    GND @BASEBOARD_FAB2_LIB.BASEBOARD_FAB2(SCH_1):GND    I23 @BASEBOARD_FAB2_LIB.BASEBOARD_FAB2(SCH_1):PAGE74
  BA80    GND @BASEBOARD_FAB2_LIB.BASEBOARD_FAB2(SCH_1):GND    I23 @BASEBOARD_FAB2_LIB.BASEBOARD_FAB2(SCH_1):PAGE74
  BA84    GND @BASEBOARD_FAB2_LIB.BASEBOARD_FAB2(SCH_1):GND    I23 @BASEBOARD_FAB2_LIB.BASEBOARD_FAB2(SCH_1):PAGE74
  BB19    GND @BASEBOARD_FAB2_LIB.BASEBOARD_FAB2(SCH_1):GND    I23 @BASEBOARD_FAB2_LIB.BASEBOARD_FAB2(SCH_1):PAGE74
  BB23    GND @BASEBOARD_FAB2_LIB.BASEBOARD_FAB2(SCH_1):GND    I23 @BASEBOARD_FAB2_LIB.BASEBOARD_FAB2(SCH_1):PAGE74
  BB63    GND @BASEBOARD_FAB2_LIB.BASEBOARD_FAB2(SCH_1):GND    I23 @BASEBOARD_FAB2_LIB.BASEBOARD_FAB2(SCH_1):PAGE74
  BB69    GND @BASEBOARD_FAB2_LIB.BASEBOARD_FAB2(SCH_1):GND    I23 @BASEBOARD_FAB2_LIB.BASEBOARD_FAB2(SCH_1):PAGE74
  BB73    GND @BASEBOARD_FAB2_LIB.BASEBOARD_FAB2(SCH_1):GND    I23 @BASEBOARD_FAB2_LIB.BASEBOARD_FAB2(SCH_1):PAGE74
  BB75    GND @BASEBOARD_FAB2_LIB.BASEBOARD_FAB2(SCH_1):GND    I23 @BASEBOARD_FAB2_LIB.BASEBOARD_FAB2(SCH_1):PAGE74
  BB77    GND @BASEBOARD_FAB2_LIB.BASEBOARD_FAB2(SCH_1):GND    I23 @BASEBOARD_FAB2_LIB.BASEBOARD_FAB2(SCH_1):PAGE74
  BB79    GND @BASEBOARD_FAB2_LIB.BASEBOARD_FAB2(SCH_1):GND    I23 @BASEBOARD_FAB2_LIB.BASEBOARD_FAB2(SCH_1):PAGE74
  BB81    GND @BASEBOARD_FAB2_LIB.BASEBOARD_FAB2(SCH_1):GND    I23 @BASEBOARD_FAB2_LIB.BASEBOARD_FAB2(SCH_1):PAGE74
  BB83    GND @BASEBOARD_FAB2_LIB.BASEBOARD_FAB2(SCH_1):GND    I23 @BASEBOARD_FAB2_LIB.BASEBOARD_FAB2(SCH_1):PAGE74
   BC4    GND @BASEBOARD_FAB2_LIB.BASEBOARD_FAB2(SCH_1):GND    I23 @BASEBOARD_FAB2_LIB.BASEBOARD_FAB2(SCH_1):PAGE74
   BC8    GND @BASEBOARD_FAB2_LIB.BASEBOARD_FAB2(SCH_1):GND    I23 @BASEBOARD_FAB2_LIB.BASEBOARD_FAB2(SCH_1):PAGE74
  BC12    GND @BASEBOARD_FAB2_LIB.BASEBOARD_FAB2(SCH_1):GND    I23 @BASEBOARD_FAB2_LIB.BASEBOARD_FAB2(SCH_1):PAGE74
  BC16    GND @BASEBOARD_FAB2_LIB.BASEBOARD_FAB2(SCH_1):GND    I23 @BASEBOARD_FAB2_LIB.BASEBOARD_FAB2(SCH_1):PAGE74
  BC70    GND @BASEBOARD_FAB2_LIB.BASEBOARD_FAB2(SCH_1):GND    I23 @BASEBOARD_FAB2_LIB.BASEBOARD_FAB2(SCH_1):PAGE74
  BC72    GND @BASEBOARD_FAB2_LIB.BASEBOARD_FAB2(SCH_1):GND    I23 @BASEBOARD_FAB2_LIB.BASEBOARD_FAB2(SCH_1):PAGE74
  BC74    GND @BASEBOARD_FAB2_LIB.BASEBOARD_FAB2(SCH_1):GND    I23 @BASEBOARD_FAB2_LIB.BASEBOARD_FAB2(SCH_1):PAGE74
  BC76    GND @BASEBOARD_FAB2_LIB.BASEBOARD_FAB2(SCH_1):GND    I23 @BASEBOARD_FAB2_LIB.BASEBOARD_FAB2(SCH_1):PAGE74
  BC78    GND @BASEBOARD_FAB2_LIB.BASEBOARD_FAB2(SCH_1):GND    I23 @BASEBOARD_FAB2_LIB.BASEBOARD_FAB2(SCH_1):PAGE74
  BC80    GND @BASEBOARD_FAB2_LIB.BASEBOARD_FAB2(SCH_1):GND    I23 @BASEBOARD_FAB2_LIB.BASEBOARD_FAB2(SCH_1):PAGE74
  BC82    GND @BASEBOARD_FAB2_LIB.BASEBOARD_FAB2(SCH_1):GND    I23 @BASEBOARD_FAB2_LIB.BASEBOARD_FAB2(SCH_1):PAGE74
   BD5    GND @BASEBOARD_FAB2_LIB.BASEBOARD_FAB2(SCH_1):GND    I23 @BASEBOARD_FAB2_LIB.BASEBOARD_FAB2(SCH_1):PAGE74
  BD11    GND @BASEBOARD_FAB2_LIB.BASEBOARD_FAB2(SCH_1):GND    I23 @BASEBOARD_FAB2_LIB.BASEBOARD_FAB2(SCH_1):PAGE74
  BD15    GND @BASEBOARD_FAB2_LIB.BASEBOARD_FAB2(SCH_1):GND    I23 @BASEBOARD_FAB2_LIB.BASEBOARD_FAB2(SCH_1):PAGE74
  BD21    GND @BASEBOARD_FAB2_LIB.BASEBOARD_FAB2(SCH_1):GND    I23 @BASEBOARD_FAB2_LIB.BASEBOARD_FAB2(SCH_1):PAGE74
  BD27    GND @BASEBOARD_FAB2_LIB.BASEBOARD_FAB2(SCH_1):GND    I23 @BASEBOARD_FAB2_LIB.BASEBOARD_FAB2(SCH_1):PAGE74
  BD63    GND @BASEBOARD_FAB2_LIB.BASEBOARD_FAB2(SCH_1):GND    I23 @BASEBOARD_FAB2_LIB.BASEBOARD_FAB2(SCH_1):PAGE74
  BD71    GND @BASEBOARD_FAB2_LIB.BASEBOARD_FAB2(SCH_1):GND    I23 @BASEBOARD_FAB2_LIB.BASEBOARD_FAB2(SCH_1):PAGE74
   BE4    GND @BASEBOARD_FAB2_LIB.BASEBOARD_FAB2(SCH_1):GND    I23 @BASEBOARD_FAB2_LIB.BASEBOARD_FAB2(SCH_1):PAGE74
   BE6    GND @BASEBOARD_FAB2_LIB.BASEBOARD_FAB2(SCH_1):GND    I23 @BASEBOARD_FAB2_LIB.BASEBOARD_FAB2(SCH_1):PAGE74
   BE8    GND @BASEBOARD_FAB2_LIB.BASEBOARD_FAB2(SCH_1):GND    I23 @BASEBOARD_FAB2_LIB.BASEBOARD_FAB2(SCH_1):PAGE74
  BE10    GND @BASEBOARD_FAB2_LIB.BASEBOARD_FAB2(SCH_1):GND    I23 @BASEBOARD_FAB2_LIB.BASEBOARD_FAB2(SCH_1):PAGE74
  BE26    GND @BASEBOARD_FAB2_LIB.BASEBOARD_FAB2(SCH_1):GND    I23 @BASEBOARD_FAB2_LIB.BASEBOARD_FAB2(SCH_1):PAGE74
  BE64    GND @BASEBOARD_FAB2_LIB.BASEBOARD_FAB2(SCH_1):GND    I23 @BASEBOARD_FAB2_LIB.BASEBOARD_FAB2(SCH_1):PAGE74
  BE66    GND @BASEBOARD_FAB2_LIB.BASEBOARD_FAB2(SCH_1):GND    I23 @BASEBOARD_FAB2_LIB.BASEBOARD_FAB2(SCH_1):PAGE74
  BE68    GND @BASEBOARD_FAB2_LIB.BASEBOARD_FAB2(SCH_1):GND    I23 @BASEBOARD_FAB2_LIB.BASEBOARD_FAB2(SCH_1):PAGE74
  BE70    GND @BASEBOARD_FAB2_LIB.BASEBOARD_FAB2(SCH_1):GND    I23 @BASEBOARD_FAB2_LIB.BASEBOARD_FAB2(SCH_1):PAGE74
   BF9    GND @BASEBOARD_FAB2_LIB.BASEBOARD_FAB2(SCH_1):GND    I23 @BASEBOARD_FAB2_LIB.BASEBOARD_FAB2(SCH_1):PAGE74
  BF15    GND @BASEBOARD_FAB2_LIB.BASEBOARD_FAB2(SCH_1):GND    I23 @BASEBOARD_FAB2_LIB.BASEBOARD_FAB2(SCH_1):PAGE74
  BF17    GND @BASEBOARD_FAB2_LIB.BASEBOARD_FAB2(SCH_1):GND    I23 @BASEBOARD_FAB2_LIB.BASEBOARD_FAB2(SCH_1):PAGE74
  BF19    GND @BASEBOARD_FAB2_LIB.BASEBOARD_FAB2(SCH_1):GND    I23 @BASEBOARD_FAB2_LIB.BASEBOARD_FAB2(SCH_1):PAGE74
  BF25    GND @BASEBOARD_FAB2_LIB.BASEBOARD_FAB2(SCH_1):GND    I23 @BASEBOARD_FAB2_LIB.BASEBOARD_FAB2(SCH_1):PAGE74
  BF63    GND @BASEBOARD_FAB2_LIB.BASEBOARD_FAB2(SCH_1):GND    I23 @BASEBOARD_FAB2_LIB.BASEBOARD_FAB2(SCH_1):PAGE74
  BF65    GND @BASEBOARD_FAB2_LIB.BASEBOARD_FAB2(SCH_1):GND    I23 @BASEBOARD_FAB2_LIB.BASEBOARD_FAB2(SCH_1):PAGE74
  BF67    GND @BASEBOARD_FAB2_LIB.BASEBOARD_FAB2(SCH_1):GND    I23 @BASEBOARD_FAB2_LIB.BASEBOARD_FAB2(SCH_1):PAGE74
  BF69    GND @BASEBOARD_FAB2_LIB.BASEBOARD_FAB2(SCH_1):GND    I23 @BASEBOARD_FAB2_LIB.BASEBOARD_FAB2(SCH_1):PAGE74
  BF71    GND @BASEBOARD_FAB2_LIB.BASEBOARD_FAB2(SCH_1):GND    I23 @BASEBOARD_FAB2_LIB.BASEBOARD_FAB2(SCH_1):PAGE74
   BG6    GND @BASEBOARD_FAB2_LIB.BASEBOARD_FAB2(SCH_1):GND    I23 @BASEBOARD_FAB2_LIB.BASEBOARD_FAB2(SCH_1):PAGE74
   BG8    GND @BASEBOARD_FAB2_LIB.BASEBOARD_FAB2(SCH_1):GND    I23 @BASEBOARD_FAB2_LIB.BASEBOARD_FAB2(SCH_1):PAGE74
  BG10    GND @BASEBOARD_FAB2_LIB.BASEBOARD_FAB2(SCH_1):GND    I23 @BASEBOARD_FAB2_LIB.BASEBOARD_FAB2(SCH_1):PAGE74
  BG22    GND @BASEBOARD_FAB2_LIB.BASEBOARD_FAB2(SCH_1):GND    I23 @BASEBOARD_FAB2_LIB.BASEBOARD_FAB2(SCH_1):PAGE74
  BG24    GND @BASEBOARD_FAB2_LIB.BASEBOARD_FAB2(SCH_1):GND    I23 @BASEBOARD_FAB2_LIB.BASEBOARD_FAB2(SCH_1):PAGE74
  BG72    GND @BASEBOARD_FAB2_LIB.BASEBOARD_FAB2(SCH_1):GND    I23 @BASEBOARD_FAB2_LIB.BASEBOARD_FAB2(SCH_1):PAGE74
  BG74    GND @BASEBOARD_FAB2_LIB.BASEBOARD_FAB2(SCH_1):GND    I17 @BASEBOARD_FAB2_LIB.BASEBOARD_FAB2(SCH_1):PAGE75
  BG76    GND @BASEBOARD_FAB2_LIB.BASEBOARD_FAB2(SCH_1):GND    I17 @BASEBOARD_FAB2_LIB.BASEBOARD_FAB2(SCH_1):PAGE75
  BG78    GND @BASEBOARD_FAB2_LIB.BASEBOARD_FAB2(SCH_1):GND    I17 @BASEBOARD_FAB2_LIB.BASEBOARD_FAB2(SCH_1):PAGE75
  BG80    GND @BASEBOARD_FAB2_LIB.BASEBOARD_FAB2(SCH_1):GND    I17 @BASEBOARD_FAB2_LIB.BASEBOARD_FAB2(SCH_1):PAGE75
  BG82    GND @BASEBOARD_FAB2_LIB.BASEBOARD_FAB2(SCH_1):GND    I17 @BASEBOARD_FAB2_LIB.BASEBOARD_FAB2(SCH_1):PAGE75
   BH7    GND @BASEBOARD_FAB2_LIB.BASEBOARD_FAB2(SCH_1):GND    I17 @BASEBOARD_FAB2_LIB.BASEBOARD_FAB2(SCH_1):PAGE75
   BH9    GND @BASEBOARD_FAB2_LIB.BASEBOARD_FAB2(SCH_1):GND    I17 @BASEBOARD_FAB2_LIB.BASEBOARD_FAB2(SCH_1):PAGE75
  BH11    GND @BASEBOARD_FAB2_LIB.BASEBOARD_FAB2(SCH_1):GND    I17 @BASEBOARD_FAB2_LIB.BASEBOARD_FAB2(SCH_1):PAGE75
  BH15    GND @BASEBOARD_FAB2_LIB.BASEBOARD_FAB2(SCH_1):GND    I17 @BASEBOARD_FAB2_LIB.BASEBOARD_FAB2(SCH_1):PAGE75
  BH21    GND @BASEBOARD_FAB2_LIB.BASEBOARD_FAB2(SCH_1):GND    I17 @BASEBOARD_FAB2_LIB.BASEBOARD_FAB2(SCH_1):PAGE75
   BJ4    GND @BASEBOARD_FAB2_LIB.BASEBOARD_FAB2(SCH_1):GND    I17 @BASEBOARD_FAB2_LIB.BASEBOARD_FAB2(SCH_1):PAGE75
   BJ6    GND @BASEBOARD_FAB2_LIB.BASEBOARD_FAB2(SCH_1):GND    I17 @BASEBOARD_FAB2_LIB.BASEBOARD_FAB2(SCH_1):PAGE75
   BK3    GND @BASEBOARD_FAB2_LIB.BASEBOARD_FAB2(SCH_1):GND    I17 @BASEBOARD_FAB2_LIB.BASEBOARD_FAB2(SCH_1):PAGE75
   BK7    GND @BASEBOARD_FAB2_LIB.BASEBOARD_FAB2(SCH_1):GND    I17 @BASEBOARD_FAB2_LIB.BASEBOARD_FAB2(SCH_1):PAGE75
  BK11    GND @BASEBOARD_FAB2_LIB.BASEBOARD_FAB2(SCH_1):GND    I17 @BASEBOARD_FAB2_LIB.BASEBOARD_FAB2(SCH_1):PAGE75
  BK19    GND @BASEBOARD_FAB2_LIB.BASEBOARD_FAB2(SCH_1):GND    I17 @BASEBOARD_FAB2_LIB.BASEBOARD_FAB2(SCH_1):PAGE75
   BL6    GND @BASEBOARD_FAB2_LIB.BASEBOARD_FAB2(SCH_1):GND    I17 @BASEBOARD_FAB2_LIB.BASEBOARD_FAB2(SCH_1):PAGE75
  BL10    GND @BASEBOARD_FAB2_LIB.BASEBOARD_FAB2(SCH_1):GND    I17 @BASEBOARD_FAB2_LIB.BASEBOARD_FAB2(SCH_1):PAGE75
  BL12    GND @BASEBOARD_FAB2_LIB.BASEBOARD_FAB2(SCH_1):GND    I17 @BASEBOARD_FAB2_LIB.BASEBOARD_FAB2(SCH_1):PAGE75
   P61    GND @BASEBOARD_FAB2_LIB.BASEBOARD_FAB2(SCH_1):GND    I17 @BASEBOARD_FAB2_LIB.BASEBOARD_FAB2(SCH_1):PAGE75
  BL22    GND @BASEBOARD_FAB2_LIB.BASEBOARD_FAB2(SCH_1):GND    I17 @BASEBOARD_FAB2_LIB.BASEBOARD_FAB2(SCH_1):PAGE75
  BL24    GND @BASEBOARD_FAB2_LIB.BASEBOARD_FAB2(SCH_1):GND    I17 @BASEBOARD_FAB2_LIB.BASEBOARD_FAB2(SCH_1):PAGE75
  BL64    GND @BASEBOARD_FAB2_LIB.BASEBOARD_FAB2(SCH_1):GND    I17 @BASEBOARD_FAB2_LIB.BASEBOARD_FAB2(SCH_1):PAGE75
  BL66    GND @BASEBOARD_FAB2_LIB.BASEBOARD_FAB2(SCH_1):GND    I17 @BASEBOARD_FAB2_LIB.BASEBOARD_FAB2(SCH_1):PAGE75
  BL68    GND @BASEBOARD_FAB2_LIB.BASEBOARD_FAB2(SCH_1):GND    I17 @BASEBOARD_FAB2_LIB.BASEBOARD_FAB2(SCH_1):PAGE75
  BL70    GND @BASEBOARD_FAB2_LIB.BASEBOARD_FAB2(SCH_1):GND    I17 @BASEBOARD_FAB2_LIB.BASEBOARD_FAB2(SCH_1):PAGE75
  BL72    GND @BASEBOARD_FAB2_LIB.BASEBOARD_FAB2(SCH_1):GND    I17 @BASEBOARD_FAB2_LIB.BASEBOARD_FAB2(SCH_1):PAGE75
  BL74    GND @BASEBOARD_FAB2_LIB.BASEBOARD_FAB2(SCH_1):GND    I17 @BASEBOARD_FAB2_LIB.BASEBOARD_FAB2(SCH_1):PAGE75
  BL76    GND @BASEBOARD_FAB2_LIB.BASEBOARD_FAB2(SCH_1):GND    I17 @BASEBOARD_FAB2_LIB.BASEBOARD_FAB2(SCH_1):PAGE75
  BL78    GND @BASEBOARD_FAB2_LIB.BASEBOARD_FAB2(SCH_1):GND    I17 @BASEBOARD_FAB2_LIB.BASEBOARD_FAB2(SCH_1):PAGE75
  BL80    GND @BASEBOARD_FAB2_LIB.BASEBOARD_FAB2(SCH_1):GND    I17 @BASEBOARD_FAB2_LIB.BASEBOARD_FAB2(SCH_1):PAGE75
  BL82    GND @BASEBOARD_FAB2_LIB.BASEBOARD_FAB2(SCH_1):GND    I17 @BASEBOARD_FAB2_LIB.BASEBOARD_FAB2(SCH_1):PAGE75
   BM9    GND @BASEBOARD_FAB2_LIB.BASEBOARD_FAB2(SCH_1):GND    I17 @BASEBOARD_FAB2_LIB.BASEBOARD_FAB2(SCH_1):PAGE75
  BM13    GND @BASEBOARD_FAB2_LIB.BASEBOARD_FAB2(SCH_1):GND    I17 @BASEBOARD_FAB2_LIB.BASEBOARD_FAB2(SCH_1):PAGE75
  BM15    GND @BASEBOARD_FAB2_LIB.BASEBOARD_FAB2(SCH_1):GND    I17 @BASEBOARD_FAB2_LIB.BASEBOARD_FAB2(SCH_1):PAGE75
   P59    GND @BASEBOARD_FAB2_LIB.BASEBOARD_FAB2(SCH_1):GND    I17 @BASEBOARD_FAB2_LIB.BASEBOARD_FAB2(SCH_1):PAGE75
  BM25    GND @BASEBOARD_FAB2_LIB.BASEBOARD_FAB2(SCH_1):GND    I17 @BASEBOARD_FAB2_LIB.BASEBOARD_FAB2(SCH_1):PAGE75
   BN6    GND @BASEBOARD_FAB2_LIB.BASEBOARD_FAB2(SCH_1):GND    I17 @BASEBOARD_FAB2_LIB.BASEBOARD_FAB2(SCH_1):PAGE75
  BN10    GND @BASEBOARD_FAB2_LIB.BASEBOARD_FAB2(SCH_1):GND    I17 @BASEBOARD_FAB2_LIB.BASEBOARD_FAB2(SCH_1):PAGE75
  BN20    GND @BASEBOARD_FAB2_LIB.BASEBOARD_FAB2(SCH_1):GND    I17 @BASEBOARD_FAB2_LIB.BASEBOARD_FAB2(SCH_1):PAGE75
  BN26    GND @BASEBOARD_FAB2_LIB.BASEBOARD_FAB2(SCH_1):GND    I17 @BASEBOARD_FAB2_LIB.BASEBOARD_FAB2(SCH_1):PAGE75
   BP3    GND @BASEBOARD_FAB2_LIB.BASEBOARD_FAB2(SCH_1):GND    I17 @BASEBOARD_FAB2_LIB.BASEBOARD_FAB2(SCH_1):PAGE75
  BP27    GND @BASEBOARD_FAB2_LIB.BASEBOARD_FAB2(SCH_1):GND    I17 @BASEBOARD_FAB2_LIB.BASEBOARD_FAB2(SCH_1):PAGE75
   BR6    GND @BASEBOARD_FAB2_LIB.BASEBOARD_FAB2(SCH_1):GND    I17 @BASEBOARD_FAB2_LIB.BASEBOARD_FAB2(SCH_1):PAGE75
  BR10    GND @BASEBOARD_FAB2_LIB.BASEBOARD_FAB2(SCH_1):GND    I17 @BASEBOARD_FAB2_LIB.BASEBOARD_FAB2(SCH_1):PAGE75
  BR16    GND @BASEBOARD_FAB2_LIB.BASEBOARD_FAB2(SCH_1):GND    I17 @BASEBOARD_FAB2_LIB.BASEBOARD_FAB2(SCH_1):PAGE75
   P57    GND @BASEBOARD_FAB2_LIB.BASEBOARD_FAB2(SCH_1):GND    I17 @BASEBOARD_FAB2_LIB.BASEBOARD_FAB2(SCH_1):PAGE75
  BR64    GND @BASEBOARD_FAB2_LIB.BASEBOARD_FAB2(SCH_1):GND    I17 @BASEBOARD_FAB2_LIB.BASEBOARD_FAB2(SCH_1):PAGE75
  BR66    GND @BASEBOARD_FAB2_LIB.BASEBOARD_FAB2(SCH_1):GND    I17 @BASEBOARD_FAB2_LIB.BASEBOARD_FAB2(SCH_1):PAGE75
  BR68    GND @BASEBOARD_FAB2_LIB.BASEBOARD_FAB2(SCH_1):GND    I17 @BASEBOARD_FAB2_LIB.BASEBOARD_FAB2(SCH_1):PAGE75
  BR70    GND @BASEBOARD_FAB2_LIB.BASEBOARD_FAB2(SCH_1):GND    I17 @BASEBOARD_FAB2_LIB.BASEBOARD_FAB2(SCH_1):PAGE75
  BR72    GND @BASEBOARD_FAB2_LIB.BASEBOARD_FAB2(SCH_1):GND    I17 @BASEBOARD_FAB2_LIB.BASEBOARD_FAB2(SCH_1):PAGE75
  BR74    GND @BASEBOARD_FAB2_LIB.BASEBOARD_FAB2(SCH_1):GND    I17 @BASEBOARD_FAB2_LIB.BASEBOARD_FAB2(SCH_1):PAGE75
  BR76    GND @BASEBOARD_FAB2_LIB.BASEBOARD_FAB2(SCH_1):GND    I17 @BASEBOARD_FAB2_LIB.BASEBOARD_FAB2(SCH_1):PAGE75
  BR78    GND @BASEBOARD_FAB2_LIB.BASEBOARD_FAB2(SCH_1):GND    I17 @BASEBOARD_FAB2_LIB.BASEBOARD_FAB2(SCH_1):PAGE75
  BR80    GND @BASEBOARD_FAB2_LIB.BASEBOARD_FAB2(SCH_1):GND    I17 @BASEBOARD_FAB2_LIB.BASEBOARD_FAB2(SCH_1):PAGE75
  BR82    GND @BASEBOARD_FAB2_LIB.BASEBOARD_FAB2(SCH_1):GND    I17 @BASEBOARD_FAB2_LIB.BASEBOARD_FAB2(SCH_1):PAGE75
   BT3    GND @BASEBOARD_FAB2_LIB.BASEBOARD_FAB2(SCH_1):GND    I17 @BASEBOARD_FAB2_LIB.BASEBOARD_FAB2(SCH_1):PAGE75
   BT5    GND @BASEBOARD_FAB2_LIB.BASEBOARD_FAB2(SCH_1):GND    I17 @BASEBOARD_FAB2_LIB.BASEBOARD_FAB2(SCH_1):PAGE75
  BT21    GND @BASEBOARD_FAB2_LIB.BASEBOARD_FAB2(SCH_1):GND    I17 @BASEBOARD_FAB2_LIB.BASEBOARD_FAB2(SCH_1):PAGE75
  BT23    GND @BASEBOARD_FAB2_LIB.BASEBOARD_FAB2(SCH_1):GND    I17 @BASEBOARD_FAB2_LIB.BASEBOARD_FAB2(SCH_1):PAGE75
  BT25    GND @BASEBOARD_FAB2_LIB.BASEBOARD_FAB2(SCH_1):GND    I17 @BASEBOARD_FAB2_LIB.BASEBOARD_FAB2(SCH_1):PAGE75
   BU8    GND @BASEBOARD_FAB2_LIB.BASEBOARD_FAB2(SCH_1):GND    I17 @BASEBOARD_FAB2_LIB.BASEBOARD_FAB2(SCH_1):PAGE75
   BV5    GND @BASEBOARD_FAB2_LIB.BASEBOARD_FAB2(SCH_1):GND    I17 @BASEBOARD_FAB2_LIB.BASEBOARD_FAB2(SCH_1):PAGE75
  BU10    GND @BASEBOARD_FAB2_LIB.BASEBOARD_FAB2(SCH_1):GND    I17 @BASEBOARD_FAB2_LIB.BASEBOARD_FAB2(SCH_1):PAGE75
  BV17    GND @BASEBOARD_FAB2_LIB.BASEBOARD_FAB2(SCH_1):GND    I17 @BASEBOARD_FAB2_LIB.BASEBOARD_FAB2(SCH_1):PAGE75
  BV25    GND @BASEBOARD_FAB2_LIB.BASEBOARD_FAB2(SCH_1):GND    I17 @BASEBOARD_FAB2_LIB.BASEBOARD_FAB2(SCH_1):PAGE75
   BW6    GND @BASEBOARD_FAB2_LIB.BASEBOARD_FAB2(SCH_1):GND    I17 @BASEBOARD_FAB2_LIB.BASEBOARD_FAB2(SCH_1):PAGE75
   P55    GND @BASEBOARD_FAB2_LIB.BASEBOARD_FAB2(SCH_1):GND    I17 @BASEBOARD_FAB2_LIB.BASEBOARD_FAB2(SCH_1):PAGE75
  BW12    GND @BASEBOARD_FAB2_LIB.BASEBOARD_FAB2(SCH_1):GND    I17 @BASEBOARD_FAB2_LIB.BASEBOARD_FAB2(SCH_1):PAGE75
  BW14    GND @BASEBOARD_FAB2_LIB.BASEBOARD_FAB2(SCH_1):GND    I17 @BASEBOARD_FAB2_LIB.BASEBOARD_FAB2(SCH_1):PAGE75
  BW16    GND @BASEBOARD_FAB2_LIB.BASEBOARD_FAB2(SCH_1):GND    I17 @BASEBOARD_FAB2_LIB.BASEBOARD_FAB2(SCH_1):PAGE75
  BW18    GND @BASEBOARD_FAB2_LIB.BASEBOARD_FAB2(SCH_1):GND    I17 @BASEBOARD_FAB2_LIB.BASEBOARD_FAB2(SCH_1):PAGE75
  BW26    GND @BASEBOARD_FAB2_LIB.BASEBOARD_FAB2(SCH_1):GND    I17 @BASEBOARD_FAB2_LIB.BASEBOARD_FAB2(SCH_1):PAGE75
  BW72    GND @BASEBOARD_FAB2_LIB.BASEBOARD_FAB2(SCH_1):GND    I17 @BASEBOARD_FAB2_LIB.BASEBOARD_FAB2(SCH_1):PAGE75
  BW74    GND @BASEBOARD_FAB2_LIB.BASEBOARD_FAB2(SCH_1):GND    I17 @BASEBOARD_FAB2_LIB.BASEBOARD_FAB2(SCH_1):PAGE75
  BW76    GND @BASEBOARD_FAB2_LIB.BASEBOARD_FAB2(SCH_1):GND    I17 @BASEBOARD_FAB2_LIB.BASEBOARD_FAB2(SCH_1):PAGE75
  BW78    GND @BASEBOARD_FAB2_LIB.BASEBOARD_FAB2(SCH_1):GND    I17 @BASEBOARD_FAB2_LIB.BASEBOARD_FAB2(SCH_1):PAGE75
  BW80    GND @BASEBOARD_FAB2_LIB.BASEBOARD_FAB2(SCH_1):GND    I17 @BASEBOARD_FAB2_LIB.BASEBOARD_FAB2(SCH_1):PAGE75
  BW82    GND @BASEBOARD_FAB2_LIB.BASEBOARD_FAB2(SCH_1):GND    I17 @BASEBOARD_FAB2_LIB.BASEBOARD_FAB2(SCH_1):PAGE75
  BY11    GND @BASEBOARD_FAB2_LIB.BASEBOARD_FAB2(SCH_1):GND    I17 @BASEBOARD_FAB2_LIB.BASEBOARD_FAB2(SCH_1):PAGE75
  BY13    GND @BASEBOARD_FAB2_LIB.BASEBOARD_FAB2(SCH_1):GND    I17 @BASEBOARD_FAB2_LIB.BASEBOARD_FAB2(SCH_1):PAGE75
  BY23    GND @BASEBOARD_FAB2_LIB.BASEBOARD_FAB2(SCH_1):GND    I17 @BASEBOARD_FAB2_LIB.BASEBOARD_FAB2(SCH_1):PAGE75
  BY63    GND @BASEBOARD_FAB2_LIB.BASEBOARD_FAB2(SCH_1):GND    I17 @BASEBOARD_FAB2_LIB.BASEBOARD_FAB2(SCH_1):PAGE75
  BY65    GND @BASEBOARD_FAB2_LIB.BASEBOARD_FAB2(SCH_1):GND    I17 @BASEBOARD_FAB2_LIB.BASEBOARD_FAB2(SCH_1):PAGE75
  BY67    GND @BASEBOARD_FAB2_LIB.BASEBOARD_FAB2(SCH_1):GND    I17 @BASEBOARD_FAB2_LIB.BASEBOARD_FAB2(SCH_1):PAGE75
  BY69    GND @BASEBOARD_FAB2_LIB.BASEBOARD_FAB2(SCH_1):GND    I17 @BASEBOARD_FAB2_LIB.BASEBOARD_FAB2(SCH_1):PAGE75
  BY71    GND @BASEBOARD_FAB2_LIB.BASEBOARD_FAB2(SCH_1):GND    I17 @BASEBOARD_FAB2_LIB.BASEBOARD_FAB2(SCH_1):PAGE75
   CA2    GND @BASEBOARD_FAB2_LIB.BASEBOARD_FAB2(SCH_1):GND    I17 @BASEBOARD_FAB2_LIB.BASEBOARD_FAB2(SCH_1):PAGE75
   CA6    GND @BASEBOARD_FAB2_LIB.BASEBOARD_FAB2(SCH_1):GND    I17 @BASEBOARD_FAB2_LIB.BASEBOARD_FAB2(SCH_1):PAGE75
   CA8    GND @BASEBOARD_FAB2_LIB.BASEBOARD_FAB2(SCH_1):GND    I17 @BASEBOARD_FAB2_LIB.BASEBOARD_FAB2(SCH_1):PAGE75
  CA10    GND @BASEBOARD_FAB2_LIB.BASEBOARD_FAB2(SCH_1):GND    I17 @BASEBOARD_FAB2_LIB.BASEBOARD_FAB2(SCH_1):PAGE75
  CA14    GND @BASEBOARD_FAB2_LIB.BASEBOARD_FAB2(SCH_1):GND    I17 @BASEBOARD_FAB2_LIB.BASEBOARD_FAB2(SCH_1):PAGE75
  CA18    GND @BASEBOARD_FAB2_LIB.BASEBOARD_FAB2(SCH_1):GND    I17 @BASEBOARD_FAB2_LIB.BASEBOARD_FAB2(SCH_1):PAGE75
  CA26    GND @BASEBOARD_FAB2_LIB.BASEBOARD_FAB2(SCH_1):GND    I17 @BASEBOARD_FAB2_LIB.BASEBOARD_FAB2(SCH_1):PAGE75
  CA64    GND @BASEBOARD_FAB2_LIB.BASEBOARD_FAB2(SCH_1):GND    I17 @BASEBOARD_FAB2_LIB.BASEBOARD_FAB2(SCH_1):PAGE75
  CA66    GND @BASEBOARD_FAB2_LIB.BASEBOARD_FAB2(SCH_1):GND    I17 @BASEBOARD_FAB2_LIB.BASEBOARD_FAB2(SCH_1):PAGE75
  CA68    GND @BASEBOARD_FAB2_LIB.BASEBOARD_FAB2(SCH_1):GND    I17 @BASEBOARD_FAB2_LIB.BASEBOARD_FAB2(SCH_1):PAGE75
  CA70    GND @BASEBOARD_FAB2_LIB.BASEBOARD_FAB2(SCH_1):GND    I17 @BASEBOARD_FAB2_LIB.BASEBOARD_FAB2(SCH_1):PAGE75
   CB7    GND @BASEBOARD_FAB2_LIB.BASEBOARD_FAB2(SCH_1):GND    I17 @BASEBOARD_FAB2_LIB.BASEBOARD_FAB2(SCH_1):PAGE75
   CB9    GND @BASEBOARD_FAB2_LIB.BASEBOARD_FAB2(SCH_1):GND    I17 @BASEBOARD_FAB2_LIB.BASEBOARD_FAB2(SCH_1):PAGE75
  CB27    GND @BASEBOARD_FAB2_LIB.BASEBOARD_FAB2(SCH_1):GND    I17 @BASEBOARD_FAB2_LIB.BASEBOARD_FAB2(SCH_1):PAGE75
  CB63    GND @BASEBOARD_FAB2_LIB.BASEBOARD_FAB2(SCH_1):GND    I17 @BASEBOARD_FAB2_LIB.BASEBOARD_FAB2(SCH_1):PAGE75
  CB71    GND @BASEBOARD_FAB2_LIB.BASEBOARD_FAB2(SCH_1):GND    I17 @BASEBOARD_FAB2_LIB.BASEBOARD_FAB2(SCH_1):PAGE75
   CC4    GND @BASEBOARD_FAB2_LIB.BASEBOARD_FAB2(SCH_1):GND    I17 @BASEBOARD_FAB2_LIB.BASEBOARD_FAB2(SCH_1):PAGE75
  CC16    GND @BASEBOARD_FAB2_LIB.BASEBOARD_FAB2(SCH_1):GND    I17 @BASEBOARD_FAB2_LIB.BASEBOARD_FAB2(SCH_1):PAGE75
  CC18    GND @BASEBOARD_FAB2_LIB.BASEBOARD_FAB2(SCH_1):GND    I17 @BASEBOARD_FAB2_LIB.BASEBOARD_FAB2(SCH_1):PAGE75
  CC24    GND @BASEBOARD_FAB2_LIB.BASEBOARD_FAB2(SCH_1):GND    I17 @BASEBOARD_FAB2_LIB.BASEBOARD_FAB2(SCH_1):PAGE75
  CC64    GND @BASEBOARD_FAB2_LIB.BASEBOARD_FAB2(SCH_1):GND    I17 @BASEBOARD_FAB2_LIB.BASEBOARD_FAB2(SCH_1):PAGE75
  CC72    GND @BASEBOARD_FAB2_LIB.BASEBOARD_FAB2(SCH_1):GND    I17 @BASEBOARD_FAB2_LIB.BASEBOARD_FAB2(SCH_1):PAGE75
  CC74    GND @BASEBOARD_FAB2_LIB.BASEBOARD_FAB2(SCH_1):GND    I17 @BASEBOARD_FAB2_LIB.BASEBOARD_FAB2(SCH_1):PAGE75
  CC76    GND @BASEBOARD_FAB2_LIB.BASEBOARD_FAB2(SCH_1):GND    I17 @BASEBOARD_FAB2_LIB.BASEBOARD_FAB2(SCH_1):PAGE75
  CC78    GND @BASEBOARD_FAB2_LIB.BASEBOARD_FAB2(SCH_1):GND    I17 @BASEBOARD_FAB2_LIB.BASEBOARD_FAB2(SCH_1):PAGE75
  CC80    GND @BASEBOARD_FAB2_LIB.BASEBOARD_FAB2(SCH_1):GND    I17 @BASEBOARD_FAB2_LIB.BASEBOARD_FAB2(SCH_1):PAGE75
  CC82    GND @BASEBOARD_FAB2_LIB.BASEBOARD_FAB2(SCH_1):GND    I17 @BASEBOARD_FAB2_LIB.BASEBOARD_FAB2(SCH_1):PAGE75
   CD5    GND @BASEBOARD_FAB2_LIB.BASEBOARD_FAB2(SCH_1):GND    I17 @BASEBOARD_FAB2_LIB.BASEBOARD_FAB2(SCH_1):PAGE75
  CD13    GND @BASEBOARD_FAB2_LIB.BASEBOARD_FAB2(SCH_1):GND    I17 @BASEBOARD_FAB2_LIB.BASEBOARD_FAB2(SCH_1):PAGE75
  CD63    GND @BASEBOARD_FAB2_LIB.BASEBOARD_FAB2(SCH_1):GND    I17 @BASEBOARD_FAB2_LIB.BASEBOARD_FAB2(SCH_1):PAGE75
  CD73    GND @BASEBOARD_FAB2_LIB.BASEBOARD_FAB2(SCH_1):GND    I17 @BASEBOARD_FAB2_LIB.BASEBOARD_FAB2(SCH_1):PAGE75
  CD75    GND @BASEBOARD_FAB2_LIB.BASEBOARD_FAB2(SCH_1):GND    I17 @BASEBOARD_FAB2_LIB.BASEBOARD_FAB2(SCH_1):PAGE75
  CD77    GND @BASEBOARD_FAB2_LIB.BASEBOARD_FAB2(SCH_1):GND    I17 @BASEBOARD_FAB2_LIB.BASEBOARD_FAB2(SCH_1):PAGE75
  CD79    GND @BASEBOARD_FAB2_LIB.BASEBOARD_FAB2(SCH_1):GND    I17 @BASEBOARD_FAB2_LIB.BASEBOARD_FAB2(SCH_1):PAGE75
  CD81    GND @BASEBOARD_FAB2_LIB.BASEBOARD_FAB2(SCH_1):GND    I17 @BASEBOARD_FAB2_LIB.BASEBOARD_FAB2(SCH_1):PAGE75
  CE10    GND @BASEBOARD_FAB2_LIB.BASEBOARD_FAB2(SCH_1):GND    I17 @BASEBOARD_FAB2_LIB.BASEBOARD_FAB2(SCH_1):PAGE75
  CE14    GND @BASEBOARD_FAB2_LIB.BASEBOARD_FAB2(SCH_1):GND    I17 @BASEBOARD_FAB2_LIB.BASEBOARD_FAB2(SCH_1):PAGE75
  CE20    GND @BASEBOARD_FAB2_LIB.BASEBOARD_FAB2(SCH_1):GND    I17 @BASEBOARD_FAB2_LIB.BASEBOARD_FAB2(SCH_1):PAGE75
  CE26    GND @BASEBOARD_FAB2_LIB.BASEBOARD_FAB2(SCH_1):GND    I17 @BASEBOARD_FAB2_LIB.BASEBOARD_FAB2(SCH_1):PAGE75
  CE62    GND @BASEBOARD_FAB2_LIB.BASEBOARD_FAB2(SCH_1):GND    I17 @BASEBOARD_FAB2_LIB.BASEBOARD_FAB2(SCH_1):PAGE75
  CE70    GND @BASEBOARD_FAB2_LIB.BASEBOARD_FAB2(SCH_1):GND    I17 @BASEBOARD_FAB2_LIB.BASEBOARD_FAB2(SCH_1):PAGE75
  CE82    GND @BASEBOARD_FAB2_LIB.BASEBOARD_FAB2(SCH_1):GND    I17 @BASEBOARD_FAB2_LIB.BASEBOARD_FAB2(SCH_1):PAGE75
   P53    GND @BASEBOARD_FAB2_LIB.BASEBOARD_FAB2(SCH_1):GND    I17 @BASEBOARD_FAB2_LIB.BASEBOARD_FAB2(SCH_1):PAGE75
   CF9    GND @BASEBOARD_FAB2_LIB.BASEBOARD_FAB2(SCH_1):GND    I17 @BASEBOARD_FAB2_LIB.BASEBOARD_FAB2(SCH_1):PAGE75
  CF63    GND @BASEBOARD_FAB2_LIB.BASEBOARD_FAB2(SCH_1):GND    I17 @BASEBOARD_FAB2_LIB.BASEBOARD_FAB2(SCH_1):PAGE75
  CF69    GND @BASEBOARD_FAB2_LIB.BASEBOARD_FAB2(SCH_1):GND    I17 @BASEBOARD_FAB2_LIB.BASEBOARD_FAB2(SCH_1):PAGE75
  CF71    GND @BASEBOARD_FAB2_LIB.BASEBOARD_FAB2(SCH_1):GND    I17 @BASEBOARD_FAB2_LIB.BASEBOARD_FAB2(SCH_1):PAGE75
  CF77    GND @BASEBOARD_FAB2_LIB.BASEBOARD_FAB2(SCH_1):GND    I17 @BASEBOARD_FAB2_LIB.BASEBOARD_FAB2(SCH_1):PAGE75
  CF83    GND @BASEBOARD_FAB2_LIB.BASEBOARD_FAB2(SCH_1):GND    I17 @BASEBOARD_FAB2_LIB.BASEBOARD_FAB2(SCH_1):PAGE75
   P51    GND @BASEBOARD_FAB2_LIB.BASEBOARD_FAB2(SCH_1):GND    I17 @BASEBOARD_FAB2_LIB.BASEBOARD_FAB2(SCH_1):PAGE75
  CG18    GND @BASEBOARD_FAB2_LIB.BASEBOARD_FAB2(SCH_1):GND    I17 @BASEBOARD_FAB2_LIB.BASEBOARD_FAB2(SCH_1):PAGE75
  CG22    GND @BASEBOARD_FAB2_LIB.BASEBOARD_FAB2(SCH_1):GND    I17 @BASEBOARD_FAB2_LIB.BASEBOARD_FAB2(SCH_1):PAGE75
  CG62    GND @BASEBOARD_FAB2_LIB.BASEBOARD_FAB2(SCH_1):GND    I17 @BASEBOARD_FAB2_LIB.BASEBOARD_FAB2(SCH_1):PAGE75
  CG68    GND @BASEBOARD_FAB2_LIB.BASEBOARD_FAB2(SCH_1):GND    I17 @BASEBOARD_FAB2_LIB.BASEBOARD_FAB2(SCH_1):PAGE75
  CG72    GND @BASEBOARD_FAB2_LIB.BASEBOARD_FAB2(SCH_1):GND    I17 @BASEBOARD_FAB2_LIB.BASEBOARD_FAB2(SCH_1):PAGE75
  CG80    GND @BASEBOARD_FAB2_LIB.BASEBOARD_FAB2(SCH_1):GND    I17 @BASEBOARD_FAB2_LIB.BASEBOARD_FAB2(SCH_1):PAGE75
   CH1    GND @BASEBOARD_FAB2_LIB.BASEBOARD_FAB2(SCH_1):GND    I17 @BASEBOARD_FAB2_LIB.BASEBOARD_FAB2(SCH_1):PAGE75
   CH3    GND @BASEBOARD_FAB2_LIB.BASEBOARD_FAB2(SCH_1):GND    I17 @BASEBOARD_FAB2_LIB.BASEBOARD_FAB2(SCH_1):PAGE75
  CH15    GND @BASEBOARD_FAB2_LIB.BASEBOARD_FAB2(SCH_1):GND    I17 @BASEBOARD_FAB2_LIB.BASEBOARD_FAB2(SCH_1):PAGE75
  CH19    GND @BASEBOARD_FAB2_LIB.BASEBOARD_FAB2(SCH_1):GND    I17 @BASEBOARD_FAB2_LIB.BASEBOARD_FAB2(SCH_1):PAGE75
  CH63    GND @BASEBOARD_FAB2_LIB.BASEBOARD_FAB2(SCH_1):GND    I17 @BASEBOARD_FAB2_LIB.BASEBOARD_FAB2(SCH_1):PAGE75
  CH67    GND @BASEBOARD_FAB2_LIB.BASEBOARD_FAB2(SCH_1):GND    I17 @BASEBOARD_FAB2_LIB.BASEBOARD_FAB2(SCH_1):PAGE75
  CH73    GND @BASEBOARD_FAB2_LIB.BASEBOARD_FAB2(SCH_1):GND    I17 @BASEBOARD_FAB2_LIB.BASEBOARD_FAB2(SCH_1):PAGE75
  CH79    GND @BASEBOARD_FAB2_LIB.BASEBOARD_FAB2(SCH_1):GND    I17 @BASEBOARD_FAB2_LIB.BASEBOARD_FAB2(SCH_1):PAGE75
  CH81    GND @BASEBOARD_FAB2_LIB.BASEBOARD_FAB2(SCH_1):GND    I17 @BASEBOARD_FAB2_LIB.BASEBOARD_FAB2(SCH_1):PAGE75
  CH83    GND @BASEBOARD_FAB2_LIB.BASEBOARD_FAB2(SCH_1):GND    I17 @BASEBOARD_FAB2_LIB.BASEBOARD_FAB2(SCH_1):PAGE75
   CJ2    GND @BASEBOARD_FAB2_LIB.BASEBOARD_FAB2(SCH_1):GND    I17 @BASEBOARD_FAB2_LIB.BASEBOARD_FAB2(SCH_1):PAGE75
   CJ6    GND @BASEBOARD_FAB2_LIB.BASEBOARD_FAB2(SCH_1):GND    I17 @BASEBOARD_FAB2_LIB.BASEBOARD_FAB2(SCH_1):PAGE75
   CJ8    GND @BASEBOARD_FAB2_LIB.BASEBOARD_FAB2(SCH_1):GND    I17 @BASEBOARD_FAB2_LIB.BASEBOARD_FAB2(SCH_1):PAGE75
  CJ10    GND @BASEBOARD_FAB2_LIB.BASEBOARD_FAB2(SCH_1):GND    I17 @BASEBOARD_FAB2_LIB.BASEBOARD_FAB2(SCH_1):PAGE75
  CJ12    GND @BASEBOARD_FAB2_LIB.BASEBOARD_FAB2(SCH_1):GND    I17 @BASEBOARD_FAB2_LIB.BASEBOARD_FAB2(SCH_1):PAGE75
   P49    GND @BASEBOARD_FAB2_LIB.BASEBOARD_FAB2(SCH_1):GND    I17 @BASEBOARD_FAB2_LIB.BASEBOARD_FAB2(SCH_1):PAGE75
   P47    GND @BASEBOARD_FAB2_LIB.BASEBOARD_FAB2(SCH_1):GND    I18 @BASEBOARD_FAB2_LIB.BASEBOARD_FAB2(SCH_1):PAGE75
  CJ62    GND @BASEBOARD_FAB2_LIB.BASEBOARD_FAB2(SCH_1):GND    I18 @BASEBOARD_FAB2_LIB.BASEBOARD_FAB2(SCH_1):PAGE75
  CJ74    GND @BASEBOARD_FAB2_LIB.BASEBOARD_FAB2(SCH_1):GND    I18 @BASEBOARD_FAB2_LIB.BASEBOARD_FAB2(SCH_1):PAGE75
  CJ76    GND @BASEBOARD_FAB2_LIB.BASEBOARD_FAB2(SCH_1):GND    I18 @BASEBOARD_FAB2_LIB.BASEBOARD_FAB2(SCH_1):PAGE75
  CJ78    GND @BASEBOARD_FAB2_LIB.BASEBOARD_FAB2(SCH_1):GND    I18 @BASEBOARD_FAB2_LIB.BASEBOARD_FAB2(SCH_1):PAGE75
  CJ82    GND @BASEBOARD_FAB2_LIB.BASEBOARD_FAB2(SCH_1):GND    I18 @BASEBOARD_FAB2_LIB.BASEBOARD_FAB2(SCH_1):PAGE75
  CJ84    GND @BASEBOARD_FAB2_LIB.BASEBOARD_FAB2(SCH_1):GND    I18 @BASEBOARD_FAB2_LIB.BASEBOARD_FAB2(SCH_1):PAGE75
  CJ86    GND @BASEBOARD_FAB2_LIB.BASEBOARD_FAB2(SCH_1):GND    I18 @BASEBOARD_FAB2_LIB.BASEBOARD_FAB2(SCH_1):PAGE75
  CK11    GND @BASEBOARD_FAB2_LIB.BASEBOARD_FAB2(SCH_1):GND    I18 @BASEBOARD_FAB2_LIB.BASEBOARD_FAB2(SCH_1):PAGE75
  CK15    GND @BASEBOARD_FAB2_LIB.BASEBOARD_FAB2(SCH_1):GND    I18 @BASEBOARD_FAB2_LIB.BASEBOARD_FAB2(SCH_1):PAGE75
  CK21    GND @BASEBOARD_FAB2_LIB.BASEBOARD_FAB2(SCH_1):GND    I18 @BASEBOARD_FAB2_LIB.BASEBOARD_FAB2(SCH_1):PAGE75
  CK27    GND @BASEBOARD_FAB2_LIB.BASEBOARD_FAB2(SCH_1):GND    I18 @BASEBOARD_FAB2_LIB.BASEBOARD_FAB2(SCH_1):PAGE75
  CK63    GND @BASEBOARD_FAB2_LIB.BASEBOARD_FAB2(SCH_1):GND    I18 @BASEBOARD_FAB2_LIB.BASEBOARD_FAB2(SCH_1):PAGE75
  CK65    GND @BASEBOARD_FAB2_LIB.BASEBOARD_FAB2(SCH_1):GND    I18 @BASEBOARD_FAB2_LIB.BASEBOARD_FAB2(SCH_1):PAGE75
  CK67    GND @BASEBOARD_FAB2_LIB.BASEBOARD_FAB2(SCH_1):GND    I18 @BASEBOARD_FAB2_LIB.BASEBOARD_FAB2(SCH_1):PAGE75
  CK69    GND @BASEBOARD_FAB2_LIB.BASEBOARD_FAB2(SCH_1):GND    I18 @BASEBOARD_FAB2_LIB.BASEBOARD_FAB2(SCH_1):PAGE75
  CK71    GND @BASEBOARD_FAB2_LIB.BASEBOARD_FAB2(SCH_1):GND    I18 @BASEBOARD_FAB2_LIB.BASEBOARD_FAB2(SCH_1):PAGE75
  CK73    GND @BASEBOARD_FAB2_LIB.BASEBOARD_FAB2(SCH_1):GND    I18 @BASEBOARD_FAB2_LIB.BASEBOARD_FAB2(SCH_1):PAGE75
  CK75    GND @BASEBOARD_FAB2_LIB.BASEBOARD_FAB2(SCH_1):GND    I18 @BASEBOARD_FAB2_LIB.BASEBOARD_FAB2(SCH_1):PAGE75
  CK83    GND @BASEBOARD_FAB2_LIB.BASEBOARD_FAB2(SCH_1):GND    I18 @BASEBOARD_FAB2_LIB.BASEBOARD_FAB2(SCH_1):PAGE75
  CK85    GND @BASEBOARD_FAB2_LIB.BASEBOARD_FAB2(SCH_1):GND    I18 @BASEBOARD_FAB2_LIB.BASEBOARD_FAB2(SCH_1):PAGE75
   CL8    GND @BASEBOARD_FAB2_LIB.BASEBOARD_FAB2(SCH_1):GND    I18 @BASEBOARD_FAB2_LIB.BASEBOARD_FAB2(SCH_1):PAGE75
  CL14    GND @BASEBOARD_FAB2_LIB.BASEBOARD_FAB2(SCH_1):GND    I18 @BASEBOARD_FAB2_LIB.BASEBOARD_FAB2(SCH_1):PAGE75
  CL18    GND @BASEBOARD_FAB2_LIB.BASEBOARD_FAB2(SCH_1):GND    I18 @BASEBOARD_FAB2_LIB.BASEBOARD_FAB2(SCH_1):PAGE75
   P45    GND @BASEBOARD_FAB2_LIB.BASEBOARD_FAB2(SCH_1):GND    I18 @BASEBOARD_FAB2_LIB.BASEBOARD_FAB2(SCH_1):PAGE75
   H63    GND @BASEBOARD_FAB2_LIB.BASEBOARD_FAB2(SCH_1):GND    I18 @BASEBOARD_FAB2_LIB.BASEBOARD_FAB2(SCH_1):PAGE75
  CL62    GND @BASEBOARD_FAB2_LIB.BASEBOARD_FAB2(SCH_1):GND    I18 @BASEBOARD_FAB2_LIB.BASEBOARD_FAB2(SCH_1):PAGE75
  CL64    GND @BASEBOARD_FAB2_LIB.BASEBOARD_FAB2(SCH_1):GND    I18 @BASEBOARD_FAB2_LIB.BASEBOARD_FAB2(SCH_1):PAGE75
  CL66    GND @BASEBOARD_FAB2_LIB.BASEBOARD_FAB2(SCH_1):GND    I18 @BASEBOARD_FAB2_LIB.BASEBOARD_FAB2(SCH_1):PAGE75
  CL74    GND @BASEBOARD_FAB2_LIB.BASEBOARD_FAB2(SCH_1):GND    I18 @BASEBOARD_FAB2_LIB.BASEBOARD_FAB2(SCH_1):PAGE75
  CL76    GND @BASEBOARD_FAB2_LIB.BASEBOARD_FAB2(SCH_1):GND    I18 @BASEBOARD_FAB2_LIB.BASEBOARD_FAB2(SCH_1):PAGE75
  CL78    GND @BASEBOARD_FAB2_LIB.BASEBOARD_FAB2(SCH_1):GND    I18 @BASEBOARD_FAB2_LIB.BASEBOARD_FAB2(SCH_1):PAGE75
  CL80    GND @BASEBOARD_FAB2_LIB.BASEBOARD_FAB2(SCH_1):GND    I18 @BASEBOARD_FAB2_LIB.BASEBOARD_FAB2(SCH_1):PAGE75
  CM19    GND @BASEBOARD_FAB2_LIB.BASEBOARD_FAB2(SCH_1):GND    I18 @BASEBOARD_FAB2_LIB.BASEBOARD_FAB2(SCH_1):PAGE75
  CM29    GND @BASEBOARD_FAB2_LIB.BASEBOARD_FAB2(SCH_1):GND    I18 @BASEBOARD_FAB2_LIB.BASEBOARD_FAB2(SCH_1):PAGE75
   CM5    GND @BASEBOARD_FAB2_LIB.BASEBOARD_FAB2(SCH_1):GND    I18 @BASEBOARD_FAB2_LIB.BASEBOARD_FAB2(SCH_1):PAGE75
  CM31    GND @BASEBOARD_FAB2_LIB.BASEBOARD_FAB2(SCH_1):GND    I18 @BASEBOARD_FAB2_LIB.BASEBOARD_FAB2(SCH_1):PAGE75
  CM61    GND @BASEBOARD_FAB2_LIB.BASEBOARD_FAB2(SCH_1):GND    I18 @BASEBOARD_FAB2_LIB.BASEBOARD_FAB2(SCH_1):PAGE75
  CM63    GND @BASEBOARD_FAB2_LIB.BASEBOARD_FAB2(SCH_1):GND    I18 @BASEBOARD_FAB2_LIB.BASEBOARD_FAB2(SCH_1):PAGE75
  CM67    GND @BASEBOARD_FAB2_LIB.BASEBOARD_FAB2(SCH_1):GND    I18 @BASEBOARD_FAB2_LIB.BASEBOARD_FAB2(SCH_1):PAGE75
  CM73    GND @BASEBOARD_FAB2_LIB.BASEBOARD_FAB2(SCH_1):GND    I18 @BASEBOARD_FAB2_LIB.BASEBOARD_FAB2(SCH_1):PAGE75
  CM77    GND @BASEBOARD_FAB2_LIB.BASEBOARD_FAB2(SCH_1):GND    I18 @BASEBOARD_FAB2_LIB.BASEBOARD_FAB2(SCH_1):PAGE75
  CM83    GND @BASEBOARD_FAB2_LIB.BASEBOARD_FAB2(SCH_1):GND    I18 @BASEBOARD_FAB2_LIB.BASEBOARD_FAB2(SCH_1):PAGE75
  CM85    GND @BASEBOARD_FAB2_LIB.BASEBOARD_FAB2(SCH_1):GND    I18 @BASEBOARD_FAB2_LIB.BASEBOARD_FAB2(SCH_1):PAGE75
   CN2    GND @BASEBOARD_FAB2_LIB.BASEBOARD_FAB2(SCH_1):GND    I18 @BASEBOARD_FAB2_LIB.BASEBOARD_FAB2(SCH_1):PAGE75
  CN12    GND @BASEBOARD_FAB2_LIB.BASEBOARD_FAB2(SCH_1):GND    I18 @BASEBOARD_FAB2_LIB.BASEBOARD_FAB2(SCH_1):PAGE75
   H61    GND @BASEBOARD_FAB2_LIB.BASEBOARD_FAB2(SCH_1):GND    I18 @BASEBOARD_FAB2_LIB.BASEBOARD_FAB2(SCH_1):PAGE75
  CN26    GND @BASEBOARD_FAB2_LIB.BASEBOARD_FAB2(SCH_1):GND    I18 @BASEBOARD_FAB2_LIB.BASEBOARD_FAB2(SCH_1):PAGE75
  CN32    GND @BASEBOARD_FAB2_LIB.BASEBOARD_FAB2(SCH_1):GND    I18 @BASEBOARD_FAB2_LIB.BASEBOARD_FAB2(SCH_1):PAGE75
  CN60    GND @BASEBOARD_FAB2_LIB.BASEBOARD_FAB2(SCH_1):GND    I18 @BASEBOARD_FAB2_LIB.BASEBOARD_FAB2(SCH_1):PAGE75
  CN62    GND @BASEBOARD_FAB2_LIB.BASEBOARD_FAB2(SCH_1):GND    I18 @BASEBOARD_FAB2_LIB.BASEBOARD_FAB2(SCH_1):PAGE75
  CN68    GND @BASEBOARD_FAB2_LIB.BASEBOARD_FAB2(SCH_1):GND    I18 @BASEBOARD_FAB2_LIB.BASEBOARD_FAB2(SCH_1):PAGE75
  CN78    GND @BASEBOARD_FAB2_LIB.BASEBOARD_FAB2(SCH_1):GND    I18 @BASEBOARD_FAB2_LIB.BASEBOARD_FAB2(SCH_1):PAGE75
   CP1    GND @BASEBOARD_FAB2_LIB.BASEBOARD_FAB2(SCH_1):GND    I18 @BASEBOARD_FAB2_LIB.BASEBOARD_FAB2(SCH_1):PAGE75
   H59    GND @BASEBOARD_FAB2_LIB.BASEBOARD_FAB2(SCH_1):GND    I18 @BASEBOARD_FAB2_LIB.BASEBOARD_FAB2(SCH_1):PAGE75
  CP25    GND @BASEBOARD_FAB2_LIB.BASEBOARD_FAB2(SCH_1):GND    I18 @BASEBOARD_FAB2_LIB.BASEBOARD_FAB2(SCH_1):PAGE75
  CP59    GND @BASEBOARD_FAB2_LIB.BASEBOARD_FAB2(SCH_1):GND    I18 @BASEBOARD_FAB2_LIB.BASEBOARD_FAB2(SCH_1):PAGE75
  CP69    GND @BASEBOARD_FAB2_LIB.BASEBOARD_FAB2(SCH_1):GND    I18 @BASEBOARD_FAB2_LIB.BASEBOARD_FAB2(SCH_1):PAGE75
  CP73    GND @BASEBOARD_FAB2_LIB.BASEBOARD_FAB2(SCH_1):GND    I18 @BASEBOARD_FAB2_LIB.BASEBOARD_FAB2(SCH_1):PAGE75
  CP75    GND @BASEBOARD_FAB2_LIB.BASEBOARD_FAB2(SCH_1):GND    I18 @BASEBOARD_FAB2_LIB.BASEBOARD_FAB2(SCH_1):PAGE75
  CP81    GND @BASEBOARD_FAB2_LIB.BASEBOARD_FAB2(SCH_1):GND    I18 @BASEBOARD_FAB2_LIB.BASEBOARD_FAB2(SCH_1):PAGE75
  CP83    GND @BASEBOARD_FAB2_LIB.BASEBOARD_FAB2(SCH_1):GND    I18 @BASEBOARD_FAB2_LIB.BASEBOARD_FAB2(SCH_1):PAGE75
   CR6    GND @BASEBOARD_FAB2_LIB.BASEBOARD_FAB2(SCH_1):GND    I18 @BASEBOARD_FAB2_LIB.BASEBOARD_FAB2(SCH_1):PAGE75
  CR10    GND @BASEBOARD_FAB2_LIB.BASEBOARD_FAB2(SCH_1):GND    I18 @BASEBOARD_FAB2_LIB.BASEBOARD_FAB2(SCH_1):PAGE75
  CR22    GND @BASEBOARD_FAB2_LIB.BASEBOARD_FAB2(SCH_1):GND    I18 @BASEBOARD_FAB2_LIB.BASEBOARD_FAB2(SCH_1):PAGE75
  CR24    GND @BASEBOARD_FAB2_LIB.BASEBOARD_FAB2(SCH_1):GND    I18 @BASEBOARD_FAB2_LIB.BASEBOARD_FAB2(SCH_1):PAGE75
  CR32    GND @BASEBOARD_FAB2_LIB.BASEBOARD_FAB2(SCH_1):GND    I18 @BASEBOARD_FAB2_LIB.BASEBOARD_FAB2(SCH_1):PAGE75
  CR58    GND @BASEBOARD_FAB2_LIB.BASEBOARD_FAB2(SCH_1):GND    I18 @BASEBOARD_FAB2_LIB.BASEBOARD_FAB2(SCH_1):PAGE75
  CR62    GND @BASEBOARD_FAB2_LIB.BASEBOARD_FAB2(SCH_1):GND    I18 @BASEBOARD_FAB2_LIB.BASEBOARD_FAB2(SCH_1):PAGE75
  CR64    GND @BASEBOARD_FAB2_LIB.BASEBOARD_FAB2(SCH_1):GND    I18 @BASEBOARD_FAB2_LIB.BASEBOARD_FAB2(SCH_1):PAGE75
  CR66    GND @BASEBOARD_FAB2_LIB.BASEBOARD_FAB2(SCH_1):GND    I18 @BASEBOARD_FAB2_LIB.BASEBOARD_FAB2(SCH_1):PAGE75
  CR68    GND @BASEBOARD_FAB2_LIB.BASEBOARD_FAB2(SCH_1):GND    I18 @BASEBOARD_FAB2_LIB.BASEBOARD_FAB2(SCH_1):PAGE75
  CR78    GND @BASEBOARD_FAB2_LIB.BASEBOARD_FAB2(SCH_1):GND    I18 @BASEBOARD_FAB2_LIB.BASEBOARD_FAB2(SCH_1):PAGE75
  CR86    GND @BASEBOARD_FAB2_LIB.BASEBOARD_FAB2(SCH_1):GND    I18 @BASEBOARD_FAB2_LIB.BASEBOARD_FAB2(SCH_1):PAGE75
   H57    GND @BASEBOARD_FAB2_LIB.BASEBOARD_FAB2(SCH_1):GND    I18 @BASEBOARD_FAB2_LIB.BASEBOARD_FAB2(SCH_1):PAGE75
  CT13    GND @BASEBOARD_FAB2_LIB.BASEBOARD_FAB2(SCH_1):GND    I18 @BASEBOARD_FAB2_LIB.BASEBOARD_FAB2(SCH_1):PAGE75
  CT19    GND @BASEBOARD_FAB2_LIB.BASEBOARD_FAB2(SCH_1):GND    I18 @BASEBOARD_FAB2_LIB.BASEBOARD_FAB2(SCH_1):PAGE75
  CT27    GND @BASEBOARD_FAB2_LIB.BASEBOARD_FAB2(SCH_1):GND    I18 @BASEBOARD_FAB2_LIB.BASEBOARD_FAB2(SCH_1):PAGE75
  CT29    GND @BASEBOARD_FAB2_LIB.BASEBOARD_FAB2(SCH_1):GND    I18 @BASEBOARD_FAB2_LIB.BASEBOARD_FAB2(SCH_1):PAGE75
  CT33    GND @BASEBOARD_FAB2_LIB.BASEBOARD_FAB2(SCH_1):GND    I18 @BASEBOARD_FAB2_LIB.BASEBOARD_FAB2(SCH_1):PAGE75
  CT35    GND @BASEBOARD_FAB2_LIB.BASEBOARD_FAB2(SCH_1):GND    I18 @BASEBOARD_FAB2_LIB.BASEBOARD_FAB2(SCH_1):PAGE75
  CT57    GND @BASEBOARD_FAB2_LIB.BASEBOARD_FAB2(SCH_1):GND    I18 @BASEBOARD_FAB2_LIB.BASEBOARD_FAB2(SCH_1):PAGE75
  CT73    GND @BASEBOARD_FAB2_LIB.BASEBOARD_FAB2(SCH_1):GND    I18 @BASEBOARD_FAB2_LIB.BASEBOARD_FAB2(SCH_1):PAGE75
  CT79    GND @BASEBOARD_FAB2_LIB.BASEBOARD_FAB2(SCH_1):GND    I18 @BASEBOARD_FAB2_LIB.BASEBOARD_FAB2(SCH_1):PAGE75
  CT83    GND @BASEBOARD_FAB2_LIB.BASEBOARD_FAB2(SCH_1):GND    I18 @BASEBOARD_FAB2_LIB.BASEBOARD_FAB2(SCH_1):PAGE75
  CT85    GND @BASEBOARD_FAB2_LIB.BASEBOARD_FAB2(SCH_1):GND    I18 @BASEBOARD_FAB2_LIB.BASEBOARD_FAB2(SCH_1):PAGE75
   CU4    GND @BASEBOARD_FAB2_LIB.BASEBOARD_FAB2(SCH_1):GND    I18 @BASEBOARD_FAB2_LIB.BASEBOARD_FAB2(SCH_1):PAGE75
  CU22    GND @BASEBOARD_FAB2_LIB.BASEBOARD_FAB2(SCH_1):GND    I18 @BASEBOARD_FAB2_LIB.BASEBOARD_FAB2(SCH_1):PAGE75
  CU28    GND @BASEBOARD_FAB2_LIB.BASEBOARD_FAB2(SCH_1):GND    I18 @BASEBOARD_FAB2_LIB.BASEBOARD_FAB2(SCH_1):PAGE75
  CU30    GND @BASEBOARD_FAB2_LIB.BASEBOARD_FAB2(SCH_1):GND    I18 @BASEBOARD_FAB2_LIB.BASEBOARD_FAB2(SCH_1):PAGE75
  CU34    GND @BASEBOARD_FAB2_LIB.BASEBOARD_FAB2(SCH_1):GND    I18 @BASEBOARD_FAB2_LIB.BASEBOARD_FAB2(SCH_1):PAGE75
  CU36    GND @BASEBOARD_FAB2_LIB.BASEBOARD_FAB2(SCH_1):GND    I18 @BASEBOARD_FAB2_LIB.BASEBOARD_FAB2(SCH_1):PAGE75
  CU56    GND @BASEBOARD_FAB2_LIB.BASEBOARD_FAB2(SCH_1):GND    I18 @BASEBOARD_FAB2_LIB.BASEBOARD_FAB2(SCH_1):PAGE75
  CU62    GND @BASEBOARD_FAB2_LIB.BASEBOARD_FAB2(SCH_1):GND    I18 @BASEBOARD_FAB2_LIB.BASEBOARD_FAB2(SCH_1):PAGE75
  CU68    GND @BASEBOARD_FAB2_LIB.BASEBOARD_FAB2(SCH_1):GND    I18 @BASEBOARD_FAB2_LIB.BASEBOARD_FAB2(SCH_1):PAGE75
  CU76    GND @BASEBOARD_FAB2_LIB.BASEBOARD_FAB2(SCH_1):GND    I18 @BASEBOARD_FAB2_LIB.BASEBOARD_FAB2(SCH_1):PAGE75
  CU78    GND @BASEBOARD_FAB2_LIB.BASEBOARD_FAB2(SCH_1):GND    I18 @BASEBOARD_FAB2_LIB.BASEBOARD_FAB2(SCH_1):PAGE75
  CU80    GND @BASEBOARD_FAB2_LIB.BASEBOARD_FAB2(SCH_1):GND    I18 @BASEBOARD_FAB2_LIB.BASEBOARD_FAB2(SCH_1):PAGE75
  CU82    GND @BASEBOARD_FAB2_LIB.BASEBOARD_FAB2(SCH_1):GND    I18 @BASEBOARD_FAB2_LIB.BASEBOARD_FAB2(SCH_1):PAGE75
  CU86    GND @BASEBOARD_FAB2_LIB.BASEBOARD_FAB2(SCH_1):GND    I18 @BASEBOARD_FAB2_LIB.BASEBOARD_FAB2(SCH_1):PAGE75
   CV1    GND @BASEBOARD_FAB2_LIB.BASEBOARD_FAB2(SCH_1):GND    I18 @BASEBOARD_FAB2_LIB.BASEBOARD_FAB2(SCH_1):PAGE75
   H55    GND @BASEBOARD_FAB2_LIB.BASEBOARD_FAB2(SCH_1):GND    I18 @BASEBOARD_FAB2_LIB.BASEBOARD_FAB2(SCH_1):PAGE75
  CV17    GND @BASEBOARD_FAB2_LIB.BASEBOARD_FAB2(SCH_1):GND    I18 @BASEBOARD_FAB2_LIB.BASEBOARD_FAB2(SCH_1):PAGE75
  CV25    GND @BASEBOARD_FAB2_LIB.BASEBOARD_FAB2(SCH_1):GND    I18 @BASEBOARD_FAB2_LIB.BASEBOARD_FAB2(SCH_1):PAGE75
  CV27    GND @BASEBOARD_FAB2_LIB.BASEBOARD_FAB2(SCH_1):GND    I18 @BASEBOARD_FAB2_LIB.BASEBOARD_FAB2(SCH_1):PAGE75
  CV31    GND @BASEBOARD_FAB2_LIB.BASEBOARD_FAB2(SCH_1):GND    I18 @BASEBOARD_FAB2_LIB.BASEBOARD_FAB2(SCH_1):PAGE75
  CV33    GND @BASEBOARD_FAB2_LIB.BASEBOARD_FAB2(SCH_1):GND    I18 @BASEBOARD_FAB2_LIB.BASEBOARD_FAB2(SCH_1):PAGE75
  CV37    GND @BASEBOARD_FAB2_LIB.BASEBOARD_FAB2(SCH_1):GND    I18 @BASEBOARD_FAB2_LIB.BASEBOARD_FAB2(SCH_1):PAGE75
  CV39    GND @BASEBOARD_FAB2_LIB.BASEBOARD_FAB2(SCH_1):GND    I18 @BASEBOARD_FAB2_LIB.BASEBOARD_FAB2(SCH_1):PAGE75
  CV41    GND @BASEBOARD_FAB2_LIB.BASEBOARD_FAB2(SCH_1):GND    I18 @BASEBOARD_FAB2_LIB.BASEBOARD_FAB2(SCH_1):PAGE75
  CV53    GND @BASEBOARD_FAB2_LIB.BASEBOARD_FAB2(SCH_1):GND    I18 @BASEBOARD_FAB2_LIB.BASEBOARD_FAB2(SCH_1):PAGE75
  CV55    GND @BASEBOARD_FAB2_LIB.BASEBOARD_FAB2(SCH_1):GND    I18 @BASEBOARD_FAB2_LIB.BASEBOARD_FAB2(SCH_1):PAGE75
  CV63    GND @BASEBOARD_FAB2_LIB.BASEBOARD_FAB2(SCH_1):GND    I18 @BASEBOARD_FAB2_LIB.BASEBOARD_FAB2(SCH_1):PAGE75
  CV67    GND @BASEBOARD_FAB2_LIB.BASEBOARD_FAB2(SCH_1):GND    I18 @BASEBOARD_FAB2_LIB.BASEBOARD_FAB2(SCH_1):PAGE75
  CV73    GND @BASEBOARD_FAB2_LIB.BASEBOARD_FAB2(SCH_1):GND    I18 @BASEBOARD_FAB2_LIB.BASEBOARD_FAB2(SCH_1):PAGE75
  CV79    GND @BASEBOARD_FAB2_LIB.BASEBOARD_FAB2(SCH_1):GND    I18 @BASEBOARD_FAB2_LIB.BASEBOARD_FAB2(SCH_1):PAGE75
  CV81    GND @BASEBOARD_FAB2_LIB.BASEBOARD_FAB2(SCH_1):GND    I18 @BASEBOARD_FAB2_LIB.BASEBOARD_FAB2(SCH_1):PAGE75
  CV83    GND @BASEBOARD_FAB2_LIB.BASEBOARD_FAB2(SCH_1):GND    I18 @BASEBOARD_FAB2_LIB.BASEBOARD_FAB2(SCH_1):PAGE75
  CW12    GND @BASEBOARD_FAB2_LIB.BASEBOARD_FAB2(SCH_1):GND    I18 @BASEBOARD_FAB2_LIB.BASEBOARD_FAB2(SCH_1):PAGE75
  CW26    GND @BASEBOARD_FAB2_LIB.BASEBOARD_FAB2(SCH_1):GND    I18 @BASEBOARD_FAB2_LIB.BASEBOARD_FAB2(SCH_1):PAGE75
  CW32    GND @BASEBOARD_FAB2_LIB.BASEBOARD_FAB2(SCH_1):GND    I18 @BASEBOARD_FAB2_LIB.BASEBOARD_FAB2(SCH_1):PAGE75
  CW38    GND @BASEBOARD_FAB2_LIB.BASEBOARD_FAB2(SCH_1):GND    I18 @BASEBOARD_FAB2_LIB.BASEBOARD_FAB2(SCH_1):PAGE75
  CW40    GND @BASEBOARD_FAB2_LIB.BASEBOARD_FAB2(SCH_1):GND    I18 @BASEBOARD_FAB2_LIB.BASEBOARD_FAB2(SCH_1):PAGE75
  CW42    GND @BASEBOARD_FAB2_LIB.BASEBOARD_FAB2(SCH_1):GND    I18 @BASEBOARD_FAB2_LIB.BASEBOARD_FAB2(SCH_1):PAGE75
  CW52    GND @BASEBOARD_FAB2_LIB.BASEBOARD_FAB2(SCH_1):GND    I18 @BASEBOARD_FAB2_LIB.BASEBOARD_FAB2(SCH_1):PAGE75
  CW54    GND @BASEBOARD_FAB2_LIB.BASEBOARD_FAB2(SCH_1):GND    I18 @BASEBOARD_FAB2_LIB.BASEBOARD_FAB2(SCH_1):PAGE75
  CW64    GND @BASEBOARD_FAB2_LIB.BASEBOARD_FAB2(SCH_1):GND    I18 @BASEBOARD_FAB2_LIB.BASEBOARD_FAB2(SCH_1):PAGE75
  CW66    GND @BASEBOARD_FAB2_LIB.BASEBOARD_FAB2(SCH_1):GND    I18 @BASEBOARD_FAB2_LIB.BASEBOARD_FAB2(SCH_1):PAGE75
  CW68    GND @BASEBOARD_FAB2_LIB.BASEBOARD_FAB2(SCH_1):GND    I18 @BASEBOARD_FAB2_LIB.BASEBOARD_FAB2(SCH_1):PAGE75
  CW74    GND @BASEBOARD_FAB2_LIB.BASEBOARD_FAB2(SCH_1):GND    I18 @BASEBOARD_FAB2_LIB.BASEBOARD_FAB2(SCH_1):PAGE75
  CW78    GND @BASEBOARD_FAB2_LIB.BASEBOARD_FAB2(SCH_1):GND    I18 @BASEBOARD_FAB2_LIB.BASEBOARD_FAB2(SCH_1):PAGE75
  CW82    GND @BASEBOARD_FAB2_LIB.BASEBOARD_FAB2(SCH_1):GND    I18 @BASEBOARD_FAB2_LIB.BASEBOARD_FAB2(SCH_1):PAGE75
   CY1    GND @BASEBOARD_FAB2_LIB.BASEBOARD_FAB2(SCH_1):GND    I18 @BASEBOARD_FAB2_LIB.BASEBOARD_FAB2(SCH_1):PAGE75
   CY9    GND @BASEBOARD_FAB2_LIB.BASEBOARD_FAB2(SCH_1):GND    I18 @BASEBOARD_FAB2_LIB.BASEBOARD_FAB2(SCH_1):PAGE75
  CY13    GND @BASEBOARD_FAB2_LIB.BASEBOARD_FAB2(SCH_1):GND    I18 @BASEBOARD_FAB2_LIB.BASEBOARD_FAB2(SCH_1):PAGE75
  CY15    GND @BASEBOARD_FAB2_LIB.BASEBOARD_FAB2(SCH_1):GND    I18 @BASEBOARD_FAB2_LIB.BASEBOARD_FAB2(SCH_1):PAGE75
  CY21    GND @BASEBOARD_FAB2_LIB.BASEBOARD_FAB2(SCH_1):GND    I18 @BASEBOARD_FAB2_LIB.BASEBOARD_FAB2(SCH_1):PAGE75
  CY41    GND @BASEBOARD_FAB2_LIB.BASEBOARD_FAB2(SCH_1):GND    I18 @BASEBOARD_FAB2_LIB.BASEBOARD_FAB2(SCH_1):PAGE75
  CY45    GND @BASEBOARD_FAB2_LIB.BASEBOARD_FAB2(SCH_1):GND    I18 @BASEBOARD_FAB2_LIB.BASEBOARD_FAB2(SCH_1):PAGE75
  CY51    GND @BASEBOARD_FAB2_LIB.BASEBOARD_FAB2(SCH_1):GND    I18 @BASEBOARD_FAB2_LIB.BASEBOARD_FAB2(SCH_1):PAGE75
  CY59    GND @BASEBOARD_FAB2_LIB.BASEBOARD_FAB2(SCH_1):GND    I18 @BASEBOARD_FAB2_LIB.BASEBOARD_FAB2(SCH_1):PAGE75
  CY61    GND @BASEBOARD_FAB2_LIB.BASEBOARD_FAB2(SCH_1):GND    I18 @BASEBOARD_FAB2_LIB.BASEBOARD_FAB2(SCH_1):PAGE75
  CY65    GND @BASEBOARD_FAB2_LIB.BASEBOARD_FAB2(SCH_1):GND    I18 @BASEBOARD_FAB2_LIB.BASEBOARD_FAB2(SCH_1):PAGE75
  CY69    GND @BASEBOARD_FAB2_LIB.BASEBOARD_FAB2(SCH_1):GND    I18 @BASEBOARD_FAB2_LIB.BASEBOARD_FAB2(SCH_1):PAGE75
  CY75    GND @BASEBOARD_FAB2_LIB.BASEBOARD_FAB2(SCH_1):GND    I18 @BASEBOARD_FAB2_LIB.BASEBOARD_FAB2(SCH_1):PAGE75
  CY77    GND @BASEBOARD_FAB2_LIB.BASEBOARD_FAB2(SCH_1):GND    I18 @BASEBOARD_FAB2_LIB.BASEBOARD_FAB2(SCH_1):PAGE75
  CY83    GND @BASEBOARD_FAB2_LIB.BASEBOARD_FAB2(SCH_1):GND    I18 @BASEBOARD_FAB2_LIB.BASEBOARD_FAB2(SCH_1):PAGE75
  CY85    GND @BASEBOARD_FAB2_LIB.BASEBOARD_FAB2(SCH_1):GND    I18 @BASEBOARD_FAB2_LIB.BASEBOARD_FAB2(SCH_1):PAGE75
   DA6    GND @BASEBOARD_FAB2_LIB.BASEBOARD_FAB2(SCH_1):GND    I18 @BASEBOARD_FAB2_LIB.BASEBOARD_FAB2(SCH_1):PAGE75
   H53    GND @BASEBOARD_FAB2_LIB.BASEBOARD_FAB2(SCH_1):GND    I18 @BASEBOARD_FAB2_LIB.BASEBOARD_FAB2(SCH_1):PAGE75
  DA18    GND @BASEBOARD_FAB2_LIB.BASEBOARD_FAB2(SCH_1):GND    I18 @BASEBOARD_FAB2_LIB.BASEBOARD_FAB2(SCH_1):PAGE75
  DA26    GND @BASEBOARD_FAB2_LIB.BASEBOARD_FAB2(SCH_1):GND    I18 @BASEBOARD_FAB2_LIB.BASEBOARD_FAB2(SCH_1):PAGE75
  DA28    GND @BASEBOARD_FAB2_LIB.BASEBOARD_FAB2(SCH_1):GND    I18 @BASEBOARD_FAB2_LIB.BASEBOARD_FAB2(SCH_1):PAGE75
  DA30    GND @BASEBOARD_FAB2_LIB.BASEBOARD_FAB2(SCH_1):GND    I18 @BASEBOARD_FAB2_LIB.BASEBOARD_FAB2(SCH_1):PAGE75
  DA32    GND @BASEBOARD_FAB2_LIB.BASEBOARD_FAB2(SCH_1):GND    I18 @BASEBOARD_FAB2_LIB.BASEBOARD_FAB2(SCH_1):PAGE75
  DA34    GND @BASEBOARD_FAB2_LIB.BASEBOARD_FAB2(SCH_1):GND    I18 @BASEBOARD_FAB2_LIB.BASEBOARD_FAB2(SCH_1):PAGE75
  DA36    GND @BASEBOARD_FAB2_LIB.BASEBOARD_FAB2(SCH_1):GND    I18 @BASEBOARD_FAB2_LIB.BASEBOARD_FAB2(SCH_1):PAGE75
  DA38    GND @BASEBOARD_FAB2_LIB.BASEBOARD_FAB2(SCH_1):GND    I18 @BASEBOARD_FAB2_LIB.BASEBOARD_FAB2(SCH_1):PAGE75
  DA44    GND @BASEBOARD_FAB2_LIB.BASEBOARD_FAB2(SCH_1):GND    I18 @BASEBOARD_FAB2_LIB.BASEBOARD_FAB2(SCH_1):PAGE75
  DA46    GND @BASEBOARD_FAB2_LIB.BASEBOARD_FAB2(SCH_1):GND    I18 @BASEBOARD_FAB2_LIB.BASEBOARD_FAB2(SCH_1):PAGE75
  DA48    GND @BASEBOARD_FAB2_LIB.BASEBOARD_FAB2(SCH_1):GND    I19 @BASEBOARD_FAB2_LIB.BASEBOARD_FAB2(SCH_1):PAGE75
  DA50    GND @BASEBOARD_FAB2_LIB.BASEBOARD_FAB2(SCH_1):GND    I19 @BASEBOARD_FAB2_LIB.BASEBOARD_FAB2(SCH_1):PAGE75
  DA64    GND @BASEBOARD_FAB2_LIB.BASEBOARD_FAB2(SCH_1):GND    I19 @BASEBOARD_FAB2_LIB.BASEBOARD_FAB2(SCH_1):PAGE75
  DA70    GND @BASEBOARD_FAB2_LIB.BASEBOARD_FAB2(SCH_1):GND    I19 @BASEBOARD_FAB2_LIB.BASEBOARD_FAB2(SCH_1):PAGE75
  DA74    GND @BASEBOARD_FAB2_LIB.BASEBOARD_FAB2(SCH_1):GND    I19 @BASEBOARD_FAB2_LIB.BASEBOARD_FAB2(SCH_1):PAGE75
  DA76    GND @BASEBOARD_FAB2_LIB.BASEBOARD_FAB2(SCH_1):GND    I19 @BASEBOARD_FAB2_LIB.BASEBOARD_FAB2(SCH_1):PAGE75
  DA78    GND @BASEBOARD_FAB2_LIB.BASEBOARD_FAB2(SCH_1):GND    I19 @BASEBOARD_FAB2_LIB.BASEBOARD_FAB2(SCH_1):PAGE75
  DA80    GND @BASEBOARD_FAB2_LIB.BASEBOARD_FAB2(SCH_1):GND    I19 @BASEBOARD_FAB2_LIB.BASEBOARD_FAB2(SCH_1):PAGE75
   DB3    GND @BASEBOARD_FAB2_LIB.BASEBOARD_FAB2(SCH_1):GND    I19 @BASEBOARD_FAB2_LIB.BASEBOARD_FAB2(SCH_1):PAGE75
  DB13    GND @BASEBOARD_FAB2_LIB.BASEBOARD_FAB2(SCH_1):GND    I19 @BASEBOARD_FAB2_LIB.BASEBOARD_FAB2(SCH_1):PAGE75
  DB17    GND @BASEBOARD_FAB2_LIB.BASEBOARD_FAB2(SCH_1):GND    I19 @BASEBOARD_FAB2_LIB.BASEBOARD_FAB2(SCH_1):PAGE75
  DB23    GND @BASEBOARD_FAB2_LIB.BASEBOARD_FAB2(SCH_1):GND    I19 @BASEBOARD_FAB2_LIB.BASEBOARD_FAB2(SCH_1):PAGE75
  DB25    GND @BASEBOARD_FAB2_LIB.BASEBOARD_FAB2(SCH_1):GND    I19 @BASEBOARD_FAB2_LIB.BASEBOARD_FAB2(SCH_1):PAGE75
  DB39    GND @BASEBOARD_FAB2_LIB.BASEBOARD_FAB2(SCH_1):GND    I19 @BASEBOARD_FAB2_LIB.BASEBOARD_FAB2(SCH_1):PAGE75
  DB41    GND @BASEBOARD_FAB2_LIB.BASEBOARD_FAB2(SCH_1):GND    I19 @BASEBOARD_FAB2_LIB.BASEBOARD_FAB2(SCH_1):PAGE75
  DB47    GND @BASEBOARD_FAB2_LIB.BASEBOARD_FAB2(SCH_1):GND    I19 @BASEBOARD_FAB2_LIB.BASEBOARD_FAB2(SCH_1):PAGE75
  DB49    GND @BASEBOARD_FAB2_LIB.BASEBOARD_FAB2(SCH_1):GND    I19 @BASEBOARD_FAB2_LIB.BASEBOARD_FAB2(SCH_1):PAGE75
  DB73    GND @BASEBOARD_FAB2_LIB.BASEBOARD_FAB2(SCH_1):GND    I19 @BASEBOARD_FAB2_LIB.BASEBOARD_FAB2(SCH_1):PAGE75
  DB77    GND @BASEBOARD_FAB2_LIB.BASEBOARD_FAB2(SCH_1):GND    I19 @BASEBOARD_FAB2_LIB.BASEBOARD_FAB2(SCH_1):PAGE75
  DB83    GND @BASEBOARD_FAB2_LIB.BASEBOARD_FAB2(SCH_1):GND    I19 @BASEBOARD_FAB2_LIB.BASEBOARD_FAB2(SCH_1):PAGE75
  DB85    GND @BASEBOARD_FAB2_LIB.BASEBOARD_FAB2(SCH_1):GND    I19 @BASEBOARD_FAB2_LIB.BASEBOARD_FAB2(SCH_1):PAGE75
  DC14    GND @BASEBOARD_FAB2_LIB.BASEBOARD_FAB2(SCH_1):GND    I19 @BASEBOARD_FAB2_LIB.BASEBOARD_FAB2(SCH_1):PAGE75
  DC24    GND @BASEBOARD_FAB2_LIB.BASEBOARD_FAB2(SCH_1):GND    I19 @BASEBOARD_FAB2_LIB.BASEBOARD_FAB2(SCH_1):PAGE75
  DC26    GND @BASEBOARD_FAB2_LIB.BASEBOARD_FAB2(SCH_1):GND    I19 @BASEBOARD_FAB2_LIB.BASEBOARD_FAB2(SCH_1):PAGE75
  DC32    GND @BASEBOARD_FAB2_LIB.BASEBOARD_FAB2(SCH_1):GND    I19 @BASEBOARD_FAB2_LIB.BASEBOARD_FAB2(SCH_1):PAGE75
  DC38    GND @BASEBOARD_FAB2_LIB.BASEBOARD_FAB2(SCH_1):GND    I19 @BASEBOARD_FAB2_LIB.BASEBOARD_FAB2(SCH_1):PAGE75
  DC42    GND @BASEBOARD_FAB2_LIB.BASEBOARD_FAB2(SCH_1):GND    I19 @BASEBOARD_FAB2_LIB.BASEBOARD_FAB2(SCH_1):PAGE75
  DC64    GND @BASEBOARD_FAB2_LIB.BASEBOARD_FAB2(SCH_1):GND    I19 @BASEBOARD_FAB2_LIB.BASEBOARD_FAB2(SCH_1):PAGE75
  DC66    GND @BASEBOARD_FAB2_LIB.BASEBOARD_FAB2(SCH_1):GND    I19 @BASEBOARD_FAB2_LIB.BASEBOARD_FAB2(SCH_1):PAGE75
  DC68    GND @BASEBOARD_FAB2_LIB.BASEBOARD_FAB2(SCH_1):GND    I19 @BASEBOARD_FAB2_LIB.BASEBOARD_FAB2(SCH_1):PAGE75
  DC70    GND @BASEBOARD_FAB2_LIB.BASEBOARD_FAB2(SCH_1):GND    I19 @BASEBOARD_FAB2_LIB.BASEBOARD_FAB2(SCH_1):PAGE75
  DC78    GND @BASEBOARD_FAB2_LIB.BASEBOARD_FAB2(SCH_1):GND    I19 @BASEBOARD_FAB2_LIB.BASEBOARD_FAB2(SCH_1):PAGE75
  DC84    GND @BASEBOARD_FAB2_LIB.BASEBOARD_FAB2(SCH_1):GND    I19 @BASEBOARD_FAB2_LIB.BASEBOARD_FAB2(SCH_1):PAGE75
  DC86    GND @BASEBOARD_FAB2_LIB.BASEBOARD_FAB2(SCH_1):GND    I19 @BASEBOARD_FAB2_LIB.BASEBOARD_FAB2(SCH_1):PAGE75
  DD11    GND @BASEBOARD_FAB2_LIB.BASEBOARD_FAB2(SCH_1):GND    I19 @BASEBOARD_FAB2_LIB.BASEBOARD_FAB2(SCH_1):PAGE75
  DD23    GND @BASEBOARD_FAB2_LIB.BASEBOARD_FAB2(SCH_1):GND    I19 @BASEBOARD_FAB2_LIB.BASEBOARD_FAB2(SCH_1):PAGE75
  DD27    GND @BASEBOARD_FAB2_LIB.BASEBOARD_FAB2(SCH_1):GND    I19 @BASEBOARD_FAB2_LIB.BASEBOARD_FAB2(SCH_1):PAGE75
  DD31    GND @BASEBOARD_FAB2_LIB.BASEBOARD_FAB2(SCH_1):GND    I19 @BASEBOARD_FAB2_LIB.BASEBOARD_FAB2(SCH_1):PAGE75
  DD33    GND @BASEBOARD_FAB2_LIB.BASEBOARD_FAB2(SCH_1):GND    I19 @BASEBOARD_FAB2_LIB.BASEBOARD_FAB2(SCH_1):PAGE75
  DD37    GND @BASEBOARD_FAB2_LIB.BASEBOARD_FAB2(SCH_1):GND    I19 @BASEBOARD_FAB2_LIB.BASEBOARD_FAB2(SCH_1):PAGE75
  DD71    GND @BASEBOARD_FAB2_LIB.BASEBOARD_FAB2(SCH_1):GND    I19 @BASEBOARD_FAB2_LIB.BASEBOARD_FAB2(SCH_1):PAGE75
  DD73    GND @BASEBOARD_FAB2_LIB.BASEBOARD_FAB2(SCH_1):GND    I19 @BASEBOARD_FAB2_LIB.BASEBOARD_FAB2(SCH_1):PAGE75
  DD75    GND @BASEBOARD_FAB2_LIB.BASEBOARD_FAB2(SCH_1):GND    I19 @BASEBOARD_FAB2_LIB.BASEBOARD_FAB2(SCH_1):PAGE75
  DD81    GND @BASEBOARD_FAB2_LIB.BASEBOARD_FAB2(SCH_1):GND    I19 @BASEBOARD_FAB2_LIB.BASEBOARD_FAB2(SCH_1):PAGE75
  DD83    GND @BASEBOARD_FAB2_LIB.BASEBOARD_FAB2(SCH_1):GND    I19 @BASEBOARD_FAB2_LIB.BASEBOARD_FAB2(SCH_1):PAGE75
   DE6    GND @BASEBOARD_FAB2_LIB.BASEBOARD_FAB2(SCH_1):GND    I19 @BASEBOARD_FAB2_LIB.BASEBOARD_FAB2(SCH_1):PAGE75
   DE8    GND @BASEBOARD_FAB2_LIB.BASEBOARD_FAB2(SCH_1):GND    I19 @BASEBOARD_FAB2_LIB.BASEBOARD_FAB2(SCH_1):PAGE75
  DE18    GND @BASEBOARD_FAB2_LIB.BASEBOARD_FAB2(SCH_1):GND    I19 @BASEBOARD_FAB2_LIB.BASEBOARD_FAB2(SCH_1):PAGE75
  DE20    GND @BASEBOARD_FAB2_LIB.BASEBOARD_FAB2(SCH_1):GND    I19 @BASEBOARD_FAB2_LIB.BASEBOARD_FAB2(SCH_1):PAGE75
  DE24    GND @BASEBOARD_FAB2_LIB.BASEBOARD_FAB2(SCH_1):GND    I19 @BASEBOARD_FAB2_LIB.BASEBOARD_FAB2(SCH_1):PAGE75
  DE28    GND @BASEBOARD_FAB2_LIB.BASEBOARD_FAB2(SCH_1):GND    I19 @BASEBOARD_FAB2_LIB.BASEBOARD_FAB2(SCH_1):PAGE75
  DE30    GND @BASEBOARD_FAB2_LIB.BASEBOARD_FAB2(SCH_1):GND    I19 @BASEBOARD_FAB2_LIB.BASEBOARD_FAB2(SCH_1):PAGE75
  DE34    GND @BASEBOARD_FAB2_LIB.BASEBOARD_FAB2(SCH_1):GND    I19 @BASEBOARD_FAB2_LIB.BASEBOARD_FAB2(SCH_1):PAGE75
  DE36    GND @BASEBOARD_FAB2_LIB.BASEBOARD_FAB2(SCH_1):GND    I19 @BASEBOARD_FAB2_LIB.BASEBOARD_FAB2(SCH_1):PAGE75
  DE64    GND @BASEBOARD_FAB2_LIB.BASEBOARD_FAB2(SCH_1):GND    I19 @BASEBOARD_FAB2_LIB.BASEBOARD_FAB2(SCH_1):PAGE75
  DE70    GND @BASEBOARD_FAB2_LIB.BASEBOARD_FAB2(SCH_1):GND    I19 @BASEBOARD_FAB2_LIB.BASEBOARD_FAB2(SCH_1):PAGE75
  DE72    GND @BASEBOARD_FAB2_LIB.BASEBOARD_FAB2(SCH_1):GND    I19 @BASEBOARD_FAB2_LIB.BASEBOARD_FAB2(SCH_1):PAGE75
  DE78    GND @BASEBOARD_FAB2_LIB.BASEBOARD_FAB2(SCH_1):GND    I19 @BASEBOARD_FAB2_LIB.BASEBOARD_FAB2(SCH_1):PAGE75
   DF5    GND @BASEBOARD_FAB2_LIB.BASEBOARD_FAB2(SCH_1):GND    I19 @BASEBOARD_FAB2_LIB.BASEBOARD_FAB2(SCH_1):PAGE75
   DF7    GND @BASEBOARD_FAB2_LIB.BASEBOARD_FAB2(SCH_1):GND    I19 @BASEBOARD_FAB2_LIB.BASEBOARD_FAB2(SCH_1):PAGE75
   H51    GND @BASEBOARD_FAB2_LIB.BASEBOARD_FAB2(SCH_1):GND    I19 @BASEBOARD_FAB2_LIB.BASEBOARD_FAB2(SCH_1):PAGE75
  DF19    GND @BASEBOARD_FAB2_LIB.BASEBOARD_FAB2(SCH_1):GND    I19 @BASEBOARD_FAB2_LIB.BASEBOARD_FAB2(SCH_1):PAGE75
  DF29    GND @BASEBOARD_FAB2_LIB.BASEBOARD_FAB2(SCH_1):GND    I19 @BASEBOARD_FAB2_LIB.BASEBOARD_FAB2(SCH_1):PAGE75
  DF35    GND @BASEBOARD_FAB2_LIB.BASEBOARD_FAB2(SCH_1):GND    I19 @BASEBOARD_FAB2_LIB.BASEBOARD_FAB2(SCH_1):PAGE75
  DF37    GND @BASEBOARD_FAB2_LIB.BASEBOARD_FAB2(SCH_1):GND    I19 @BASEBOARD_FAB2_LIB.BASEBOARD_FAB2(SCH_1):PAGE75
  DF39    GND @BASEBOARD_FAB2_LIB.BASEBOARD_FAB2(SCH_1):GND    I19 @BASEBOARD_FAB2_LIB.BASEBOARD_FAB2(SCH_1):PAGE75
  DF41    GND @BASEBOARD_FAB2_LIB.BASEBOARD_FAB2(SCH_1):GND    I19 @BASEBOARD_FAB2_LIB.BASEBOARD_FAB2(SCH_1):PAGE75
  DF65    GND @BASEBOARD_FAB2_LIB.BASEBOARD_FAB2(SCH_1):GND    I19 @BASEBOARD_FAB2_LIB.BASEBOARD_FAB2(SCH_1):PAGE75
  DF69    GND @BASEBOARD_FAB2_LIB.BASEBOARD_FAB2(SCH_1):GND    I19 @BASEBOARD_FAB2_LIB.BASEBOARD_FAB2(SCH_1):PAGE75
  DF73    GND @BASEBOARD_FAB2_LIB.BASEBOARD_FAB2(SCH_1):GND    I19 @BASEBOARD_FAB2_LIB.BASEBOARD_FAB2(SCH_1):PAGE75
  DF79    GND @BASEBOARD_FAB2_LIB.BASEBOARD_FAB2(SCH_1):GND    I19 @BASEBOARD_FAB2_LIB.BASEBOARD_FAB2(SCH_1):PAGE75
  DF83    GND @BASEBOARD_FAB2_LIB.BASEBOARD_FAB2(SCH_1):GND    I19 @BASEBOARD_FAB2_LIB.BASEBOARD_FAB2(SCH_1):PAGE75
  DF85    GND @BASEBOARD_FAB2_LIB.BASEBOARD_FAB2(SCH_1):GND    I19 @BASEBOARD_FAB2_LIB.BASEBOARD_FAB2(SCH_1):PAGE75
   DG2    GND @BASEBOARD_FAB2_LIB.BASEBOARD_FAB2(SCH_1):GND    I19 @BASEBOARD_FAB2_LIB.BASEBOARD_FAB2(SCH_1):PAGE75
   H49    GND @BASEBOARD_FAB2_LIB.BASEBOARD_FAB2(SCH_1):GND    I19 @BASEBOARD_FAB2_LIB.BASEBOARD_FAB2(SCH_1):PAGE75
  DG14    GND @BASEBOARD_FAB2_LIB.BASEBOARD_FAB2(SCH_1):GND    I19 @BASEBOARD_FAB2_LIB.BASEBOARD_FAB2(SCH_1):PAGE75
  DG16    GND @BASEBOARD_FAB2_LIB.BASEBOARD_FAB2(SCH_1):GND    I19 @BASEBOARD_FAB2_LIB.BASEBOARD_FAB2(SCH_1):PAGE75
  DG24    GND @BASEBOARD_FAB2_LIB.BASEBOARD_FAB2(SCH_1):GND    I19 @BASEBOARD_FAB2_LIB.BASEBOARD_FAB2(SCH_1):PAGE75
  DG66    GND @BASEBOARD_FAB2_LIB.BASEBOARD_FAB2(SCH_1):GND    I19 @BASEBOARD_FAB2_LIB.BASEBOARD_FAB2(SCH_1):PAGE75
  DG68    GND @BASEBOARD_FAB2_LIB.BASEBOARD_FAB2(SCH_1):GND    I19 @BASEBOARD_FAB2_LIB.BASEBOARD_FAB2(SCH_1):PAGE75
  DG76    GND @BASEBOARD_FAB2_LIB.BASEBOARD_FAB2(SCH_1):GND    I19 @BASEBOARD_FAB2_LIB.BASEBOARD_FAB2(SCH_1):PAGE75
  DG78    GND @BASEBOARD_FAB2_LIB.BASEBOARD_FAB2(SCH_1):GND    I19 @BASEBOARD_FAB2_LIB.BASEBOARD_FAB2(SCH_1):PAGE75
  DG80    GND @BASEBOARD_FAB2_LIB.BASEBOARD_FAB2(SCH_1):GND    I19 @BASEBOARD_FAB2_LIB.BASEBOARD_FAB2(SCH_1):PAGE75
  DG82    GND @BASEBOARD_FAB2_LIB.BASEBOARD_FAB2(SCH_1):GND    I19 @BASEBOARD_FAB2_LIB.BASEBOARD_FAB2(SCH_1):PAGE75
  DH13    GND @BASEBOARD_FAB2_LIB.BASEBOARD_FAB2(SCH_1):GND    I19 @BASEBOARD_FAB2_LIB.BASEBOARD_FAB2(SCH_1):PAGE75
  DH15    GND @BASEBOARD_FAB2_LIB.BASEBOARD_FAB2(SCH_1):GND    I19 @BASEBOARD_FAB2_LIB.BASEBOARD_FAB2(SCH_1):PAGE75
  DH23    GND @BASEBOARD_FAB2_LIB.BASEBOARD_FAB2(SCH_1):GND    I19 @BASEBOARD_FAB2_LIB.BASEBOARD_FAB2(SCH_1):PAGE75
  DH25    GND @BASEBOARD_FAB2_LIB.BASEBOARD_FAB2(SCH_1):GND    I19 @BASEBOARD_FAB2_LIB.BASEBOARD_FAB2(SCH_1):PAGE75
  DH27    GND @BASEBOARD_FAB2_LIB.BASEBOARD_FAB2(SCH_1):GND    I19 @BASEBOARD_FAB2_LIB.BASEBOARD_FAB2(SCH_1):PAGE75
  DH29    GND @BASEBOARD_FAB2_LIB.BASEBOARD_FAB2(SCH_1):GND    I19 @BASEBOARD_FAB2_LIB.BASEBOARD_FAB2(SCH_1):PAGE75
  DH31    GND @BASEBOARD_FAB2_LIB.BASEBOARD_FAB2(SCH_1):GND    I19 @BASEBOARD_FAB2_LIB.BASEBOARD_FAB2(SCH_1):PAGE75
  DH33    GND @BASEBOARD_FAB2_LIB.BASEBOARD_FAB2(SCH_1):GND    I19 @BASEBOARD_FAB2_LIB.BASEBOARD_FAB2(SCH_1):PAGE75
  DH35    GND @BASEBOARD_FAB2_LIB.BASEBOARD_FAB2(SCH_1):GND    I19 @BASEBOARD_FAB2_LIB.BASEBOARD_FAB2(SCH_1):PAGE75
  DH37    GND @BASEBOARD_FAB2_LIB.BASEBOARD_FAB2(SCH_1):GND    I19 @BASEBOARD_FAB2_LIB.BASEBOARD_FAB2(SCH_1):PAGE75
  DH41    GND @BASEBOARD_FAB2_LIB.BASEBOARD_FAB2(SCH_1):GND    I19 @BASEBOARD_FAB2_LIB.BASEBOARD_FAB2(SCH_1):PAGE75
  DH67    GND @BASEBOARD_FAB2_LIB.BASEBOARD_FAB2(SCH_1):GND    I19 @BASEBOARD_FAB2_LIB.BASEBOARD_FAB2(SCH_1):PAGE75
  DH71    GND @BASEBOARD_FAB2_LIB.BASEBOARD_FAB2(SCH_1):GND    I19 @BASEBOARD_FAB2_LIB.BASEBOARD_FAB2(SCH_1):PAGE75
  DH73    GND @BASEBOARD_FAB2_LIB.BASEBOARD_FAB2(SCH_1):GND    I19 @BASEBOARD_FAB2_LIB.BASEBOARD_FAB2(SCH_1):PAGE75
  DH79    GND @BASEBOARD_FAB2_LIB.BASEBOARD_FAB2(SCH_1):GND    I19 @BASEBOARD_FAB2_LIB.BASEBOARD_FAB2(SCH_1):PAGE75
  DH81    GND @BASEBOARD_FAB2_LIB.BASEBOARD_FAB2(SCH_1):GND    I19 @BASEBOARD_FAB2_LIB.BASEBOARD_FAB2(SCH_1):PAGE75
  DH83    GND @BASEBOARD_FAB2_LIB.BASEBOARD_FAB2(SCH_1):GND    I19 @BASEBOARD_FAB2_LIB.BASEBOARD_FAB2(SCH_1):PAGE75
   DJ2    GND @BASEBOARD_FAB2_LIB.BASEBOARD_FAB2(SCH_1):GND    I19 @BASEBOARD_FAB2_LIB.BASEBOARD_FAB2(SCH_1):PAGE75
  DJ10    GND @BASEBOARD_FAB2_LIB.BASEBOARD_FAB2(SCH_1):GND    I19 @BASEBOARD_FAB2_LIB.BASEBOARD_FAB2(SCH_1):PAGE75
   H47    GND @BASEBOARD_FAB2_LIB.BASEBOARD_FAB2(SCH_1):GND    I19 @BASEBOARD_FAB2_LIB.BASEBOARD_FAB2(SCH_1):PAGE75
  DJ22    GND @BASEBOARD_FAB2_LIB.BASEBOARD_FAB2(SCH_1):GND    I19 @BASEBOARD_FAB2_LIB.BASEBOARD_FAB2(SCH_1):PAGE75
  DJ38    GND @BASEBOARD_FAB2_LIB.BASEBOARD_FAB2(SCH_1):GND    I19 @BASEBOARD_FAB2_LIB.BASEBOARD_FAB2(SCH_1):PAGE75
  DJ42    GND @BASEBOARD_FAB2_LIB.BASEBOARD_FAB2(SCH_1):GND    I19 @BASEBOARD_FAB2_LIB.BASEBOARD_FAB2(SCH_1):PAGE75
  DJ68    GND @BASEBOARD_FAB2_LIB.BASEBOARD_FAB2(SCH_1):GND    I19 @BASEBOARD_FAB2_LIB.BASEBOARD_FAB2(SCH_1):PAGE75
  DJ74    GND @BASEBOARD_FAB2_LIB.BASEBOARD_FAB2(SCH_1):GND    I19 @BASEBOARD_FAB2_LIB.BASEBOARD_FAB2(SCH_1):PAGE75
  DJ78    GND @BASEBOARD_FAB2_LIB.BASEBOARD_FAB2(SCH_1):GND    I19 @BASEBOARD_FAB2_LIB.BASEBOARD_FAB2(SCH_1):PAGE75
  DJ82    GND @BASEBOARD_FAB2_LIB.BASEBOARD_FAB2(SCH_1):GND    I19 @BASEBOARD_FAB2_LIB.BASEBOARD_FAB2(SCH_1):PAGE75
  DJ84    GND @BASEBOARD_FAB2_LIB.BASEBOARD_FAB2(SCH_1):GND    I19 @BASEBOARD_FAB2_LIB.BASEBOARD_FAB2(SCH_1):PAGE75
   DK7    GND @BASEBOARD_FAB2_LIB.BASEBOARD_FAB2(SCH_1):GND    I19 @BASEBOARD_FAB2_LIB.BASEBOARD_FAB2(SCH_1):PAGE75
  DK23    GND @BASEBOARD_FAB2_LIB.BASEBOARD_FAB2(SCH_1):GND    I19 @BASEBOARD_FAB2_LIB.BASEBOARD_FAB2(SCH_1):PAGE75
  DK29    GND @BASEBOARD_FAB2_LIB.BASEBOARD_FAB2(SCH_1):GND    I19 @BASEBOARD_FAB2_LIB.BASEBOARD_FAB2(SCH_1):PAGE75
  DK35    GND @BASEBOARD_FAB2_LIB.BASEBOARD_FAB2(SCH_1):GND    I19 @BASEBOARD_FAB2_LIB.BASEBOARD_FAB2(SCH_1):PAGE75
  DK39    GND @BASEBOARD_FAB2_LIB.BASEBOARD_FAB2(SCH_1):GND    I19 @BASEBOARD_FAB2_LIB.BASEBOARD_FAB2(SCH_1):PAGE75
  DK41    GND @BASEBOARD_FAB2_LIB.BASEBOARD_FAB2(SCH_1):GND    I19 @BASEBOARD_FAB2_LIB.BASEBOARD_FAB2(SCH_1):PAGE75
  DK73    GND @BASEBOARD_FAB2_LIB.BASEBOARD_FAB2(SCH_1):GND    I19 @BASEBOARD_FAB2_LIB.BASEBOARD_FAB2(SCH_1):PAGE75
  DK75    GND @BASEBOARD_FAB2_LIB.BASEBOARD_FAB2(SCH_1):GND    I19 @BASEBOARD_FAB2_LIB.BASEBOARD_FAB2(SCH_1):PAGE75
  DK77    GND @BASEBOARD_FAB2_LIB.BASEBOARD_FAB2(SCH_1):GND    I19 @BASEBOARD_FAB2_LIB.BASEBOARD_FAB2(SCH_1):PAGE75
  DK83    GND @BASEBOARD_FAB2_LIB.BASEBOARD_FAB2(SCH_1):GND    I19 @BASEBOARD_FAB2_LIB.BASEBOARD_FAB2(SCH_1):PAGE75
  DK85    GND @BASEBOARD_FAB2_LIB.BASEBOARD_FAB2(SCH_1):GND    I19 @BASEBOARD_FAB2_LIB.BASEBOARD_FAB2(SCH_1):PAGE75
  DL16    GND @BASEBOARD_FAB2_LIB.BASEBOARD_FAB2(SCH_1):GND    I19 @BASEBOARD_FAB2_LIB.BASEBOARD_FAB2(SCH_1):PAGE75
  DL18    GND @BASEBOARD_FAB2_LIB.BASEBOARD_FAB2(SCH_1):GND    I19 @BASEBOARD_FAB2_LIB.BASEBOARD_FAB2(SCH_1):PAGE75
   DL4    GND @BASEBOARD_FAB2_LIB.BASEBOARD_FAB2(SCH_1):GND    I19 @BASEBOARD_FAB2_LIB.BASEBOARD_FAB2(SCH_1):PAGE75
  DL22    GND @BASEBOARD_FAB2_LIB.BASEBOARD_FAB2(SCH_1):GND    I19 @BASEBOARD_FAB2_LIB.BASEBOARD_FAB2(SCH_1):PAGE75
  DL24    GND @BASEBOARD_FAB2_LIB.BASEBOARD_FAB2(SCH_1):GND    I19 @BASEBOARD_FAB2_LIB.BASEBOARD_FAB2(SCH_1):PAGE75
  DL28    GND @BASEBOARD_FAB2_LIB.BASEBOARD_FAB2(SCH_1):GND    I19 @BASEBOARD_FAB2_LIB.BASEBOARD_FAB2(SCH_1):PAGE75
  DL30    GND @BASEBOARD_FAB2_LIB.BASEBOARD_FAB2(SCH_1):GND    I19 @BASEBOARD_FAB2_LIB.BASEBOARD_FAB2(SCH_1):PAGE75
  DL34    GND @BASEBOARD_FAB2_LIB.BASEBOARD_FAB2(SCH_1):GND    I19 @BASEBOARD_FAB2_LIB.BASEBOARD_FAB2(SCH_1):PAGE75
  DL36    GND @BASEBOARD_FAB2_LIB.BASEBOARD_FAB2(SCH_1):GND    I19 @BASEBOARD_FAB2_LIB.BASEBOARD_FAB2(SCH_1):PAGE75
  DL40    GND @BASEBOARD_FAB2_LIB.BASEBOARD_FAB2(SCH_1):GND    I19 @BASEBOARD_FAB2_LIB.BASEBOARD_FAB2(SCH_1):PAGE75
  DL68    GND @BASEBOARD_FAB2_LIB.BASEBOARD_FAB2(SCH_1):GND    I19 @BASEBOARD_FAB2_LIB.BASEBOARD_FAB2(SCH_1):PAGE75
  DL70    GND @BASEBOARD_FAB2_LIB.BASEBOARD_FAB2(SCH_1):GND    I19 @BASEBOARD_FAB2_LIB.BASEBOARD_FAB2(SCH_1):PAGE75
  DL74    GND @BASEBOARD_FAB2_LIB.BASEBOARD_FAB2(SCH_1):GND    I19 @BASEBOARD_FAB2_LIB.BASEBOARD_FAB2(SCH_1):PAGE75
  DL76    GND @BASEBOARD_FAB2_LIB.BASEBOARD_FAB2(SCH_1):GND    I19 @BASEBOARD_FAB2_LIB.BASEBOARD_FAB2(SCH_1):PAGE75
  DL78    GND @BASEBOARD_FAB2_LIB.BASEBOARD_FAB2(SCH_1):GND    I19 @BASEBOARD_FAB2_LIB.BASEBOARD_FAB2(SCH_1):PAGE75
  DL80    GND @BASEBOARD_FAB2_LIB.BASEBOARD_FAB2(SCH_1):GND    I19 @BASEBOARD_FAB2_LIB.BASEBOARD_FAB2(SCH_1):PAGE75
  DM15    GND @BASEBOARD_FAB2_LIB.BASEBOARD_FAB2(SCH_1):GND    I19 @BASEBOARD_FAB2_LIB.BASEBOARD_FAB2(SCH_1):PAGE75
   H45    GND @BASEBOARD_FAB2_LIB.BASEBOARD_FAB2(SCH_1):GND    I19 @BASEBOARD_FAB2_LIB.BASEBOARD_FAB2(SCH_1):PAGE75
  DM25    GND @BASEBOARD_FAB2_LIB.BASEBOARD_FAB2(SCH_1):GND    I19 @BASEBOARD_FAB2_LIB.BASEBOARD_FAB2(SCH_1):PAGE75
  DM27    GND @BASEBOARD_FAB2_LIB.BASEBOARD_FAB2(SCH_1):GND    I19 @BASEBOARD_FAB2_LIB.BASEBOARD_FAB2(SCH_1):PAGE75
  DM31    GND @BASEBOARD_FAB2_LIB.BASEBOARD_FAB2(SCH_1):GND    I19 @BASEBOARD_FAB2_LIB.BASEBOARD_FAB2(SCH_1):PAGE75
  DM33    GND @BASEBOARD_FAB2_LIB.BASEBOARD_FAB2(SCH_1):GND    I19 @BASEBOARD_FAB2_LIB.BASEBOARD_FAB2(SCH_1):PAGE75
  DM37    GND @BASEBOARD_FAB2_LIB.BASEBOARD_FAB2(SCH_1):GND    I19 @BASEBOARD_FAB2_LIB.BASEBOARD_FAB2(SCH_1):PAGE75
  DM39    GND @BASEBOARD_FAB2_LIB.BASEBOARD_FAB2(SCH_1):GND    I19 @BASEBOARD_FAB2_LIB.BASEBOARD_FAB2(SCH_1):PAGE75
  DM65    GND @BASEBOARD_FAB2_LIB.BASEBOARD_FAB2(SCH_1):GND    I19 @BASEBOARD_FAB2_LIB.BASEBOARD_FAB2(SCH_1):PAGE75
  DM73    GND @BASEBOARD_FAB2_LIB.BASEBOARD_FAB2(SCH_1):GND    I19 @BASEBOARD_FAB2_LIB.BASEBOARD_FAB2(SCH_1):PAGE75
  DM77    GND @BASEBOARD_FAB2_LIB.BASEBOARD_FAB2(SCH_1):GND    I19 @BASEBOARD_FAB2_LIB.BASEBOARD_FAB2(SCH_1):PAGE75
  DM83    GND @BASEBOARD_FAB2_LIB.BASEBOARD_FAB2(SCH_1):GND    I19 @BASEBOARD_FAB2_LIB.BASEBOARD_FAB2(SCH_1):PAGE75
   DN2    GND @BASEBOARD_FAB2_LIB.BASEBOARD_FAB2(SCH_1):GND    I19 @BASEBOARD_FAB2_LIB.BASEBOARD_FAB2(SCH_1):PAGE75
  BH17    GND @BASEBOARD_FAB2_LIB.BASEBOARD_FAB2(SCH_1):GND    I19 @BASEBOARD_FAB2_LIB.BASEBOARD_FAB2(SCH_1):PAGE75
  DN12    GND @BASEBOARD_FAB2_LIB.BASEBOARD_FAB2(SCH_1):GND    I19 @BASEBOARD_FAB2_LIB.BASEBOARD_FAB2(SCH_1):PAGE75
  DN22    GND @BASEBOARD_FAB2_LIB.BASEBOARD_FAB2(SCH_1):GND    I19 @BASEBOARD_FAB2_LIB.BASEBOARD_FAB2(SCH_1):PAGE75
  DN26    GND @BASEBOARD_FAB2_LIB.BASEBOARD_FAB2(SCH_1):GND    I19 @BASEBOARD_FAB2_LIB.BASEBOARD_FAB2(SCH_1):PAGE75
  DN32    GND @BASEBOARD_FAB2_LIB.BASEBOARD_FAB2(SCH_1):GND    I19 @BASEBOARD_FAB2_LIB.BASEBOARD_FAB2(SCH_1):PAGE75
  DN38    GND @BASEBOARD_FAB2_LIB.BASEBOARD_FAB2(SCH_1):GND    I19 @BASEBOARD_FAB2_LIB.BASEBOARD_FAB2(SCH_1):PAGE75
  DN68    GND @BASEBOARD_FAB2_LIB.BASEBOARD_FAB2(SCH_1):GND    I19 @BASEBOARD_FAB2_LIB.BASEBOARD_FAB2(SCH_1):PAGE75
  DN72    GND @BASEBOARD_FAB2_LIB.BASEBOARD_FAB2(SCH_1):GND    I19 @BASEBOARD_FAB2_LIB.BASEBOARD_FAB2(SCH_1):PAGE75
  DN78    GND @BASEBOARD_FAB2_LIB.BASEBOARD_FAB2(SCH_1):GND    I20 @BASEBOARD_FAB2_LIB.BASEBOARD_FAB2(SCH_1):PAGE75
  DP67    GND @BASEBOARD_FAB2_LIB.BASEBOARD_FAB2(SCH_1):GND    I20 @BASEBOARD_FAB2_LIB.BASEBOARD_FAB2(SCH_1):PAGE75
  DP69    GND @BASEBOARD_FAB2_LIB.BASEBOARD_FAB2(SCH_1):GND    I20 @BASEBOARD_FAB2_LIB.BASEBOARD_FAB2(SCH_1):PAGE75
  DP71    GND @BASEBOARD_FAB2_LIB.BASEBOARD_FAB2(SCH_1):GND    I20 @BASEBOARD_FAB2_LIB.BASEBOARD_FAB2(SCH_1):PAGE75
  DP81    GND @BASEBOARD_FAB2_LIB.BASEBOARD_FAB2(SCH_1):GND    I20 @BASEBOARD_FAB2_LIB.BASEBOARD_FAB2(SCH_1):PAGE75
  DP83    GND @BASEBOARD_FAB2_LIB.BASEBOARD_FAB2(SCH_1):GND    I20 @BASEBOARD_FAB2_LIB.BASEBOARD_FAB2(SCH_1):PAGE75
  BR26    GND @BASEBOARD_FAB2_LIB.BASEBOARD_FAB2(SCH_1):GND    I20 @BASEBOARD_FAB2_LIB.BASEBOARD_FAB2(SCH_1):PAGE75
   DR6    GND @BASEBOARD_FAB2_LIB.BASEBOARD_FAB2(SCH_1):GND    I20 @BASEBOARD_FAB2_LIB.BASEBOARD_FAB2(SCH_1):PAGE75
  CA20    GND @BASEBOARD_FAB2_LIB.BASEBOARD_FAB2(SCH_1):GND    I20 @BASEBOARD_FAB2_LIB.BASEBOARD_FAB2(SCH_1):PAGE75
  CL22    GND @BASEBOARD_FAB2_LIB.BASEBOARD_FAB2(SCH_1):GND    I20 @BASEBOARD_FAB2_LIB.BASEBOARD_FAB2(SCH_1):PAGE75
  DR20    GND @BASEBOARD_FAB2_LIB.BASEBOARD_FAB2(SCH_1):GND    I20 @BASEBOARD_FAB2_LIB.BASEBOARD_FAB2(SCH_1):PAGE75
  DR22    GND @BASEBOARD_FAB2_LIB.BASEBOARD_FAB2(SCH_1):GND    I20 @BASEBOARD_FAB2_LIB.BASEBOARD_FAB2(SCH_1):PAGE75
  DR24    GND @BASEBOARD_FAB2_LIB.BASEBOARD_FAB2(SCH_1):GND    I20 @BASEBOARD_FAB2_LIB.BASEBOARD_FAB2(SCH_1):PAGE75
  DR26    GND @BASEBOARD_FAB2_LIB.BASEBOARD_FAB2(SCH_1):GND    I20 @BASEBOARD_FAB2_LIB.BASEBOARD_FAB2(SCH_1):PAGE75
  DR28    GND @BASEBOARD_FAB2_LIB.BASEBOARD_FAB2(SCH_1):GND    I20 @BASEBOARD_FAB2_LIB.BASEBOARD_FAB2(SCH_1):PAGE75
  DR30    GND @BASEBOARD_FAB2_LIB.BASEBOARD_FAB2(SCH_1):GND    I20 @BASEBOARD_FAB2_LIB.BASEBOARD_FAB2(SCH_1):PAGE75
  DR32    GND @BASEBOARD_FAB2_LIB.BASEBOARD_FAB2(SCH_1):GND    I20 @BASEBOARD_FAB2_LIB.BASEBOARD_FAB2(SCH_1):PAGE75
  DR34    GND @BASEBOARD_FAB2_LIB.BASEBOARD_FAB2(SCH_1):GND    I20 @BASEBOARD_FAB2_LIB.BASEBOARD_FAB2(SCH_1):PAGE75
  DR36    GND @BASEBOARD_FAB2_LIB.BASEBOARD_FAB2(SCH_1):GND    I20 @BASEBOARD_FAB2_LIB.BASEBOARD_FAB2(SCH_1):PAGE75
  DR38    GND @BASEBOARD_FAB2_LIB.BASEBOARD_FAB2(SCH_1):GND    I20 @BASEBOARD_FAB2_LIB.BASEBOARD_FAB2(SCH_1):PAGE75
  DR40    GND @BASEBOARD_FAB2_LIB.BASEBOARD_FAB2(SCH_1):GND    I20 @BASEBOARD_FAB2_LIB.BASEBOARD_FAB2(SCH_1):PAGE75
  DR42    GND @BASEBOARD_FAB2_LIB.BASEBOARD_FAB2(SCH_1):GND    I20 @BASEBOARD_FAB2_LIB.BASEBOARD_FAB2(SCH_1):PAGE75
  DR66    GND @BASEBOARD_FAB2_LIB.BASEBOARD_FAB2(SCH_1):GND    I20 @BASEBOARD_FAB2_LIB.BASEBOARD_FAB2(SCH_1):PAGE75
  DR68    GND @BASEBOARD_FAB2_LIB.BASEBOARD_FAB2(SCH_1):GND    I20 @BASEBOARD_FAB2_LIB.BASEBOARD_FAB2(SCH_1):PAGE75
  DR70    GND @BASEBOARD_FAB2_LIB.BASEBOARD_FAB2(SCH_1):GND    I20 @BASEBOARD_FAB2_LIB.BASEBOARD_FAB2(SCH_1):PAGE75
  DR72    GND @BASEBOARD_FAB2_LIB.BASEBOARD_FAB2(SCH_1):GND    I20 @BASEBOARD_FAB2_LIB.BASEBOARD_FAB2(SCH_1):PAGE75
  DR74    GND @BASEBOARD_FAB2_LIB.BASEBOARD_FAB2(SCH_1):GND    I20 @BASEBOARD_FAB2_LIB.BASEBOARD_FAB2(SCH_1):PAGE75
  DR76    GND @BASEBOARD_FAB2_LIB.BASEBOARD_FAB2(SCH_1):GND    I20 @BASEBOARD_FAB2_LIB.BASEBOARD_FAB2(SCH_1):PAGE75
  DR78    GND @BASEBOARD_FAB2_LIB.BASEBOARD_FAB2(SCH_1):GND    I20 @BASEBOARD_FAB2_LIB.BASEBOARD_FAB2(SCH_1):PAGE75
   DT3    GND @BASEBOARD_FAB2_LIB.BASEBOARD_FAB2(SCH_1):GND    I20 @BASEBOARD_FAB2_LIB.BASEBOARD_FAB2(SCH_1):PAGE75
  DT17    GND @BASEBOARD_FAB2_LIB.BASEBOARD_FAB2(SCH_1):GND    I20 @BASEBOARD_FAB2_LIB.BASEBOARD_FAB2(SCH_1):PAGE75
  DH21    GND @BASEBOARD_FAB2_LIB.BASEBOARD_FAB2(SCH_1):GND    I20 @BASEBOARD_FAB2_LIB.BASEBOARD_FAB2(SCH_1):PAGE75
  DT65    GND @BASEBOARD_FAB2_LIB.BASEBOARD_FAB2(SCH_1):GND    I20 @BASEBOARD_FAB2_LIB.BASEBOARD_FAB2(SCH_1):PAGE75
  DT69    GND @BASEBOARD_FAB2_LIB.BASEBOARD_FAB2(SCH_1):GND    I20 @BASEBOARD_FAB2_LIB.BASEBOARD_FAB2(SCH_1):PAGE75
  DT79    GND @BASEBOARD_FAB2_LIB.BASEBOARD_FAB2(SCH_1):GND    I20 @BASEBOARD_FAB2_LIB.BASEBOARD_FAB2(SCH_1):PAGE75
  DT83    GND @BASEBOARD_FAB2_LIB.BASEBOARD_FAB2(SCH_1):GND    I20 @BASEBOARD_FAB2_LIB.BASEBOARD_FAB2(SCH_1):PAGE75
  DT85    GND @BASEBOARD_FAB2_LIB.BASEBOARD_FAB2(SCH_1):GND    I20 @BASEBOARD_FAB2_LIB.BASEBOARD_FAB2(SCH_1):PAGE75
  DU10    GND @BASEBOARD_FAB2_LIB.BASEBOARD_FAB2(SCH_1):GND    I20 @BASEBOARD_FAB2_LIB.BASEBOARD_FAB2(SCH_1):PAGE75
  DU14    GND @BASEBOARD_FAB2_LIB.BASEBOARD_FAB2(SCH_1):GND    I20 @BASEBOARD_FAB2_LIB.BASEBOARD_FAB2(SCH_1):PAGE75
  CN14    GND @BASEBOARD_FAB2_LIB.BASEBOARD_FAB2(SCH_1):GND    I20 @BASEBOARD_FAB2_LIB.BASEBOARD_FAB2(SCH_1):PAGE75
  DU22    GND @BASEBOARD_FAB2_LIB.BASEBOARD_FAB2(SCH_1):GND    I20 @BASEBOARD_FAB2_LIB.BASEBOARD_FAB2(SCH_1):PAGE75
  DU26    GND @BASEBOARD_FAB2_LIB.BASEBOARD_FAB2(SCH_1):GND    I20 @BASEBOARD_FAB2_LIB.BASEBOARD_FAB2(SCH_1):PAGE75
  DU32    GND @BASEBOARD_FAB2_LIB.BASEBOARD_FAB2(SCH_1):GND    I20 @BASEBOARD_FAB2_LIB.BASEBOARD_FAB2(SCH_1):PAGE75
  DU38    GND @BASEBOARD_FAB2_LIB.BASEBOARD_FAB2(SCH_1):GND    I20 @BASEBOARD_FAB2_LIB.BASEBOARD_FAB2(SCH_1):PAGE75
  DU70    GND @BASEBOARD_FAB2_LIB.BASEBOARD_FAB2(SCH_1):GND    I20 @BASEBOARD_FAB2_LIB.BASEBOARD_FAB2(SCH_1):PAGE75
  DU72    GND @BASEBOARD_FAB2_LIB.BASEBOARD_FAB2(SCH_1):GND    I20 @BASEBOARD_FAB2_LIB.BASEBOARD_FAB2(SCH_1):PAGE75
  DU78    GND @BASEBOARD_FAB2_LIB.BASEBOARD_FAB2(SCH_1):GND    I20 @BASEBOARD_FAB2_LIB.BASEBOARD_FAB2(SCH_1):PAGE75
  DU80    GND @BASEBOARD_FAB2_LIB.BASEBOARD_FAB2(SCH_1):GND    I20 @BASEBOARD_FAB2_LIB.BASEBOARD_FAB2(SCH_1):PAGE75
  DU82    GND @BASEBOARD_FAB2_LIB.BASEBOARD_FAB2(SCH_1):GND    I20 @BASEBOARD_FAB2_LIB.BASEBOARD_FAB2(SCH_1):PAGE75
  DU84    GND @BASEBOARD_FAB2_LIB.BASEBOARD_FAB2(SCH_1):GND    I20 @BASEBOARD_FAB2_LIB.BASEBOARD_FAB2(SCH_1):PAGE75
  DV21    GND @BASEBOARD_FAB2_LIB.BASEBOARD_FAB2(SCH_1):GND    I20 @BASEBOARD_FAB2_LIB.BASEBOARD_FAB2(SCH_1):PAGE75
  DV25    GND @BASEBOARD_FAB2_LIB.BASEBOARD_FAB2(SCH_1):GND    I20 @BASEBOARD_FAB2_LIB.BASEBOARD_FAB2(SCH_1):PAGE75
  DV27    GND @BASEBOARD_FAB2_LIB.BASEBOARD_FAB2(SCH_1):GND    I20 @BASEBOARD_FAB2_LIB.BASEBOARD_FAB2(SCH_1):PAGE75
  DV31    GND @BASEBOARD_FAB2_LIB.BASEBOARD_FAB2(SCH_1):GND    I20 @BASEBOARD_FAB2_LIB.BASEBOARD_FAB2(SCH_1):PAGE75
  DV33    GND @BASEBOARD_FAB2_LIB.BASEBOARD_FAB2(SCH_1):GND    I20 @BASEBOARD_FAB2_LIB.BASEBOARD_FAB2(SCH_1):PAGE75
  DV37    GND @BASEBOARD_FAB2_LIB.BASEBOARD_FAB2(SCH_1):GND    I20 @BASEBOARD_FAB2_LIB.BASEBOARD_FAB2(SCH_1):PAGE75
  DV39    GND @BASEBOARD_FAB2_LIB.BASEBOARD_FAB2(SCH_1):GND    I20 @BASEBOARD_FAB2_LIB.BASEBOARD_FAB2(SCH_1):PAGE75
  DV73    GND @BASEBOARD_FAB2_LIB.BASEBOARD_FAB2(SCH_1):GND    I20 @BASEBOARD_FAB2_LIB.BASEBOARD_FAB2(SCH_1):PAGE75
  DV77    GND @BASEBOARD_FAB2_LIB.BASEBOARD_FAB2(SCH_1):GND    I20 @BASEBOARD_FAB2_LIB.BASEBOARD_FAB2(SCH_1):PAGE75
  DV81    GND @BASEBOARD_FAB2_LIB.BASEBOARD_FAB2(SCH_1):GND    I20 @BASEBOARD_FAB2_LIB.BASEBOARD_FAB2(SCH_1):PAGE75
  DW12    GND @BASEBOARD_FAB2_LIB.BASEBOARD_FAB2(SCH_1):GND    I20 @BASEBOARD_FAB2_LIB.BASEBOARD_FAB2(SCH_1):PAGE75
  DW20    GND @BASEBOARD_FAB2_LIB.BASEBOARD_FAB2(SCH_1):GND    I20 @BASEBOARD_FAB2_LIB.BASEBOARD_FAB2(SCH_1):PAGE75
  DW24    GND @BASEBOARD_FAB2_LIB.BASEBOARD_FAB2(SCH_1):GND    I20 @BASEBOARD_FAB2_LIB.BASEBOARD_FAB2(SCH_1):PAGE75
  DW28    GND @BASEBOARD_FAB2_LIB.BASEBOARD_FAB2(SCH_1):GND    I20 @BASEBOARD_FAB2_LIB.BASEBOARD_FAB2(SCH_1):PAGE75
  DW30    GND @BASEBOARD_FAB2_LIB.BASEBOARD_FAB2(SCH_1):GND    I20 @BASEBOARD_FAB2_LIB.BASEBOARD_FAB2(SCH_1):PAGE75
  DW34    GND @BASEBOARD_FAB2_LIB.BASEBOARD_FAB2(SCH_1):GND    I20 @BASEBOARD_FAB2_LIB.BASEBOARD_FAB2(SCH_1):PAGE75
  DW36    GND @BASEBOARD_FAB2_LIB.BASEBOARD_FAB2(SCH_1):GND    I20 @BASEBOARD_FAB2_LIB.BASEBOARD_FAB2(SCH_1):PAGE75
  DW40    GND @BASEBOARD_FAB2_LIB.BASEBOARD_FAB2(SCH_1):GND    I20 @BASEBOARD_FAB2_LIB.BASEBOARD_FAB2(SCH_1):PAGE75
  DW64    GND @BASEBOARD_FAB2_LIB.BASEBOARD_FAB2(SCH_1):GND    I20 @BASEBOARD_FAB2_LIB.BASEBOARD_FAB2(SCH_1):PAGE75
  DW66    GND @BASEBOARD_FAB2_LIB.BASEBOARD_FAB2(SCH_1):GND    I20 @BASEBOARD_FAB2_LIB.BASEBOARD_FAB2(SCH_1):PAGE75
  DW68    GND @BASEBOARD_FAB2_LIB.BASEBOARD_FAB2(SCH_1):GND    I20 @BASEBOARD_FAB2_LIB.BASEBOARD_FAB2(SCH_1):PAGE75
  DW70    GND @BASEBOARD_FAB2_LIB.BASEBOARD_FAB2(SCH_1):GND    I20 @BASEBOARD_FAB2_LIB.BASEBOARD_FAB2(SCH_1):PAGE75
  DW72    GND @BASEBOARD_FAB2_LIB.BASEBOARD_FAB2(SCH_1):GND    I20 @BASEBOARD_FAB2_LIB.BASEBOARD_FAB2(SCH_1):PAGE75
  DW74    GND @BASEBOARD_FAB2_LIB.BASEBOARD_FAB2(SCH_1):GND    I20 @BASEBOARD_FAB2_LIB.BASEBOARD_FAB2(SCH_1):PAGE75
  DW76    GND @BASEBOARD_FAB2_LIB.BASEBOARD_FAB2(SCH_1):GND    I20 @BASEBOARD_FAB2_LIB.BASEBOARD_FAB2(SCH_1):PAGE75
   DW8    GND @BASEBOARD_FAB2_LIB.BASEBOARD_FAB2(SCH_1):GND    I20 @BASEBOARD_FAB2_LIB.BASEBOARD_FAB2(SCH_1):PAGE75
  DW82    GND @BASEBOARD_FAB2_LIB.BASEBOARD_FAB2(SCH_1):GND    I20 @BASEBOARD_FAB2_LIB.BASEBOARD_FAB2(SCH_1):PAGE75
  DW84    GND @BASEBOARD_FAB2_LIB.BASEBOARD_FAB2(SCH_1):GND    I20 @BASEBOARD_FAB2_LIB.BASEBOARD_FAB2(SCH_1):PAGE75
   DY5    GND @BASEBOARD_FAB2_LIB.BASEBOARD_FAB2(SCH_1):GND    I20 @BASEBOARD_FAB2_LIB.BASEBOARD_FAB2(SCH_1):PAGE75
  DY19    GND @BASEBOARD_FAB2_LIB.BASEBOARD_FAB2(SCH_1):GND    I20 @BASEBOARD_FAB2_LIB.BASEBOARD_FAB2(SCH_1):PAGE75
  DY23    GND @BASEBOARD_FAB2_LIB.BASEBOARD_FAB2(SCH_1):GND    I20 @BASEBOARD_FAB2_LIB.BASEBOARD_FAB2(SCH_1):PAGE75
  DY29    GND @BASEBOARD_FAB2_LIB.BASEBOARD_FAB2(SCH_1):GND    I20 @BASEBOARD_FAB2_LIB.BASEBOARD_FAB2(SCH_1):PAGE75
  DY35    GND @BASEBOARD_FAB2_LIB.BASEBOARD_FAB2(SCH_1):GND    I20 @BASEBOARD_FAB2_LIB.BASEBOARD_FAB2(SCH_1):PAGE75
  DY41    GND @BASEBOARD_FAB2_LIB.BASEBOARD_FAB2(SCH_1):GND    I20 @BASEBOARD_FAB2_LIB.BASEBOARD_FAB2(SCH_1):PAGE75
  DY71    GND @BASEBOARD_FAB2_LIB.BASEBOARD_FAB2(SCH_1):GND    I20 @BASEBOARD_FAB2_LIB.BASEBOARD_FAB2(SCH_1):PAGE75
  DY75    GND @BASEBOARD_FAB2_LIB.BASEBOARD_FAB2(SCH_1):GND    I20 @BASEBOARD_FAB2_LIB.BASEBOARD_FAB2(SCH_1):PAGE75
   EA6    GND @BASEBOARD_FAB2_LIB.BASEBOARD_FAB2(SCH_1):GND    I20 @BASEBOARD_FAB2_LIB.BASEBOARD_FAB2(SCH_1):PAGE75
   J16    GND @BASEBOARD_FAB2_LIB.BASEBOARD_FAB2(SCH_1):GND    I20 @BASEBOARD_FAB2_LIB.BASEBOARD_FAB2(SCH_1):PAGE75
  EA16    GND @BASEBOARD_FAB2_LIB.BASEBOARD_FAB2(SCH_1):GND    I20 @BASEBOARD_FAB2_LIB.BASEBOARD_FAB2(SCH_1):PAGE75
  EA20    GND @BASEBOARD_FAB2_LIB.BASEBOARD_FAB2(SCH_1):GND    I20 @BASEBOARD_FAB2_LIB.BASEBOARD_FAB2(SCH_1):PAGE75
  EA22    GND @BASEBOARD_FAB2_LIB.BASEBOARD_FAB2(SCH_1):GND    I20 @BASEBOARD_FAB2_LIB.BASEBOARD_FAB2(SCH_1):PAGE75
  EA42    GND @BASEBOARD_FAB2_LIB.BASEBOARD_FAB2(SCH_1):GND    I20 @BASEBOARD_FAB2_LIB.BASEBOARD_FAB2(SCH_1):PAGE75
  EA64    GND @BASEBOARD_FAB2_LIB.BASEBOARD_FAB2(SCH_1):GND    I20 @BASEBOARD_FAB2_LIB.BASEBOARD_FAB2(SCH_1):PAGE75
  EA70    GND @BASEBOARD_FAB2_LIB.BASEBOARD_FAB2(SCH_1):GND    I20 @BASEBOARD_FAB2_LIB.BASEBOARD_FAB2(SCH_1):PAGE75
  EA76    GND @BASEBOARD_FAB2_LIB.BASEBOARD_FAB2(SCH_1):GND    I20 @BASEBOARD_FAB2_LIB.BASEBOARD_FAB2(SCH_1):PAGE75
  EA78    GND @BASEBOARD_FAB2_LIB.BASEBOARD_FAB2(SCH_1):GND    I20 @BASEBOARD_FAB2_LIB.BASEBOARD_FAB2(SCH_1):PAGE75
  EA80    GND @BASEBOARD_FAB2_LIB.BASEBOARD_FAB2(SCH_1):GND    I20 @BASEBOARD_FAB2_LIB.BASEBOARD_FAB2(SCH_1):PAGE75
  EA82    GND @BASEBOARD_FAB2_LIB.BASEBOARD_FAB2(SCH_1):GND    I20 @BASEBOARD_FAB2_LIB.BASEBOARD_FAB2(SCH_1):PAGE75
  EB13    GND @BASEBOARD_FAB2_LIB.BASEBOARD_FAB2(SCH_1):GND    I20 @BASEBOARD_FAB2_LIB.BASEBOARD_FAB2(SCH_1):PAGE75
  BR18    GND @BASEBOARD_FAB2_LIB.BASEBOARD_FAB2(SCH_1):GND    I20 @BASEBOARD_FAB2_LIB.BASEBOARD_FAB2(SCH_1):PAGE75
  EB23    GND @BASEBOARD_FAB2_LIB.BASEBOARD_FAB2(SCH_1):GND    I20 @BASEBOARD_FAB2_LIB.BASEBOARD_FAB2(SCH_1):PAGE75
  EB25    GND @BASEBOARD_FAB2_LIB.BASEBOARD_FAB2(SCH_1):GND    I20 @BASEBOARD_FAB2_LIB.BASEBOARD_FAB2(SCH_1):PAGE75
  EB27    GND @BASEBOARD_FAB2_LIB.BASEBOARD_FAB2(SCH_1):GND    I20 @BASEBOARD_FAB2_LIB.BASEBOARD_FAB2(SCH_1):PAGE75
  EB29    GND @BASEBOARD_FAB2_LIB.BASEBOARD_FAB2(SCH_1):GND    I20 @BASEBOARD_FAB2_LIB.BASEBOARD_FAB2(SCH_1):PAGE75
  EB31    GND @BASEBOARD_FAB2_LIB.BASEBOARD_FAB2(SCH_1):GND    I20 @BASEBOARD_FAB2_LIB.BASEBOARD_FAB2(SCH_1):PAGE75
  EB33    GND @BASEBOARD_FAB2_LIB.BASEBOARD_FAB2(SCH_1):GND    I20 @BASEBOARD_FAB2_LIB.BASEBOARD_FAB2(SCH_1):PAGE75
  EB35    GND @BASEBOARD_FAB2_LIB.BASEBOARD_FAB2(SCH_1):GND    I20 @BASEBOARD_FAB2_LIB.BASEBOARD_FAB2(SCH_1):PAGE75
  EB37    GND @BASEBOARD_FAB2_LIB.BASEBOARD_FAB2(SCH_1):GND    I20 @BASEBOARD_FAB2_LIB.BASEBOARD_FAB2(SCH_1):PAGE75
  EB39    GND @BASEBOARD_FAB2_LIB.BASEBOARD_FAB2(SCH_1):GND    I20 @BASEBOARD_FAB2_LIB.BASEBOARD_FAB2(SCH_1):PAGE75
  EB41    GND @BASEBOARD_FAB2_LIB.BASEBOARD_FAB2(SCH_1):GND    I20 @BASEBOARD_FAB2_LIB.BASEBOARD_FAB2(SCH_1):PAGE75
  EB65    GND @BASEBOARD_FAB2_LIB.BASEBOARD_FAB2(SCH_1):GND    I20 @BASEBOARD_FAB2_LIB.BASEBOARD_FAB2(SCH_1):PAGE75
  EB69    GND @BASEBOARD_FAB2_LIB.BASEBOARD_FAB2(SCH_1):GND    I20 @BASEBOARD_FAB2_LIB.BASEBOARD_FAB2(SCH_1):PAGE75
  EC10    GND @BASEBOARD_FAB2_LIB.BASEBOARD_FAB2(SCH_1):GND    I20 @BASEBOARD_FAB2_LIB.BASEBOARD_FAB2(SCH_1):PAGE75
  EC70    GND @BASEBOARD_FAB2_LIB.BASEBOARD_FAB2(SCH_1):GND    I20 @BASEBOARD_FAB2_LIB.BASEBOARD_FAB2(SCH_1):PAGE75
  EC72    GND @BASEBOARD_FAB2_LIB.BASEBOARD_FAB2(SCH_1):GND    I20 @BASEBOARD_FAB2_LIB.BASEBOARD_FAB2(SCH_1):PAGE75
  EC74    GND @BASEBOARD_FAB2_LIB.BASEBOARD_FAB2(SCH_1):GND    I20 @BASEBOARD_FAB2_LIB.BASEBOARD_FAB2(SCH_1):PAGE75
  EC76    GND @BASEBOARD_FAB2_LIB.BASEBOARD_FAB2(SCH_1):GND    I20 @BASEBOARD_FAB2_LIB.BASEBOARD_FAB2(SCH_1):PAGE75
  ED11    GND @BASEBOARD_FAB2_LIB.BASEBOARD_FAB2(SCH_1):GND    I20 @BASEBOARD_FAB2_LIB.BASEBOARD_FAB2(SCH_1):PAGE75
  ED15    GND @BASEBOARD_FAB2_LIB.BASEBOARD_FAB2(SCH_1):GND    I20 @BASEBOARD_FAB2_LIB.BASEBOARD_FAB2(SCH_1):PAGE75
  ED23    GND @BASEBOARD_FAB2_LIB.BASEBOARD_FAB2(SCH_1):GND    I20 @BASEBOARD_FAB2_LIB.BASEBOARD_FAB2(SCH_1):PAGE75
  ED29    GND @BASEBOARD_FAB2_LIB.BASEBOARD_FAB2(SCH_1):GND    I20 @BASEBOARD_FAB2_LIB.BASEBOARD_FAB2(SCH_1):PAGE75
  ED35    GND @BASEBOARD_FAB2_LIB.BASEBOARD_FAB2(SCH_1):GND    I20 @BASEBOARD_FAB2_LIB.BASEBOARD_FAB2(SCH_1):PAGE75
  ED77    GND @BASEBOARD_FAB2_LIB.BASEBOARD_FAB2(SCH_1):GND    I20 @BASEBOARD_FAB2_LIB.BASEBOARD_FAB2(SCH_1):PAGE75
  EE24    GND @BASEBOARD_FAB2_LIB.BASEBOARD_FAB2(SCH_1):GND    I20 @BASEBOARD_FAB2_LIB.BASEBOARD_FAB2(SCH_1):PAGE75
  EE28    GND @BASEBOARD_FAB2_LIB.BASEBOARD_FAB2(SCH_1):GND    I20 @BASEBOARD_FAB2_LIB.BASEBOARD_FAB2(SCH_1):PAGE75
  EE30    GND @BASEBOARD_FAB2_LIB.BASEBOARD_FAB2(SCH_1):GND    I20 @BASEBOARD_FAB2_LIB.BASEBOARD_FAB2(SCH_1):PAGE75
  EE34    GND @BASEBOARD_FAB2_LIB.BASEBOARD_FAB2(SCH_1):GND    I20 @BASEBOARD_FAB2_LIB.BASEBOARD_FAB2(SCH_1):PAGE75
  EE36    GND @BASEBOARD_FAB2_LIB.BASEBOARD_FAB2(SCH_1):GND    I20 @BASEBOARD_FAB2_LIB.BASEBOARD_FAB2(SCH_1):PAGE75
  EE70    GND @BASEBOARD_FAB2_LIB.BASEBOARD_FAB2(SCH_1):GND    I20 @BASEBOARD_FAB2_LIB.BASEBOARD_FAB2(SCH_1):PAGE75
  EE76    GND @BASEBOARD_FAB2_LIB.BASEBOARD_FAB2(SCH_1):GND    I20 @BASEBOARD_FAB2_LIB.BASEBOARD_FAB2(SCH_1):PAGE75
  EE78    GND @BASEBOARD_FAB2_LIB.BASEBOARD_FAB2(SCH_1):GND    I20 @BASEBOARD_FAB2_LIB.BASEBOARD_FAB2(SCH_1):PAGE75
  EF71    GND @BASEBOARD_FAB2_LIB.BASEBOARD_FAB2(SCH_1):GND    I20 @BASEBOARD_FAB2_LIB.BASEBOARD_FAB2(SCH_1):PAGE75
  EF75    GND @BASEBOARD_FAB2_LIB.BASEBOARD_FAB2(SCH_1):GND    I20 @BASEBOARD_FAB2_LIB.BASEBOARD_FAB2(SCH_1):PAGE75
  EF79    GND @BASEBOARD_FAB2_LIB.BASEBOARD_FAB2(SCH_1):GND    I20 @BASEBOARD_FAB2_LIB.BASEBOARD_FAB2(SCH_1):PAGE75

U2M1 NC7SB3157_SMLF-IC,C99406-001
     6 FM_CPU0_CD_PRES @BASEBOARD_FAB2_LIB.BASEBOARD_FAB2(SCH_1):FM_CPU0_CD_PRES   I255 @BASEBOARD_FAB2_LIB.BASEBOARD_FAB2(SCH_1):PAGE113
     3 JTAG_MCP_CPU1_TDI @BASEBOARD_FAB2_LIB.BASEBOARD_FAB2(SCH_1):JTAG_MCP_CPU1_TDI   I255 @BASEBOARD_FAB2_LIB.BASEBOARD_FAB2(SCH_1):PAGE113
     1 JTAG_MCP_CPU0_TDI @BASEBOARD_FAB2_LIB.BASEBOARD_FAB2(SCH_1):JTAG_MCP_CPU0_TDI   I255 @BASEBOARD_FAB2_LIB.BASEBOARD_FAB2(SCH_1):PAGE113
     4 JTAG_MCP_MUX_TDI @BASEBOARD_FAB2_LIB.BASEBOARD_FAB2(SCH_1):JTAG_MCP_MUX_TDI   I255 @BASEBOARD_FAB2_LIB.BASEBOARD_FAB2(SCH_1):PAGE113
     5 P3V3_STBY @BASEBOARD_FAB2_LIB.BASEBOARD_FAB2(SCH_1):P3V3_STBY   I255 @BASEBOARD_FAB2_LIB.BASEBOARD_FAB2(SCH_1):PAGE113
     2    GND @BASEBOARD_FAB2_LIB.BASEBOARD_FAB2(SCH_1):GND   I255 @BASEBOARD_FAB2_LIB.BASEBOARD_FAB2(SCH_1):PAGE113

U2P1 TTL1G07_A_SOP-74LVC1G07,IC,C88B
     2 FM_M2_SSD_PEDET @BASEBOARD_FAB2_LIB.BASEBOARD_FAB2(SCH_1):FM_M2_SSD_PEDET   I110 @BASEBOARD_FAB2_LIB.BASEBOARD_FAB2(SCH_1):PAGE185
     4 FM_M2_DET_LVC3 @BASEBOARD_FAB2_LIB.BASEBOARD_FAB2(SCH_1):FM_M2_DET_LVC3   I110 @BASEBOARD_FAB2_LIB.BASEBOARD_FAB2(SCH_1):PAGE185

U2R1 TC7PZ14FU-GP_DISCRET-GA1-TC7PZA
     1 FP_NMI_BTN @BASEBOARD_FAB2_LIB.BASEBOARD_FAB2(SCH_1):FP_NMI_BTN   I390 @BASEBOARD_FAB2_LIB.BASEBOARD_FAB2(SCH_1):PAGE157
     2    GND @BASEBOARD_FAB2_LIB.BASEBOARD_FAB2(SCH_1):GND   I390 @BASEBOARD_FAB2_LIB.BASEBOARD_FAB2(SCH_1):PAGE157
     3 FP_NMI_BTN_OUT_N @BASEBOARD_FAB2_LIB.BASEBOARD_FAB2(SCH_1):FP_NMI_BTN_OUT_N   I390 @BASEBOARD_FAB2_LIB.BASEBOARD_FAB2(SCH_1):PAGE157
     4 FP_NMI_BTN @BASEBOARD_FAB2_LIB.BASEBOARD_FAB2(SCH_1):FP_NMI_BTN   I390 @BASEBOARD_FAB2_LIB.BASEBOARD_FAB2(SCH_1):PAGE157
     5 P3V3_STBY @BASEBOARD_FAB2_LIB.BASEBOARD_FAB2(SCH_1):P3V3_STBY   I390 @BASEBOARD_FAB2_LIB.BASEBOARD_FAB2(SCH_1):PAGE157
     6 FP_NMI_BTN_R_N @BASEBOARD_FAB2_LIB.BASEBOARD_FAB2(SCH_1):FP_NMI_BTN_R_N   I390 @BASEBOARD_FAB2_LIB.BASEBOARD_FAB2(SCH_1):PAGE157

U2T1 PI3B3257A_TSSOPLF-IC,E16801-001
    16 P3V3_STBY @BASEBOARD_FAB2_LIB.BASEBOARD_FAB2(SCH_1):P3V3_STBY    I75 @BASEBOARD_FAB2_LIB.BASEBOARD_FAB2(SCH_1):PAGE154
     8    GND @BASEBOARD_FAB2_LIB.BASEBOARD_FAB2(SCH_1):GND    I75 @BASEBOARD_FAB2_LIB.BASEBOARD_FAB2(SCH_1):PAGE154
    15    GND @BASEBOARD_FAB2_LIB.BASEBOARD_FAB2(SCH_1):GND    I75 @BASEBOARD_FAB2_LIB.BASEBOARD_FAB2(SCH_1):PAGE154
     1 FM_BIOS_SPI_BMC_CTRL @BASEBOARD_FAB2_LIB.BASEBOARD_FAB2(SCH_1):FM_BIOS_SPI_BMC_CTRL    I75 @BASEBOARD_FAB2_LIB.BASEBOARD_FAB2(SCH_1):PAGE154
     4 SPI_BIOS_SOCKET_IO2 @BASEBOARD_FAB2_LIB.BASEBOARD_FAB2(SCH_1):SPI_BIOS_SOCKET_IO2    I75 @BASEBOARD_FAB2_LIB.BASEBOARD_FAB2(SCH_1):PAGE154
     7 SPI_BIOS_SOCKET_IO3 @BASEBOARD_FAB2_LIB.BASEBOARD_FAB2(SCH_1):SPI_BIOS_SOCKET_IO3    I75 @BASEBOARD_FAB2_LIB.BASEBOARD_FAB2(SCH_1):PAGE154
     9 TP_SPI_SWITCH1_9 @BASEBOARD_FAB2_LIB.BASEBOARD_FAB2(SCH_1):TP_SPI_SWITCH1_9    I75 @BASEBOARD_FAB2_LIB.BASEBOARD_FAB2(SCH_1):PAGE154
    12 TP_SPI_SWITCH1_12 @BASEBOARD_FAB2_LIB.BASEBOARD_FAB2(SCH_1):TP_SPI_SWITCH1_12    I75 @BASEBOARD_FAB2_LIB.BASEBOARD_FAB2(SCH_1):PAGE154
     2 SPI_PCH_IO2_R1 @BASEBOARD_FAB2_LIB.BASEBOARD_FAB2(SCH_1):SPI_PCH_IO2_R1    I75 @BASEBOARD_FAB2_LIB.BASEBOARD_FAB2(SCH_1):PAGE154
     3 TP_SPI_SWITCH1_3 @BASEBOARD_FAB2_LIB.BASEBOARD_FAB2(SCH_1):TP_SPI_SWITCH1_3    I75 @BASEBOARD_FAB2_LIB.BASEBOARD_FAB2(SCH_1):PAGE154
     5 SPI_PCH_IO3_R1 @BASEBOARD_FAB2_LIB.BASEBOARD_FAB2(SCH_1):SPI_PCH_IO3_R1    I75 @BASEBOARD_FAB2_LIB.BASEBOARD_FAB2(SCH_1):PAGE154
     6 TP_SPI_SWITCH1_6 @BASEBOARD_FAB2_LIB.BASEBOARD_FAB2(SCH_1):TP_SPI_SWITCH1_6    I75 @BASEBOARD_FAB2_LIB.BASEBOARD_FAB2(SCH_1):PAGE154
    11 TP_SPI_SWITCH1_11 @BASEBOARD_FAB2_LIB.BASEBOARD_FAB2(SCH_1):TP_SPI_SWITCH1_11    I75 @BASEBOARD_FAB2_LIB.BASEBOARD_FAB2(SCH_1):PAGE154
    10 TP_SPI_SWITCH1_10 @BASEBOARD_FAB2_LIB.BASEBOARD_FAB2(SCH_1):TP_SPI_SWITCH1_10    I75 @BASEBOARD_FAB2_LIB.BASEBOARD_FAB2(SCH_1):PAGE154
    14 TP_SPI_SWITCH1_14 @BASEBOARD_FAB2_LIB.BASEBOARD_FAB2(SCH_1):TP_SPI_SWITCH1_14    I75 @BASEBOARD_FAB2_LIB.BASEBOARD_FAB2(SCH_1):PAGE154
    13 TP_SPI_SWITCH1_13 @BASEBOARD_FAB2_LIB.BASEBOARD_FAB2(SCH_1):TP_SPI_SWITCH1_13    I75 @BASEBOARD_FAB2_LIB.BASEBOARD_FAB2(SCH_1):PAGE154

U2T2 TTL1G32_A_SOT-74LVC1G32,IC,E60B
     1 FM_BACKUP_BIOS_SEL_N @BASEBOARD_FAB2_LIB.BASEBOARD_FAB2(SCH_1):FM_BACKUP_BIOS_SEL_N   I100 @BASEBOARD_FAB2_LIB.BASEBOARD_FAB2(SCH_1):PAGE154
     2 SPI_SWITCH_CS0_N @BASEBOARD_FAB2_LIB.BASEBOARD_FAB2(SCH_1):SPI_SWITCH_CS0_N   I100 @BASEBOARD_FAB2_LIB.BASEBOARD_FAB2(SCH_1):PAGE154
     4 SPI_CS0_SECONDARY_N @BASEBOARD_FAB2_LIB.BASEBOARD_FAB2(SCH_1):SPI_CS0_SECONDARY_N   I100 @BASEBOARD_FAB2_LIB.BASEBOARD_FAB2(SCH_1):PAGE154

U2T3 TTL1G32_A_SOT-74LVC1G32,IC,E60B
     1 FM_DUAL_BIOS_SEL_N @BASEBOARD_FAB2_LIB.BASEBOARD_FAB2(SCH_1):FM_DUAL_BIOS_SEL_N    I99 @BASEBOARD_FAB2_LIB.BASEBOARD_FAB2(SCH_1):PAGE154
     2 SPI_SWITCH_CS0_N @BASEBOARD_FAB2_LIB.BASEBOARD_FAB2(SCH_1):SPI_SWITCH_CS0_N    I99 @BASEBOARD_FAB2_LIB.BASEBOARD_FAB2(SCH_1):PAGE154
     4 SPI_CS0_PRIMARY_N @BASEBOARD_FAB2_LIB.BASEBOARD_FAB2(SCH_1):SPI_CS0_PRIMARY_N    I99 @BASEBOARD_FAB2_LIB.BASEBOARD_FAB2(SCH_1):PAGE154

U2T4 GTL2014_SM-IC,D66151-001
    13 FM_CPU1_PROCHOT_LVT3_R_N @BASEBOARD_FAB2_LIB.BASEBOARD_FAB2(SCH_1):FM_CPU1_PROCHOT_LVT3_R_N    I30 @BASEBOARD_FAB2_LIB.BASEBOARD_FAB2(SCH_1):PAGE93
    12 FM_CPU0_PROCHOT_LVT3_R_N @BASEBOARD_FAB2_LIB.BASEBOARD_FAB2(SCH_1):FM_CPU0_PROCHOT_LVT3_R_N    I30 @BASEBOARD_FAB2_LIB.BASEBOARD_FAB2(SCH_1):PAGE93
    10 FM_CPU_ERR1_LVT3_R_N @BASEBOARD_FAB2_LIB.BASEBOARD_FAB2(SCH_1):FM_CPU_ERR1_LVT3_R_N    I30 @BASEBOARD_FAB2_LIB.BASEBOARD_FAB2(SCH_1):PAGE93
     9 FM_CPU_ERR0_LVT3_R_N @BASEBOARD_FAB2_LIB.BASEBOARD_FAB2(SCH_1):FM_CPU_ERR0_LVT3_R_N    I30 @BASEBOARD_FAB2_LIB.BASEBOARD_FAB2(SCH_1):PAGE93
     2 H_CPU1_PROCHOT_G_R_N @BASEBOARD_FAB2_LIB.BASEBOARD_FAB2(SCH_1):H_CPU1_PROCHOT_G_R_N    I30 @BASEBOARD_FAB2_LIB.BASEBOARD_FAB2(SCH_1):PAGE93
     3 H_CPU0_PROCHOT_G_R_N @BASEBOARD_FAB2_LIB.BASEBOARD_FAB2(SCH_1):H_CPU0_PROCHOT_G_R_N    I30 @BASEBOARD_FAB2_LIB.BASEBOARD_FAB2(SCH_1):PAGE93
     5 H_CPU_ERR1_GTL_N @BASEBOARD_FAB2_LIB.BASEBOARD_FAB2(SCH_1):H_CPU_ERR1_GTL_N    I30 @BASEBOARD_FAB2_LIB.BASEBOARD_FAB2(SCH_1):PAGE93
     6 H_CPU_ERR0_GTL_N @BASEBOARD_FAB2_LIB.BASEBOARD_FAB2(SCH_1):H_CPU_ERR0_GTL_N    I30 @BASEBOARD_FAB2_LIB.BASEBOARD_FAB2(SCH_1):PAGE93
     1 PD_GTL2104_4_DIR @BASEBOARD_FAB2_LIB.BASEBOARD_FAB2(SCH_1):PD_GTL2104_4_DIR    I30 @BASEBOARD_FAB2_LIB.BASEBOARD_FAB2(SCH_1):PAGE93
    11    GND @BASEBOARD_FAB2_LIB.BASEBOARD_FAB2(SCH_1):GND    I30 @BASEBOARD_FAB2_LIB.BASEBOARD_FAB2(SCH_1):PAGE93
     8    GND @BASEBOARD_FAB2_LIB.BASEBOARD_FAB2(SCH_1):GND    I30 @BASEBOARD_FAB2_LIB.BASEBOARD_FAB2(SCH_1):PAGE93
     7    GND @BASEBOARD_FAB2_LIB.BASEBOARD_FAB2(SCH_1):GND    I30 @BASEBOARD_FAB2_LIB.BASEBOARD_FAB2(SCH_1):PAGE93
    14   P3V3 @BASEBOARD_FAB2_LIB.BASEBOARD_FAB2(SCH_1):P3V3    I30 @BASEBOARD_FAB2_LIB.BASEBOARD_FAB2(SCH_1):PAGE93
     4 P0V7_GTL2104_5_VREF @BASEBOARD_FAB2_LIB.BASEBOARD_FAB2(SCH_1):P0V7_GTL2104_5_VREF    I30 @BASEBOARD_FAB2_LIB.BASEBOARD_FAB2(SCH_1):PAGE93

U3B1 PCA9617_SSOP-IC,G81764-001-GNDA
     5 TP_SMB_DDR_KLM_EN @BASEBOARD_FAB2_LIB.BASEBOARD_FAB2(SCH_1):TP_SMB_DDR_KLM_EN    I75 @BASEBOARD_FAB2_LIB.BASEBOARD_FAB2(SCH_1):PAGE99
     2 SMB_DDR_KLM_SCL_G @BASEBOARD_FAB2_LIB.BASEBOARD_FAB2(SCH_1):SMB_DDR_KLM_SCL_G    I75 @BASEBOARD_FAB2_LIB.BASEBOARD_FAB2(SCH_1):PAGE99
     7 SMB_DDR_KLM_VPP_SCL_R @BASEBOARD_FAB2_LIB.BASEBOARD_FAB2(SCH_1):SMB_DDR_KLM_VPP_SCL_R    I75 @BASEBOARD_FAB2_LIB.BASEBOARD_FAB2(SCH_1):PAGE99
     3 SMB_DDR_KLM_SDA_G @BASEBOARD_FAB2_LIB.BASEBOARD_FAB2(SCH_1):SMB_DDR_KLM_SDA_G    I75 @BASEBOARD_FAB2_LIB.BASEBOARD_FAB2(SCH_1):PAGE99
     6 SMB_DDR_KLM_VPP_SDA_R @BASEBOARD_FAB2_LIB.BASEBOARD_FAB2(SCH_1):SMB_DDR_KLM_VPP_SDA_R    I75 @BASEBOARD_FAB2_LIB.BASEBOARD_FAB2(SCH_1):PAGE99
     1 PVCCIO_CPU1 @BASEBOARD_FAB2_LIB.BASEBOARD_FAB2(SCH_1):PVCCIO_CPU1    I75 @BASEBOARD_FAB2_LIB.BASEBOARD_FAB2(SCH_1):PAGE99
     8 PVPP_KLM @BASEBOARD_FAB2_LIB.BASEBOARD_FAB2(SCH_1):PVPP_KLM    I75 @BASEBOARD_FAB2_LIB.BASEBOARD_FAB2(SCH_1):PAGE99

U3P1 GTL2014_SM-IC,D66151-001
    13 PWRGD_DRAMPWRGD @BASEBOARD_FAB2_LIB.BASEBOARD_FAB2(SCH_1):PWRGD_DRAMPWRGD    I42 @BASEBOARD_FAB2_LIB.BASEBOARD_FAB2(SCH_1):PAGE96
    12 PWRGD_DRAMPWRGD @BASEBOARD_FAB2_LIB.BASEBOARD_FAB2(SCH_1):PWRGD_DRAMPWRGD    I42 @BASEBOARD_FAB2_LIB.BASEBOARD_FAB2(SCH_1):PAGE96
    10 RST_CPU0_LVC3_N @BASEBOARD_FAB2_LIB.BASEBOARD_FAB2(SCH_1):RST_CPU0_LVC3_N    I42 @BASEBOARD_FAB2_LIB.BASEBOARD_FAB2(SCH_1):PAGE96
     9 PWRGD_CPU0_LVC3 @BASEBOARD_FAB2_LIB.BASEBOARD_FAB2(SCH_1):PWRGD_CPU0_LVC3    I42 @BASEBOARD_FAB2_LIB.BASEBOARD_FAB2(SCH_1):PAGE96
     2 PWRGD_CPU0_DRAMPWROK_DEF_G @BASEBOARD_FAB2_LIB.BASEBOARD_FAB2(SCH_1):PWRGD_CPU0_DRAMPWROK_DEF_G    I42 @BASEBOARD_FAB2_LIB.BASEBOARD_FAB2(SCH_1):PAGE96
     3 PWRGD_CPU0_DRAMPWROK_ABC_G @BASEBOARD_FAB2_LIB.BASEBOARD_FAB2(SCH_1):PWRGD_CPU0_DRAMPWROK_ABC_G    I42 @BASEBOARD_FAB2_LIB.BASEBOARD_FAB2(SCH_1):PAGE96
     5 RST_CPU0_G_N @BASEBOARD_FAB2_LIB.BASEBOARD_FAB2(SCH_1):RST_CPU0_G_N    I42 @BASEBOARD_FAB2_LIB.BASEBOARD_FAB2(SCH_1):PAGE96
     6 PWRGD_CPU0_G @BASEBOARD_FAB2_LIB.BASEBOARD_FAB2(SCH_1):PWRGD_CPU0_G    I42 @BASEBOARD_FAB2_LIB.BASEBOARD_FAB2(SCH_1):PAGE96
     1 PU_GTL2014_1_DIR @BASEBOARD_FAB2_LIB.BASEBOARD_FAB2(SCH_1):PU_GTL2014_1_DIR    I42 @BASEBOARD_FAB2_LIB.BASEBOARD_FAB2(SCH_1):PAGE96
    11    GND @BASEBOARD_FAB2_LIB.BASEBOARD_FAB2(SCH_1):GND    I42 @BASEBOARD_FAB2_LIB.BASEBOARD_FAB2(SCH_1):PAGE96
     8    GND @BASEBOARD_FAB2_LIB.BASEBOARD_FAB2(SCH_1):GND    I42 @BASEBOARD_FAB2_LIB.BASEBOARD_FAB2(SCH_1):PAGE96
     7    GND @BASEBOARD_FAB2_LIB.BASEBOARD_FAB2(SCH_1):GND    I42 @BASEBOARD_FAB2_LIB.BASEBOARD_FAB2(SCH_1):PAGE96
    14 P3V3_STBY @BASEBOARD_FAB2_LIB.BASEBOARD_FAB2(SCH_1):P3V3_STBY    I42 @BASEBOARD_FAB2_LIB.BASEBOARD_FAB2(SCH_1):PAGE96
     4 PD_GTL2014_1_VREF @BASEBOARD_FAB2_LIB.BASEBOARD_FAB2(SCH_1):PD_GTL2014_1_VREF    I42 @BASEBOARD_FAB2_LIB.BASEBOARD_FAB2(SCH_1):PAGE96

U3P2 GTL2014_SM-IC,D66151-001
    13 PWRGD_CPUPWRGD_R1 @BASEBOARD_FAB2_LIB.BASEBOARD_FAB2(SCH_1):PWRGD_CPUPWRGD_R1     I1 @BASEBOARD_FAB2_LIB.BASEBOARD_FAB2(SCH_1):PAGE92
    12 FM_CPU1_FIVR_FAULT_R_LVT3 @BASEBOARD_FAB2_LIB.BASEBOARD_FAB2(SCH_1):FM_CPU1_FIVR_FAULT_R_LVT3     I1 @BASEBOARD_FAB2_LIB.BASEBOARD_FAB2(SCH_1):PAGE92
    10 FM_CPU_CATERR_LVT3_R2_N @BASEBOARD_FAB2_LIB.BASEBOARD_FAB2(SCH_1):FM_CPU_CATERR_LVT3_R2_N     I1 @BASEBOARD_FAB2_LIB.BASEBOARD_FAB2(SCH_1):PAGE92
     9 FM_CPU1_THERMTRIP_LVT3_R_N @BASEBOARD_FAB2_LIB.BASEBOARD_FAB2(SCH_1):FM_CPU1_THERMTRIP_LVT3_R_N     I1 @BASEBOARD_FAB2_LIB.BASEBOARD_FAB2(SCH_1):PAGE92
     2 PWRGD_CPUPWRGD_GTL @BASEBOARD_FAB2_LIB.BASEBOARD_FAB2(SCH_1):PWRGD_CPUPWRGD_GTL     I1 @BASEBOARD_FAB2_LIB.BASEBOARD_FAB2(SCH_1):PAGE92
     3 H_CPU1_FIVR_FAULT_G @BASEBOARD_FAB2_LIB.BASEBOARD_FAB2(SCH_1):H_CPU1_FIVR_FAULT_G     I1 @BASEBOARD_FAB2_LIB.BASEBOARD_FAB2(SCH_1):PAGE92
     5 H_CPU_CATERR_G_N @BASEBOARD_FAB2_LIB.BASEBOARD_FAB2(SCH_1):H_CPU_CATERR_G_N     I1 @BASEBOARD_FAB2_LIB.BASEBOARD_FAB2(SCH_1):PAGE92
     6 H_CPU1_THERMTRIP_G_N @BASEBOARD_FAB2_LIB.BASEBOARD_FAB2(SCH_1):H_CPU1_THERMTRIP_G_N     I1 @BASEBOARD_FAB2_LIB.BASEBOARD_FAB2(SCH_1):PAGE92
     1 PD_GTL2104_DIR_1 @BASEBOARD_FAB2_LIB.BASEBOARD_FAB2(SCH_1):PD_GTL2104_DIR_1     I1 @BASEBOARD_FAB2_LIB.BASEBOARD_FAB2(SCH_1):PAGE92
    11    GND @BASEBOARD_FAB2_LIB.BASEBOARD_FAB2(SCH_1):GND     I1 @BASEBOARD_FAB2_LIB.BASEBOARD_FAB2(SCH_1):PAGE92
     8    GND @BASEBOARD_FAB2_LIB.BASEBOARD_FAB2(SCH_1):GND     I1 @BASEBOARD_FAB2_LIB.BASEBOARD_FAB2(SCH_1):PAGE92
     7    GND @BASEBOARD_FAB2_LIB.BASEBOARD_FAB2(SCH_1):GND     I1 @BASEBOARD_FAB2_LIB.BASEBOARD_FAB2(SCH_1):PAGE92
    14   P3V3 @BASEBOARD_FAB2_LIB.BASEBOARD_FAB2(SCH_1):P3V3     I1 @BASEBOARD_FAB2_LIB.BASEBOARD_FAB2(SCH_1):PAGE92
     4 P0V7_GTL2104_VREF_1 @BASEBOARD_FAB2_LIB.BASEBOARD_FAB2(SCH_1):P0V7_GTL2104_VREF_1     I1 @BASEBOARD_FAB2_LIB.BASEBOARD_FAB2(SCH_1):PAGE92

U3T1 W25Q256FVFIG-GP_MEMORY-G4-W25QA
     1 PU_BIOS_SPI_HOLD1_N @BASEBOARD_FAB2_LIB.BASEBOARD_FAB2(SCH_1):PU_BIOS_SPI_HOLD1_N   I185 @BASEBOARD_FAB2_LIB.BASEBOARD_FAB2(SCH_1):PAGE153
     2 P3V3_STBY @BASEBOARD_FAB2_LIB.BASEBOARD_FAB2(SCH_1):P3V3_STBY   I185 @BASEBOARD_FAB2_LIB.BASEBOARD_FAB2(SCH_1):PAGE153
     3 PU_SPI1_RST @BASEBOARD_FAB2_LIB.BASEBOARD_FAB2(SCH_1):PU_SPI1_RST   I185 @BASEBOARD_FAB2_LIB.BASEBOARD_FAB2(SCH_1):PAGE153
     4 TP_SPI_1_6 @BASEBOARD_FAB2_LIB.BASEBOARD_FAB2(SCH_1):TP_SPI_1_6   I185 @BASEBOARD_FAB2_LIB.BASEBOARD_FAB2(SCH_1):PAGE153
     5 TP_SPI_1_5 @BASEBOARD_FAB2_LIB.BASEBOARD_FAB2(SCH_1):TP_SPI_1_5   I185 @BASEBOARD_FAB2_LIB.BASEBOARD_FAB2(SCH_1):PAGE153
     6 TP_SPI_1_4 @BASEBOARD_FAB2_LIB.BASEBOARD_FAB2(SCH_1):TP_SPI_1_4   I185 @BASEBOARD_FAB2_LIB.BASEBOARD_FAB2(SCH_1):PAGE153
     7 SPI_CS0_SECONDARY_R_N @BASEBOARD_FAB2_LIB.BASEBOARD_FAB2(SCH_1):SPI_CS0_SECONDARY_R_N   I185 @BASEBOARD_FAB2_LIB.BASEBOARD_FAB2(SCH_1):PAGE153
     8 SPI_MISO_R1 @BASEBOARD_FAB2_LIB.BASEBOARD_FAB2(SCH_1):SPI_MISO_R1   I185 @BASEBOARD_FAB2_LIB.BASEBOARD_FAB2(SCH_1):PAGE153
     9 PU_BIOS_SPI_WP1_N @BASEBOARD_FAB2_LIB.BASEBOARD_FAB2(SCH_1):PU_BIOS_SPI_WP1_N   I185 @BASEBOARD_FAB2_LIB.BASEBOARD_FAB2(SCH_1):PAGE153
    10    GND @BASEBOARD_FAB2_LIB.BASEBOARD_FAB2(SCH_1):GND   I185 @BASEBOARD_FAB2_LIB.BASEBOARD_FAB2(SCH_1):PAGE153
    11 TP_SPI_1_3 @BASEBOARD_FAB2_LIB.BASEBOARD_FAB2(SCH_1):TP_SPI_1_3   I185 @BASEBOARD_FAB2_LIB.BASEBOARD_FAB2(SCH_1):PAGE153
    12 TP_SPI_1_2 @BASEBOARD_FAB2_LIB.BASEBOARD_FAB2(SCH_1):TP_SPI_1_2   I185 @BASEBOARD_FAB2_LIB.BASEBOARD_FAB2(SCH_1):PAGE153
    13 TP_SPI_1_1 @BASEBOARD_FAB2_LIB.BASEBOARD_FAB2(SCH_1):TP_SPI_1_1   I185 @BASEBOARD_FAB2_LIB.BASEBOARD_FAB2(SCH_1):PAGE153
    14 TP_SPI_1_0 @BASEBOARD_FAB2_LIB.BASEBOARD_FAB2(SCH_1):TP_SPI_1_0   I185 @BASEBOARD_FAB2_LIB.BASEBOARD_FAB2(SCH_1):PAGE153
    15 SPI_SWITCH_MOSI_R1 @BASEBOARD_FAB2_LIB.BASEBOARD_FAB2(SCH_1):SPI_SWITCH_MOSI_R1   I185 @BASEBOARD_FAB2_LIB.BASEBOARD_FAB2(SCH_1):PAGE153
    16 SPI_CLK_R1 @BASEBOARD_FAB2_LIB.BASEBOARD_FAB2(SCH_1):SPI_CLK_R1   I185 @BASEBOARD_FAB2_LIB.BASEBOARD_FAB2(SCH_1):PAGE153

U4C2 GTL2014_SM-IC,D66151-001
    13 PWRGD_DRAMPWRGD @BASEBOARD_FAB2_LIB.BASEBOARD_FAB2(SCH_1):PWRGD_DRAMPWRGD    I46 @BASEBOARD_FAB2_LIB.BASEBOARD_FAB2(SCH_1):PAGE96
    12 PWRGD_DRAMPWRGD @BASEBOARD_FAB2_LIB.BASEBOARD_FAB2(SCH_1):PWRGD_DRAMPWRGD    I46 @BASEBOARD_FAB2_LIB.BASEBOARD_FAB2(SCH_1):PAGE96
    10 RST_CPU1_LVC3_N @BASEBOARD_FAB2_LIB.BASEBOARD_FAB2(SCH_1):RST_CPU1_LVC3_N    I46 @BASEBOARD_FAB2_LIB.BASEBOARD_FAB2(SCH_1):PAGE96
     9 PWRGD_CPU1_LVC3 @BASEBOARD_FAB2_LIB.BASEBOARD_FAB2(SCH_1):PWRGD_CPU1_LVC3    I46 @BASEBOARD_FAB2_LIB.BASEBOARD_FAB2(SCH_1):PAGE96
     2 PWRGD_CPU1_DRAMPWROK_KLM_G @BASEBOARD_FAB2_LIB.BASEBOARD_FAB2(SCH_1):PWRGD_CPU1_DRAMPWROK_KLM_G    I46 @BASEBOARD_FAB2_LIB.BASEBOARD_FAB2(SCH_1):PAGE96
     3 PWRGD_CPU1_DRAMPWROK_GHJ_G @BASEBOARD_FAB2_LIB.BASEBOARD_FAB2(SCH_1):PWRGD_CPU1_DRAMPWROK_GHJ_G    I46 @BASEBOARD_FAB2_LIB.BASEBOARD_FAB2(SCH_1):PAGE96
     5 RST_CPU1_G_N @BASEBOARD_FAB2_LIB.BASEBOARD_FAB2(SCH_1):RST_CPU1_G_N    I46 @BASEBOARD_FAB2_LIB.BASEBOARD_FAB2(SCH_1):PAGE96
     6 PWRGD_CPU1_G @BASEBOARD_FAB2_LIB.BASEBOARD_FAB2(SCH_1):PWRGD_CPU1_G    I46 @BASEBOARD_FAB2_LIB.BASEBOARD_FAB2(SCH_1):PAGE96
     1 PU_GTL2014_2_DIR @BASEBOARD_FAB2_LIB.BASEBOARD_FAB2(SCH_1):PU_GTL2014_2_DIR    I46 @BASEBOARD_FAB2_LIB.BASEBOARD_FAB2(SCH_1):PAGE96
    11    GND @BASEBOARD_FAB2_LIB.BASEBOARD_FAB2(SCH_1):GND    I46 @BASEBOARD_FAB2_LIB.BASEBOARD_FAB2(SCH_1):PAGE96
     8    GND @BASEBOARD_FAB2_LIB.BASEBOARD_FAB2(SCH_1):GND    I46 @BASEBOARD_FAB2_LIB.BASEBOARD_FAB2(SCH_1):PAGE96
     7    GND @BASEBOARD_FAB2_LIB.BASEBOARD_FAB2(SCH_1):GND    I46 @BASEBOARD_FAB2_LIB.BASEBOARD_FAB2(SCH_1):PAGE96
    14 P3V3_STBY @BASEBOARD_FAB2_LIB.BASEBOARD_FAB2(SCH_1):P3V3_STBY    I46 @BASEBOARD_FAB2_LIB.BASEBOARD_FAB2(SCH_1):PAGE96
     4 PD_GTL2014_2_VREF @BASEBOARD_FAB2_LIB.BASEBOARD_FAB2(SCH_1):PD_GTL2014_2_VREF    I46 @BASEBOARD_FAB2_LIB.BASEBOARD_FAB2(SCH_1):PAGE96

U4G1 PCA9617_SSOP-IC,G81764-001-GNDA
     5 TP_SMB_DDR_GHJ_EN @BASEBOARD_FAB2_LIB.BASEBOARD_FAB2(SCH_1):TP_SMB_DDR_GHJ_EN    I63 @BASEBOARD_FAB2_LIB.BASEBOARD_FAB2(SCH_1):PAGE99
     2 SMB_DDR_GHJ_SCL_G @BASEBOARD_FAB2_LIB.BASEBOARD_FAB2(SCH_1):SMB_DDR_GHJ_SCL_G    I63 @BASEBOARD_FAB2_LIB.BASEBOARD_FAB2(SCH_1):PAGE99
     7 SMB_DDR_GHJ_VPP_SCL_R @BASEBOARD_FAB2_LIB.BASEBOARD_FAB2(SCH_1):SMB_DDR_GHJ_VPP_SCL_R    I63 @BASEBOARD_FAB2_LIB.BASEBOARD_FAB2(SCH_1):PAGE99
     3 SMB_DDR_GHJ_SDA_G @BASEBOARD_FAB2_LIB.BASEBOARD_FAB2(SCH_1):SMB_DDR_GHJ_SDA_G    I63 @BASEBOARD_FAB2_LIB.BASEBOARD_FAB2(SCH_1):PAGE99
     6 SMB_DDR_GHJ_VPP_SDA_R @BASEBOARD_FAB2_LIB.BASEBOARD_FAB2(SCH_1):SMB_DDR_GHJ_VPP_SDA_R    I63 @BASEBOARD_FAB2_LIB.BASEBOARD_FAB2(SCH_1):PAGE99
     1 PVCCIO_CPU1 @BASEBOARD_FAB2_LIB.BASEBOARD_FAB2(SCH_1):PVCCIO_CPU1    I63 @BASEBOARD_FAB2_LIB.BASEBOARD_FAB2(SCH_1):PAGE99
     8 PVPP_GHJ @BASEBOARD_FAB2_LIB.BASEBOARD_FAB2(SCH_1):PVPP_GHJ    I63 @BASEBOARD_FAB2_LIB.BASEBOARD_FAB2(SCH_1):PAGE99

U4R1 74CBTLV1G125_SMLF-IC,C88177-00A
     4 JTAG_MCP_CPU0_TDI_R @BASEBOARD_FAB2_LIB.BASEBOARD_FAB2(SCH_1):JTAG_MCP_CPU0_TDI_R   I206 @BASEBOARD_FAB2_LIB.BASEBOARD_FAB2(SCH_1):PAGE113
     1 FM_CPU0_PKGID1 @BASEBOARD_FAB2_LIB.BASEBOARD_FAB2(SCH_1):FM_CPU0_PKGID1   I206 @BASEBOARD_FAB2_LIB.BASEBOARD_FAB2(SCH_1):PAGE113
     2 P1V8_MCP_CPU0 @BASEBOARD_FAB2_LIB.BASEBOARD_FAB2(SCH_1):P1V8_MCP_CPU0   I206 @BASEBOARD_FAB2_LIB.BASEBOARD_FAB2(SCH_1):PAGE113

U5D1 SKX_EXT_B_BGA1-IC,TBD
  AU24 CLK_100M_CPU0_BCLK0_DN @BASEBOARD_FAB2_LIB.BASEBOARD_FAB2(SCH_1):CLK_100M_CPU0_BCLK0_DN   I259 @BASEBOARD_FAB2_LIB.BASEBOARD_FAB2(SCH_1):PAGE21
  AW24 CLK_100M_CPU0_BCLK0_DP @BASEBOARD_FAB2_LIB.BASEBOARD_FAB2(SCH_1):CLK_100M_CPU0_BCLK0_DP   I259 @BASEBOARD_FAB2_LIB.BASEBOARD_FAB2(SCH_1):PAGE21
  CR26 CLK_100M_CPU0_BCLK1_DN @BASEBOARD_FAB2_LIB.BASEBOARD_FAB2(SCH_1):CLK_100M_CPU0_BCLK1_DN   I259 @BASEBOARD_FAB2_LIB.BASEBOARD_FAB2(SCH_1):PAGE21
  CP27 CLK_100M_CPU0_BCLK1_DP @BASEBOARD_FAB2_LIB.BASEBOARD_FAB2(SCH_1):CLK_100M_CPU0_BCLK1_DP   I259 @BASEBOARD_FAB2_LIB.BASEBOARD_FAB2(SCH_1):PAGE21
  CT25 CLK_100M_CPU0_BCLK2_DN @BASEBOARD_FAB2_LIB.BASEBOARD_FAB2(SCH_1):CLK_100M_CPU0_BCLK2_DN   I259 @BASEBOARD_FAB2_LIB.BASEBOARD_FAB2(SCH_1):PAGE21
  CU26 CLK_100M_CPU0_BCLK2_DP @BASEBOARD_FAB2_LIB.BASEBOARD_FAB2(SCH_1):CLK_100M_CPU0_BCLK2_DP   I259 @BASEBOARD_FAB2_LIB.BASEBOARD_FAB2(SCH_1):PAGE21
  BA20 PD_CPU0_BIST_ENABLE @BASEBOARD_FAB2_LIB.BASEBOARD_FAB2(SCH_1):PD_CPU0_BIST_ENABLE   I259 @BASEBOARD_FAB2_LIB.BASEBOARD_FAB2(SCH_1):PAGE21
  BD23 H_CPU0_BMCINIT @BASEBOARD_FAB2_LIB.BASEBOARD_FAB2(SCH_1):H_CPU0_BMCINIT   I259 @BASEBOARD_FAB2_LIB.BASEBOARD_FAB2(SCH_1):PAGE21
  AC12 XDP_CPU_OBSFN_B1_MBP7_N @BASEBOARD_FAB2_LIB.BASEBOARD_FAB2(SCH_1):XDP_CPU_OBSFN_B1_MBP7_N   I259 @BASEBOARD_FAB2_LIB.BASEBOARD_FAB2(SCH_1):PAGE21
  AE12 XDP_CPU_OBSFN_B0_MBP6_N @BASEBOARD_FAB2_LIB.BASEBOARD_FAB2(SCH_1):XDP_CPU_OBSFN_B0_MBP6_N   I259 @BASEBOARD_FAB2_LIB.BASEBOARD_FAB2(SCH_1):PAGE21
   Y11 TP_XDP_CPU0_OBSDATA_A3_MBP5_N @BASEBOARD_FAB2_LIB.BASEBOARD_FAB2(SCH_1):TP_XDP_CPU0_OBSDATA_A3_MBP5_N   I259 @BASEBOARD_FAB2_LIB.BASEBOARD_FAB2(SCH_1):PAGE21
  AA12 TP_XDP_CPU0_OBSDATA_A2_MBP4_N @BASEBOARD_FAB2_LIB.BASEBOARD_FAB2(SCH_1):TP_XDP_CPU0_OBSDATA_A2_MBP4_N   I259 @BASEBOARD_FAB2_LIB.BASEBOARD_FAB2(SCH_1):PAGE21
  AF11 TP_XDP_CPU0_OBSDATA_A1_MBP3_N @BASEBOARD_FAB2_LIB.BASEBOARD_FAB2(SCH_1):TP_XDP_CPU0_OBSDATA_A1_MBP3_N   I259 @BASEBOARD_FAB2_LIB.BASEBOARD_FAB2(SCH_1):PAGE21
  AG10 TP_XDP_CPU0_OBSDATA_A0_MBP2_N @BASEBOARD_FAB2_LIB.BASEBOARD_FAB2(SCH_1):TP_XDP_CPU0_OBSDATA_A0_MBP2_N   I259 @BASEBOARD_FAB2_LIB.BASEBOARD_FAB2(SCH_1):PAGE21
  AH11 XDP_CPU_MBP1_N @BASEBOARD_FAB2_LIB.BASEBOARD_FAB2(SCH_1):XDP_CPU_MBP1_N   I259 @BASEBOARD_FAB2_LIB.BASEBOARD_FAB2(SCH_1):PAGE21
  AJ10 XDP_CPU_MBP0_N @BASEBOARD_FAB2_LIB.BASEBOARD_FAB2(SCH_1):XDP_CPU_MBP0_N   I259 @BASEBOARD_FAB2_LIB.BASEBOARD_FAB2(SCH_1):PAGE21
  AL14 H_CPU0_CATERR_G_N @BASEBOARD_FAB2_LIB.BASEBOARD_FAB2(SCH_1):H_CPU0_CATERR_G_N   I259 @BASEBOARD_FAB2_LIB.BASEBOARD_FAB2(SCH_1):PAGE21
  AN30 PWRGD_CPU0_DRAMPWROK_ABC_G @BASEBOARD_FAB2_LIB.BASEBOARD_FAB2(SCH_1):PWRGD_CPU0_DRAMPWROK_ABC_G   I259 @BASEBOARD_FAB2_LIB.BASEBOARD_FAB2(SCH_1):PAGE21
  AC42 A_CPU0_ABC_RCOMP2 @BASEBOARD_FAB2_LIB.BASEBOARD_FAB2(SCH_1):A_CPU0_ABC_RCOMP2   I259 @BASEBOARD_FAB2_LIB.BASEBOARD_FAB2(SCH_1):PAGE21
  AB43 A_CPU0_ABC_RCOMP1 @BASEBOARD_FAB2_LIB.BASEBOARD_FAB2(SCH_1):A_CPU0_ABC_RCOMP1   I259 @BASEBOARD_FAB2_LIB.BASEBOARD_FAB2(SCH_1):PAGE21
   Y43 A_CPU0_ABC_RCOMP0 @BASEBOARD_FAB2_LIB.BASEBOARD_FAB2(SCH_1):A_CPU0_ABC_RCOMP0   I259 @BASEBOARD_FAB2_LIB.BASEBOARD_FAB2(SCH_1):PAGE21
   U64 M_ABC_RST_N @BASEBOARD_FAB2_LIB.BASEBOARD_FAB2(SCH_1):M_ABC_RST_N   I259 @BASEBOARD_FAB2_LIB.BASEBOARD_FAB2(SCH_1):PAGE21
  AJ18 SMB_DDR_ABC_SCL_G_R @BASEBOARD_FAB2_LIB.BASEBOARD_FAB2(SCH_1):SMB_DDR_ABC_SCL_G_R   I259 @BASEBOARD_FAB2_LIB.BASEBOARD_FAB2(SCH_1):PAGE21
  AF17 SMB_DDR_ABC_SDA_G_R @BASEBOARD_FAB2_LIB.BASEBOARD_FAB2(SCH_1):SMB_DDR_ABC_SDA_G_R   I259 @BASEBOARD_FAB2_LIB.BASEBOARD_FAB2(SCH_1):PAGE21
  AJ64 M_A_CPU_VREF @BASEBOARD_FAB2_LIB.BASEBOARD_FAB2(SCH_1):M_A_CPU_VREF   I259 @BASEBOARD_FAB2_LIB.BASEBOARD_FAB2(SCH_1):PAGE21
  AK63 M_B_CPU_VREF @BASEBOARD_FAB2_LIB.BASEBOARD_FAB2(SCH_1):M_B_CPU_VREF   I259 @BASEBOARD_FAB2_LIB.BASEBOARD_FAB2(SCH_1):PAGE21
  AH63 M_C_CPU_VREF @BASEBOARD_FAB2_LIB.BASEBOARD_FAB2(SCH_1):M_C_CPU_VREF   I259 @BASEBOARD_FAB2_LIB.BASEBOARD_FAB2(SCH_1):PAGE21
  CR28 PWRGD_CPU0_DRAMPWROK_DEF_G @BASEBOARD_FAB2_LIB.BASEBOARD_FAB2(SCH_1):PWRGD_CPU0_DRAMPWROK_DEF_G   I259 @BASEBOARD_FAB2_LIB.BASEBOARD_FAB2(SCH_1):PAGE21
  DD49 A_CPU0_DEF_RCOMP2 @BASEBOARD_FAB2_LIB.BASEBOARD_FAB2(SCH_1):A_CPU0_DEF_RCOMP2   I259 @BASEBOARD_FAB2_LIB.BASEBOARD_FAB2(SCH_1):PAGE21
  DD47 A_CPU0_DEF_RCOMP1 @BASEBOARD_FAB2_LIB.BASEBOARD_FAB2(SCH_1):A_CPU0_DEF_RCOMP1   I259 @BASEBOARD_FAB2_LIB.BASEBOARD_FAB2(SCH_1):PAGE21
  DC48 A_CPU0_DEF_RCOMP0 @BASEBOARD_FAB2_LIB.BASEBOARD_FAB2(SCH_1):A_CPU0_DEF_RCOMP0   I259 @BASEBOARD_FAB2_LIB.BASEBOARD_FAB2(SCH_1):PAGE21
  DV63 M_DEF_RST_N @BASEBOARD_FAB2_LIB.BASEBOARD_FAB2(SCH_1):M_DEF_RST_N   I259 @BASEBOARD_FAB2_LIB.BASEBOARD_FAB2(SCH_1):PAGE21
  AE18 SMB_DDR_DEF_SCL_G_R @BASEBOARD_FAB2_LIB.BASEBOARD_FAB2(SCH_1):SMB_DDR_DEF_SCL_G_R   I259 @BASEBOARD_FAB2_LIB.BASEBOARD_FAB2(SCH_1):PAGE21
  AD17 SMB_DDR_DEF_SDA_G_R @BASEBOARD_FAB2_LIB.BASEBOARD_FAB2(SCH_1):SMB_DDR_DEF_SDA_G_R   I259 @BASEBOARD_FAB2_LIB.BASEBOARD_FAB2(SCH_1):PAGE21
  CP61 M_D_CPU_VREF @BASEBOARD_FAB2_LIB.BASEBOARD_FAB2(SCH_1):M_D_CPU_VREF   I259 @BASEBOARD_FAB2_LIB.BASEBOARD_FAB2(SCH_1):PAGE21
  CT61 M_E_CPU_VREF @BASEBOARD_FAB2_LIB.BASEBOARD_FAB2(SCH_1):M_E_CPU_VREF   I259 @BASEBOARD_FAB2_LIB.BASEBOARD_FAB2(SCH_1):PAGE21
  CV61 M_F_CPU_VREF @BASEBOARD_FAB2_LIB.BASEBOARD_FAB2(SCH_1):M_F_CPU_VREF   I259 @BASEBOARD_FAB2_LIB.BASEBOARD_FAB2(SCH_1):PAGE21
  AJ14 PD_CPU0_EAR_N @BASEBOARD_FAB2_LIB.BASEBOARD_FAB2(SCH_1):PD_CPU0_EAR_N   I259 @BASEBOARD_FAB2_LIB.BASEBOARD_FAB2(SCH_1):PAGE21
  AL12 H_CPU0_ERR2_G_N @BASEBOARD_FAB2_LIB.BASEBOARD_FAB2(SCH_1):H_CPU0_ERR2_G_N   I259 @BASEBOARD_FAB2_LIB.BASEBOARD_FAB2(SCH_1):PAGE21
  AK11 H_CPU0_ERR1_G_N @BASEBOARD_FAB2_LIB.BASEBOARD_FAB2(SCH_1):H_CPU0_ERR1_G_N   I259 @BASEBOARD_FAB2_LIB.BASEBOARD_FAB2(SCH_1):PAGE21
  AJ12 H_CPU0_ERR0_G_N @BASEBOARD_FAB2_LIB.BASEBOARD_FAB2(SCH_1):H_CPU0_ERR0_G_N   I259 @BASEBOARD_FAB2_LIB.BASEBOARD_FAB2(SCH_1):PAGE21
  AV17 PU_CPU0_FRMAGENT @BASEBOARD_FAB2_LIB.BASEBOARD_FAB2(SCH_1):PU_CPU0_FRMAGENT   I259 @BASEBOARD_FAB2_LIB.BASEBOARD_FAB2(SCH_1):PAGE21
  AE20 PU_CPU0_LEGACY_SKT @BASEBOARD_FAB2_LIB.BASEBOARD_FAB2(SCH_1):PU_CPU0_LEGACY_SKT   I259 @BASEBOARD_FAB2_LIB.BASEBOARD_FAB2(SCH_1):PAGE21
  CT31 A_CPU0_MCP01_RBIAS @BASEBOARD_FAB2_LIB.BASEBOARD_FAB2(SCH_1):A_CPU0_MCP01_RBIAS   I259 @BASEBOARD_FAB2_LIB.BASEBOARD_FAB2(SCH_1):PAGE21
  CU32 A_CPU0_MCP01_RBIAS @BASEBOARD_FAB2_LIB.BASEBOARD_FAB2(SCH_1):A_CPU0_MCP01_RBIAS   I259 @BASEBOARD_FAB2_LIB.BASEBOARD_FAB2(SCH_1):PAGE21
  AH13 H_CPU0_MEMABC_MEMHOT_G_N @BASEBOARD_FAB2_LIB.BASEBOARD_FAB2(SCH_1):H_CPU0_MEMABC_MEMHOT_G_N   I259 @BASEBOARD_FAB2_LIB.BASEBOARD_FAB2(SCH_1):PAGE21
  AF13 H_CPU0_MEMDEF_MEMHOT_G_N @BASEBOARD_FAB2_LIB.BASEBOARD_FAB2(SCH_1):H_CPU0_MEMDEF_MEMHOT_G_N   I259 @BASEBOARD_FAB2_LIB.BASEBOARD_FAB2(SCH_1):PAGE21
  AN20 H_CPU0_MSMI_G_N @BASEBOARD_FAB2_LIB.BASEBOARD_FAB2(SCH_1):H_CPU0_MSMI_G_N   I259 @BASEBOARD_FAB2_LIB.BASEBOARD_FAB2(SCH_1):PAGE21
  AP11 TP_NMI_CPU0 @BASEBOARD_FAB2_LIB.BASEBOARD_FAB2(SCH_1):TP_NMI_CPU0   I259 @BASEBOARD_FAB2_LIB.BASEBOARD_FAB2(SCH_1):PAGE21
  CL30 A_CPU0_PE012_RBIAS @BASEBOARD_FAB2_LIB.BASEBOARD_FAB2(SCH_1):A_CPU0_PE012_RBIAS   I259 @BASEBOARD_FAB2_LIB.BASEBOARD_FAB2(SCH_1):PAGE21
  CN30 A_CPU0_PE012_RBIAS @BASEBOARD_FAB2_LIB.BASEBOARD_FAB2(SCH_1):A_CPU0_PE012_RBIAS   I259 @BASEBOARD_FAB2_LIB.BASEBOARD_FAB2(SCH_1):PAGE21
  CR30 A_CPU0_PE3_RBIAS @BASEBOARD_FAB2_LIB.BASEBOARD_FAB2(SCH_1):A_CPU0_PE3_RBIAS   I259 @BASEBOARD_FAB2_LIB.BASEBOARD_FAB2(SCH_1):PAGE21
  CP29 A_CPU0_PE3_RBIAS @BASEBOARD_FAB2_LIB.BASEBOARD_FAB2(SCH_1):A_CPU0_PE3_RBIAS   I259 @BASEBOARD_FAB2_LIB.BASEBOARD_FAB2(SCH_1):PAGE21
  AU12 PECI_CPU_G @BASEBOARD_FAB2_LIB.BASEBOARD_FAB2(SCH_1):PECI_CPU_G   I259 @BASEBOARD_FAB2_LIB.BASEBOARD_FAB2(SCH_1):PAGE21
  AM19 SMB_CPU0_PE_HP_GTL_SCL @BASEBOARD_FAB2_LIB.BASEBOARD_FAB2(SCH_1):SMB_CPU0_PE_HP_GTL_SCL   I259 @BASEBOARD_FAB2_LIB.BASEBOARD_FAB2(SCH_1):PAGE21
  AL18 SMB_CPU0_PE_HP_GTL_SDA @BASEBOARD_FAB2_LIB.BASEBOARD_FAB2(SCH_1):SMB_CPU0_PE_HP_GTL_SDA   I259 @BASEBOARD_FAB2_LIB.BASEBOARD_FAB2(SCH_1):PAGE21
  CW56 PD_PIROM_CPU0_ADDR2 @BASEBOARD_FAB2_LIB.BASEBOARD_FAB2(SCH_1):PD_PIROM_CPU0_ADDR2   I259 @BASEBOARD_FAB2_LIB.BASEBOARD_FAB2(SCH_1):PAGE21
  CV57 PD_PIROM_CPU0_ADDR1 @BASEBOARD_FAB2_LIB.BASEBOARD_FAB2(SCH_1):PD_PIROM_CPU0_ADDR1   I259 @BASEBOARD_FAB2_LIB.BASEBOARD_FAB2(SCH_1):PAGE21
  CU58 PD_PIROM_CPU0_ADDR0 @BASEBOARD_FAB2_LIB.BASEBOARD_FAB2(SCH_1):PD_PIROM_CPU0_ADDR0   I259 @BASEBOARD_FAB2_LIB.BASEBOARD_FAB2(SCH_1):PAGE21
  DA72 FM_CPU0_PKGID2 @BASEBOARD_FAB2_LIB.BASEBOARD_FAB2(SCH_1):FM_CPU0_PKGID2   I259 @BASEBOARD_FAB2_LIB.BASEBOARD_FAB2(SCH_1):PAGE21
  CW72 FM_CPU0_PKGID1 @BASEBOARD_FAB2_LIB.BASEBOARD_FAB2(SCH_1):FM_CPU0_PKGID1   I259 @BASEBOARD_FAB2_LIB.BASEBOARD_FAB2(SCH_1):PAGE21
  DC72 FM_CPU0_PKGID0 @BASEBOARD_FAB2_LIB.BASEBOARD_FAB2(SCH_1):FM_CPU0_PKGID0   I259 @BASEBOARD_FAB2_LIB.BASEBOARD_FAB2(SCH_1):PAGE21
  AR14 H_PM_SYNC_GTL_R1 @BASEBOARD_FAB2_LIB.BASEBOARD_FAB2(SCH_1):H_PM_SYNC_GTL_R1   I259 @BASEBOARD_FAB2_LIB.BASEBOARD_FAB2(SCH_1):PAGE21
  AT19 H_PMSYNC_CLK_24M_CPU0 @BASEBOARD_FAB2_LIB.BASEBOARD_FAB2(SCH_1):H_PMSYNC_CLK_24M_CPU0   I259 @BASEBOARD_FAB2_LIB.BASEBOARD_FAB2(SCH_1):PAGE21
  AF15 H_CPU0_FAST_WAKE_N @BASEBOARD_FAB2_LIB.BASEBOARD_FAB2(SCH_1):H_CPU0_FAST_WAKE_N   I259 @BASEBOARD_FAB2_LIB.BASEBOARD_FAB2(SCH_1):PAGE21
  AG16 XDP_CPU_PRDY_N @BASEBOARD_FAB2_LIB.BASEBOARD_FAB2(SCH_1):XDP_CPU_PRDY_N   I259 @BASEBOARD_FAB2_LIB.BASEBOARD_FAB2(SCH_1):PAGE21
  AR12 XDP_CPU_PREQ_N @BASEBOARD_FAB2_LIB.BASEBOARD_FAB2(SCH_1):XDP_CPU_PREQ_N   I259 @BASEBOARD_FAB2_LIB.BASEBOARD_FAB2(SCH_1):PAGE21
  AB17 TP_CPU0_PROCDIS_G_N @BASEBOARD_FAB2_LIB.BASEBOARD_FAB2(SCH_1):TP_CPU0_PROCDIS_G_N   I259 @BASEBOARD_FAB2_LIB.BASEBOARD_FAB2(SCH_1):PAGE21
  AC16 H_CPU0_PROCHOT_G_N @BASEBOARD_FAB2_LIB.BASEBOARD_FAB2(SCH_1):H_CPU0_PROCHOT_G_N   I259 @BASEBOARD_FAB2_LIB.BASEBOARD_FAB2(SCH_1):PAGE21
  DB71 FM_CPU0_PROC_ID1 @BASEBOARD_FAB2_LIB.BASEBOARD_FAB2(SCH_1):FM_CPU0_PROC_ID1   I259 @BASEBOARD_FAB2_LIB.BASEBOARD_FAB2(SCH_1):PAGE21
  CY71 FM_CPU0_PROC_ID0 @BASEBOARD_FAB2_LIB.BASEBOARD_FAB2(SCH_1):FM_CPU0_PROC_ID0   I259 @BASEBOARD_FAB2_LIB.BASEBOARD_FAB2(SCH_1):PAGE21
  BC24 PWRGD_CPU0_G @BASEBOARD_FAB2_LIB.BASEBOARD_FAB2(SCH_1):PWRGD_CPU0_G   I259 @BASEBOARD_FAB2_LIB.BASEBOARD_FAB2(SCH_1):PAGE21
  AP21 RST_CPU0_G_N @BASEBOARD_FAB2_LIB.BASEBOARD_FAB2(SCH_1):RST_CPU0_G_N   I259 @BASEBOARD_FAB2_LIB.BASEBOARD_FAB2(SCH_1):PAGE21
  AR18 PU_CPU0_SAFE_MODE_BOOT @BASEBOARD_FAB2_LIB.BASEBOARD_FAB2(SCH_1):PU_CPU0_SAFE_MODE_BOOT   I259 @BASEBOARD_FAB2_LIB.BASEBOARD_FAB2(SCH_1):PAGE21
  AB13 FM_CPU0_SKTOCC_LVT3_N @BASEBOARD_FAB2_LIB.BASEBOARD_FAB2(SCH_1):FM_CPU0_SKTOCC_LVT3_N   I259 @BASEBOARD_FAB2_LIB.BASEBOARD_FAB2(SCH_1):PAGE21
  CT59 SMB_PIROM_CPU0_SCL @BASEBOARD_FAB2_LIB.BASEBOARD_FAB2(SCH_1):SMB_PIROM_CPU0_SCL   I259 @BASEBOARD_FAB2_LIB.BASEBOARD_FAB2(SCH_1):PAGE21
  CW58 SMB_PIROM_CPU0_SDA @BASEBOARD_FAB2_LIB.BASEBOARD_FAB2(SCH_1):SMB_PIROM_CPU0_SDA   I259 @BASEBOARD_FAB2_LIB.BASEBOARD_FAB2(SCH_1):PAGE21
  CV59 FM_CPU0_SM_WP @BASEBOARD_FAB2_LIB.BASEBOARD_FAB2(SCH_1):FM_CPU0_SM_WP   I259 @BASEBOARD_FAB2_LIB.BASEBOARD_FAB2(SCH_1):PAGE21
  AU20 TP_CPU0_SOCKET_ID_2 @BASEBOARD_FAB2_LIB.BASEBOARD_FAB2(SCH_1):TP_CPU0_SOCKET_ID_2   I259 @BASEBOARD_FAB2_LIB.BASEBOARD_FAB2(SCH_1):PAGE21
  AU16 PU_CPU0_SOCKET_ID_1 @BASEBOARD_FAB2_LIB.BASEBOARD_FAB2(SCH_1):PU_CPU0_SOCKET_ID_1   I259 @BASEBOARD_FAB2_LIB.BASEBOARD_FAB2(SCH_1):PAGE21
  AU22 PU_CPU0_SOCKET_ID_0 @BASEBOARD_FAB2_LIB.BASEBOARD_FAB2(SCH_1):PU_CPU0_SOCKET_ID_0   I259 @BASEBOARD_FAB2_LIB.BASEBOARD_FAB2(SCH_1):PAGE21
  DL44 SVID_ALERT1_CPU0_N @BASEBOARD_FAB2_LIB.BASEBOARD_FAB2(SCH_1):SVID_ALERT1_CPU0_N   I259 @BASEBOARD_FAB2_LIB.BASEBOARD_FAB2(SCH_1):PAGE21
  DE44 SVID_ALERT0_CPU0_N @BASEBOARD_FAB2_LIB.BASEBOARD_FAB2(SCH_1):SVID_ALERT0_CPU0_N   I259 @BASEBOARD_FAB2_LIB.BASEBOARD_FAB2(SCH_1):PAGE21
  DG44 SVID_CLK1_CPU0 @BASEBOARD_FAB2_LIB.BASEBOARD_FAB2(SCH_1):SVID_CLK1_CPU0   I259 @BASEBOARD_FAB2_LIB.BASEBOARD_FAB2(SCH_1):PAGE21
  DC44 SVID_CLK0_CPU0 @BASEBOARD_FAB2_LIB.BASEBOARD_FAB2(SCH_1):SVID_CLK0_CPU0   I259 @BASEBOARD_FAB2_LIB.BASEBOARD_FAB2(SCH_1):PAGE21
  DJ44 SVID_DIO1_CPU0 @BASEBOARD_FAB2_LIB.BASEBOARD_FAB2(SCH_1):SVID_DIO1_CPU0   I259 @BASEBOARD_FAB2_LIB.BASEBOARD_FAB2(SCH_1):PAGE21
  DB45 SVID_DIO0_CPU0 @BASEBOARD_FAB2_LIB.BASEBOARD_FAB2(SCH_1):SVID_DIO0_CPU0   I259 @BASEBOARD_FAB2_LIB.BASEBOARD_FAB2(SCH_1):PAGE21
  AA14 XDP_CPU_TCK0 @BASEBOARD_FAB2_LIB.BASEBOARD_FAB2(SCH_1):XDP_CPU_TCK0   I259 @BASEBOARD_FAB2_LIB.BASEBOARD_FAB2(SCH_1):PAGE21
  AC14 XDP_CPU_TDI @BASEBOARD_FAB2_LIB.BASEBOARD_FAB2(SCH_1):XDP_CPU_TDI   I259 @BASEBOARD_FAB2_LIB.BASEBOARD_FAB2(SCH_1):PAGE21
  AE14 XDP_CPU0_TDO @BASEBOARD_FAB2_LIB.BASEBOARD_FAB2(SCH_1):XDP_CPU0_TDO   I259 @BASEBOARD_FAB2_LIB.BASEBOARD_FAB2(SCH_1):PAGE21
  AY19 PD_CPU0_TEST12 @BASEBOARD_FAB2_LIB.BASEBOARD_FAB2(SCH_1):PD_CPU0_TEST12   I259 @BASEBOARD_FAB2_LIB.BASEBOARD_FAB2(SCH_1):PAGE21
  DB51 PD_CPU0_TEST13 @BASEBOARD_FAB2_LIB.BASEBOARD_FAB2(SCH_1):PD_CPU0_TEST13   I259 @BASEBOARD_FAB2_LIB.BASEBOARD_FAB2(SCH_1):PAGE21
  DC50 PD_CPU0_TEST14 @BASEBOARD_FAB2_LIB.BASEBOARD_FAB2(SCH_1):PD_CPU0_TEST14   I259 @BASEBOARD_FAB2_LIB.BASEBOARD_FAB2(SCH_1):PAGE21
  AW14 PD_CPU0_KSFC_DIS @BASEBOARD_FAB2_LIB.BASEBOARD_FAB2(SCH_1):PD_CPU0_KSFC_DIS   I259 @BASEBOARD_FAB2_LIB.BASEBOARD_FAB2(SCH_1):PAGE21
  AB15 H_CPU0_THERMTRIP_G_N @BASEBOARD_FAB2_LIB.BASEBOARD_FAB2(SCH_1):H_CPU0_THERMTRIP_G_N   I259 @BASEBOARD_FAB2_LIB.BASEBOARD_FAB2(SCH_1):PAGE21
   W14 XDP_CPU_TMS @BASEBOARD_FAB2_LIB.BASEBOARD_FAB2(SCH_1):XDP_CPU_TMS   I259 @BASEBOARD_FAB2_LIB.BASEBOARD_FAB2(SCH_1):PAGE21
   Y13 XDP_CPU_TRST_N @BASEBOARD_FAB2_LIB.BASEBOARD_FAB2(SCH_1):XDP_CPU_TRST_N   I259 @BASEBOARD_FAB2_LIB.BASEBOARD_FAB2(SCH_1):PAGE21
  AM11 PU_CPU0_TSC_SYNC @BASEBOARD_FAB2_LIB.BASEBOARD_FAB2(SCH_1):PU_CPU0_TSC_SYNC   I259 @BASEBOARD_FAB2_LIB.BASEBOARD_FAB2(SCH_1):PAGE21
  AW18 PU_CPU0_TXT_AGENT @BASEBOARD_FAB2_LIB.BASEBOARD_FAB2(SCH_1):PU_CPU0_TXT_AGENT   I259 @BASEBOARD_FAB2_LIB.BASEBOARD_FAB2(SCH_1):PAGE21
  AV15 PD_CPU0_TXT_PLTEN @BASEBOARD_FAB2_LIB.BASEBOARD_FAB2(SCH_1):PD_CPU0_TXT_PLTEN   I259 @BASEBOARD_FAB2_LIB.BASEBOARD_FAB2(SCH_1):PAGE21
  AP29 A_CPU0_UPI01_RBIAS @BASEBOARD_FAB2_LIB.BASEBOARD_FAB2(SCH_1):A_CPU0_UPI01_RBIAS   I259 @BASEBOARD_FAB2_LIB.BASEBOARD_FAB2(SCH_1):PAGE21
  AT29 A_CPU0_UPI01_RBIAS @BASEBOARD_FAB2_LIB.BASEBOARD_FAB2(SCH_1):A_CPU0_UPI01_RBIAS   I259 @BASEBOARD_FAB2_LIB.BASEBOARD_FAB2(SCH_1):PAGE21
  CK29 A_CPU0_UPI2_RBIAS @BASEBOARD_FAB2_LIB.BASEBOARD_FAB2(SCH_1):A_CPU0_UPI2_RBIAS   I259 @BASEBOARD_FAB2_LIB.BASEBOARD_FAB2(SCH_1):PAGE21
  CL28 A_CPU0_UPI2_RBIAS @BASEBOARD_FAB2_LIB.BASEBOARD_FAB2(SCH_1):A_CPU0_UPI2_RBIAS   I259 @BASEBOARD_FAB2_LIB.BASEBOARD_FAB2(SCH_1):PAGE21
  AV21 CPU_XDP_PRESENT_N @BASEBOARD_FAB2_LIB.BASEBOARD_FAB2(SCH_1):CPU_XDP_PRESENT_N   I204 @BASEBOARD_FAB2_LIB.BASEBOARD_FAB2(SCH_1):PAGE22
  AW12 PD_CPU0_DMIMODE_OVERRIDE @BASEBOARD_FAB2_LIB.BASEBOARD_FAB2(SCH_1):PD_CPU0_DMIMODE_OVERRIDE   I204 @BASEBOARD_FAB2_LIB.BASEBOARD_FAB2(SCH_1):PAGE22
  AU14 H_CPU0_FIVR_FAULT_G @BASEBOARD_FAB2_LIB.BASEBOARD_FAB2(SCH_1):H_CPU0_FIVR_FAULT_G   I204 @BASEBOARD_FAB2_LIB.BASEBOARD_FAB2(SCH_1):PAGE22
  AP17 XDP_CPU_PWR_DEBUG_N @BASEBOARD_FAB2_LIB.BASEBOARD_FAB2(SCH_1):XDP_CPU_PWR_DEBUG_N   I204 @BASEBOARD_FAB2_LIB.BASEBOARD_FAB2(SCH_1):PAGE22
    A4 TP_CPU0_RSVD_304 @BASEBOARD_FAB2_LIB.BASEBOARD_FAB2(SCH_1):TP_CPU0_RSVD_304   I204 @BASEBOARD_FAB2_LIB.BASEBOARD_FAB2(SCH_1):PAGE22
    A6 TP_CPU0_RSVD_303 @BASEBOARD_FAB2_LIB.BASEBOARD_FAB2(SCH_1):TP_CPU0_RSVD_303   I204 @BASEBOARD_FAB2_LIB.BASEBOARD_FAB2(SCH_1):PAGE22
   A14 P1V8_MCP_CPU0 @BASEBOARD_FAB2_LIB.BASEBOARD_FAB2(SCH_1):P1V8_MCP_CPU0   I204 @BASEBOARD_FAB2_LIB.BASEBOARD_FAB2(SCH_1):PAGE22
   A16 P1V8_MCP_CPU0 @BASEBOARD_FAB2_LIB.BASEBOARD_FAB2(SCH_1):P1V8_MCP_CPU0   I204 @BASEBOARD_FAB2_LIB.BASEBOARD_FAB2(SCH_1):PAGE22
   A24 TP_CPU0_RSVD_300 @BASEBOARD_FAB2_LIB.BASEBOARD_FAB2(SCH_1):TP_CPU0_RSVD_300   I204 @BASEBOARD_FAB2_LIB.BASEBOARD_FAB2(SCH_1):PAGE22
    B3 TP_CPU0_RSVD_299 @BASEBOARD_FAB2_LIB.BASEBOARD_FAB2(SCH_1):TP_CPU0_RSVD_299   I204 @BASEBOARD_FAB2_LIB.BASEBOARD_FAB2(SCH_1):PAGE22
    B7 TP_CPU0_RSVD_298 @BASEBOARD_FAB2_LIB.BASEBOARD_FAB2(SCH_1):TP_CPU0_RSVD_298   I204 @BASEBOARD_FAB2_LIB.BASEBOARD_FAB2(SCH_1):PAGE22
   B13 P1V8_MCP_CPU0 @BASEBOARD_FAB2_LIB.BASEBOARD_FAB2(SCH_1):P1V8_MCP_CPU0   I204 @BASEBOARD_FAB2_LIB.BASEBOARD_FAB2(SCH_1):PAGE22
   B15 P1V8_MCP_CPU0 @BASEBOARD_FAB2_LIB.BASEBOARD_FAB2(SCH_1):P1V8_MCP_CPU0   I204 @BASEBOARD_FAB2_LIB.BASEBOARD_FAB2(SCH_1):PAGE22
   B17 P1V8_MCP_CPU0 @BASEBOARD_FAB2_LIB.BASEBOARD_FAB2(SCH_1):P1V8_MCP_CPU0   I204 @BASEBOARD_FAB2_LIB.BASEBOARD_FAB2(SCH_1):PAGE22
   B77 TP_CPU0_RSVD_293 @BASEBOARD_FAB2_LIB.BASEBOARD_FAB2(SCH_1):TP_CPU0_RSVD_293   I204 @BASEBOARD_FAB2_LIB.BASEBOARD_FAB2(SCH_1):PAGE22
   B81 TP_CPU0_RSVD_292 @BASEBOARD_FAB2_LIB.BASEBOARD_FAB2(SCH_1):TP_CPU0_RSVD_292   I204 @BASEBOARD_FAB2_LIB.BASEBOARD_FAB2(SCH_1):PAGE22
    C6 TP_CPU0_RSVD_291 @BASEBOARD_FAB2_LIB.BASEBOARD_FAB2(SCH_1):TP_CPU0_RSVD_291   I204 @BASEBOARD_FAB2_LIB.BASEBOARD_FAB2(SCH_1):PAGE22
   C18 TP_CPU0_RSVD_290 @BASEBOARD_FAB2_LIB.BASEBOARD_FAB2(SCH_1):TP_CPU0_RSVD_290   I204 @BASEBOARD_FAB2_LIB.BASEBOARD_FAB2(SCH_1):PAGE22
   C24 TP_CPU0_RSVD_289 @BASEBOARD_FAB2_LIB.BASEBOARD_FAB2(SCH_1):TP_CPU0_RSVD_289   I204 @BASEBOARD_FAB2_LIB.BASEBOARD_FAB2(SCH_1):PAGE22
   C82 TP_CPU0_RSVD_288 @BASEBOARD_FAB2_LIB.BASEBOARD_FAB2(SCH_1):TP_CPU0_RSVD_288   I204 @BASEBOARD_FAB2_LIB.BASEBOARD_FAB2(SCH_1):PAGE22
    D5 TP_CPU0_RSVD_287 @BASEBOARD_FAB2_LIB.BASEBOARD_FAB2(SCH_1):TP_CPU0_RSVD_287   I204 @BASEBOARD_FAB2_LIB.BASEBOARD_FAB2(SCH_1):PAGE22
   D17 TP_CPU0_RSVD_286 @BASEBOARD_FAB2_LIB.BASEBOARD_FAB2(SCH_1):TP_CPU0_RSVD_286   I204 @BASEBOARD_FAB2_LIB.BASEBOARD_FAB2(SCH_1):PAGE22
   D65 TP_CPU0_RSVD_285 @BASEBOARD_FAB2_LIB.BASEBOARD_FAB2(SCH_1):TP_CPU0_RSVD_285   I204 @BASEBOARD_FAB2_LIB.BASEBOARD_FAB2(SCH_1):PAGE22
   D83 TP_CPU0_RSVD_284 @BASEBOARD_FAB2_LIB.BASEBOARD_FAB2(SCH_1):TP_CPU0_RSVD_284   I204 @BASEBOARD_FAB2_LIB.BASEBOARD_FAB2(SCH_1):PAGE22
    E2 TP_CPU0_RSVD_283 @BASEBOARD_FAB2_LIB.BASEBOARD_FAB2(SCH_1):TP_CPU0_RSVD_283   I204 @BASEBOARD_FAB2_LIB.BASEBOARD_FAB2(SCH_1):PAGE22
    E4 TP_CPU0_RSVD_282 @BASEBOARD_FAB2_LIB.BASEBOARD_FAB2(SCH_1):TP_CPU0_RSVD_282   I204 @BASEBOARD_FAB2_LIB.BASEBOARD_FAB2(SCH_1):PAGE22
   E24 TP_CPU0_RSVD_281 @BASEBOARD_FAB2_LIB.BASEBOARD_FAB2(SCH_1):TP_CPU0_RSVD_281   I204 @BASEBOARD_FAB2_LIB.BASEBOARD_FAB2(SCH_1):PAGE22
   E84 TP_CPU0_RSVD_280 @BASEBOARD_FAB2_LIB.BASEBOARD_FAB2(SCH_1):TP_CPU0_RSVD_280   I204 @BASEBOARD_FAB2_LIB.BASEBOARD_FAB2(SCH_1):PAGE22
    F3 TP_CPU0_RSVD_279 @BASEBOARD_FAB2_LIB.BASEBOARD_FAB2(SCH_1):TP_CPU0_RSVD_279   I204 @BASEBOARD_FAB2_LIB.BASEBOARD_FAB2(SCH_1):PAGE22
   F23 TP_CPU0_RSVD_278 @BASEBOARD_FAB2_LIB.BASEBOARD_FAB2(SCH_1):TP_CPU0_RSVD_278   I204 @BASEBOARD_FAB2_LIB.BASEBOARD_FAB2(SCH_1):PAGE22
   F65 TP_CPU0_RSVD_277 @BASEBOARD_FAB2_LIB.BASEBOARD_FAB2(SCH_1):TP_CPU0_RSVD_277   I204 @BASEBOARD_FAB2_LIB.BASEBOARD_FAB2(SCH_1):PAGE22
   F83 TP_CPU0_RSVD_276 @BASEBOARD_FAB2_LIB.BASEBOARD_FAB2(SCH_1):TP_CPU0_RSVD_276   I204 @BASEBOARD_FAB2_LIB.BASEBOARD_FAB2(SCH_1):PAGE22
    G2 TP_CPU0_RSVD_275 @BASEBOARD_FAB2_LIB.BASEBOARD_FAB2(SCH_1):TP_CPU0_RSVD_275   I204 @BASEBOARD_FAB2_LIB.BASEBOARD_FAB2(SCH_1):PAGE22
   G64 TP_CPU0_RSVD_274 @BASEBOARD_FAB2_LIB.BASEBOARD_FAB2(SCH_1):TP_CPU0_RSVD_274   I204 @BASEBOARD_FAB2_LIB.BASEBOARD_FAB2(SCH_1):PAGE22
   G84 TP_CPU0_RSVD_273 @BASEBOARD_FAB2_LIB.BASEBOARD_FAB2(SCH_1):TP_CPU0_RSVD_273   I204 @BASEBOARD_FAB2_LIB.BASEBOARD_FAB2(SCH_1):PAGE22
    H1 TP_CPU0_RSVD_272 @BASEBOARD_FAB2_LIB.BASEBOARD_FAB2(SCH_1):TP_CPU0_RSVD_272   I204 @BASEBOARD_FAB2_LIB.BASEBOARD_FAB2(SCH_1):PAGE22
   H83 TP_CPU0_RSVD_271 @BASEBOARD_FAB2_LIB.BASEBOARD_FAB2(SCH_1):TP_CPU0_RSVD_271   I204 @BASEBOARD_FAB2_LIB.BASEBOARD_FAB2(SCH_1):PAGE22
   H85 TP_CPU0_RSVD_270 @BASEBOARD_FAB2_LIB.BASEBOARD_FAB2(SCH_1):TP_CPU0_RSVD_270   I204 @BASEBOARD_FAB2_LIB.BASEBOARD_FAB2(SCH_1):PAGE22
   J46 TP_CPU0_RSVD_269 @BASEBOARD_FAB2_LIB.BASEBOARD_FAB2(SCH_1):TP_CPU0_RSVD_269   I204 @BASEBOARD_FAB2_LIB.BASEBOARD_FAB2(SCH_1):PAGE22
   J62 TP_CPU0_RSVD_268 @BASEBOARD_FAB2_LIB.BASEBOARD_FAB2(SCH_1):TP_CPU0_RSVD_268   I204 @BASEBOARD_FAB2_LIB.BASEBOARD_FAB2(SCH_1):PAGE22
   K61 TP_CPU0_RSVD_267 @BASEBOARD_FAB2_LIB.BASEBOARD_FAB2(SCH_1):TP_CPU0_RSVD_267   I204 @BASEBOARD_FAB2_LIB.BASEBOARD_FAB2(SCH_1):PAGE22
   M63 TP_CPU0_RSVD_266 @BASEBOARD_FAB2_LIB.BASEBOARD_FAB2(SCH_1):TP_CPU0_RSVD_266   I204 @BASEBOARD_FAB2_LIB.BASEBOARD_FAB2(SCH_1):PAGE22
   P65 TP_CPU0_RSVD_265 @BASEBOARD_FAB2_LIB.BASEBOARD_FAB2(SCH_1):TP_CPU0_RSVD_265   I204 @BASEBOARD_FAB2_LIB.BASEBOARD_FAB2(SCH_1):PAGE22
   R62 TP_CPU0_RSVD_264 @BASEBOARD_FAB2_LIB.BASEBOARD_FAB2(SCH_1):TP_CPU0_RSVD_264   I204 @BASEBOARD_FAB2_LIB.BASEBOARD_FAB2(SCH_1):PAGE22
   R66 TP_CPU0_RSVD_263 @BASEBOARD_FAB2_LIB.BASEBOARD_FAB2(SCH_1):TP_CPU0_RSVD_263   I204 @BASEBOARD_FAB2_LIB.BASEBOARD_FAB2(SCH_1):PAGE22
   T67 TP_CPU0_RSVD_262 @BASEBOARD_FAB2_LIB.BASEBOARD_FAB2(SCH_1):TP_CPU0_RSVD_262   I204 @BASEBOARD_FAB2_LIB.BASEBOARD_FAB2(SCH_1):PAGE22
   U66 TP_CPU0_RSVD_261 @BASEBOARD_FAB2_LIB.BASEBOARD_FAB2(SCH_1):TP_CPU0_RSVD_261   I204 @BASEBOARD_FAB2_LIB.BASEBOARD_FAB2(SCH_1):PAGE22
   V65 TP_CPU0_RSVD_260 @BASEBOARD_FAB2_LIB.BASEBOARD_FAB2(SCH_1):TP_CPU0_RSVD_260   I204 @BASEBOARD_FAB2_LIB.BASEBOARD_FAB2(SCH_1):PAGE22
   V67 TP_CPU0_RSVD_259 @BASEBOARD_FAB2_LIB.BASEBOARD_FAB2(SCH_1):TP_CPU0_RSVD_259   I204 @BASEBOARD_FAB2_LIB.BASEBOARD_FAB2(SCH_1):PAGE22
   W66 TP_CPU0_RSVD_258 @BASEBOARD_FAB2_LIB.BASEBOARD_FAB2(SCH_1):TP_CPU0_RSVD_258   I204 @BASEBOARD_FAB2_LIB.BASEBOARD_FAB2(SCH_1):PAGE22
   Y23 FM_CPU0_RC_ERROR_N @BASEBOARD_FAB2_LIB.BASEBOARD_FAB2(SCH_1):FM_CPU0_RC_ERROR_N   I204 @BASEBOARD_FAB2_LIB.BASEBOARD_FAB2(SCH_1):PAGE22
   Y65 TP_CPU0_RSVD_256 @BASEBOARD_FAB2_LIB.BASEBOARD_FAB2(SCH_1):TP_CPU0_RSVD_256   I204 @BASEBOARD_FAB2_LIB.BASEBOARD_FAB2(SCH_1):PAGE22
  AD47 TP_CPU0_RSVD_254 @BASEBOARD_FAB2_LIB.BASEBOARD_FAB2(SCH_1):TP_CPU0_RSVD_254   I204 @BASEBOARD_FAB2_LIB.BASEBOARD_FAB2(SCH_1):PAGE22
  AD49 TP_CPU0_RSVD_253 @BASEBOARD_FAB2_LIB.BASEBOARD_FAB2(SCH_1):TP_CPU0_RSVD_253   I204 @BASEBOARD_FAB2_LIB.BASEBOARD_FAB2(SCH_1):PAGE22
  AD51 TP_CPU0_RSVD_252 @BASEBOARD_FAB2_LIB.BASEBOARD_FAB2(SCH_1):TP_CPU0_RSVD_252   I204 @BASEBOARD_FAB2_LIB.BASEBOARD_FAB2(SCH_1):PAGE22
  AE46 TP_CPU0_RSVD_251 @BASEBOARD_FAB2_LIB.BASEBOARD_FAB2(SCH_1):TP_CPU0_RSVD_251   I204 @BASEBOARD_FAB2_LIB.BASEBOARD_FAB2(SCH_1):PAGE22
  AE48 TP_CPU0_RSVD_250 @BASEBOARD_FAB2_LIB.BASEBOARD_FAB2(SCH_1):TP_CPU0_RSVD_250   I204 @BASEBOARD_FAB2_LIB.BASEBOARD_FAB2(SCH_1):PAGE22
  AE50 TP_CPU0_RSVD_249 @BASEBOARD_FAB2_LIB.BASEBOARD_FAB2(SCH_1):TP_CPU0_RSVD_249   I204 @BASEBOARD_FAB2_LIB.BASEBOARD_FAB2(SCH_1):PAGE22
  AE52 TP_CPU0_RSVD_248 @BASEBOARD_FAB2_LIB.BASEBOARD_FAB2(SCH_1):TP_CPU0_RSVD_248   I204 @BASEBOARD_FAB2_LIB.BASEBOARD_FAB2(SCH_1):PAGE22
  AE72 TP_CPU0_RSVD_247 @BASEBOARD_FAB2_LIB.BASEBOARD_FAB2(SCH_1):TP_CPU0_RSVD_247   I204 @BASEBOARD_FAB2_LIB.BASEBOARD_FAB2(SCH_1):PAGE22
  AF19 TP_CPU0_RSVD_246 @BASEBOARD_FAB2_LIB.BASEBOARD_FAB2(SCH_1):TP_CPU0_RSVD_246   I204 @BASEBOARD_FAB2_LIB.BASEBOARD_FAB2(SCH_1):PAGE22
  AF47 TP_CPU0_RSVD_245 @BASEBOARD_FAB2_LIB.BASEBOARD_FAB2(SCH_1):TP_CPU0_RSVD_245   I204 @BASEBOARD_FAB2_LIB.BASEBOARD_FAB2(SCH_1):PAGE22
  AF49 TP_CPU0_RSVD_244 @BASEBOARD_FAB2_LIB.BASEBOARD_FAB2(SCH_1):TP_CPU0_RSVD_244   I204 @BASEBOARD_FAB2_LIB.BASEBOARD_FAB2(SCH_1):PAGE22
  AF51 TP_CPU0_RSVD_243 @BASEBOARD_FAB2_LIB.BASEBOARD_FAB2(SCH_1):TP_CPU0_RSVD_243   I204 @BASEBOARD_FAB2_LIB.BASEBOARD_FAB2(SCH_1):PAGE22
  AF53 TP_CPU0_RSVD_242 @BASEBOARD_FAB2_LIB.BASEBOARD_FAB2(SCH_1):TP_CPU0_RSVD_242   I204 @BASEBOARD_FAB2_LIB.BASEBOARD_FAB2(SCH_1):PAGE22
  AF71 TP_CPU0_RSVD_241 @BASEBOARD_FAB2_LIB.BASEBOARD_FAB2(SCH_1):TP_CPU0_RSVD_241   I204 @BASEBOARD_FAB2_LIB.BASEBOARD_FAB2(SCH_1):PAGE22
  AG20 TP_CPU0_RSVD_240 @BASEBOARD_FAB2_LIB.BASEBOARD_FAB2(SCH_1):TP_CPU0_RSVD_240   I204 @BASEBOARD_FAB2_LIB.BASEBOARD_FAB2(SCH_1):PAGE22
  AG48 TP_CPU0_RSVD_239 @BASEBOARD_FAB2_LIB.BASEBOARD_FAB2(SCH_1):TP_CPU0_RSVD_239   I204 @BASEBOARD_FAB2_LIB.BASEBOARD_FAB2(SCH_1):PAGE22
  AG50 TP_CPU0_RSVD_238 @BASEBOARD_FAB2_LIB.BASEBOARD_FAB2(SCH_1):TP_CPU0_RSVD_238   I204 @BASEBOARD_FAB2_LIB.BASEBOARD_FAB2(SCH_1):PAGE22
  AG52 TP_CPU0_RSVD_237 @BASEBOARD_FAB2_LIB.BASEBOARD_FAB2(SCH_1):TP_CPU0_RSVD_237   I204 @BASEBOARD_FAB2_LIB.BASEBOARD_FAB2(SCH_1):PAGE22
  AG54 TP_CPU0_RSVD_236 @BASEBOARD_FAB2_LIB.BASEBOARD_FAB2(SCH_1):TP_CPU0_RSVD_236   I204 @BASEBOARD_FAB2_LIB.BASEBOARD_FAB2(SCH_1):PAGE22
  AG56 TP_CPU0_RSVD_235 @BASEBOARD_FAB2_LIB.BASEBOARD_FAB2(SCH_1):TP_CPU0_RSVD_235   I204 @BASEBOARD_FAB2_LIB.BASEBOARD_FAB2(SCH_1):PAGE22
  AG72 TP_CPU0_RSVD_234 @BASEBOARD_FAB2_LIB.BASEBOARD_FAB2(SCH_1):TP_CPU0_RSVD_234   I204 @BASEBOARD_FAB2_LIB.BASEBOARD_FAB2(SCH_1):PAGE22
  AH15 TP_CPU0_RSVD_233 @BASEBOARD_FAB2_LIB.BASEBOARD_FAB2(SCH_1):TP_CPU0_RSVD_233   I204 @BASEBOARD_FAB2_LIB.BASEBOARD_FAB2(SCH_1):PAGE22
  AH19 TP_CPU0_RSVD_232 @BASEBOARD_FAB2_LIB.BASEBOARD_FAB2(SCH_1):TP_CPU0_RSVD_232   I204 @BASEBOARD_FAB2_LIB.BASEBOARD_FAB2(SCH_1):PAGE22
  AH55 TP_CPU0_RSVD_231 @BASEBOARD_FAB2_LIB.BASEBOARD_FAB2(SCH_1):TP_CPU0_RSVD_231   I204 @BASEBOARD_FAB2_LIB.BASEBOARD_FAB2(SCH_1):PAGE22
  AH57 TP_CPU0_RSVD_230 @BASEBOARD_FAB2_LIB.BASEBOARD_FAB2(SCH_1):TP_CPU0_RSVD_230   I204 @BASEBOARD_FAB2_LIB.BASEBOARD_FAB2(SCH_1):PAGE22
  AH71 TP_CPU0_RSVD_229 @BASEBOARD_FAB2_LIB.BASEBOARD_FAB2(SCH_1):TP_CPU0_RSVD_229   I204 @BASEBOARD_FAB2_LIB.BASEBOARD_FAB2(SCH_1):PAGE22
  AH73 TP_CPU0_RSVD_228 @BASEBOARD_FAB2_LIB.BASEBOARD_FAB2(SCH_1):TP_CPU0_RSVD_228   I204 @BASEBOARD_FAB2_LIB.BASEBOARD_FAB2(SCH_1):PAGE22
  AJ20 TP_CPU0_RSVD_227 @BASEBOARD_FAB2_LIB.BASEBOARD_FAB2(SCH_1):TP_CPU0_RSVD_227   I204 @BASEBOARD_FAB2_LIB.BASEBOARD_FAB2(SCH_1):PAGE22
  AJ56 TP_CPU0_RSVD_226 @BASEBOARD_FAB2_LIB.BASEBOARD_FAB2(SCH_1):TP_CPU0_RSVD_226   I204 @BASEBOARD_FAB2_LIB.BASEBOARD_FAB2(SCH_1):PAGE22
  AJ58 TP_CPU0_RSVD_225 @BASEBOARD_FAB2_LIB.BASEBOARD_FAB2(SCH_1):TP_CPU0_RSVD_225   I204 @BASEBOARD_FAB2_LIB.BASEBOARD_FAB2(SCH_1):PAGE22
  AJ60 TP_CPU0_RSVD_224 @BASEBOARD_FAB2_LIB.BASEBOARD_FAB2(SCH_1):TP_CPU0_RSVD_224   I204 @BASEBOARD_FAB2_LIB.BASEBOARD_FAB2(SCH_1):PAGE22
  AJ62 TP_CPU0_RSVD_223 @BASEBOARD_FAB2_LIB.BASEBOARD_FAB2(SCH_1):TP_CPU0_RSVD_223   I204 @BASEBOARD_FAB2_LIB.BASEBOARD_FAB2(SCH_1):PAGE22
  AJ70 TP_CPU0_RSVD_222 @BASEBOARD_FAB2_LIB.BASEBOARD_FAB2(SCH_1):TP_CPU0_RSVD_222   I204 @BASEBOARD_FAB2_LIB.BASEBOARD_FAB2(SCH_1):PAGE22
  AK21 VSENSE_P1V8MCP_CPU0_SKT_VSEN @BASEBOARD_FAB2_LIB.BASEBOARD_FAB2(SCH_1):VSENSE_P1V8MCP_CPU0_SKT_VSEN   I204 @BASEBOARD_FAB2_LIB.BASEBOARD_FAB2(SCH_1):PAGE22
  AK27 CLK_322M_OSC_CPU0_RC_DP @BASEBOARD_FAB2_LIB.BASEBOARD_FAB2(SCH_1):CLK_322M_OSC_CPU0_RC_DP   I204 @BASEBOARD_FAB2_LIB.BASEBOARD_FAB2(SCH_1):PAGE22
  AK57 TP_CPU0_RSVD_219 @BASEBOARD_FAB2_LIB.BASEBOARD_FAB2(SCH_1):TP_CPU0_RSVD_219   I204 @BASEBOARD_FAB2_LIB.BASEBOARD_FAB2(SCH_1):PAGE22
  AK59 TP_CPU0_RSVD_218 @BASEBOARD_FAB2_LIB.BASEBOARD_FAB2(SCH_1):TP_CPU0_RSVD_218   I204 @BASEBOARD_FAB2_LIB.BASEBOARD_FAB2(SCH_1):PAGE22
  AK61 TP_CPU0_RSVD_217 @BASEBOARD_FAB2_LIB.BASEBOARD_FAB2(SCH_1):TP_CPU0_RSVD_217   I204 @BASEBOARD_FAB2_LIB.BASEBOARD_FAB2(SCH_1):PAGE22
  AK69 TP_CPU0_RSVD_216 @BASEBOARD_FAB2_LIB.BASEBOARD_FAB2(SCH_1):TP_CPU0_RSVD_216   I204 @BASEBOARD_FAB2_LIB.BASEBOARD_FAB2(SCH_1):PAGE22
  AL20 VSENSE_P1V8MCP_CPU0_SKT_VRTN @BASEBOARD_FAB2_LIB.BASEBOARD_FAB2(SCH_1):VSENSE_P1V8MCP_CPU0_SKT_VRTN   I204 @BASEBOARD_FAB2_LIB.BASEBOARD_FAB2(SCH_1):PAGE22
  AL22 TP_CPU0_RSVD_214 @BASEBOARD_FAB2_LIB.BASEBOARD_FAB2(SCH_1):TP_CPU0_RSVD_214   I204 @BASEBOARD_FAB2_LIB.BASEBOARD_FAB2(SCH_1):PAGE22
  AL26 CLK_322M_OSC_CPU0_RC_DN @BASEBOARD_FAB2_LIB.BASEBOARD_FAB2(SCH_1):CLK_322M_OSC_CPU0_RC_DN   I204 @BASEBOARD_FAB2_LIB.BASEBOARD_FAB2(SCH_1):PAGE22
  AL58 TP_CPU0_RSVD_212 @BASEBOARD_FAB2_LIB.BASEBOARD_FAB2(SCH_1):TP_CPU0_RSVD_212   I204 @BASEBOARD_FAB2_LIB.BASEBOARD_FAB2(SCH_1):PAGE22
  AL60 TP_CPU0_RSVD_211 @BASEBOARD_FAB2_LIB.BASEBOARD_FAB2(SCH_1):TP_CPU0_RSVD_211   I204 @BASEBOARD_FAB2_LIB.BASEBOARD_FAB2(SCH_1):PAGE22
  AL62 TP_CPU0_RSVD_210 @BASEBOARD_FAB2_LIB.BASEBOARD_FAB2(SCH_1):TP_CPU0_RSVD_210   I204 @BASEBOARD_FAB2_LIB.BASEBOARD_FAB2(SCH_1):PAGE22
  AM21 PVCCMCP_CPU0 @BASEBOARD_FAB2_LIB.BASEBOARD_FAB2(SCH_1):PVCCMCP_CPU0   I204 @BASEBOARD_FAB2_LIB.BASEBOARD_FAB2(SCH_1):PAGE22
  AM23 TP_CPU0_RSVD_208 @BASEBOARD_FAB2_LIB.BASEBOARD_FAB2(SCH_1):TP_CPU0_RSVD_208   I204 @BASEBOARD_FAB2_LIB.BASEBOARD_FAB2(SCH_1):PAGE22
  AM25 PVCCMCP_CPU0 @BASEBOARD_FAB2_LIB.BASEBOARD_FAB2(SCH_1):PVCCMCP_CPU0   I204 @BASEBOARD_FAB2_LIB.BASEBOARD_FAB2(SCH_1):PAGE22
  AM27 CLK_100M_CPU0_RC_REFCLK0_DP @BASEBOARD_FAB2_LIB.BASEBOARD_FAB2(SCH_1):CLK_100M_CPU0_RC_REFCLK0_DP   I204 @BASEBOARD_FAB2_LIB.BASEBOARD_FAB2(SCH_1):PAGE22
  AM59 TP_CPU0_RSVD_205 @BASEBOARD_FAB2_LIB.BASEBOARD_FAB2(SCH_1):TP_CPU0_RSVD_205   I204 @BASEBOARD_FAB2_LIB.BASEBOARD_FAB2(SCH_1):PAGE22
  AM61 TP_CPU0_RSVD_204 @BASEBOARD_FAB2_LIB.BASEBOARD_FAB2(SCH_1):TP_CPU0_RSVD_204   I204 @BASEBOARD_FAB2_LIB.BASEBOARD_FAB2(SCH_1):PAGE22
  AN18 PVCCMCP_CPU0 @BASEBOARD_FAB2_LIB.BASEBOARD_FAB2(SCH_1):PVCCMCP_CPU0   I204 @BASEBOARD_FAB2_LIB.BASEBOARD_FAB2(SCH_1):PAGE22
  AN22 PVCCMCP_CPU0 @BASEBOARD_FAB2_LIB.BASEBOARD_FAB2(SCH_1):PVCCMCP_CPU0   I204 @BASEBOARD_FAB2_LIB.BASEBOARD_FAB2(SCH_1):PAGE22
  AN24 PVCCMCP_CPU0 @BASEBOARD_FAB2_LIB.BASEBOARD_FAB2(SCH_1):PVCCMCP_CPU0   I204 @BASEBOARD_FAB2_LIB.BASEBOARD_FAB2(SCH_1):PAGE22
  AN26 PVCCMCP_CPU0 @BASEBOARD_FAB2_LIB.BASEBOARD_FAB2(SCH_1):PVCCMCP_CPU0   I204 @BASEBOARD_FAB2_LIB.BASEBOARD_FAB2(SCH_1):PAGE22
  AN60 TP_CPU0_RSVD_199 @BASEBOARD_FAB2_LIB.BASEBOARD_FAB2(SCH_1):TP_CPU0_RSVD_199   I204 @BASEBOARD_FAB2_LIB.BASEBOARD_FAB2(SCH_1):PAGE22
  AN62 TP_CPU0_RSVD_198 @BASEBOARD_FAB2_LIB.BASEBOARD_FAB2(SCH_1):TP_CPU0_RSVD_198   I204 @BASEBOARD_FAB2_LIB.BASEBOARD_FAB2(SCH_1):PAGE22
  AP23 PVCCMCP_CPU0 @BASEBOARD_FAB2_LIB.BASEBOARD_FAB2(SCH_1):PVCCMCP_CPU0   I204 @BASEBOARD_FAB2_LIB.BASEBOARD_FAB2(SCH_1):PAGE22
  AP25 PVCCMCP_CPU0 @BASEBOARD_FAB2_LIB.BASEBOARD_FAB2(SCH_1):PVCCMCP_CPU0   I204 @BASEBOARD_FAB2_LIB.BASEBOARD_FAB2(SCH_1):PAGE22
  AP27 CLK_100M_CPU0_RC_REFCLK0_DN @BASEBOARD_FAB2_LIB.BASEBOARD_FAB2(SCH_1):CLK_100M_CPU0_RC_REFCLK0_DN   I204 @BASEBOARD_FAB2_LIB.BASEBOARD_FAB2(SCH_1):PAGE22
  AP61 TP_CPU0_RSVD_194 @BASEBOARD_FAB2_LIB.BASEBOARD_FAB2(SCH_1):TP_CPU0_RSVD_194   I204 @BASEBOARD_FAB2_LIB.BASEBOARD_FAB2(SCH_1):PAGE22
  AF45 PD_CPU0_RSVD_TEST_1 @BASEBOARD_FAB2_LIB.BASEBOARD_FAB2(SCH_1):PD_CPU0_RSVD_TEST_1   I204 @BASEBOARD_FAB2_LIB.BASEBOARD_FAB2(SCH_1):PAGE22
  AY13 TP_CPU0_RSVD_TEST_11 @BASEBOARD_FAB2_LIB.BASEBOARD_FAB2(SCH_1):TP_CPU0_RSVD_TEST_11   I204 @BASEBOARD_FAB2_LIB.BASEBOARD_FAB2(SCH_1):PAGE22
  AG46 PD_CPU0_RSVD_TEST_2 @BASEBOARD_FAB2_LIB.BASEBOARD_FAB2(SCH_1):PD_CPU0_RSVD_TEST_2   I204 @BASEBOARD_FAB2_LIB.BASEBOARD_FAB2(SCH_1):PAGE22
  AM13 TP_CPU0_RSVD_TEST_3 @BASEBOARD_FAB2_LIB.BASEBOARD_FAB2(SCH_1):TP_CPU0_RSVD_TEST_3   I204 @BASEBOARD_FAB2_LIB.BASEBOARD_FAB2(SCH_1):PAGE22
  AN12 TP_CPU0_RSVD_TEST_4 @BASEBOARD_FAB2_LIB.BASEBOARD_FAB2(SCH_1):TP_CPU0_RSVD_TEST_4   I204 @BASEBOARD_FAB2_LIB.BASEBOARD_FAB2(SCH_1):PAGE22
  AN14 TP_CPU0_RSVD_TEST_5 @BASEBOARD_FAB2_LIB.BASEBOARD_FAB2(SCH_1):TP_CPU0_RSVD_TEST_5   I204 @BASEBOARD_FAB2_LIB.BASEBOARD_FAB2(SCH_1):PAGE22
   J60 M_A_ACT_N @BASEBOARD_FAB2_LIB.BASEBOARD_FAB2(SCH_1):M_A_ACT_N   I172 @BASEBOARD_FAB2_LIB.BASEBOARD_FAB2(SCH_1):PAGE23
   B61 M_A_ALERT_N @BASEBOARD_FAB2_LIB.BASEBOARD_FAB2(SCH_1):M_A_ALERT_N   I172 @BASEBOARD_FAB2_LIB.BASEBOARD_FAB2(SCH_1):PAGE23
   G54 M_A_BA<1> @BASEBOARD_FAB2_LIB.BASEBOARD_FAB2(SCH_1):M_A_BA(1)   I172 @BASEBOARD_FAB2_LIB.BASEBOARD_FAB2(SCH_1):PAGE23
   C52 M_A_BA<0> @BASEBOARD_FAB2_LIB.BASEBOARD_FAB2(SCH_1):M_A_BA(0)   I172 @BASEBOARD_FAB2_LIB.BASEBOARD_FAB2(SCH_1):PAGE23
   F63 M_A_BG<1> @BASEBOARD_FAB2_LIB.BASEBOARD_FAB2(SCH_1):M_A_BG(1)   I172 @BASEBOARD_FAB2_LIB.BASEBOARD_FAB2(SCH_1):PAGE23
   D61 M_A_BG<0> @BASEBOARD_FAB2_LIB.BASEBOARD_FAB2(SCH_1):M_A_BG(0)   I172 @BASEBOARD_FAB2_LIB.BASEBOARD_FAB2(SCH_1):PAGE23
   G46 M_A_C<2> @BASEBOARD_FAB2_LIB.BASEBOARD_FAB2(SCH_1):M_A_C(2)   I172 @BASEBOARD_FAB2_LIB.BASEBOARD_FAB2(SCH_1):PAGE23
   D63 M_A_CKE<3> @BASEBOARD_FAB2_LIB.BASEBOARD_FAB2(SCH_1):M_A_CKE(3)   I172 @BASEBOARD_FAB2_LIB.BASEBOARD_FAB2(SCH_1):PAGE23
   B63 M_A_CKE<2> @BASEBOARD_FAB2_LIB.BASEBOARD_FAB2(SCH_1):M_A_CKE(2)   I172 @BASEBOARD_FAB2_LIB.BASEBOARD_FAB2(SCH_1):PAGE23
   C64 M_A_CKE<1> @BASEBOARD_FAB2_LIB.BASEBOARD_FAB2(SCH_1):M_A_CKE(1)   I172 @BASEBOARD_FAB2_LIB.BASEBOARD_FAB2(SCH_1):PAGE23
   C62 M_A_CKE<0> @BASEBOARD_FAB2_LIB.BASEBOARD_FAB2(SCH_1):M_A_CKE(0)   I172 @BASEBOARD_FAB2_LIB.BASEBOARD_FAB2(SCH_1):PAGE23
   C56 M_A_CLK_DN<3> @BASEBOARD_FAB2_LIB.BASEBOARD_FAB2(SCH_1):M_A_CLK_DN(3)   I172 @BASEBOARD_FAB2_LIB.BASEBOARD_FAB2(SCH_1):PAGE23
   J56 M_A_CLK_DN<2> @BASEBOARD_FAB2_LIB.BASEBOARD_FAB2(SCH_1):M_A_CLK_DN(2)   I172 @BASEBOARD_FAB2_LIB.BASEBOARD_FAB2(SCH_1):PAGE23
   C54 M_A_CLK_DN<1> @BASEBOARD_FAB2_LIB.BASEBOARD_FAB2(SCH_1):M_A_CLK_DN(1)   I172 @BASEBOARD_FAB2_LIB.BASEBOARD_FAB2(SCH_1):PAGE23
   F55 M_A_CLK_DN<0> @BASEBOARD_FAB2_LIB.BASEBOARD_FAB2(SCH_1):M_A_CLK_DN(0)   I172 @BASEBOARD_FAB2_LIB.BASEBOARD_FAB2(SCH_1):PAGE23
   B57 M_A_CLK_DP<3> @BASEBOARD_FAB2_LIB.BASEBOARD_FAB2(SCH_1):M_A_CLK_DP(3)   I172 @BASEBOARD_FAB2_LIB.BASEBOARD_FAB2(SCH_1):PAGE23
   G56 M_A_CLK_DP<2> @BASEBOARD_FAB2_LIB.BASEBOARD_FAB2(SCH_1):M_A_CLK_DP(2)   I172 @BASEBOARD_FAB2_LIB.BASEBOARD_FAB2(SCH_1):PAGE23
   B55 M_A_CLK_DP<1> @BASEBOARD_FAB2_LIB.BASEBOARD_FAB2(SCH_1):M_A_CLK_DP(1)   I172 @BASEBOARD_FAB2_LIB.BASEBOARD_FAB2(SCH_1):PAGE23
   D55 M_A_CLK_DP<0> @BASEBOARD_FAB2_LIB.BASEBOARD_FAB2(SCH_1):M_A_CLK_DP(0)   I172 @BASEBOARD_FAB2_LIB.BASEBOARD_FAB2(SCH_1):PAGE23
   K45 M_A_CS_N<7> @BASEBOARD_FAB2_LIB.BASEBOARD_FAB2(SCH_1):M_A_CS_N(7)   I172 @BASEBOARD_FAB2_LIB.BASEBOARD_FAB2(SCH_1):PAGE23
   F45 M_A_CS_N<6> @BASEBOARD_FAB2_LIB.BASEBOARD_FAB2(SCH_1):M_A_CS_N(6)   I172 @BASEBOARD_FAB2_LIB.BASEBOARD_FAB2(SCH_1):PAGE23
   D49 M_A_CS_N<5> @BASEBOARD_FAB2_LIB.BASEBOARD_FAB2(SCH_1):M_A_CS_N(5)   I172 @BASEBOARD_FAB2_LIB.BASEBOARD_FAB2(SCH_1):PAGE23
   B51 M_A_CS_N<4> @BASEBOARD_FAB2_LIB.BASEBOARD_FAB2(SCH_1):M_A_CS_N(4)   I172 @BASEBOARD_FAB2_LIB.BASEBOARD_FAB2(SCH_1):PAGE23
   F47 M_A_CS_N<3> @BASEBOARD_FAB2_LIB.BASEBOARD_FAB2(SCH_1):M_A_CS_N(3)   I172 @BASEBOARD_FAB2_LIB.BASEBOARD_FAB2(SCH_1):PAGE23
   D47 M_A_CS_N<2> @BASEBOARD_FAB2_LIB.BASEBOARD_FAB2(SCH_1):M_A_CS_N(2)   I172 @BASEBOARD_FAB2_LIB.BASEBOARD_FAB2(SCH_1):PAGE23
   F49 M_A_CS_N<1> @BASEBOARD_FAB2_LIB.BASEBOARD_FAB2(SCH_1):M_A_CS_N(1)   I172 @BASEBOARD_FAB2_LIB.BASEBOARD_FAB2(SCH_1):PAGE23
   G52 M_A_CS_N<0> @BASEBOARD_FAB2_LIB.BASEBOARD_FAB2(SCH_1):M_A_CS_N(0)   I172 @BASEBOARD_FAB2_LIB.BASEBOARD_FAB2(SCH_1):PAGE23
   K23 M_A_DQ<63> @BASEBOARD_FAB2_LIB.BASEBOARD_FAB2(SCH_1):M_A_DQ(63)   I172 @BASEBOARD_FAB2_LIB.BASEBOARD_FAB2(SCH_1):PAGE23
   H23 M_A_DQ<62> @BASEBOARD_FAB2_LIB.BASEBOARD_FAB2(SCH_1):M_A_DQ(62)   I172 @BASEBOARD_FAB2_LIB.BASEBOARD_FAB2(SCH_1):PAGE23
   N26 M_A_DQ<61> @BASEBOARD_FAB2_LIB.BASEBOARD_FAB2(SCH_1):M_A_DQ(61)   I172 @BASEBOARD_FAB2_LIB.BASEBOARD_FAB2(SCH_1):PAGE23
   L26 M_A_DQ<60> @BASEBOARD_FAB2_LIB.BASEBOARD_FAB2(SCH_1):M_A_DQ(60)   I172 @BASEBOARD_FAB2_LIB.BASEBOARD_FAB2(SCH_1):PAGE23
   T23 M_A_DQ<59> @BASEBOARD_FAB2_LIB.BASEBOARD_FAB2(SCH_1):M_A_DQ(59)   I172 @BASEBOARD_FAB2_LIB.BASEBOARD_FAB2(SCH_1):PAGE23
   P23 M_A_DQ<58> @BASEBOARD_FAB2_LIB.BASEBOARD_FAB2(SCH_1):M_A_DQ(58)   I172 @BASEBOARD_FAB2_LIB.BASEBOARD_FAB2(SCH_1):PAGE23
   P25 M_A_DQ<57> @BASEBOARD_FAB2_LIB.BASEBOARD_FAB2(SCH_1):M_A_DQ(57)   I172 @BASEBOARD_FAB2_LIB.BASEBOARD_FAB2(SCH_1):PAGE23
   K25 M_A_DQ<56> @BASEBOARD_FAB2_LIB.BASEBOARD_FAB2(SCH_1):M_A_DQ(56)   I172 @BASEBOARD_FAB2_LIB.BASEBOARD_FAB2(SCH_1):PAGE23
   P29 M_A_DQ<55> @BASEBOARD_FAB2_LIB.BASEBOARD_FAB2(SCH_1):M_A_DQ(55)   I172 @BASEBOARD_FAB2_LIB.BASEBOARD_FAB2(SCH_1):PAGE23
   K29 M_A_DQ<54> @BASEBOARD_FAB2_LIB.BASEBOARD_FAB2(SCH_1):M_A_DQ(54)   I172 @BASEBOARD_FAB2_LIB.BASEBOARD_FAB2(SCH_1):PAGE23
   N32 M_A_DQ<53> @BASEBOARD_FAB2_LIB.BASEBOARD_FAB2(SCH_1):M_A_DQ(53)   I172 @BASEBOARD_FAB2_LIB.BASEBOARD_FAB2(SCH_1):PAGE23
   L32 M_A_DQ<52> @BASEBOARD_FAB2_LIB.BASEBOARD_FAB2(SCH_1):M_A_DQ(52)   I172 @BASEBOARD_FAB2_LIB.BASEBOARD_FAB2(SCH_1):PAGE23
   N28 M_A_DQ<51> @BASEBOARD_FAB2_LIB.BASEBOARD_FAB2(SCH_1):M_A_DQ(51)   I172 @BASEBOARD_FAB2_LIB.BASEBOARD_FAB2(SCH_1):PAGE23
   L28 M_A_DQ<50> @BASEBOARD_FAB2_LIB.BASEBOARD_FAB2(SCH_1):M_A_DQ(50)   I172 @BASEBOARD_FAB2_LIB.BASEBOARD_FAB2(SCH_1):PAGE23
   P31 M_A_DQ<49> @BASEBOARD_FAB2_LIB.BASEBOARD_FAB2(SCH_1):M_A_DQ(49)   I172 @BASEBOARD_FAB2_LIB.BASEBOARD_FAB2(SCH_1):PAGE23
   K31 M_A_DQ<48> @BASEBOARD_FAB2_LIB.BASEBOARD_FAB2(SCH_1):M_A_DQ(48)   I172 @BASEBOARD_FAB2_LIB.BASEBOARD_FAB2(SCH_1):PAGE23
   P35 M_A_DQ<47> @BASEBOARD_FAB2_LIB.BASEBOARD_FAB2(SCH_1):M_A_DQ(47)   I172 @BASEBOARD_FAB2_LIB.BASEBOARD_FAB2(SCH_1):PAGE23
   K35 M_A_DQ<46> @BASEBOARD_FAB2_LIB.BASEBOARD_FAB2(SCH_1):M_A_DQ(46)   I172 @BASEBOARD_FAB2_LIB.BASEBOARD_FAB2(SCH_1):PAGE23
   N38 M_A_DQ<45> @BASEBOARD_FAB2_LIB.BASEBOARD_FAB2(SCH_1):M_A_DQ(45)   I172 @BASEBOARD_FAB2_LIB.BASEBOARD_FAB2(SCH_1):PAGE23
   L38 M_A_DQ<44> @BASEBOARD_FAB2_LIB.BASEBOARD_FAB2(SCH_1):M_A_DQ(44)   I172 @BASEBOARD_FAB2_LIB.BASEBOARD_FAB2(SCH_1):PAGE23
   N34 M_A_DQ<43> @BASEBOARD_FAB2_LIB.BASEBOARD_FAB2(SCH_1):M_A_DQ(43)   I172 @BASEBOARD_FAB2_LIB.BASEBOARD_FAB2(SCH_1):PAGE23
   L34 M_A_DQ<42> @BASEBOARD_FAB2_LIB.BASEBOARD_FAB2(SCH_1):M_A_DQ(42)   I172 @BASEBOARD_FAB2_LIB.BASEBOARD_FAB2(SCH_1):PAGE23
   P37 M_A_DQ<41> @BASEBOARD_FAB2_LIB.BASEBOARD_FAB2(SCH_1):M_A_DQ(41)   I172 @BASEBOARD_FAB2_LIB.BASEBOARD_FAB2(SCH_1):PAGE23
   K37 M_A_DQ<40> @BASEBOARD_FAB2_LIB.BASEBOARD_FAB2(SCH_1):M_A_DQ(40)   I172 @BASEBOARD_FAB2_LIB.BASEBOARD_FAB2(SCH_1):PAGE23
   F39 M_A_DQ<39> @BASEBOARD_FAB2_LIB.BASEBOARD_FAB2(SCH_1):M_A_DQ(39)   I172 @BASEBOARD_FAB2_LIB.BASEBOARD_FAB2(SCH_1):PAGE23
   B39 M_A_DQ<38> @BASEBOARD_FAB2_LIB.BASEBOARD_FAB2(SCH_1):M_A_DQ(38)   I172 @BASEBOARD_FAB2_LIB.BASEBOARD_FAB2(SCH_1):PAGE23
   F41 M_A_DQ<37> @BASEBOARD_FAB2_LIB.BASEBOARD_FAB2(SCH_1):M_A_DQ(37)   I172 @BASEBOARD_FAB2_LIB.BASEBOARD_FAB2(SCH_1):PAGE23
   E42 M_A_DQ<36> @BASEBOARD_FAB2_LIB.BASEBOARD_FAB2(SCH_1):M_A_DQ(36)   I172 @BASEBOARD_FAB2_LIB.BASEBOARD_FAB2(SCH_1):PAGE23
   E38 M_A_DQ<35> @BASEBOARD_FAB2_LIB.BASEBOARD_FAB2(SCH_1):M_A_DQ(35)   I172 @BASEBOARD_FAB2_LIB.BASEBOARD_FAB2(SCH_1):PAGE23
   C38 M_A_DQ<34> @BASEBOARD_FAB2_LIB.BASEBOARD_FAB2(SCH_1):M_A_DQ(34)   I172 @BASEBOARD_FAB2_LIB.BASEBOARD_FAB2(SCH_1):PAGE23
   B41 M_A_DQ<33> @BASEBOARD_FAB2_LIB.BASEBOARD_FAB2(SCH_1):M_A_DQ(33)   I172 @BASEBOARD_FAB2_LIB.BASEBOARD_FAB2(SCH_1):PAGE23
   C42 M_A_DQ<32> @BASEBOARD_FAB2_LIB.BASEBOARD_FAB2(SCH_1):M_A_DQ(32)   I172 @BASEBOARD_FAB2_LIB.BASEBOARD_FAB2(SCH_1):PAGE23
   R74 M_A_DQ<31> @BASEBOARD_FAB2_LIB.BASEBOARD_FAB2(SCH_1):M_A_DQ(31)   I172 @BASEBOARD_FAB2_LIB.BASEBOARD_FAB2(SCH_1):PAGE23
   L74 M_A_DQ<30> @BASEBOARD_FAB2_LIB.BASEBOARD_FAB2(SCH_1):M_A_DQ(30)   I172 @BASEBOARD_FAB2_LIB.BASEBOARD_FAB2(SCH_1):PAGE23
   P77 M_A_DQ<29> @BASEBOARD_FAB2_LIB.BASEBOARD_FAB2(SCH_1):M_A_DQ(29)   I172 @BASEBOARD_FAB2_LIB.BASEBOARD_FAB2(SCH_1):PAGE23
   M77 M_A_DQ<28> @BASEBOARD_FAB2_LIB.BASEBOARD_FAB2(SCH_1):M_A_DQ(28)   I172 @BASEBOARD_FAB2_LIB.BASEBOARD_FAB2(SCH_1):PAGE23
   P73 M_A_DQ<27> @BASEBOARD_FAB2_LIB.BASEBOARD_FAB2(SCH_1):M_A_DQ(27)   I172 @BASEBOARD_FAB2_LIB.BASEBOARD_FAB2(SCH_1):PAGE23
   M73 M_A_DQ<26> @BASEBOARD_FAB2_LIB.BASEBOARD_FAB2(SCH_1):M_A_DQ(26)   I172 @BASEBOARD_FAB2_LIB.BASEBOARD_FAB2(SCH_1):PAGE23
   R76 M_A_DQ<25> @BASEBOARD_FAB2_LIB.BASEBOARD_FAB2(SCH_1):M_A_DQ(25)   I172 @BASEBOARD_FAB2_LIB.BASEBOARD_FAB2(SCH_1):PAGE23
   L76 M_A_DQ<24> @BASEBOARD_FAB2_LIB.BASEBOARD_FAB2(SCH_1):M_A_DQ(24)   I172 @BASEBOARD_FAB2_LIB.BASEBOARD_FAB2(SCH_1):PAGE23
   N80 M_A_DQ<23> @BASEBOARD_FAB2_LIB.BASEBOARD_FAB2(SCH_1):M_A_DQ(23)   I172 @BASEBOARD_FAB2_LIB.BASEBOARD_FAB2(SCH_1):PAGE23
   R82 M_A_DQ<22> @BASEBOARD_FAB2_LIB.BASEBOARD_FAB2(SCH_1):M_A_DQ(22)   I172 @BASEBOARD_FAB2_LIB.BASEBOARD_FAB2(SCH_1):PAGE23
   V79 M_A_DQ<21> @BASEBOARD_FAB2_LIB.BASEBOARD_FAB2(SCH_1):M_A_DQ(21)   I172 @BASEBOARD_FAB2_LIB.BASEBOARD_FAB2(SCH_1):PAGE23
   W80 M_A_DQ<20> @BASEBOARD_FAB2_LIB.BASEBOARD_FAB2(SCH_1):M_A_DQ(20)   I172 @BASEBOARD_FAB2_LIB.BASEBOARD_FAB2(SCH_1):PAGE23
   M81 M_A_DQ<19> @BASEBOARD_FAB2_LIB.BASEBOARD_FAB2(SCH_1):M_A_DQ(19)   I172 @BASEBOARD_FAB2_LIB.BASEBOARD_FAB2(SCH_1):PAGE23
   N82 M_A_DQ<18> @BASEBOARD_FAB2_LIB.BASEBOARD_FAB2(SCH_1):M_A_DQ(18)   I172 @BASEBOARD_FAB2_LIB.BASEBOARD_FAB2(SCH_1):PAGE23
   T79 M_A_DQ<17> @BASEBOARD_FAB2_LIB.BASEBOARD_FAB2(SCH_1):M_A_DQ(17)   I172 @BASEBOARD_FAB2_LIB.BASEBOARD_FAB2(SCH_1):PAGE23
   V81 M_A_DQ<16> @BASEBOARD_FAB2_LIB.BASEBOARD_FAB2(SCH_1):M_A_DQ(16)   I172 @BASEBOARD_FAB2_LIB.BASEBOARD_FAB2(SCH_1):PAGE23
   N84 M_A_DQ<15> @BASEBOARD_FAB2_LIB.BASEBOARD_FAB2(SCH_1):M_A_DQ(15)   I172 @BASEBOARD_FAB2_LIB.BASEBOARD_FAB2(SCH_1):PAGE23
   N86 M_A_DQ<14> @BASEBOARD_FAB2_LIB.BASEBOARD_FAB2(SCH_1):M_A_DQ(14)   I172 @BASEBOARD_FAB2_LIB.BASEBOARD_FAB2(SCH_1):PAGE23
  AA84 M_A_DQ<13> @BASEBOARD_FAB2_LIB.BASEBOARD_FAB2(SCH_1):M_A_DQ(13)   I172 @BASEBOARD_FAB2_LIB.BASEBOARD_FAB2(SCH_1):PAGE23
  AA86 M_A_DQ<12> @BASEBOARD_FAB2_LIB.BASEBOARD_FAB2(SCH_1):M_A_DQ(12)   I172 @BASEBOARD_FAB2_LIB.BASEBOARD_FAB2(SCH_1):PAGE23
   L84 M_A_DQ<11> @BASEBOARD_FAB2_LIB.BASEBOARD_FAB2(SCH_1):M_A_DQ(11)   I172 @BASEBOARD_FAB2_LIB.BASEBOARD_FAB2(SCH_1):PAGE23
   L86 M_A_DQ<10> @BASEBOARD_FAB2_LIB.BASEBOARD_FAB2(SCH_1):M_A_DQ(10)   I172 @BASEBOARD_FAB2_LIB.BASEBOARD_FAB2(SCH_1):PAGE23
   W84 M_A_DQ<9> @BASEBOARD_FAB2_LIB.BASEBOARD_FAB2(SCH_1):M_A_DQ(9)   I172 @BASEBOARD_FAB2_LIB.BASEBOARD_FAB2(SCH_1):PAGE23
   W86 M_A_DQ<8> @BASEBOARD_FAB2_LIB.BASEBOARD_FAB2(SCH_1):M_A_DQ(8)   I172 @BASEBOARD_FAB2_LIB.BASEBOARD_FAB2(SCH_1):PAGE23
  AG84 M_A_DQ<7> @BASEBOARD_FAB2_LIB.BASEBOARD_FAB2(SCH_1):M_A_DQ(7)   I172 @BASEBOARD_FAB2_LIB.BASEBOARD_FAB2(SCH_1):PAGE23
  AG86 M_A_DQ<6> @BASEBOARD_FAB2_LIB.BASEBOARD_FAB2(SCH_1):M_A_DQ(6)   I172 @BASEBOARD_FAB2_LIB.BASEBOARD_FAB2(SCH_1):PAGE23
  AR84 M_A_DQ<5> @BASEBOARD_FAB2_LIB.BASEBOARD_FAB2(SCH_1):M_A_DQ(5)   I172 @BASEBOARD_FAB2_LIB.BASEBOARD_FAB2(SCH_1):PAGE23
  AR86 M_A_DQ<4> @BASEBOARD_FAB2_LIB.BASEBOARD_FAB2(SCH_1):M_A_DQ(4)   I172 @BASEBOARD_FAB2_LIB.BASEBOARD_FAB2(SCH_1):PAGE23
  AE84 M_A_DQ<3> @BASEBOARD_FAB2_LIB.BASEBOARD_FAB2(SCH_1):M_A_DQ(3)   I172 @BASEBOARD_FAB2_LIB.BASEBOARD_FAB2(SCH_1):PAGE23
  AE86 M_A_DQ<2> @BASEBOARD_FAB2_LIB.BASEBOARD_FAB2(SCH_1):M_A_DQ(2)   I172 @BASEBOARD_FAB2_LIB.BASEBOARD_FAB2(SCH_1):PAGE23
  AN84 M_A_DQ<1> @BASEBOARD_FAB2_LIB.BASEBOARD_FAB2(SCH_1):M_A_DQ(1)   I172 @BASEBOARD_FAB2_LIB.BASEBOARD_FAB2(SCH_1):PAGE23
  AN86 M_A_DQ<0> @BASEBOARD_FAB2_LIB.BASEBOARD_FAB2(SCH_1):M_A_DQ(0)   I172 @BASEBOARD_FAB2_LIB.BASEBOARD_FAB2(SCH_1):PAGE23
  AB67 M_A_DQS_DN<17> @BASEBOARD_FAB2_LIB.BASEBOARD_FAB2(SCH_1):M_A_DQS_DN(17)   I172 @BASEBOARD_FAB2_LIB.BASEBOARD_FAB2(SCH_1):PAGE23
   J24 M_A_DQS_DN<16> @BASEBOARD_FAB2_LIB.BASEBOARD_FAB2(SCH_1):M_A_DQS_DN(16)   I172 @BASEBOARD_FAB2_LIB.BASEBOARD_FAB2(SCH_1):PAGE23
   J30 M_A_DQS_DN<15> @BASEBOARD_FAB2_LIB.BASEBOARD_FAB2(SCH_1):M_A_DQS_DN(15)   I172 @BASEBOARD_FAB2_LIB.BASEBOARD_FAB2(SCH_1):PAGE23
   J36 M_A_DQS_DN<14> @BASEBOARD_FAB2_LIB.BASEBOARD_FAB2(SCH_1):M_A_DQS_DN(14)   I172 @BASEBOARD_FAB2_LIB.BASEBOARD_FAB2(SCH_1):PAGE23
   A40 M_A_DQS_DN<13> @BASEBOARD_FAB2_LIB.BASEBOARD_FAB2(SCH_1):M_A_DQS_DN(13)   I172 @BASEBOARD_FAB2_LIB.BASEBOARD_FAB2(SCH_1):PAGE23
   K75 M_A_DQS_DN<12> @BASEBOARD_FAB2_LIB.BASEBOARD_FAB2(SCH_1):M_A_DQS_DN(12)   I172 @BASEBOARD_FAB2_LIB.BASEBOARD_FAB2(SCH_1):PAGE23
   U82 M_A_DQS_DN<11> @BASEBOARD_FAB2_LIB.BASEBOARD_FAB2(SCH_1):M_A_DQS_DN(11)   I172 @BASEBOARD_FAB2_LIB.BASEBOARD_FAB2(SCH_1):PAGE23
   U84 M_A_DQS_DN<10> @BASEBOARD_FAB2_LIB.BASEBOARD_FAB2(SCH_1):M_A_DQS_DN(10)   I172 @BASEBOARD_FAB2_LIB.BASEBOARD_FAB2(SCH_1):PAGE23
  AL84 M_A_DQS_DN<9> @BASEBOARD_FAB2_LIB.BASEBOARD_FAB2(SCH_1):M_A_DQS_DN(9)   I172 @BASEBOARD_FAB2_LIB.BASEBOARD_FAB2(SCH_1):PAGE23
  AH67 M_A_DQS_DN<8> @BASEBOARD_FAB2_LIB.BASEBOARD_FAB2(SCH_1):M_A_DQS_DN(8)   I172 @BASEBOARD_FAB2_LIB.BASEBOARD_FAB2(SCH_1):PAGE23
   N24 M_A_DQS_DN<7> @BASEBOARD_FAB2_LIB.BASEBOARD_FAB2(SCH_1):M_A_DQS_DN(7)   I172 @BASEBOARD_FAB2_LIB.BASEBOARD_FAB2(SCH_1):PAGE23
   R30 M_A_DQS_DN<6> @BASEBOARD_FAB2_LIB.BASEBOARD_FAB2(SCH_1):M_A_DQS_DN(6)   I172 @BASEBOARD_FAB2_LIB.BASEBOARD_FAB2(SCH_1):PAGE23
   R36 M_A_DQS_DN<5> @BASEBOARD_FAB2_LIB.BASEBOARD_FAB2(SCH_1):M_A_DQS_DN(5)   I172 @BASEBOARD_FAB2_LIB.BASEBOARD_FAB2(SCH_1):PAGE23
   G40 M_A_DQS_DN<4> @BASEBOARD_FAB2_LIB.BASEBOARD_FAB2(SCH_1):M_A_DQS_DN(4)   I172 @BASEBOARD_FAB2_LIB.BASEBOARD_FAB2(SCH_1):PAGE23
   T75 M_A_DQS_DN<3> @BASEBOARD_FAB2_LIB.BASEBOARD_FAB2(SCH_1):M_A_DQS_DN(3)   I172 @BASEBOARD_FAB2_LIB.BASEBOARD_FAB2(SCH_1):PAGE23
   P79 M_A_DQS_DN<2> @BASEBOARD_FAB2_LIB.BASEBOARD_FAB2(SCH_1):M_A_DQS_DN(2)   I172 @BASEBOARD_FAB2_LIB.BASEBOARD_FAB2(SCH_1):PAGE23
   R84 M_A_DQS_DN<1> @BASEBOARD_FAB2_LIB.BASEBOARD_FAB2(SCH_1):M_A_DQS_DN(1)   I172 @BASEBOARD_FAB2_LIB.BASEBOARD_FAB2(SCH_1):PAGE23
  AJ84 M_A_DQS_DN<0> @BASEBOARD_FAB2_LIB.BASEBOARD_FAB2(SCH_1):M_A_DQS_DN(0)   I172 @BASEBOARD_FAB2_LIB.BASEBOARD_FAB2(SCH_1):PAGE23
  AD67 M_A_DQS_DP<17> @BASEBOARD_FAB2_LIB.BASEBOARD_FAB2(SCH_1):M_A_DQS_DP(17)   I172 @BASEBOARD_FAB2_LIB.BASEBOARD_FAB2(SCH_1):PAGE23
   L24 M_A_DQS_DP<16> @BASEBOARD_FAB2_LIB.BASEBOARD_FAB2(SCH_1):M_A_DQS_DP(16)   I172 @BASEBOARD_FAB2_LIB.BASEBOARD_FAB2(SCH_1):PAGE23
   L30 M_A_DQS_DP<15> @BASEBOARD_FAB2_LIB.BASEBOARD_FAB2(SCH_1):M_A_DQS_DP(15)   I172 @BASEBOARD_FAB2_LIB.BASEBOARD_FAB2(SCH_1):PAGE23
   L36 M_A_DQS_DP<14> @BASEBOARD_FAB2_LIB.BASEBOARD_FAB2(SCH_1):M_A_DQS_DP(14)   I172 @BASEBOARD_FAB2_LIB.BASEBOARD_FAB2(SCH_1):PAGE23
   C40 M_A_DQS_DP<13> @BASEBOARD_FAB2_LIB.BASEBOARD_FAB2(SCH_1):M_A_DQS_DP(13)   I172 @BASEBOARD_FAB2_LIB.BASEBOARD_FAB2(SCH_1):PAGE23
   M75 M_A_DQS_DP<12> @BASEBOARD_FAB2_LIB.BASEBOARD_FAB2(SCH_1):M_A_DQS_DP(12)   I172 @BASEBOARD_FAB2_LIB.BASEBOARD_FAB2(SCH_1):PAGE23
   T81 M_A_DQS_DP<11> @BASEBOARD_FAB2_LIB.BASEBOARD_FAB2(SCH_1):M_A_DQS_DP(11)   I172 @BASEBOARD_FAB2_LIB.BASEBOARD_FAB2(SCH_1):PAGE23
   V85 M_A_DQS_DP<10> @BASEBOARD_FAB2_LIB.BASEBOARD_FAB2(SCH_1):M_A_DQS_DP(10)   I172 @BASEBOARD_FAB2_LIB.BASEBOARD_FAB2(SCH_1):PAGE23
  AM85 M_A_DQS_DP<9> @BASEBOARD_FAB2_LIB.BASEBOARD_FAB2(SCH_1):M_A_DQS_DP(9)   I172 @BASEBOARD_FAB2_LIB.BASEBOARD_FAB2(SCH_1):PAGE23
  AF67 M_A_DQS_DP<8> @BASEBOARD_FAB2_LIB.BASEBOARD_FAB2(SCH_1):M_A_DQS_DP(8)   I172 @BASEBOARD_FAB2_LIB.BASEBOARD_FAB2(SCH_1):PAGE23
   R24 M_A_DQS_DP<7> @BASEBOARD_FAB2_LIB.BASEBOARD_FAB2(SCH_1):M_A_DQS_DP(7)   I172 @BASEBOARD_FAB2_LIB.BASEBOARD_FAB2(SCH_1):PAGE23
   N30 M_A_DQS_DP<6> @BASEBOARD_FAB2_LIB.BASEBOARD_FAB2(SCH_1):M_A_DQS_DP(6)   I172 @BASEBOARD_FAB2_LIB.BASEBOARD_FAB2(SCH_1):PAGE23
   N36 M_A_DQS_DP<5> @BASEBOARD_FAB2_LIB.BASEBOARD_FAB2(SCH_1):M_A_DQS_DP(5)   I172 @BASEBOARD_FAB2_LIB.BASEBOARD_FAB2(SCH_1):PAGE23
   E40 M_A_DQS_DP<4> @BASEBOARD_FAB2_LIB.BASEBOARD_FAB2(SCH_1):M_A_DQS_DP(4)   I172 @BASEBOARD_FAB2_LIB.BASEBOARD_FAB2(SCH_1):PAGE23
   P75 M_A_DQS_DP<3> @BASEBOARD_FAB2_LIB.BASEBOARD_FAB2(SCH_1):M_A_DQS_DP(3)   I172 @BASEBOARD_FAB2_LIB.BASEBOARD_FAB2(SCH_1):PAGE23
   R80 M_A_DQS_DP<2> @BASEBOARD_FAB2_LIB.BASEBOARD_FAB2(SCH_1):M_A_DQS_DP(2)   I172 @BASEBOARD_FAB2_LIB.BASEBOARD_FAB2(SCH_1):PAGE23
   P85 M_A_DQS_DP<1> @BASEBOARD_FAB2_LIB.BASEBOARD_FAB2(SCH_1):M_A_DQS_DP(1)   I172 @BASEBOARD_FAB2_LIB.BASEBOARD_FAB2(SCH_1):PAGE23
  AH85 M_A_DQS_DP<0> @BASEBOARD_FAB2_LIB.BASEBOARD_FAB2(SCH_1):M_A_DQS_DP(0)   I172 @BASEBOARD_FAB2_LIB.BASEBOARD_FAB2(SCH_1):PAGE23
  AG66 M_A_ECC<7> @BASEBOARD_FAB2_LIB.BASEBOARD_FAB2(SCH_1):M_A_ECC(7)   I172 @BASEBOARD_FAB2_LIB.BASEBOARD_FAB2(SCH_1):PAGE23
  AC66 M_A_ECC<6> @BASEBOARD_FAB2_LIB.BASEBOARD_FAB2(SCH_1):M_A_ECC(6)   I172 @BASEBOARD_FAB2_LIB.BASEBOARD_FAB2(SCH_1):PAGE23
  AF69 M_A_ECC<5> @BASEBOARD_FAB2_LIB.BASEBOARD_FAB2(SCH_1):M_A_ECC(5)   I172 @BASEBOARD_FAB2_LIB.BASEBOARD_FAB2(SCH_1):PAGE23
  AD69 M_A_ECC<4> @BASEBOARD_FAB2_LIB.BASEBOARD_FAB2(SCH_1):M_A_ECC(4)   I172 @BASEBOARD_FAB2_LIB.BASEBOARD_FAB2(SCH_1):PAGE23
  AF65 M_A_ECC<3> @BASEBOARD_FAB2_LIB.BASEBOARD_FAB2(SCH_1):M_A_ECC(3)   I172 @BASEBOARD_FAB2_LIB.BASEBOARD_FAB2(SCH_1):PAGE23
  AD65 M_A_ECC<2> @BASEBOARD_FAB2_LIB.BASEBOARD_FAB2(SCH_1):M_A_ECC(2)   I172 @BASEBOARD_FAB2_LIB.BASEBOARD_FAB2(SCH_1):PAGE23
  AG68 M_A_ECC<1> @BASEBOARD_FAB2_LIB.BASEBOARD_FAB2(SCH_1):M_A_ECC(1)   I172 @BASEBOARD_FAB2_LIB.BASEBOARD_FAB2(SCH_1):PAGE23
  AC68 M_A_ECC<0> @BASEBOARD_FAB2_LIB.BASEBOARD_FAB2(SCH_1):M_A_ECC(0)   I172 @BASEBOARD_FAB2_LIB.BASEBOARD_FAB2(SCH_1):PAGE23
   K47 M_A_MA<17> @BASEBOARD_FAB2_LIB.BASEBOARD_FAB2(SCH_1):M_A_MA(17)   I172 @BASEBOARD_FAB2_LIB.BASEBOARD_FAB2(SCH_1):PAGE23
   D51 M_A_MA<16> @BASEBOARD_FAB2_LIB.BASEBOARD_FAB2(SCH_1):M_A_MA(16)   I172 @BASEBOARD_FAB2_LIB.BASEBOARD_FAB2(SCH_1):PAGE23
   K49 M_A_MA<15> @BASEBOARD_FAB2_LIB.BASEBOARD_FAB2(SCH_1):M_A_MA(15)   I172 @BASEBOARD_FAB2_LIB.BASEBOARD_FAB2(SCH_1):PAGE23
   F51 M_A_MA<14> @BASEBOARD_FAB2_LIB.BASEBOARD_FAB2(SCH_1):M_A_MA(14)   I172 @BASEBOARD_FAB2_LIB.BASEBOARD_FAB2(SCH_1):PAGE23
   J48 M_A_MA<13> @BASEBOARD_FAB2_LIB.BASEBOARD_FAB2(SCH_1):M_A_MA(13)   I172 @BASEBOARD_FAB2_LIB.BASEBOARD_FAB2(SCH_1):PAGE23
   J64 M_A_MA<12> @BASEBOARD_FAB2_LIB.BASEBOARD_FAB2(SCH_1):M_A_MA(12)   I172 @BASEBOARD_FAB2_LIB.BASEBOARD_FAB2(SCH_1):PAGE23
   G62 M_A_MA<11> @BASEBOARD_FAB2_LIB.BASEBOARD_FAB2(SCH_1):M_A_MA(11)   I172 @BASEBOARD_FAB2_LIB.BASEBOARD_FAB2(SCH_1):PAGE23
   J54 M_A_MA<10> @BASEBOARD_FAB2_LIB.BASEBOARD_FAB2(SCH_1):M_A_MA(10)   I172 @BASEBOARD_FAB2_LIB.BASEBOARD_FAB2(SCH_1):PAGE23
   F61 M_A_MA<9> @BASEBOARD_FAB2_LIB.BASEBOARD_FAB2(SCH_1):M_A_MA(9)   I172 @BASEBOARD_FAB2_LIB.BASEBOARD_FAB2(SCH_1):PAGE23
   C60 M_A_MA<8> @BASEBOARD_FAB2_LIB.BASEBOARD_FAB2(SCH_1):M_A_MA(8)   I172 @BASEBOARD_FAB2_LIB.BASEBOARD_FAB2(SCH_1):PAGE23
   G60 M_A_MA<7> @BASEBOARD_FAB2_LIB.BASEBOARD_FAB2(SCH_1):M_A_MA(7)   I172 @BASEBOARD_FAB2_LIB.BASEBOARD_FAB2(SCH_1):PAGE23
   D59 M_A_MA<6> @BASEBOARD_FAB2_LIB.BASEBOARD_FAB2(SCH_1):M_A_MA(6)   I172 @BASEBOARD_FAB2_LIB.BASEBOARD_FAB2(SCH_1):PAGE23
   F59 M_A_MA<5> @BASEBOARD_FAB2_LIB.BASEBOARD_FAB2(SCH_1):M_A_MA(5)   I172 @BASEBOARD_FAB2_LIB.BASEBOARD_FAB2(SCH_1):PAGE23
   G58 M_A_MA<4> @BASEBOARD_FAB2_LIB.BASEBOARD_FAB2(SCH_1):M_A_MA(4)   I172 @BASEBOARD_FAB2_LIB.BASEBOARD_FAB2(SCH_1):PAGE23
   C58 M_A_MA<3> @BASEBOARD_FAB2_LIB.BASEBOARD_FAB2(SCH_1):M_A_MA(3)   I172 @BASEBOARD_FAB2_LIB.BASEBOARD_FAB2(SCH_1):PAGE23
   D57 M_A_MA<2> @BASEBOARD_FAB2_LIB.BASEBOARD_FAB2(SCH_1):M_A_MA(2)   I172 @BASEBOARD_FAB2_LIB.BASEBOARD_FAB2(SCH_1):PAGE23
   F57 M_A_MA<1> @BASEBOARD_FAB2_LIB.BASEBOARD_FAB2(SCH_1):M_A_MA(1)   I172 @BASEBOARD_FAB2_LIB.BASEBOARD_FAB2(SCH_1):PAGE23
   F53 M_A_MA<0> @BASEBOARD_FAB2_LIB.BASEBOARD_FAB2(SCH_1):M_A_MA(0)   I172 @BASEBOARD_FAB2_LIB.BASEBOARD_FAB2(SCH_1):PAGE23
   G48 M_A_ODT<3> @BASEBOARD_FAB2_LIB.BASEBOARD_FAB2(SCH_1):M_A_ODT(3)   I172 @BASEBOARD_FAB2_LIB.BASEBOARD_FAB2(SCH_1):PAGE23
   G50 M_A_ODT<2> @BASEBOARD_FAB2_LIB.BASEBOARD_FAB2(SCH_1):M_A_ODT(2)   I172 @BASEBOARD_FAB2_LIB.BASEBOARD_FAB2(SCH_1):PAGE23
   C48 M_A_ODT<1> @BASEBOARD_FAB2_LIB.BASEBOARD_FAB2(SCH_1):M_A_ODT(1)   I172 @BASEBOARD_FAB2_LIB.BASEBOARD_FAB2(SCH_1):PAGE23
   C50 M_A_ODT<0> @BASEBOARD_FAB2_LIB.BASEBOARD_FAB2(SCH_1):M_A_ODT(0)   I172 @BASEBOARD_FAB2_LIB.BASEBOARD_FAB2(SCH_1):PAGE23
   D53 M_A_PAR @BASEBOARD_FAB2_LIB.BASEBOARD_FAB2(SCH_1):M_A_PAR   I172 @BASEBOARD_FAB2_LIB.BASEBOARD_FAB2(SCH_1):PAGE23
   T63 M_B_ACT_N @BASEBOARD_FAB2_LIB.BASEBOARD_FAB2(SCH_1):M_B_ACT_N   I172 @BASEBOARD_FAB2_LIB.BASEBOARD_FAB2(SCH_1):PAGE24
   W62 M_B_ALERT_N @BASEBOARD_FAB2_LIB.BASEBOARD_FAB2(SCH_1):M_B_ALERT_N   I172 @BASEBOARD_FAB2_LIB.BASEBOARD_FAB2(SCH_1):PAGE24
   K55 M_B_BA<1> @BASEBOARD_FAB2_LIB.BASEBOARD_FAB2(SCH_1):M_B_BA(1)   I172 @BASEBOARD_FAB2_LIB.BASEBOARD_FAB2(SCH_1):PAGE24
   T53 M_B_BA<0> @BASEBOARD_FAB2_LIB.BASEBOARD_FAB2(SCH_1):M_B_BA(0)   I172 @BASEBOARD_FAB2_LIB.BASEBOARD_FAB2(SCH_1):PAGE24
   N60 M_B_BG<1> @BASEBOARD_FAB2_LIB.BASEBOARD_FAB2(SCH_1):M_B_BG(1)   I172 @BASEBOARD_FAB2_LIB.BASEBOARD_FAB2(SCH_1):PAGE24
   M61 M_B_BG<0> @BASEBOARD_FAB2_LIB.BASEBOARD_FAB2(SCH_1):M_B_BG(0)   I172 @BASEBOARD_FAB2_LIB.BASEBOARD_FAB2(SCH_1):PAGE24
   M47 M_B_C<2> @BASEBOARD_FAB2_LIB.BASEBOARD_FAB2(SCH_1):M_B_C(2)   I172 @BASEBOARD_FAB2_LIB.BASEBOARD_FAB2(SCH_1):PAGE24
   L64 M_B_CKE<3> @BASEBOARD_FAB2_LIB.BASEBOARD_FAB2(SCH_1):M_B_CKE(3)   I172 @BASEBOARD_FAB2_LIB.BASEBOARD_FAB2(SCH_1):PAGE24
   K63 M_B_CKE<2> @BASEBOARD_FAB2_LIB.BASEBOARD_FAB2(SCH_1):M_B_CKE(2)   I172 @BASEBOARD_FAB2_LIB.BASEBOARD_FAB2(SCH_1):PAGE24
   R64 M_B_CKE<1> @BASEBOARD_FAB2_LIB.BASEBOARD_FAB2(SCH_1):M_B_CKE(1)   I172 @BASEBOARD_FAB2_LIB.BASEBOARD_FAB2(SCH_1):PAGE24
   N62 M_B_CKE<0> @BASEBOARD_FAB2_LIB.BASEBOARD_FAB2(SCH_1):M_B_CKE(0)   I172 @BASEBOARD_FAB2_LIB.BASEBOARD_FAB2(SCH_1):PAGE24
   R56 M_B_CLK_DN<3> @BASEBOARD_FAB2_LIB.BASEBOARD_FAB2(SCH_1):M_B_CLK_DN(3)   I172 @BASEBOARD_FAB2_LIB.BASEBOARD_FAB2(SCH_1):PAGE24
   N56 M_B_CLK_DN<2> @BASEBOARD_FAB2_LIB.BASEBOARD_FAB2(SCH_1):M_B_CLK_DN(2)   I172 @BASEBOARD_FAB2_LIB.BASEBOARD_FAB2(SCH_1):PAGE24
   R54 M_B_CLK_DN<1> @BASEBOARD_FAB2_LIB.BASEBOARD_FAB2(SCH_1):M_B_CLK_DN(1)   I172 @BASEBOARD_FAB2_LIB.BASEBOARD_FAB2(SCH_1):PAGE24
   M53 M_B_CLK_DN<0> @BASEBOARD_FAB2_LIB.BASEBOARD_FAB2(SCH_1):M_B_CLK_DN(0)   I172 @BASEBOARD_FAB2_LIB.BASEBOARD_FAB2(SCH_1):PAGE24
   T57 M_B_CLK_DP<3> @BASEBOARD_FAB2_LIB.BASEBOARD_FAB2(SCH_1):M_B_CLK_DP(3)   I172 @BASEBOARD_FAB2_LIB.BASEBOARD_FAB2(SCH_1):PAGE24
   M57 M_B_CLK_DP<2> @BASEBOARD_FAB2_LIB.BASEBOARD_FAB2(SCH_1):M_B_CLK_DP(2)   I172 @BASEBOARD_FAB2_LIB.BASEBOARD_FAB2(SCH_1):PAGE24
   T55 M_B_CLK_DP<1> @BASEBOARD_FAB2_LIB.BASEBOARD_FAB2(SCH_1):M_B_CLK_DP(1)   I172 @BASEBOARD_FAB2_LIB.BASEBOARD_FAB2(SCH_1):PAGE24
   N54 M_B_CLK_DP<0> @BASEBOARD_FAB2_LIB.BASEBOARD_FAB2(SCH_1):M_B_CLK_DP(0)   I172 @BASEBOARD_FAB2_LIB.BASEBOARD_FAB2(SCH_1):PAGE24
   R46 M_B_CS_N<7> @BASEBOARD_FAB2_LIB.BASEBOARD_FAB2(SCH_1):M_B_CS_N(7)   I172 @BASEBOARD_FAB2_LIB.BASEBOARD_FAB2(SCH_1):PAGE24
   M45 M_B_CS_N<6> @BASEBOARD_FAB2_LIB.BASEBOARD_FAB2(SCH_1):M_B_CS_N(6)   I172 @BASEBOARD_FAB2_LIB.BASEBOARD_FAB2(SCH_1):PAGE24
   T49 M_B_CS_N<5> @BASEBOARD_FAB2_LIB.BASEBOARD_FAB2(SCH_1):M_B_CS_N(5)   I172 @BASEBOARD_FAB2_LIB.BASEBOARD_FAB2(SCH_1):PAGE24
   J50 M_B_CS_N<4> @BASEBOARD_FAB2_LIB.BASEBOARD_FAB2(SCH_1):M_B_CS_N(4)   I172 @BASEBOARD_FAB2_LIB.BASEBOARD_FAB2(SCH_1):PAGE24
   V47 M_B_CS_N<3> @BASEBOARD_FAB2_LIB.BASEBOARD_FAB2(SCH_1):M_B_CS_N(3)   I172 @BASEBOARD_FAB2_LIB.BASEBOARD_FAB2(SCH_1):PAGE24
   N46 M_B_CS_N<2> @BASEBOARD_FAB2_LIB.BASEBOARD_FAB2(SCH_1):M_B_CS_N(2)   I172 @BASEBOARD_FAB2_LIB.BASEBOARD_FAB2(SCH_1):PAGE24
   R50 M_B_CS_N<1> @BASEBOARD_FAB2_LIB.BASEBOARD_FAB2(SCH_1):M_B_CS_N(1)   I172 @BASEBOARD_FAB2_LIB.BASEBOARD_FAB2(SCH_1):PAGE24
   K51 M_B_CS_N<0> @BASEBOARD_FAB2_LIB.BASEBOARD_FAB2(SCH_1):M_B_CS_N(0)   I172 @BASEBOARD_FAB2_LIB.BASEBOARD_FAB2(SCH_1):PAGE24
  AA26 M_B_DQ<63> @BASEBOARD_FAB2_LIB.BASEBOARD_FAB2(SCH_1):M_B_DQ(63)   I172 @BASEBOARD_FAB2_LIB.BASEBOARD_FAB2(SCH_1):PAGE24
   U26 M_B_DQ<62> @BASEBOARD_FAB2_LIB.BASEBOARD_FAB2(SCH_1):M_B_DQ(62)   I172 @BASEBOARD_FAB2_LIB.BASEBOARD_FAB2(SCH_1):PAGE24
   Y29 M_B_DQ<61> @BASEBOARD_FAB2_LIB.BASEBOARD_FAB2(SCH_1):M_B_DQ(61)   I172 @BASEBOARD_FAB2_LIB.BASEBOARD_FAB2(SCH_1):PAGE24
   V29 M_B_DQ<60> @BASEBOARD_FAB2_LIB.BASEBOARD_FAB2(SCH_1):M_B_DQ(60)   I172 @BASEBOARD_FAB2_LIB.BASEBOARD_FAB2(SCH_1):PAGE24
   Y25 M_B_DQ<59> @BASEBOARD_FAB2_LIB.BASEBOARD_FAB2(SCH_1):M_B_DQ(59)   I172 @BASEBOARD_FAB2_LIB.BASEBOARD_FAB2(SCH_1):PAGE24
   V25 M_B_DQ<58> @BASEBOARD_FAB2_LIB.BASEBOARD_FAB2(SCH_1):M_B_DQ(58)   I172 @BASEBOARD_FAB2_LIB.BASEBOARD_FAB2(SCH_1):PAGE24
  AA28 M_B_DQ<57> @BASEBOARD_FAB2_LIB.BASEBOARD_FAB2(SCH_1):M_B_DQ(57)   I172 @BASEBOARD_FAB2_LIB.BASEBOARD_FAB2(SCH_1):PAGE24
   U28 M_B_DQ<56> @BASEBOARD_FAB2_LIB.BASEBOARD_FAB2(SCH_1):M_B_DQ(56)   I172 @BASEBOARD_FAB2_LIB.BASEBOARD_FAB2(SCH_1):PAGE24
   F27 M_B_DQ<55> @BASEBOARD_FAB2_LIB.BASEBOARD_FAB2(SCH_1):M_B_DQ(55)   I172 @BASEBOARD_FAB2_LIB.BASEBOARD_FAB2(SCH_1):PAGE24
   B27 M_B_DQ<54> @BASEBOARD_FAB2_LIB.BASEBOARD_FAB2(SCH_1):M_B_DQ(54)   I172 @BASEBOARD_FAB2_LIB.BASEBOARD_FAB2(SCH_1):PAGE24
   F29 M_B_DQ<53> @BASEBOARD_FAB2_LIB.BASEBOARD_FAB2(SCH_1):M_B_DQ(53)   I172 @BASEBOARD_FAB2_LIB.BASEBOARD_FAB2(SCH_1):PAGE24
   E30 M_B_DQ<52> @BASEBOARD_FAB2_LIB.BASEBOARD_FAB2(SCH_1):M_B_DQ(52)   I172 @BASEBOARD_FAB2_LIB.BASEBOARD_FAB2(SCH_1):PAGE24
   E26 M_B_DQ<51> @BASEBOARD_FAB2_LIB.BASEBOARD_FAB2(SCH_1):M_B_DQ(51)   I172 @BASEBOARD_FAB2_LIB.BASEBOARD_FAB2(SCH_1):PAGE24
   C26 M_B_DQ<50> @BASEBOARD_FAB2_LIB.BASEBOARD_FAB2(SCH_1):M_B_DQ(50)   I172 @BASEBOARD_FAB2_LIB.BASEBOARD_FAB2(SCH_1):PAGE24
   B29 M_B_DQ<49> @BASEBOARD_FAB2_LIB.BASEBOARD_FAB2(SCH_1):M_B_DQ(49)   I172 @BASEBOARD_FAB2_LIB.BASEBOARD_FAB2(SCH_1):PAGE24
   C30 M_B_DQ<48> @BASEBOARD_FAB2_LIB.BASEBOARD_FAB2(SCH_1):M_B_DQ(48)   I172 @BASEBOARD_FAB2_LIB.BASEBOARD_FAB2(SCH_1):PAGE24
   F33 M_B_DQ<47> @BASEBOARD_FAB2_LIB.BASEBOARD_FAB2(SCH_1):M_B_DQ(47)   I172 @BASEBOARD_FAB2_LIB.BASEBOARD_FAB2(SCH_1):PAGE24
   B33 M_B_DQ<46> @BASEBOARD_FAB2_LIB.BASEBOARD_FAB2(SCH_1):M_B_DQ(46)   I172 @BASEBOARD_FAB2_LIB.BASEBOARD_FAB2(SCH_1):PAGE24
   F35 M_B_DQ<45> @BASEBOARD_FAB2_LIB.BASEBOARD_FAB2(SCH_1):M_B_DQ(45)   I172 @BASEBOARD_FAB2_LIB.BASEBOARD_FAB2(SCH_1):PAGE24
   E36 M_B_DQ<44> @BASEBOARD_FAB2_LIB.BASEBOARD_FAB2(SCH_1):M_B_DQ(44)   I172 @BASEBOARD_FAB2_LIB.BASEBOARD_FAB2(SCH_1):PAGE24
   E32 M_B_DQ<43> @BASEBOARD_FAB2_LIB.BASEBOARD_FAB2(SCH_1):M_B_DQ(43)   I172 @BASEBOARD_FAB2_LIB.BASEBOARD_FAB2(SCH_1):PAGE24
   C32 M_B_DQ<42> @BASEBOARD_FAB2_LIB.BASEBOARD_FAB2(SCH_1):M_B_DQ(42)   I172 @BASEBOARD_FAB2_LIB.BASEBOARD_FAB2(SCH_1):PAGE24
   B35 M_B_DQ<41> @BASEBOARD_FAB2_LIB.BASEBOARD_FAB2(SCH_1):M_B_DQ(41)   I172 @BASEBOARD_FAB2_LIB.BASEBOARD_FAB2(SCH_1):PAGE24
   C36 M_B_DQ<40> @BASEBOARD_FAB2_LIB.BASEBOARD_FAB2(SCH_1):M_B_DQ(40)   I172 @BASEBOARD_FAB2_LIB.BASEBOARD_FAB2(SCH_1):PAGE24
   P41 M_B_DQ<39> @BASEBOARD_FAB2_LIB.BASEBOARD_FAB2(SCH_1):M_B_DQ(39)   I172 @BASEBOARD_FAB2_LIB.BASEBOARD_FAB2(SCH_1):PAGE24
   K41 M_B_DQ<38> @BASEBOARD_FAB2_LIB.BASEBOARD_FAB2(SCH_1):M_B_DQ(38)   I172 @BASEBOARD_FAB2_LIB.BASEBOARD_FAB2(SCH_1):PAGE24
   T43 M_B_DQ<37> @BASEBOARD_FAB2_LIB.BASEBOARD_FAB2(SCH_1):M_B_DQ(37)   I172 @BASEBOARD_FAB2_LIB.BASEBOARD_FAB2(SCH_1):PAGE24
   P43 M_B_DQ<36> @BASEBOARD_FAB2_LIB.BASEBOARD_FAB2(SCH_1):M_B_DQ(36)   I172 @BASEBOARD_FAB2_LIB.BASEBOARD_FAB2(SCH_1):PAGE24
   N40 M_B_DQ<35> @BASEBOARD_FAB2_LIB.BASEBOARD_FAB2(SCH_1):M_B_DQ(35)   I172 @BASEBOARD_FAB2_LIB.BASEBOARD_FAB2(SCH_1):PAGE24
   L40 M_B_DQ<34> @BASEBOARD_FAB2_LIB.BASEBOARD_FAB2(SCH_1):M_B_DQ(34)   I172 @BASEBOARD_FAB2_LIB.BASEBOARD_FAB2(SCH_1):PAGE24
   H43 M_B_DQ<33> @BASEBOARD_FAB2_LIB.BASEBOARD_FAB2(SCH_1):M_B_DQ(33)   I172 @BASEBOARD_FAB2_LIB.BASEBOARD_FAB2(SCH_1):PAGE24
   K43 M_B_DQ<32> @BASEBOARD_FAB2_LIB.BASEBOARD_FAB2(SCH_1):M_B_DQ(32)   I172 @BASEBOARD_FAB2_LIB.BASEBOARD_FAB2(SCH_1):PAGE24
   G72 M_B_DQ<31> @BASEBOARD_FAB2_LIB.BASEBOARD_FAB2(SCH_1):M_B_DQ(31)   I172 @BASEBOARD_FAB2_LIB.BASEBOARD_FAB2(SCH_1):PAGE24
   C72 M_B_DQ<30> @BASEBOARD_FAB2_LIB.BASEBOARD_FAB2(SCH_1):M_B_DQ(30)   I172 @BASEBOARD_FAB2_LIB.BASEBOARD_FAB2(SCH_1):PAGE24
   G74 M_B_DQ<29> @BASEBOARD_FAB2_LIB.BASEBOARD_FAB2(SCH_1):M_B_DQ(29)   I172 @BASEBOARD_FAB2_LIB.BASEBOARD_FAB2(SCH_1):PAGE24
   F75 M_B_DQ<28> @BASEBOARD_FAB2_LIB.BASEBOARD_FAB2(SCH_1):M_B_DQ(28)   I172 @BASEBOARD_FAB2_LIB.BASEBOARD_FAB2(SCH_1):PAGE24
   F71 M_B_DQ<27> @BASEBOARD_FAB2_LIB.BASEBOARD_FAB2(SCH_1):M_B_DQ(27)   I172 @BASEBOARD_FAB2_LIB.BASEBOARD_FAB2(SCH_1):PAGE24
   D71 M_B_DQ<26> @BASEBOARD_FAB2_LIB.BASEBOARD_FAB2(SCH_1):M_B_DQ(26)   I172 @BASEBOARD_FAB2_LIB.BASEBOARD_FAB2(SCH_1):PAGE24
   C74 M_B_DQ<25> @BASEBOARD_FAB2_LIB.BASEBOARD_FAB2(SCH_1):M_B_DQ(25)   I172 @BASEBOARD_FAB2_LIB.BASEBOARD_FAB2(SCH_1):PAGE24
   D75 M_B_DQ<24> @BASEBOARD_FAB2_LIB.BASEBOARD_FAB2(SCH_1):M_B_DQ(24)   I172 @BASEBOARD_FAB2_LIB.BASEBOARD_FAB2(SCH_1):PAGE24
   J78 M_B_DQ<23> @BASEBOARD_FAB2_LIB.BASEBOARD_FAB2(SCH_1):M_B_DQ(23)   I172 @BASEBOARD_FAB2_LIB.BASEBOARD_FAB2(SCH_1):PAGE24
   E78 M_B_DQ<22> @BASEBOARD_FAB2_LIB.BASEBOARD_FAB2(SCH_1):M_B_DQ(22)   I172 @BASEBOARD_FAB2_LIB.BASEBOARD_FAB2(SCH_1):PAGE24
   H81 M_B_DQ<21> @BASEBOARD_FAB2_LIB.BASEBOARD_FAB2(SCH_1):M_B_DQ(21)   I172 @BASEBOARD_FAB2_LIB.BASEBOARD_FAB2(SCH_1):PAGE24
   F81 M_B_DQ<20> @BASEBOARD_FAB2_LIB.BASEBOARD_FAB2(SCH_1):M_B_DQ(20)   I172 @BASEBOARD_FAB2_LIB.BASEBOARD_FAB2(SCH_1):PAGE24
   H77 M_B_DQ<19> @BASEBOARD_FAB2_LIB.BASEBOARD_FAB2(SCH_1):M_B_DQ(19)   I172 @BASEBOARD_FAB2_LIB.BASEBOARD_FAB2(SCH_1):PAGE24
   F77 M_B_DQ<18> @BASEBOARD_FAB2_LIB.BASEBOARD_FAB2(SCH_1):M_B_DQ(18)   I172 @BASEBOARD_FAB2_LIB.BASEBOARD_FAB2(SCH_1):PAGE24
   J80 M_B_DQ<17> @BASEBOARD_FAB2_LIB.BASEBOARD_FAB2(SCH_1):M_B_DQ(17)   I172 @BASEBOARD_FAB2_LIB.BASEBOARD_FAB2(SCH_1):PAGE24
   E80 M_B_DQ<16> @BASEBOARD_FAB2_LIB.BASEBOARD_FAB2(SCH_1):M_B_DQ(16)   I172 @BASEBOARD_FAB2_LIB.BASEBOARD_FAB2(SCH_1):PAGE24
  AC80 M_B_DQ<15> @BASEBOARD_FAB2_LIB.BASEBOARD_FAB2(SCH_1):M_B_DQ(15)   I172 @BASEBOARD_FAB2_LIB.BASEBOARD_FAB2(SCH_1):PAGE24
  AE82 M_B_DQ<14> @BASEBOARD_FAB2_LIB.BASEBOARD_FAB2(SCH_1):M_B_DQ(14)   I172 @BASEBOARD_FAB2_LIB.BASEBOARD_FAB2(SCH_1):PAGE24
  AH79 M_B_DQ<13> @BASEBOARD_FAB2_LIB.BASEBOARD_FAB2(SCH_1):M_B_DQ(13)   I172 @BASEBOARD_FAB2_LIB.BASEBOARD_FAB2(SCH_1):PAGE24
  AJ80 M_B_DQ<12> @BASEBOARD_FAB2_LIB.BASEBOARD_FAB2(SCH_1):M_B_DQ(12)   I172 @BASEBOARD_FAB2_LIB.BASEBOARD_FAB2(SCH_1):PAGE24
  AB81 M_B_DQ<11> @BASEBOARD_FAB2_LIB.BASEBOARD_FAB2(SCH_1):M_B_DQ(11)   I172 @BASEBOARD_FAB2_LIB.BASEBOARD_FAB2(SCH_1):PAGE24
  AC82 M_B_DQ<10> @BASEBOARD_FAB2_LIB.BASEBOARD_FAB2(SCH_1):M_B_DQ(10)   I172 @BASEBOARD_FAB2_LIB.BASEBOARD_FAB2(SCH_1):PAGE24
  AF79 M_B_DQ<9> @BASEBOARD_FAB2_LIB.BASEBOARD_FAB2(SCH_1):M_B_DQ(9)   I172 @BASEBOARD_FAB2_LIB.BASEBOARD_FAB2(SCH_1):PAGE24
  AH81 M_B_DQ<8> @BASEBOARD_FAB2_LIB.BASEBOARD_FAB2(SCH_1):M_B_DQ(8)   I172 @BASEBOARD_FAB2_LIB.BASEBOARD_FAB2(SCH_1):PAGE24
  AN80 M_B_DQ<7> @BASEBOARD_FAB2_LIB.BASEBOARD_FAB2(SCH_1):M_B_DQ(7)   I172 @BASEBOARD_FAB2_LIB.BASEBOARD_FAB2(SCH_1):PAGE24
  AR82 M_B_DQ<6> @BASEBOARD_FAB2_LIB.BASEBOARD_FAB2(SCH_1):M_B_DQ(6)   I172 @BASEBOARD_FAB2_LIB.BASEBOARD_FAB2(SCH_1):PAGE24
  AV79 M_B_DQ<5> @BASEBOARD_FAB2_LIB.BASEBOARD_FAB2(SCH_1):M_B_DQ(5)   I172 @BASEBOARD_FAB2_LIB.BASEBOARD_FAB2(SCH_1):PAGE24
  AW80 M_B_DQ<4> @BASEBOARD_FAB2_LIB.BASEBOARD_FAB2(SCH_1):M_B_DQ(4)   I172 @BASEBOARD_FAB2_LIB.BASEBOARD_FAB2(SCH_1):PAGE24
  AM81 M_B_DQ<3> @BASEBOARD_FAB2_LIB.BASEBOARD_FAB2(SCH_1):M_B_DQ(3)   I172 @BASEBOARD_FAB2_LIB.BASEBOARD_FAB2(SCH_1):PAGE24
  AN82 M_B_DQ<2> @BASEBOARD_FAB2_LIB.BASEBOARD_FAB2(SCH_1):M_B_DQ(2)   I172 @BASEBOARD_FAB2_LIB.BASEBOARD_FAB2(SCH_1):PAGE24
  AT79 M_B_DQ<1> @BASEBOARD_FAB2_LIB.BASEBOARD_FAB2(SCH_1):M_B_DQ(1)   I172 @BASEBOARD_FAB2_LIB.BASEBOARD_FAB2(SCH_1):PAGE24
  AV81 M_B_DQ<0> @BASEBOARD_FAB2_LIB.BASEBOARD_FAB2(SCH_1):M_B_DQ(0)   I172 @BASEBOARD_FAB2_LIB.BASEBOARD_FAB2(SCH_1):PAGE24
   G68 M_B_DQS_DN<17> @BASEBOARD_FAB2_LIB.BASEBOARD_FAB2(SCH_1):M_B_DQS_DN(17)   I172 @BASEBOARD_FAB2_LIB.BASEBOARD_FAB2(SCH_1):PAGE24
   T27 M_B_DQS_DN<16> @BASEBOARD_FAB2_LIB.BASEBOARD_FAB2(SCH_1):M_B_DQS_DN(16)   I172 @BASEBOARD_FAB2_LIB.BASEBOARD_FAB2(SCH_1):PAGE24
   A28 M_B_DQS_DN<15> @BASEBOARD_FAB2_LIB.BASEBOARD_FAB2(SCH_1):M_B_DQS_DN(15)   I172 @BASEBOARD_FAB2_LIB.BASEBOARD_FAB2(SCH_1):PAGE24
   A34 M_B_DQS_DN<14> @BASEBOARD_FAB2_LIB.BASEBOARD_FAB2(SCH_1):M_B_DQS_DN(14)   I172 @BASEBOARD_FAB2_LIB.BASEBOARD_FAB2(SCH_1):PAGE24
   J42 M_B_DQS_DN<13> @BASEBOARD_FAB2_LIB.BASEBOARD_FAB2(SCH_1):M_B_DQS_DN(13)   I172 @BASEBOARD_FAB2_LIB.BASEBOARD_FAB2(SCH_1):PAGE24
   B73 M_B_DQS_DN<12> @BASEBOARD_FAB2_LIB.BASEBOARD_FAB2(SCH_1):M_B_DQS_DN(12)   I172 @BASEBOARD_FAB2_LIB.BASEBOARD_FAB2(SCH_1):PAGE24
   D79 M_B_DQS_DN<11> @BASEBOARD_FAB2_LIB.BASEBOARD_FAB2(SCH_1):M_B_DQS_DN(11)   I172 @BASEBOARD_FAB2_LIB.BASEBOARD_FAB2(SCH_1):PAGE24
  AG82 M_B_DQS_DN<10> @BASEBOARD_FAB2_LIB.BASEBOARD_FAB2(SCH_1):M_B_DQS_DN(10)   I172 @BASEBOARD_FAB2_LIB.BASEBOARD_FAB2(SCH_1):PAGE24
  AU82 M_B_DQS_DN<9> @BASEBOARD_FAB2_LIB.BASEBOARD_FAB2(SCH_1):M_B_DQS_DN(9)   I172 @BASEBOARD_FAB2_LIB.BASEBOARD_FAB2(SCH_1):PAGE24
   N68 M_B_DQS_DN<8> @BASEBOARD_FAB2_LIB.BASEBOARD_FAB2(SCH_1):M_B_DQS_DN(8)   I172 @BASEBOARD_FAB2_LIB.BASEBOARD_FAB2(SCH_1):PAGE24
  AB27 M_B_DQS_DN<7> @BASEBOARD_FAB2_LIB.BASEBOARD_FAB2(SCH_1):M_B_DQS_DN(7)   I172 @BASEBOARD_FAB2_LIB.BASEBOARD_FAB2(SCH_1):PAGE24
   G28 M_B_DQS_DN<6> @BASEBOARD_FAB2_LIB.BASEBOARD_FAB2(SCH_1):M_B_DQS_DN(6)   I172 @BASEBOARD_FAB2_LIB.BASEBOARD_FAB2(SCH_1):PAGE24
   G34 M_B_DQS_DN<5> @BASEBOARD_FAB2_LIB.BASEBOARD_FAB2(SCH_1):M_B_DQS_DN(5)   I172 @BASEBOARD_FAB2_LIB.BASEBOARD_FAB2(SCH_1):PAGE24
   N42 M_B_DQS_DN<4> @BASEBOARD_FAB2_LIB.BASEBOARD_FAB2(SCH_1):M_B_DQS_DN(4)   I172 @BASEBOARD_FAB2_LIB.BASEBOARD_FAB2(SCH_1):PAGE24
   H73 M_B_DQS_DN<3> @BASEBOARD_FAB2_LIB.BASEBOARD_FAB2(SCH_1):M_B_DQS_DN(3)   I172 @BASEBOARD_FAB2_LIB.BASEBOARD_FAB2(SCH_1):PAGE24
   K79 M_B_DQS_DN<2> @BASEBOARD_FAB2_LIB.BASEBOARD_FAB2(SCH_1):M_B_DQS_DN(2)   I172 @BASEBOARD_FAB2_LIB.BASEBOARD_FAB2(SCH_1):PAGE24
  AD79 M_B_DQS_DN<1> @BASEBOARD_FAB2_LIB.BASEBOARD_FAB2(SCH_1):M_B_DQS_DN(1)   I172 @BASEBOARD_FAB2_LIB.BASEBOARD_FAB2(SCH_1):PAGE24
  AP79 M_B_DQS_DN<0> @BASEBOARD_FAB2_LIB.BASEBOARD_FAB2(SCH_1):M_B_DQS_DN(0)   I172 @BASEBOARD_FAB2_LIB.BASEBOARD_FAB2(SCH_1):PAGE24
   J68 M_B_DQS_DP<17> @BASEBOARD_FAB2_LIB.BASEBOARD_FAB2(SCH_1):M_B_DQS_DP(17)   I172 @BASEBOARD_FAB2_LIB.BASEBOARD_FAB2(SCH_1):PAGE24
   V27 M_B_DQS_DP<16> @BASEBOARD_FAB2_LIB.BASEBOARD_FAB2(SCH_1):M_B_DQS_DP(16)   I172 @BASEBOARD_FAB2_LIB.BASEBOARD_FAB2(SCH_1):PAGE24
   C28 M_B_DQS_DP<15> @BASEBOARD_FAB2_LIB.BASEBOARD_FAB2(SCH_1):M_B_DQS_DP(15)   I172 @BASEBOARD_FAB2_LIB.BASEBOARD_FAB2(SCH_1):PAGE24
   C34 M_B_DQS_DP<14> @BASEBOARD_FAB2_LIB.BASEBOARD_FAB2(SCH_1):M_B_DQS_DP(14)   I172 @BASEBOARD_FAB2_LIB.BASEBOARD_FAB2(SCH_1):PAGE24
   L42 M_B_DQS_DP<13> @BASEBOARD_FAB2_LIB.BASEBOARD_FAB2(SCH_1):M_B_DQS_DP(13)   I172 @BASEBOARD_FAB2_LIB.BASEBOARD_FAB2(SCH_1):PAGE24
   D73 M_B_DQS_DP<12> @BASEBOARD_FAB2_LIB.BASEBOARD_FAB2(SCH_1):M_B_DQS_DP(12)   I172 @BASEBOARD_FAB2_LIB.BASEBOARD_FAB2(SCH_1):PAGE24
   F79 M_B_DQS_DP<11> @BASEBOARD_FAB2_LIB.BASEBOARD_FAB2(SCH_1):M_B_DQS_DP(11)   I172 @BASEBOARD_FAB2_LIB.BASEBOARD_FAB2(SCH_1):PAGE24
  AF81 M_B_DQS_DP<10> @BASEBOARD_FAB2_LIB.BASEBOARD_FAB2(SCH_1):M_B_DQS_DP(10)   I172 @BASEBOARD_FAB2_LIB.BASEBOARD_FAB2(SCH_1):PAGE24
  AT81 M_B_DQS_DP<9> @BASEBOARD_FAB2_LIB.BASEBOARD_FAB2(SCH_1):M_B_DQS_DP(9)   I172 @BASEBOARD_FAB2_LIB.BASEBOARD_FAB2(SCH_1):PAGE24
   L68 M_B_DQS_DP<8> @BASEBOARD_FAB2_LIB.BASEBOARD_FAB2(SCH_1):M_B_DQS_DP(8)   I172 @BASEBOARD_FAB2_LIB.BASEBOARD_FAB2(SCH_1):PAGE24
   Y27 M_B_DQS_DP<7> @BASEBOARD_FAB2_LIB.BASEBOARD_FAB2(SCH_1):M_B_DQS_DP(7)   I172 @BASEBOARD_FAB2_LIB.BASEBOARD_FAB2(SCH_1):PAGE24
   E28 M_B_DQS_DP<6> @BASEBOARD_FAB2_LIB.BASEBOARD_FAB2(SCH_1):M_B_DQS_DP(6)   I172 @BASEBOARD_FAB2_LIB.BASEBOARD_FAB2(SCH_1):PAGE24
   E34 M_B_DQS_DP<5> @BASEBOARD_FAB2_LIB.BASEBOARD_FAB2(SCH_1):M_B_DQS_DP(5)   I172 @BASEBOARD_FAB2_LIB.BASEBOARD_FAB2(SCH_1):PAGE24
   R42 M_B_DQS_DP<4> @BASEBOARD_FAB2_LIB.BASEBOARD_FAB2(SCH_1):M_B_DQS_DP(4)   I172 @BASEBOARD_FAB2_LIB.BASEBOARD_FAB2(SCH_1):PAGE24
   F73 M_B_DQS_DP<3> @BASEBOARD_FAB2_LIB.BASEBOARD_FAB2(SCH_1):M_B_DQS_DP(3)   I172 @BASEBOARD_FAB2_LIB.BASEBOARD_FAB2(SCH_1):PAGE24
   H79 M_B_DQS_DP<2> @BASEBOARD_FAB2_LIB.BASEBOARD_FAB2(SCH_1):M_B_DQS_DP(2)   I172 @BASEBOARD_FAB2_LIB.BASEBOARD_FAB2(SCH_1):PAGE24
  AE80 M_B_DQS_DP<1> @BASEBOARD_FAB2_LIB.BASEBOARD_FAB2(SCH_1):M_B_DQS_DP(1)   I172 @BASEBOARD_FAB2_LIB.BASEBOARD_FAB2(SCH_1):PAGE24
  AR80 M_B_DQS_DP<0> @BASEBOARD_FAB2_LIB.BASEBOARD_FAB2(SCH_1):M_B_DQS_DP(0)   I172 @BASEBOARD_FAB2_LIB.BASEBOARD_FAB2(SCH_1):PAGE24
   M67 M_B_ECC<7> @BASEBOARD_FAB2_LIB.BASEBOARD_FAB2(SCH_1):M_B_ECC(7)   I172 @BASEBOARD_FAB2_LIB.BASEBOARD_FAB2(SCH_1):PAGE24
   H67 M_B_ECC<6> @BASEBOARD_FAB2_LIB.BASEBOARD_FAB2(SCH_1):M_B_ECC(6)   I172 @BASEBOARD_FAB2_LIB.BASEBOARD_FAB2(SCH_1):PAGE24
   M69 M_B_ECC<5> @BASEBOARD_FAB2_LIB.BASEBOARD_FAB2(SCH_1):M_B_ECC(5)   I172 @BASEBOARD_FAB2_LIB.BASEBOARD_FAB2(SCH_1):PAGE24
   L70 M_B_ECC<4> @BASEBOARD_FAB2_LIB.BASEBOARD_FAB2(SCH_1):M_B_ECC(4)   I172 @BASEBOARD_FAB2_LIB.BASEBOARD_FAB2(SCH_1):PAGE24
   L66 M_B_ECC<3> @BASEBOARD_FAB2_LIB.BASEBOARD_FAB2(SCH_1):M_B_ECC(3)   I172 @BASEBOARD_FAB2_LIB.BASEBOARD_FAB2(SCH_1):PAGE24
   J66 M_B_ECC<2> @BASEBOARD_FAB2_LIB.BASEBOARD_FAB2(SCH_1):M_B_ECC(2)   I172 @BASEBOARD_FAB2_LIB.BASEBOARD_FAB2(SCH_1):PAGE24
   H69 M_B_ECC<1> @BASEBOARD_FAB2_LIB.BASEBOARD_FAB2(SCH_1):M_B_ECC(1)   I172 @BASEBOARD_FAB2_LIB.BASEBOARD_FAB2(SCH_1):PAGE24
   J70 M_B_ECC<0> @BASEBOARD_FAB2_LIB.BASEBOARD_FAB2(SCH_1):M_B_ECC(0)   I172 @BASEBOARD_FAB2_LIB.BASEBOARD_FAB2(SCH_1):PAGE24
   N48 M_B_MA<17> @BASEBOARD_FAB2_LIB.BASEBOARD_FAB2(SCH_1):M_B_MA(17)   I172 @BASEBOARD_FAB2_LIB.BASEBOARD_FAB2(SCH_1):PAGE24
   R52 M_B_MA<16> @BASEBOARD_FAB2_LIB.BASEBOARD_FAB2(SCH_1):M_B_MA(16)   I172 @BASEBOARD_FAB2_LIB.BASEBOARD_FAB2(SCH_1):PAGE24
   N52 M_B_MA<15> @BASEBOARD_FAB2_LIB.BASEBOARD_FAB2(SCH_1):M_B_MA(15)   I172 @BASEBOARD_FAB2_LIB.BASEBOARD_FAB2(SCH_1):PAGE24
   T51 M_B_MA<14> @BASEBOARD_FAB2_LIB.BASEBOARD_FAB2(SCH_1):M_B_MA(14)   I172 @BASEBOARD_FAB2_LIB.BASEBOARD_FAB2(SCH_1):PAGE24
   M51 M_B_MA<13> @BASEBOARD_FAB2_LIB.BASEBOARD_FAB2(SCH_1):M_B_MA(13)   I172 @BASEBOARD_FAB2_LIB.BASEBOARD_FAB2(SCH_1):PAGE24
   T61 M_B_MA<12> @BASEBOARD_FAB2_LIB.BASEBOARD_FAB2(SCH_1):M_B_MA(12)   I172 @BASEBOARD_FAB2_LIB.BASEBOARD_FAB2(SCH_1):PAGE24
   R60 M_B_MA<11> @BASEBOARD_FAB2_LIB.BASEBOARD_FAB2(SCH_1):M_B_MA(11)   I172 @BASEBOARD_FAB2_LIB.BASEBOARD_FAB2(SCH_1):PAGE24
   M55 M_B_MA<10> @BASEBOARD_FAB2_LIB.BASEBOARD_FAB2(SCH_1):M_B_MA(10)   I172 @BASEBOARD_FAB2_LIB.BASEBOARD_FAB2(SCH_1):PAGE24
   K59 M_B_MA<9> @BASEBOARD_FAB2_LIB.BASEBOARD_FAB2(SCH_1):M_B_MA(9)   I172 @BASEBOARD_FAB2_LIB.BASEBOARD_FAB2(SCH_1):PAGE24
   W60 M_B_MA<8> @BASEBOARD_FAB2_LIB.BASEBOARD_FAB2(SCH_1):M_B_MA(8)   I172 @BASEBOARD_FAB2_LIB.BASEBOARD_FAB2(SCH_1):PAGE24
   V61 M_B_MA<7> @BASEBOARD_FAB2_LIB.BASEBOARD_FAB2(SCH_1):M_B_MA(7)   I172 @BASEBOARD_FAB2_LIB.BASEBOARD_FAB2(SCH_1):PAGE24
   T59 M_B_MA<6> @BASEBOARD_FAB2_LIB.BASEBOARD_FAB2(SCH_1):M_B_MA(6)   I172 @BASEBOARD_FAB2_LIB.BASEBOARD_FAB2(SCH_1):PAGE24
   R58 M_B_MA<5> @BASEBOARD_FAB2_LIB.BASEBOARD_FAB2(SCH_1):M_B_MA(5)   I172 @BASEBOARD_FAB2_LIB.BASEBOARD_FAB2(SCH_1):PAGE24
   M59 M_B_MA<4> @BASEBOARD_FAB2_LIB.BASEBOARD_FAB2(SCH_1):M_B_MA(4)   I172 @BASEBOARD_FAB2_LIB.BASEBOARD_FAB2(SCH_1):PAGE24
   N58 M_B_MA<3> @BASEBOARD_FAB2_LIB.BASEBOARD_FAB2(SCH_1):M_B_MA(3)   I172 @BASEBOARD_FAB2_LIB.BASEBOARD_FAB2(SCH_1):PAGE24
   K57 M_B_MA<2> @BASEBOARD_FAB2_LIB.BASEBOARD_FAB2(SCH_1):M_B_MA(2)   I172 @BASEBOARD_FAB2_LIB.BASEBOARD_FAB2(SCH_1):PAGE24
   J58 M_B_MA<1> @BASEBOARD_FAB2_LIB.BASEBOARD_FAB2(SCH_1):M_B_MA(1)   I172 @BASEBOARD_FAB2_LIB.BASEBOARD_FAB2(SCH_1):PAGE24
   J52 M_B_MA<0> @BASEBOARD_FAB2_LIB.BASEBOARD_FAB2(SCH_1):M_B_MA(0)   I172 @BASEBOARD_FAB2_LIB.BASEBOARD_FAB2(SCH_1):PAGE24
   T47 M_B_ODT<3> @BASEBOARD_FAB2_LIB.BASEBOARD_FAB2(SCH_1):M_B_ODT(3)   I172 @BASEBOARD_FAB2_LIB.BASEBOARD_FAB2(SCH_1):PAGE24
   M49 M_B_ODT<2> @BASEBOARD_FAB2_LIB.BASEBOARD_FAB2(SCH_1):M_B_ODT(2)   I172 @BASEBOARD_FAB2_LIB.BASEBOARD_FAB2(SCH_1):PAGE24
   R48 M_B_ODT<1> @BASEBOARD_FAB2_LIB.BASEBOARD_FAB2(SCH_1):M_B_ODT(1)   I172 @BASEBOARD_FAB2_LIB.BASEBOARD_FAB2(SCH_1):PAGE24
   N50 M_B_ODT<0> @BASEBOARD_FAB2_LIB.BASEBOARD_FAB2(SCH_1):M_B_ODT(0)   I172 @BASEBOARD_FAB2_LIB.BASEBOARD_FAB2(SCH_1):PAGE24
   K53 M_B_PAR @BASEBOARD_FAB2_LIB.BASEBOARD_FAB2(SCH_1):M_B_PAR   I172 @BASEBOARD_FAB2_LIB.BASEBOARD_FAB2(SCH_1):PAGE24
  AB61 M_C_ACT_N @BASEBOARD_FAB2_LIB.BASEBOARD_FAB2(SCH_1):M_C_ACT_N   I172 @BASEBOARD_FAB2_LIB.BASEBOARD_FAB2(SCH_1):PAGE25
  AD61 M_C_ALERT_N @BASEBOARD_FAB2_LIB.BASEBOARD_FAB2(SCH_1):M_C_ALERT_N   I172 @BASEBOARD_FAB2_LIB.BASEBOARD_FAB2(SCH_1):PAGE25
  AE56 M_C_BA<1> @BASEBOARD_FAB2_LIB.BASEBOARD_FAB2(SCH_1):M_C_BA(1)   I172 @BASEBOARD_FAB2_LIB.BASEBOARD_FAB2(SCH_1):PAGE25
   W52 M_C_BA<0> @BASEBOARD_FAB2_LIB.BASEBOARD_FAB2(SCH_1):M_C_BA(0)   I172 @BASEBOARD_FAB2_LIB.BASEBOARD_FAB2(SCH_1):PAGE25
  AE62 M_C_BG<1> @BASEBOARD_FAB2_LIB.BASEBOARD_FAB2(SCH_1):M_C_BG(1)   I172 @BASEBOARD_FAB2_LIB.BASEBOARD_FAB2(SCH_1):PAGE25
  AA60 M_C_BG<0> @BASEBOARD_FAB2_LIB.BASEBOARD_FAB2(SCH_1):M_C_BG(0)   I172 @BASEBOARD_FAB2_LIB.BASEBOARD_FAB2(SCH_1):PAGE25
  AB45 M_C_C<2> @BASEBOARD_FAB2_LIB.BASEBOARD_FAB2(SCH_1):M_C_C(2)   I172 @BASEBOARD_FAB2_LIB.BASEBOARD_FAB2(SCH_1):PAGE25
  AB63 M_C_CKE<3> @BASEBOARD_FAB2_LIB.BASEBOARD_FAB2(SCH_1):M_C_CKE(3)   I172 @BASEBOARD_FAB2_LIB.BASEBOARD_FAB2(SCH_1):PAGE25
   V63 M_C_CKE<2> @BASEBOARD_FAB2_LIB.BASEBOARD_FAB2(SCH_1):M_C_CKE(2)   I172 @BASEBOARD_FAB2_LIB.BASEBOARD_FAB2(SCH_1):PAGE25
  AD63 M_C_CKE<1> @BASEBOARD_FAB2_LIB.BASEBOARD_FAB2(SCH_1):M_C_CKE(1)   I172 @BASEBOARD_FAB2_LIB.BASEBOARD_FAB2(SCH_1):PAGE25
  AA62 M_C_CKE<0> @BASEBOARD_FAB2_LIB.BASEBOARD_FAB2(SCH_1):M_C_CKE(0)   I172 @BASEBOARD_FAB2_LIB.BASEBOARD_FAB2(SCH_1):PAGE25
   W56 M_C_CLK_DN<3> @BASEBOARD_FAB2_LIB.BASEBOARD_FAB2(SCH_1):M_C_CLK_DN(3)   I172 @BASEBOARD_FAB2_LIB.BASEBOARD_FAB2(SCH_1):PAGE25
  AA56 M_C_CLK_DN<2> @BASEBOARD_FAB2_LIB.BASEBOARD_FAB2(SCH_1):M_C_CLK_DN(2)   I172 @BASEBOARD_FAB2_LIB.BASEBOARD_FAB2(SCH_1):PAGE25
   W54 M_C_CLK_DN<1> @BASEBOARD_FAB2_LIB.BASEBOARD_FAB2(SCH_1):M_C_CLK_DN(1)   I172 @BASEBOARD_FAB2_LIB.BASEBOARD_FAB2(SCH_1):PAGE25
  AA54 M_C_CLK_DN<0> @BASEBOARD_FAB2_LIB.BASEBOARD_FAB2(SCH_1):M_C_CLK_DN(0)   I172 @BASEBOARD_FAB2_LIB.BASEBOARD_FAB2(SCH_1):PAGE25
   V57 M_C_CLK_DP<3> @BASEBOARD_FAB2_LIB.BASEBOARD_FAB2(SCH_1):M_C_CLK_DP(3)   I172 @BASEBOARD_FAB2_LIB.BASEBOARD_FAB2(SCH_1):PAGE25
  AB57 M_C_CLK_DP<2> @BASEBOARD_FAB2_LIB.BASEBOARD_FAB2(SCH_1):M_C_CLK_DP(2)   I172 @BASEBOARD_FAB2_LIB.BASEBOARD_FAB2(SCH_1):PAGE25
   V55 M_C_CLK_DP<1> @BASEBOARD_FAB2_LIB.BASEBOARD_FAB2(SCH_1):M_C_CLK_DP(1)   I172 @BASEBOARD_FAB2_LIB.BASEBOARD_FAB2(SCH_1):PAGE25
  AB55 M_C_CLK_DP<0> @BASEBOARD_FAB2_LIB.BASEBOARD_FAB2(SCH_1):M_C_CLK_DP(0)   I172 @BASEBOARD_FAB2_LIB.BASEBOARD_FAB2(SCH_1):PAGE25
   V45 M_C_CS_N<7> @BASEBOARD_FAB2_LIB.BASEBOARD_FAB2(SCH_1):M_C_CS_N(7)   I172 @BASEBOARD_FAB2_LIB.BASEBOARD_FAB2(SCH_1):PAGE25
   T45 M_C_CS_N<6> @BASEBOARD_FAB2_LIB.BASEBOARD_FAB2(SCH_1):M_C_CS_N(6)   I172 @BASEBOARD_FAB2_LIB.BASEBOARD_FAB2(SCH_1):PAGE25
   W48 M_C_CS_N<5> @BASEBOARD_FAB2_LIB.BASEBOARD_FAB2(SCH_1):M_C_CS_N(5)   I172 @BASEBOARD_FAB2_LIB.BASEBOARD_FAB2(SCH_1):PAGE25
  AB51 M_C_CS_N<4> @BASEBOARD_FAB2_LIB.BASEBOARD_FAB2(SCH_1):M_C_CS_N(4)   I172 @BASEBOARD_FAB2_LIB.BASEBOARD_FAB2(SCH_1):PAGE25
  AA46 M_C_CS_N<3> @BASEBOARD_FAB2_LIB.BASEBOARD_FAB2(SCH_1):M_C_CS_N(3)   I172 @BASEBOARD_FAB2_LIB.BASEBOARD_FAB2(SCH_1):PAGE25
   W46 M_C_CS_N<2> @BASEBOARD_FAB2_LIB.BASEBOARD_FAB2(SCH_1):M_C_CS_N(2)   I172 @BASEBOARD_FAB2_LIB.BASEBOARD_FAB2(SCH_1):PAGE25
  AB49 M_C_CS_N<1> @BASEBOARD_FAB2_LIB.BASEBOARD_FAB2(SCH_1):M_C_CS_N(1)   I172 @BASEBOARD_FAB2_LIB.BASEBOARD_FAB2(SCH_1):PAGE25
   V51 M_C_CS_N<0> @BASEBOARD_FAB2_LIB.BASEBOARD_FAB2(SCH_1):M_C_CS_N(0)   I172 @BASEBOARD_FAB2_LIB.BASEBOARD_FAB2(SCH_1):PAGE25
  AH23 M_C_DQ<63> @BASEBOARD_FAB2_LIB.BASEBOARD_FAB2(SCH_1):M_C_DQ(63)   I172 @BASEBOARD_FAB2_LIB.BASEBOARD_FAB2(SCH_1):PAGE25
  AD23 M_C_DQ<62> @BASEBOARD_FAB2_LIB.BASEBOARD_FAB2(SCH_1):M_C_DQ(62)   I172 @BASEBOARD_FAB2_LIB.BASEBOARD_FAB2(SCH_1):PAGE25
  AG26 M_C_DQ<61> @BASEBOARD_FAB2_LIB.BASEBOARD_FAB2(SCH_1):M_C_DQ(61)   I172 @BASEBOARD_FAB2_LIB.BASEBOARD_FAB2(SCH_1):PAGE25
  AE26 M_C_DQ<60> @BASEBOARD_FAB2_LIB.BASEBOARD_FAB2(SCH_1):M_C_DQ(60)   I172 @BASEBOARD_FAB2_LIB.BASEBOARD_FAB2(SCH_1):PAGE25
  AG22 M_C_DQ<59> @BASEBOARD_FAB2_LIB.BASEBOARD_FAB2(SCH_1):M_C_DQ(59)   I172 @BASEBOARD_FAB2_LIB.BASEBOARD_FAB2(SCH_1):PAGE25
  AE22 M_C_DQ<58> @BASEBOARD_FAB2_LIB.BASEBOARD_FAB2(SCH_1):M_C_DQ(58)   I172 @BASEBOARD_FAB2_LIB.BASEBOARD_FAB2(SCH_1):PAGE25
  AH25 M_C_DQ<57> @BASEBOARD_FAB2_LIB.BASEBOARD_FAB2(SCH_1):M_C_DQ(57)   I172 @BASEBOARD_FAB2_LIB.BASEBOARD_FAB2(SCH_1):PAGE25
  AD25 M_C_DQ<56> @BASEBOARD_FAB2_LIB.BASEBOARD_FAB2(SCH_1):M_C_DQ(56)   I172 @BASEBOARD_FAB2_LIB.BASEBOARD_FAB2(SCH_1):PAGE25
  AH29 M_C_DQ<55> @BASEBOARD_FAB2_LIB.BASEBOARD_FAB2(SCH_1):M_C_DQ(55)   I172 @BASEBOARD_FAB2_LIB.BASEBOARD_FAB2(SCH_1):PAGE25
  AD29 M_C_DQ<54> @BASEBOARD_FAB2_LIB.BASEBOARD_FAB2(SCH_1):M_C_DQ(54)   I172 @BASEBOARD_FAB2_LIB.BASEBOARD_FAB2(SCH_1):PAGE25
  AG32 M_C_DQ<53> @BASEBOARD_FAB2_LIB.BASEBOARD_FAB2(SCH_1):M_C_DQ(53)   I172 @BASEBOARD_FAB2_LIB.BASEBOARD_FAB2(SCH_1):PAGE25
  AE32 M_C_DQ<52> @BASEBOARD_FAB2_LIB.BASEBOARD_FAB2(SCH_1):M_C_DQ(52)   I172 @BASEBOARD_FAB2_LIB.BASEBOARD_FAB2(SCH_1):PAGE25
  AG28 M_C_DQ<51> @BASEBOARD_FAB2_LIB.BASEBOARD_FAB2(SCH_1):M_C_DQ(51)   I172 @BASEBOARD_FAB2_LIB.BASEBOARD_FAB2(SCH_1):PAGE25
  AE28 M_C_DQ<50> @BASEBOARD_FAB2_LIB.BASEBOARD_FAB2(SCH_1):M_C_DQ(50)   I172 @BASEBOARD_FAB2_LIB.BASEBOARD_FAB2(SCH_1):PAGE25
  AH31 M_C_DQ<49> @BASEBOARD_FAB2_LIB.BASEBOARD_FAB2(SCH_1):M_C_DQ(49)   I172 @BASEBOARD_FAB2_LIB.BASEBOARD_FAB2(SCH_1):PAGE25
  AD31 M_C_DQ<48> @BASEBOARD_FAB2_LIB.BASEBOARD_FAB2(SCH_1):M_C_DQ(48)   I172 @BASEBOARD_FAB2_LIB.BASEBOARD_FAB2(SCH_1):PAGE25
  AA32 M_C_DQ<47> @BASEBOARD_FAB2_LIB.BASEBOARD_FAB2(SCH_1):M_C_DQ(47)   I172 @BASEBOARD_FAB2_LIB.BASEBOARD_FAB2(SCH_1):PAGE25
   U32 M_C_DQ<46> @BASEBOARD_FAB2_LIB.BASEBOARD_FAB2(SCH_1):M_C_DQ(46)   I172 @BASEBOARD_FAB2_LIB.BASEBOARD_FAB2(SCH_1):PAGE25
   Y35 M_C_DQ<45> @BASEBOARD_FAB2_LIB.BASEBOARD_FAB2(SCH_1):M_C_DQ(45)   I172 @BASEBOARD_FAB2_LIB.BASEBOARD_FAB2(SCH_1):PAGE25
   V35 M_C_DQ<44> @BASEBOARD_FAB2_LIB.BASEBOARD_FAB2(SCH_1):M_C_DQ(44)   I172 @BASEBOARD_FAB2_LIB.BASEBOARD_FAB2(SCH_1):PAGE25
   Y31 M_C_DQ<43> @BASEBOARD_FAB2_LIB.BASEBOARD_FAB2(SCH_1):M_C_DQ(43)   I172 @BASEBOARD_FAB2_LIB.BASEBOARD_FAB2(SCH_1):PAGE25
   V31 M_C_DQ<42> @BASEBOARD_FAB2_LIB.BASEBOARD_FAB2(SCH_1):M_C_DQ(42)   I172 @BASEBOARD_FAB2_LIB.BASEBOARD_FAB2(SCH_1):PAGE25
  AA34 M_C_DQ<41> @BASEBOARD_FAB2_LIB.BASEBOARD_FAB2(SCH_1):M_C_DQ(41)   I172 @BASEBOARD_FAB2_LIB.BASEBOARD_FAB2(SCH_1):PAGE25
   U34 M_C_DQ<40> @BASEBOARD_FAB2_LIB.BASEBOARD_FAB2(SCH_1):M_C_DQ(40)   I172 @BASEBOARD_FAB2_LIB.BASEBOARD_FAB2(SCH_1):PAGE25
  AA38 M_C_DQ<39> @BASEBOARD_FAB2_LIB.BASEBOARD_FAB2(SCH_1):M_C_DQ(39)   I172 @BASEBOARD_FAB2_LIB.BASEBOARD_FAB2(SCH_1):PAGE25
   U38 M_C_DQ<38> @BASEBOARD_FAB2_LIB.BASEBOARD_FAB2(SCH_1):M_C_DQ(38)   I172 @BASEBOARD_FAB2_LIB.BASEBOARD_FAB2(SCH_1):PAGE25
   Y41 M_C_DQ<37> @BASEBOARD_FAB2_LIB.BASEBOARD_FAB2(SCH_1):M_C_DQ(37)   I172 @BASEBOARD_FAB2_LIB.BASEBOARD_FAB2(SCH_1):PAGE25
   V41 M_C_DQ<36> @BASEBOARD_FAB2_LIB.BASEBOARD_FAB2(SCH_1):M_C_DQ(36)   I172 @BASEBOARD_FAB2_LIB.BASEBOARD_FAB2(SCH_1):PAGE25
   Y37 M_C_DQ<35> @BASEBOARD_FAB2_LIB.BASEBOARD_FAB2(SCH_1):M_C_DQ(35)   I172 @BASEBOARD_FAB2_LIB.BASEBOARD_FAB2(SCH_1):PAGE25
   V37 M_C_DQ<34> @BASEBOARD_FAB2_LIB.BASEBOARD_FAB2(SCH_1):M_C_DQ(34)   I172 @BASEBOARD_FAB2_LIB.BASEBOARD_FAB2(SCH_1):PAGE25
  AA40 M_C_DQ<33> @BASEBOARD_FAB2_LIB.BASEBOARD_FAB2(SCH_1):M_C_DQ(33)   I172 @BASEBOARD_FAB2_LIB.BASEBOARD_FAB2(SCH_1):PAGE25
   U40 M_C_DQ<32> @BASEBOARD_FAB2_LIB.BASEBOARD_FAB2(SCH_1):M_C_DQ(32)   I172 @BASEBOARD_FAB2_LIB.BASEBOARD_FAB2(SCH_1):PAGE25
  AT65 M_C_DQ<31> @BASEBOARD_FAB2_LIB.BASEBOARD_FAB2(SCH_1):M_C_DQ(31)   I172 @BASEBOARD_FAB2_LIB.BASEBOARD_FAB2(SCH_1):PAGE25
  AM65 M_C_DQ<30> @BASEBOARD_FAB2_LIB.BASEBOARD_FAB2(SCH_1):M_C_DQ(30)   I172 @BASEBOARD_FAB2_LIB.BASEBOARD_FAB2(SCH_1):PAGE25
  AR68 M_C_DQ<29> @BASEBOARD_FAB2_LIB.BASEBOARD_FAB2(SCH_1):M_C_DQ(29)   I172 @BASEBOARD_FAB2_LIB.BASEBOARD_FAB2(SCH_1):PAGE25
  AN68 M_C_DQ<28> @BASEBOARD_FAB2_LIB.BASEBOARD_FAB2(SCH_1):M_C_DQ(28)   I172 @BASEBOARD_FAB2_LIB.BASEBOARD_FAB2(SCH_1):PAGE25
  AR64 M_C_DQ<27> @BASEBOARD_FAB2_LIB.BASEBOARD_FAB2(SCH_1):M_C_DQ(27)   I172 @BASEBOARD_FAB2_LIB.BASEBOARD_FAB2(SCH_1):PAGE25
  AN64 M_C_DQ<26> @BASEBOARD_FAB2_LIB.BASEBOARD_FAB2(SCH_1):M_C_DQ(26)   I172 @BASEBOARD_FAB2_LIB.BASEBOARD_FAB2(SCH_1):PAGE25
  AT67 M_C_DQ<25> @BASEBOARD_FAB2_LIB.BASEBOARD_FAB2(SCH_1):M_C_DQ(25)   I172 @BASEBOARD_FAB2_LIB.BASEBOARD_FAB2(SCH_1):PAGE25
  AM67 M_C_DQ<24> @BASEBOARD_FAB2_LIB.BASEBOARD_FAB2(SCH_1):M_C_DQ(24)   I172 @BASEBOARD_FAB2_LIB.BASEBOARD_FAB2(SCH_1):PAGE25
   V69 M_C_DQ<23> @BASEBOARD_FAB2_LIB.BASEBOARD_FAB2(SCH_1):M_C_DQ(23)   I172 @BASEBOARD_FAB2_LIB.BASEBOARD_FAB2(SCH_1):PAGE25
   T71 M_C_DQ<22> @BASEBOARD_FAB2_LIB.BASEBOARD_FAB2(SCH_1):M_C_DQ(22)   I172 @BASEBOARD_FAB2_LIB.BASEBOARD_FAB2(SCH_1):PAGE25
  AB71 M_C_DQ<21> @BASEBOARD_FAB2_LIB.BASEBOARD_FAB2(SCH_1):M_C_DQ(21)   I172 @BASEBOARD_FAB2_LIB.BASEBOARD_FAB2(SCH_1):PAGE25
  AA72 M_C_DQ<20> @BASEBOARD_FAB2_LIB.BASEBOARD_FAB2(SCH_1):M_C_DQ(20)   I172 @BASEBOARD_FAB2_LIB.BASEBOARD_FAB2(SCH_1):PAGE25
   T69 M_C_DQ<19> @BASEBOARD_FAB2_LIB.BASEBOARD_FAB2(SCH_1):M_C_DQ(19)   I172 @BASEBOARD_FAB2_LIB.BASEBOARD_FAB2(SCH_1):PAGE25
   R70 M_C_DQ<18> @BASEBOARD_FAB2_LIB.BASEBOARD_FAB2(SCH_1):M_C_DQ(18)   I172 @BASEBOARD_FAB2_LIB.BASEBOARD_FAB2(SCH_1):PAGE25
  AA70 M_C_DQ<17> @BASEBOARD_FAB2_LIB.BASEBOARD_FAB2(SCH_1):M_C_DQ(17)   I172 @BASEBOARD_FAB2_LIB.BASEBOARD_FAB2(SCH_1):PAGE25
   W72 M_C_DQ<16> @BASEBOARD_FAB2_LIB.BASEBOARD_FAB2(SCH_1):M_C_DQ(16)   I172 @BASEBOARD_FAB2_LIB.BASEBOARD_FAB2(SCH_1):PAGE25
   Y75 M_C_DQ<15> @BASEBOARD_FAB2_LIB.BASEBOARD_FAB2(SCH_1):M_C_DQ(15)   I172 @BASEBOARD_FAB2_LIB.BASEBOARD_FAB2(SCH_1):PAGE25
  AB77 M_C_DQ<14> @BASEBOARD_FAB2_LIB.BASEBOARD_FAB2(SCH_1):M_C_DQ(14)   I172 @BASEBOARD_FAB2_LIB.BASEBOARD_FAB2(SCH_1):PAGE25
  AE74 M_C_DQ<13> @BASEBOARD_FAB2_LIB.BASEBOARD_FAB2(SCH_1):M_C_DQ(13)   I172 @BASEBOARD_FAB2_LIB.BASEBOARD_FAB2(SCH_1):PAGE25
  AF75 M_C_DQ<12> @BASEBOARD_FAB2_LIB.BASEBOARD_FAB2(SCH_1):M_C_DQ(12)   I172 @BASEBOARD_FAB2_LIB.BASEBOARD_FAB2(SCH_1):PAGE25
   W76 M_C_DQ<11> @BASEBOARD_FAB2_LIB.BASEBOARD_FAB2(SCH_1):M_C_DQ(11)   I172 @BASEBOARD_FAB2_LIB.BASEBOARD_FAB2(SCH_1):PAGE25
   Y77 M_C_DQ<10> @BASEBOARD_FAB2_LIB.BASEBOARD_FAB2(SCH_1):M_C_DQ(10)   I172 @BASEBOARD_FAB2_LIB.BASEBOARD_FAB2(SCH_1):PAGE25
  AC74 M_C_DQ<9> @BASEBOARD_FAB2_LIB.BASEBOARD_FAB2(SCH_1):M_C_DQ(9)   I172 @BASEBOARD_FAB2_LIB.BASEBOARD_FAB2(SCH_1):PAGE25
  AE76 M_C_DQ<8> @BASEBOARD_FAB2_LIB.BASEBOARD_FAB2(SCH_1):M_C_DQ(8)   I172 @BASEBOARD_FAB2_LIB.BASEBOARD_FAB2(SCH_1):PAGE25
  AK75 M_C_DQ<7> @BASEBOARD_FAB2_LIB.BASEBOARD_FAB2(SCH_1):M_C_DQ(7)   I172 @BASEBOARD_FAB2_LIB.BASEBOARD_FAB2(SCH_1):PAGE25
  AM77 M_C_DQ<6> @BASEBOARD_FAB2_LIB.BASEBOARD_FAB2(SCH_1):M_C_DQ(6)   I172 @BASEBOARD_FAB2_LIB.BASEBOARD_FAB2(SCH_1):PAGE25
  AR74 M_C_DQ<5> @BASEBOARD_FAB2_LIB.BASEBOARD_FAB2(SCH_1):M_C_DQ(5)   I172 @BASEBOARD_FAB2_LIB.BASEBOARD_FAB2(SCH_1):PAGE25
  AT75 M_C_DQ<4> @BASEBOARD_FAB2_LIB.BASEBOARD_FAB2(SCH_1):M_C_DQ(4)   I172 @BASEBOARD_FAB2_LIB.BASEBOARD_FAB2(SCH_1):PAGE25
  AJ76 M_C_DQ<3> @BASEBOARD_FAB2_LIB.BASEBOARD_FAB2(SCH_1):M_C_DQ(3)   I172 @BASEBOARD_FAB2_LIB.BASEBOARD_FAB2(SCH_1):PAGE25
  AK77 M_C_DQ<2> @BASEBOARD_FAB2_LIB.BASEBOARD_FAB2(SCH_1):M_C_DQ(2)   I172 @BASEBOARD_FAB2_LIB.BASEBOARD_FAB2(SCH_1):PAGE25
  AN74 M_C_DQ<1> @BASEBOARD_FAB2_LIB.BASEBOARD_FAB2(SCH_1):M_C_DQ(1)   I172 @BASEBOARD_FAB2_LIB.BASEBOARD_FAB2(SCH_1):PAGE25
  AR76 M_C_DQ<0> @BASEBOARD_FAB2_LIB.BASEBOARD_FAB2(SCH_1):M_C_DQ(0)   I172 @BASEBOARD_FAB2_LIB.BASEBOARD_FAB2(SCH_1):PAGE25
  AT71 M_C_DQS_DN<17> @BASEBOARD_FAB2_LIB.BASEBOARD_FAB2(SCH_1):M_C_DQS_DN(17)   I172 @BASEBOARD_FAB2_LIB.BASEBOARD_FAB2(SCH_1):PAGE25
  AC24 M_C_DQS_DN<16> @BASEBOARD_FAB2_LIB.BASEBOARD_FAB2(SCH_1):M_C_DQS_DN(16)   I172 @BASEBOARD_FAB2_LIB.BASEBOARD_FAB2(SCH_1):PAGE25
  AC30 M_C_DQS_DN<15> @BASEBOARD_FAB2_LIB.BASEBOARD_FAB2(SCH_1):M_C_DQS_DN(15)   I172 @BASEBOARD_FAB2_LIB.BASEBOARD_FAB2(SCH_1):PAGE25
   T33 M_C_DQS_DN<14> @BASEBOARD_FAB2_LIB.BASEBOARD_FAB2(SCH_1):M_C_DQS_DN(14)   I172 @BASEBOARD_FAB2_LIB.BASEBOARD_FAB2(SCH_1):PAGE25
   T39 M_C_DQS_DN<13> @BASEBOARD_FAB2_LIB.BASEBOARD_FAB2(SCH_1):M_C_DQS_DN(13)   I172 @BASEBOARD_FAB2_LIB.BASEBOARD_FAB2(SCH_1):PAGE25
  AL66 M_C_DQS_DN<12> @BASEBOARD_FAB2_LIB.BASEBOARD_FAB2(SCH_1):M_C_DQS_DN(12)   I172 @BASEBOARD_FAB2_LIB.BASEBOARD_FAB2(SCH_1):PAGE25
   U72 M_C_DQS_DN<11> @BASEBOARD_FAB2_LIB.BASEBOARD_FAB2(SCH_1):M_C_DQS_DN(11)   I172 @BASEBOARD_FAB2_LIB.BASEBOARD_FAB2(SCH_1):PAGE25
  AD77 M_C_DQS_DN<10> @BASEBOARD_FAB2_LIB.BASEBOARD_FAB2(SCH_1):M_C_DQS_DN(10)   I172 @BASEBOARD_FAB2_LIB.BASEBOARD_FAB2(SCH_1):PAGE25
  AP77 M_C_DQS_DN<9> @BASEBOARD_FAB2_LIB.BASEBOARD_FAB2(SCH_1):M_C_DQS_DN(9)   I172 @BASEBOARD_FAB2_LIB.BASEBOARD_FAB2(SCH_1):PAGE25
  BB71 M_C_DQS_DN<8> @BASEBOARD_FAB2_LIB.BASEBOARD_FAB2(SCH_1):M_C_DQS_DN(8)   I172 @BASEBOARD_FAB2_LIB.BASEBOARD_FAB2(SCH_1):PAGE25
  AJ24 M_C_DQS_DN<7> @BASEBOARD_FAB2_LIB.BASEBOARD_FAB2(SCH_1):M_C_DQS_DN(7)   I172 @BASEBOARD_FAB2_LIB.BASEBOARD_FAB2(SCH_1):PAGE25
  AJ30 M_C_DQS_DN<6> @BASEBOARD_FAB2_LIB.BASEBOARD_FAB2(SCH_1):M_C_DQS_DN(6)   I172 @BASEBOARD_FAB2_LIB.BASEBOARD_FAB2(SCH_1):PAGE25
  AB33 M_C_DQS_DN<5> @BASEBOARD_FAB2_LIB.BASEBOARD_FAB2(SCH_1):M_C_DQS_DN(5)   I172 @BASEBOARD_FAB2_LIB.BASEBOARD_FAB2(SCH_1):PAGE25
  AB39 M_C_DQS_DN<4> @BASEBOARD_FAB2_LIB.BASEBOARD_FAB2(SCH_1):M_C_DQS_DN(4)   I172 @BASEBOARD_FAB2_LIB.BASEBOARD_FAB2(SCH_1):PAGE25
  AU66 M_C_DQS_DN<3> @BASEBOARD_FAB2_LIB.BASEBOARD_FAB2(SCH_1):M_C_DQS_DN(3)   I172 @BASEBOARD_FAB2_LIB.BASEBOARD_FAB2(SCH_1):PAGE25
   Y69 M_C_DQS_DN<2> @BASEBOARD_FAB2_LIB.BASEBOARD_FAB2(SCH_1):M_C_DQS_DN(2)   I172 @BASEBOARD_FAB2_LIB.BASEBOARD_FAB2(SCH_1):PAGE25
  AA74 M_C_DQS_DN<1> @BASEBOARD_FAB2_LIB.BASEBOARD_FAB2(SCH_1):M_C_DQS_DN(1)   I172 @BASEBOARD_FAB2_LIB.BASEBOARD_FAB2(SCH_1):PAGE25
  AL74 M_C_DQS_DN<0> @BASEBOARD_FAB2_LIB.BASEBOARD_FAB2(SCH_1):M_C_DQS_DN(0)   I172 @BASEBOARD_FAB2_LIB.BASEBOARD_FAB2(SCH_1):PAGE25
  AV71 M_C_DQS_DP<17> @BASEBOARD_FAB2_LIB.BASEBOARD_FAB2(SCH_1):M_C_DQS_DP(17)   I172 @BASEBOARD_FAB2_LIB.BASEBOARD_FAB2(SCH_1):PAGE25
  AE24 M_C_DQS_DP<16> @BASEBOARD_FAB2_LIB.BASEBOARD_FAB2(SCH_1):M_C_DQS_DP(16)   I172 @BASEBOARD_FAB2_LIB.BASEBOARD_FAB2(SCH_1):PAGE25
  AE30 M_C_DQS_DP<15> @BASEBOARD_FAB2_LIB.BASEBOARD_FAB2(SCH_1):M_C_DQS_DP(15)   I172 @BASEBOARD_FAB2_LIB.BASEBOARD_FAB2(SCH_1):PAGE25
   V33 M_C_DQS_DP<14> @BASEBOARD_FAB2_LIB.BASEBOARD_FAB2(SCH_1):M_C_DQS_DP(14)   I172 @BASEBOARD_FAB2_LIB.BASEBOARD_FAB2(SCH_1):PAGE25
   V39 M_C_DQS_DP<13> @BASEBOARD_FAB2_LIB.BASEBOARD_FAB2(SCH_1):M_C_DQS_DP(13)   I172 @BASEBOARD_FAB2_LIB.BASEBOARD_FAB2(SCH_1):PAGE25
  AN66 M_C_DQS_DP<12> @BASEBOARD_FAB2_LIB.BASEBOARD_FAB2(SCH_1):M_C_DQS_DP(12)   I172 @BASEBOARD_FAB2_LIB.BASEBOARD_FAB2(SCH_1):PAGE25
   V71 M_C_DQS_DP<11> @BASEBOARD_FAB2_LIB.BASEBOARD_FAB2(SCH_1):M_C_DQS_DP(11)   I172 @BASEBOARD_FAB2_LIB.BASEBOARD_FAB2(SCH_1):PAGE25
  AC76 M_C_DQS_DP<10> @BASEBOARD_FAB2_LIB.BASEBOARD_FAB2(SCH_1):M_C_DQS_DP(10)   I172 @BASEBOARD_FAB2_LIB.BASEBOARD_FAB2(SCH_1):PAGE25
  AN76 M_C_DQS_DP<9> @BASEBOARD_FAB2_LIB.BASEBOARD_FAB2(SCH_1):M_C_DQS_DP(9)   I172 @BASEBOARD_FAB2_LIB.BASEBOARD_FAB2(SCH_1):PAGE25
  AY71 M_C_DQS_DP<8> @BASEBOARD_FAB2_LIB.BASEBOARD_FAB2(SCH_1):M_C_DQS_DP(8)   I172 @BASEBOARD_FAB2_LIB.BASEBOARD_FAB2(SCH_1):PAGE25
  AG24 M_C_DQS_DP<7> @BASEBOARD_FAB2_LIB.BASEBOARD_FAB2(SCH_1):M_C_DQS_DP(7)   I172 @BASEBOARD_FAB2_LIB.BASEBOARD_FAB2(SCH_1):PAGE25
  AG30 M_C_DQS_DP<6> @BASEBOARD_FAB2_LIB.BASEBOARD_FAB2(SCH_1):M_C_DQS_DP(6)   I172 @BASEBOARD_FAB2_LIB.BASEBOARD_FAB2(SCH_1):PAGE25
   Y33 M_C_DQS_DP<5> @BASEBOARD_FAB2_LIB.BASEBOARD_FAB2(SCH_1):M_C_DQS_DP(5)   I172 @BASEBOARD_FAB2_LIB.BASEBOARD_FAB2(SCH_1):PAGE25
   Y39 M_C_DQS_DP<4> @BASEBOARD_FAB2_LIB.BASEBOARD_FAB2(SCH_1):M_C_DQS_DP(4)   I172 @BASEBOARD_FAB2_LIB.BASEBOARD_FAB2(SCH_1):PAGE25
  AR66 M_C_DQS_DP<3> @BASEBOARD_FAB2_LIB.BASEBOARD_FAB2(SCH_1):M_C_DQS_DP(3)   I172 @BASEBOARD_FAB2_LIB.BASEBOARD_FAB2(SCH_1):PAGE25
   W70 M_C_DQS_DP<2> @BASEBOARD_FAB2_LIB.BASEBOARD_FAB2(SCH_1):M_C_DQS_DP(2)   I172 @BASEBOARD_FAB2_LIB.BASEBOARD_FAB2(SCH_1):PAGE25
  AB75 M_C_DQS_DP<1> @BASEBOARD_FAB2_LIB.BASEBOARD_FAB2(SCH_1):M_C_DQS_DP(1)   I172 @BASEBOARD_FAB2_LIB.BASEBOARD_FAB2(SCH_1):PAGE25
  AM75 M_C_DQS_DP<0> @BASEBOARD_FAB2_LIB.BASEBOARD_FAB2(SCH_1):M_C_DQS_DP(0)   I172 @BASEBOARD_FAB2_LIB.BASEBOARD_FAB2(SCH_1):PAGE25
  BA70 M_C_ECC<7> @BASEBOARD_FAB2_LIB.BASEBOARD_FAB2(SCH_1):M_C_ECC(7)   I172 @BASEBOARD_FAB2_LIB.BASEBOARD_FAB2(SCH_1):PAGE25
  AU70 M_C_ECC<6> @BASEBOARD_FAB2_LIB.BASEBOARD_FAB2(SCH_1):M_C_ECC(6)   I172 @BASEBOARD_FAB2_LIB.BASEBOARD_FAB2(SCH_1):PAGE25
  AY73 M_C_ECC<5> @BASEBOARD_FAB2_LIB.BASEBOARD_FAB2(SCH_1):M_C_ECC(5)   I172 @BASEBOARD_FAB2_LIB.BASEBOARD_FAB2(SCH_1):PAGE25
  AV73 M_C_ECC<4> @BASEBOARD_FAB2_LIB.BASEBOARD_FAB2(SCH_1):M_C_ECC(4)   I172 @BASEBOARD_FAB2_LIB.BASEBOARD_FAB2(SCH_1):PAGE25
  AY69 M_C_ECC<3> @BASEBOARD_FAB2_LIB.BASEBOARD_FAB2(SCH_1):M_C_ECC(3)   I172 @BASEBOARD_FAB2_LIB.BASEBOARD_FAB2(SCH_1):PAGE25
  AV69 M_C_ECC<2> @BASEBOARD_FAB2_LIB.BASEBOARD_FAB2(SCH_1):M_C_ECC(2)   I172 @BASEBOARD_FAB2_LIB.BASEBOARD_FAB2(SCH_1):PAGE25
  BA72 M_C_ECC<1> @BASEBOARD_FAB2_LIB.BASEBOARD_FAB2(SCH_1):M_C_ECC(1)   I172 @BASEBOARD_FAB2_LIB.BASEBOARD_FAB2(SCH_1):PAGE25
  AU72 M_C_ECC<0> @BASEBOARD_FAB2_LIB.BASEBOARD_FAB2(SCH_1):M_C_ECC(0)   I172 @BASEBOARD_FAB2_LIB.BASEBOARD_FAB2(SCH_1):PAGE25
  AC46 M_C_MA<17> @BASEBOARD_FAB2_LIB.BASEBOARD_FAB2(SCH_1):M_C_MA(17)   I172 @BASEBOARD_FAB2_LIB.BASEBOARD_FAB2(SCH_1):PAGE25
  AA52 M_C_MA<16> @BASEBOARD_FAB2_LIB.BASEBOARD_FAB2(SCH_1):M_C_MA(16)   I172 @BASEBOARD_FAB2_LIB.BASEBOARD_FAB2(SCH_1):PAGE25
  AE54 M_C_MA<15> @BASEBOARD_FAB2_LIB.BASEBOARD_FAB2(SCH_1):M_C_MA(15)   I172 @BASEBOARD_FAB2_LIB.BASEBOARD_FAB2(SCH_1):PAGE25
   W50 M_C_MA<14> @BASEBOARD_FAB2_LIB.BASEBOARD_FAB2(SCH_1):M_C_MA(14)   I172 @BASEBOARD_FAB2_LIB.BASEBOARD_FAB2(SCH_1):PAGE25
  AD53 M_C_MA<13> @BASEBOARD_FAB2_LIB.BASEBOARD_FAB2(SCH_1):M_C_MA(13)   I172 @BASEBOARD_FAB2_LIB.BASEBOARD_FAB2(SCH_1):PAGE25
  AG62 M_C_MA<12> @BASEBOARD_FAB2_LIB.BASEBOARD_FAB2(SCH_1):M_C_MA(12)   I172 @BASEBOARD_FAB2_LIB.BASEBOARD_FAB2(SCH_1):PAGE25
  AG60 M_C_MA<11> @BASEBOARD_FAB2_LIB.BASEBOARD_FAB2(SCH_1):M_C_MA(11)   I172 @BASEBOARD_FAB2_LIB.BASEBOARD_FAB2(SCH_1):PAGE25
  AD55 M_C_MA<10> @BASEBOARD_FAB2_LIB.BASEBOARD_FAB2(SCH_1):M_C_MA(10)   I172 @BASEBOARD_FAB2_LIB.BASEBOARD_FAB2(SCH_1):PAGE25
  AG58 M_C_MA<9> @BASEBOARD_FAB2_LIB.BASEBOARD_FAB2(SCH_1):M_C_MA(9)   I172 @BASEBOARD_FAB2_LIB.BASEBOARD_FAB2(SCH_1):PAGE25
  AD59 M_C_MA<8> @BASEBOARD_FAB2_LIB.BASEBOARD_FAB2(SCH_1):M_C_MA(8)   I172 @BASEBOARD_FAB2_LIB.BASEBOARD_FAB2(SCH_1):PAGE25
  AE60 M_C_MA<7> @BASEBOARD_FAB2_LIB.BASEBOARD_FAB2(SCH_1):M_C_MA(7)   I172 @BASEBOARD_FAB2_LIB.BASEBOARD_FAB2(SCH_1):PAGE25
  AB59 M_C_MA<6> @BASEBOARD_FAB2_LIB.BASEBOARD_FAB2(SCH_1):M_C_MA(6)   I172 @BASEBOARD_FAB2_LIB.BASEBOARD_FAB2(SCH_1):PAGE25
   V59 M_C_MA<5> @BASEBOARD_FAB2_LIB.BASEBOARD_FAB2(SCH_1):M_C_MA(5)   I172 @BASEBOARD_FAB2_LIB.BASEBOARD_FAB2(SCH_1):PAGE25
  AA58 M_C_MA<4> @BASEBOARD_FAB2_LIB.BASEBOARD_FAB2(SCH_1):M_C_MA(4)   I172 @BASEBOARD_FAB2_LIB.BASEBOARD_FAB2(SCH_1):PAGE25
   W58 M_C_MA<3> @BASEBOARD_FAB2_LIB.BASEBOARD_FAB2(SCH_1):M_C_MA(3)   I172 @BASEBOARD_FAB2_LIB.BASEBOARD_FAB2(SCH_1):PAGE25
  AD57 M_C_MA<2> @BASEBOARD_FAB2_LIB.BASEBOARD_FAB2(SCH_1):M_C_MA(2)   I172 @BASEBOARD_FAB2_LIB.BASEBOARD_FAB2(SCH_1):PAGE25
  AE58 M_C_MA<1> @BASEBOARD_FAB2_LIB.BASEBOARD_FAB2(SCH_1):M_C_MA(1)   I172 @BASEBOARD_FAB2_LIB.BASEBOARD_FAB2(SCH_1):PAGE25
  AB53 M_C_MA<0> @BASEBOARD_FAB2_LIB.BASEBOARD_FAB2(SCH_1):M_C_MA(0)   I172 @BASEBOARD_FAB2_LIB.BASEBOARD_FAB2(SCH_1):PAGE25
  AB47 M_C_ODT<3> @BASEBOARD_FAB2_LIB.BASEBOARD_FAB2(SCH_1):M_C_ODT(3)   I172 @BASEBOARD_FAB2_LIB.BASEBOARD_FAB2(SCH_1):PAGE25
   V49 M_C_ODT<2> @BASEBOARD_FAB2_LIB.BASEBOARD_FAB2(SCH_1):M_C_ODT(2)   I172 @BASEBOARD_FAB2_LIB.BASEBOARD_FAB2(SCH_1):PAGE25
  AA48 M_C_ODT<1> @BASEBOARD_FAB2_LIB.BASEBOARD_FAB2(SCH_1):M_C_ODT(1)   I172 @BASEBOARD_FAB2_LIB.BASEBOARD_FAB2(SCH_1):PAGE25
  AA50 M_C_ODT<0> @BASEBOARD_FAB2_LIB.BASEBOARD_FAB2(SCH_1):M_C_ODT(0)   I172 @BASEBOARD_FAB2_LIB.BASEBOARD_FAB2(SCH_1):PAGE25
   V53 M_C_PAR @BASEBOARD_FAB2_LIB.BASEBOARD_FAB2(SCH_1):M_C_PAR   I172 @BASEBOARD_FAB2_LIB.BASEBOARD_FAB2(SCH_1):PAGE25
  DW60 M_D_ACT_N @BASEBOARD_FAB2_LIB.BASEBOARD_FAB2(SCH_1):M_D_ACT_N   I172 @BASEBOARD_FAB2_LIB.BASEBOARD_FAB2(SCH_1):PAGE26
  ED63 M_D_ALERT_N @BASEBOARD_FAB2_LIB.BASEBOARD_FAB2(SCH_1):M_D_ALERT_N   I172 @BASEBOARD_FAB2_LIB.BASEBOARD_FAB2(SCH_1):PAGE26
  EA54 M_D_BA<1> @BASEBOARD_FAB2_LIB.BASEBOARD_FAB2(SCH_1):M_D_BA(1)   I172 @BASEBOARD_FAB2_LIB.BASEBOARD_FAB2(SCH_1):PAGE26
  EE52 M_D_BA<0> @BASEBOARD_FAB2_LIB.BASEBOARD_FAB2(SCH_1):M_D_BA(0)   I172 @BASEBOARD_FAB2_LIB.BASEBOARD_FAB2(SCH_1):PAGE26
  DW62 M_D_BG<1> @BASEBOARD_FAB2_LIB.BASEBOARD_FAB2(SCH_1):M_D_BG(1)   I172 @BASEBOARD_FAB2_LIB.BASEBOARD_FAB2(SCH_1):PAGE26
  ED61 M_D_BG<0> @BASEBOARD_FAB2_LIB.BASEBOARD_FAB2(SCH_1):M_D_BG(0)   I172 @BASEBOARD_FAB2_LIB.BASEBOARD_FAB2(SCH_1):PAGE26
  DV47 M_D_C<2> @BASEBOARD_FAB2_LIB.BASEBOARD_FAB2(SCH_1):M_D_C(2)   I172 @BASEBOARD_FAB2_LIB.BASEBOARD_FAB2(SCH_1):PAGE26
  EB63 M_D_CKE<3> @BASEBOARD_FAB2_LIB.BASEBOARD_FAB2(SCH_1):M_D_CKE(3)   I172 @BASEBOARD_FAB2_LIB.BASEBOARD_FAB2(SCH_1):PAGE26
  EA62 M_D_CKE<2> @BASEBOARD_FAB2_LIB.BASEBOARD_FAB2(SCH_1):M_D_CKE(2)   I172 @BASEBOARD_FAB2_LIB.BASEBOARD_FAB2(SCH_1):PAGE26
  EF63 M_D_CKE<1> @BASEBOARD_FAB2_LIB.BASEBOARD_FAB2(SCH_1):M_D_CKE(1)   I172 @BASEBOARD_FAB2_LIB.BASEBOARD_FAB2(SCH_1):PAGE26
  EE62 M_D_CKE<0> @BASEBOARD_FAB2_LIB.BASEBOARD_FAB2(SCH_1):M_D_CKE(0)   I172 @BASEBOARD_FAB2_LIB.BASEBOARD_FAB2(SCH_1):PAGE26
  EF57 M_D_CLK_DN<3> @BASEBOARD_FAB2_LIB.BASEBOARD_FAB2(SCH_1):M_D_CLK_DN(3)   I172 @BASEBOARD_FAB2_LIB.BASEBOARD_FAB2(SCH_1):PAGE26
  DW56 M_D_CLK_DN<2> @BASEBOARD_FAB2_LIB.BASEBOARD_FAB2(SCH_1):M_D_CLK_DN(2)   I172 @BASEBOARD_FAB2_LIB.BASEBOARD_FAB2(SCH_1):PAGE26
  EF55 M_D_CLK_DN<1> @BASEBOARD_FAB2_LIB.BASEBOARD_FAB2(SCH_1):M_D_CLK_DN(1)   I172 @BASEBOARD_FAB2_LIB.BASEBOARD_FAB2(SCH_1):PAGE26
  ED55 M_D_CLK_DN<0> @BASEBOARD_FAB2_LIB.BASEBOARD_FAB2(SCH_1):M_D_CLK_DN(0)   I172 @BASEBOARD_FAB2_LIB.BASEBOARD_FAB2(SCH_1):PAGE26
  EE56 M_D_CLK_DP<3> @BASEBOARD_FAB2_LIB.BASEBOARD_FAB2(SCH_1):M_D_CLK_DP(3)   I172 @BASEBOARD_FAB2_LIB.BASEBOARD_FAB2(SCH_1):PAGE26
  EA56 M_D_CLK_DP<2> @BASEBOARD_FAB2_LIB.BASEBOARD_FAB2(SCH_1):M_D_CLK_DP(2)   I172 @BASEBOARD_FAB2_LIB.BASEBOARD_FAB2(SCH_1):PAGE26
  EE54 M_D_CLK_DP<1> @BASEBOARD_FAB2_LIB.BASEBOARD_FAB2(SCH_1):M_D_CLK_DP(1)   I172 @BASEBOARD_FAB2_LIB.BASEBOARD_FAB2(SCH_1):PAGE26
  EB55 M_D_CLK_DP<0> @BASEBOARD_FAB2_LIB.BASEBOARD_FAB2(SCH_1):M_D_CLK_DP(0)   I172 @BASEBOARD_FAB2_LIB.BASEBOARD_FAB2(SCH_1):PAGE26
  EB45 M_D_CS_N<7> @BASEBOARD_FAB2_LIB.BASEBOARD_FAB2(SCH_1):M_D_CS_N(7)   I172 @BASEBOARD_FAB2_LIB.BASEBOARD_FAB2(SCH_1):PAGE26
  DV45 M_D_CS_N<6> @BASEBOARD_FAB2_LIB.BASEBOARD_FAB2(SCH_1):M_D_CS_N(6)   I172 @BASEBOARD_FAB2_LIB.BASEBOARD_FAB2(SCH_1):PAGE26
  EB49 M_D_CS_N<5> @BASEBOARD_FAB2_LIB.BASEBOARD_FAB2(SCH_1):M_D_CS_N(5)   I172 @BASEBOARD_FAB2_LIB.BASEBOARD_FAB2(SCH_1):PAGE26
  EB51 M_D_CS_N<4> @BASEBOARD_FAB2_LIB.BASEBOARD_FAB2(SCH_1):M_D_CS_N(4)   I172 @BASEBOARD_FAB2_LIB.BASEBOARD_FAB2(SCH_1):PAGE26
  EB47 M_D_CS_N<3> @BASEBOARD_FAB2_LIB.BASEBOARD_FAB2(SCH_1):M_D_CS_N(3)   I172 @BASEBOARD_FAB2_LIB.BASEBOARD_FAB2(SCH_1):PAGE26
  ED47 M_D_CS_N<2> @BASEBOARD_FAB2_LIB.BASEBOARD_FAB2(SCH_1):M_D_CS_N(2)   I172 @BASEBOARD_FAB2_LIB.BASEBOARD_FAB2(SCH_1):PAGE26
  ED49 M_D_CS_N<1> @BASEBOARD_FAB2_LIB.BASEBOARD_FAB2(SCH_1):M_D_CS_N(1)   I172 @BASEBOARD_FAB2_LIB.BASEBOARD_FAB2(SCH_1):PAGE26
  EF51 M_D_CS_N<0> @BASEBOARD_FAB2_LIB.BASEBOARD_FAB2(SCH_1):M_D_CS_N(0)   I172 @BASEBOARD_FAB2_LIB.BASEBOARD_FAB2(SCH_1):PAGE26
  DW22 M_D_DQ<63> @BASEBOARD_FAB2_LIB.BASEBOARD_FAB2(SCH_1):M_D_DQ(63)   I172 @BASEBOARD_FAB2_LIB.BASEBOARD_FAB2(SCH_1):PAGE26
  EC22 M_D_DQ<62> @BASEBOARD_FAB2_LIB.BASEBOARD_FAB2(SCH_1):M_D_DQ(62)   I172 @BASEBOARD_FAB2_LIB.BASEBOARD_FAB2(SCH_1):PAGE26
  DT25 M_D_DQ<61> @BASEBOARD_FAB2_LIB.BASEBOARD_FAB2(SCH_1):M_D_DQ(61)   I172 @BASEBOARD_FAB2_LIB.BASEBOARD_FAB2(SCH_1):PAGE26
  DP25 M_D_DQ<60> @BASEBOARD_FAB2_LIB.BASEBOARD_FAB2(SCH_1):M_D_DQ(60)   I172 @BASEBOARD_FAB2_LIB.BASEBOARD_FAB2(SCH_1):PAGE26
  EB21 M_D_DQ<59> @BASEBOARD_FAB2_LIB.BASEBOARD_FAB2(SCH_1):M_D_DQ(59)   I172 @BASEBOARD_FAB2_LIB.BASEBOARD_FAB2(SCH_1):PAGE26
  DY21 M_D_DQ<58> @BASEBOARD_FAB2_LIB.BASEBOARD_FAB2(SCH_1):M_D_DQ(58)   I172 @BASEBOARD_FAB2_LIB.BASEBOARD_FAB2(SCH_1):PAGE26
  DU24 M_D_DQ<57> @BASEBOARD_FAB2_LIB.BASEBOARD_FAB2(SCH_1):M_D_DQ(57)   I172 @BASEBOARD_FAB2_LIB.BASEBOARD_FAB2(SCH_1):PAGE26
  DN24 M_D_DQ<56> @BASEBOARD_FAB2_LIB.BASEBOARD_FAB2(SCH_1):M_D_DQ(56)   I172 @BASEBOARD_FAB2_LIB.BASEBOARD_FAB2(SCH_1):PAGE26
  DU28 M_D_DQ<55> @BASEBOARD_FAB2_LIB.BASEBOARD_FAB2(SCH_1):M_D_DQ(55)   I172 @BASEBOARD_FAB2_LIB.BASEBOARD_FAB2(SCH_1):PAGE26
  DN28 M_D_DQ<54> @BASEBOARD_FAB2_LIB.BASEBOARD_FAB2(SCH_1):M_D_DQ(54)   I172 @BASEBOARD_FAB2_LIB.BASEBOARD_FAB2(SCH_1):PAGE26
  DT31 M_D_DQ<53> @BASEBOARD_FAB2_LIB.BASEBOARD_FAB2(SCH_1):M_D_DQ(53)   I172 @BASEBOARD_FAB2_LIB.BASEBOARD_FAB2(SCH_1):PAGE26
  DP31 M_D_DQ<52> @BASEBOARD_FAB2_LIB.BASEBOARD_FAB2(SCH_1):M_D_DQ(52)   I172 @BASEBOARD_FAB2_LIB.BASEBOARD_FAB2(SCH_1):PAGE26
  DT27 M_D_DQ<51> @BASEBOARD_FAB2_LIB.BASEBOARD_FAB2(SCH_1):M_D_DQ(51)   I172 @BASEBOARD_FAB2_LIB.BASEBOARD_FAB2(SCH_1):PAGE26
  DP27 M_D_DQ<50> @BASEBOARD_FAB2_LIB.BASEBOARD_FAB2(SCH_1):M_D_DQ(50)   I172 @BASEBOARD_FAB2_LIB.BASEBOARD_FAB2(SCH_1):PAGE26
  DU30 M_D_DQ<49> @BASEBOARD_FAB2_LIB.BASEBOARD_FAB2(SCH_1):M_D_DQ(49)   I172 @BASEBOARD_FAB2_LIB.BASEBOARD_FAB2(SCH_1):PAGE26
  DN30 M_D_DQ<48> @BASEBOARD_FAB2_LIB.BASEBOARD_FAB2(SCH_1):M_D_DQ(48)   I172 @BASEBOARD_FAB2_LIB.BASEBOARD_FAB2(SCH_1):PAGE26
  DU34 M_D_DQ<47> @BASEBOARD_FAB2_LIB.BASEBOARD_FAB2(SCH_1):M_D_DQ(47)   I172 @BASEBOARD_FAB2_LIB.BASEBOARD_FAB2(SCH_1):PAGE26
  DN34 M_D_DQ<46> @BASEBOARD_FAB2_LIB.BASEBOARD_FAB2(SCH_1):M_D_DQ(46)   I172 @BASEBOARD_FAB2_LIB.BASEBOARD_FAB2(SCH_1):PAGE26
  DT37 M_D_DQ<45> @BASEBOARD_FAB2_LIB.BASEBOARD_FAB2(SCH_1):M_D_DQ(45)   I172 @BASEBOARD_FAB2_LIB.BASEBOARD_FAB2(SCH_1):PAGE26
  DP37 M_D_DQ<44> @BASEBOARD_FAB2_LIB.BASEBOARD_FAB2(SCH_1):M_D_DQ(44)   I172 @BASEBOARD_FAB2_LIB.BASEBOARD_FAB2(SCH_1):PAGE26
  DT33 M_D_DQ<43> @BASEBOARD_FAB2_LIB.BASEBOARD_FAB2(SCH_1):M_D_DQ(43)   I172 @BASEBOARD_FAB2_LIB.BASEBOARD_FAB2(SCH_1):PAGE26
  DP33 M_D_DQ<42> @BASEBOARD_FAB2_LIB.BASEBOARD_FAB2(SCH_1):M_D_DQ(42)   I172 @BASEBOARD_FAB2_LIB.BASEBOARD_FAB2(SCH_1):PAGE26
  DU36 M_D_DQ<41> @BASEBOARD_FAB2_LIB.BASEBOARD_FAB2(SCH_1):M_D_DQ(41)   I172 @BASEBOARD_FAB2_LIB.BASEBOARD_FAB2(SCH_1):PAGE26
  DN36 M_D_DQ<40> @BASEBOARD_FAB2_LIB.BASEBOARD_FAB2(SCH_1):M_D_DQ(40)   I172 @BASEBOARD_FAB2_LIB.BASEBOARD_FAB2(SCH_1):PAGE26
  ED37 M_D_DQ<39> @BASEBOARD_FAB2_LIB.BASEBOARD_FAB2(SCH_1):M_D_DQ(39)   I172 @BASEBOARD_FAB2_LIB.BASEBOARD_FAB2(SCH_1):PAGE26
  DY37 M_D_DQ<38> @BASEBOARD_FAB2_LIB.BASEBOARD_FAB2(SCH_1):M_D_DQ(38)   I172 @BASEBOARD_FAB2_LIB.BASEBOARD_FAB2(SCH_1):PAGE26
  EA40 M_D_DQ<37> @BASEBOARD_FAB2_LIB.BASEBOARD_FAB2(SCH_1):M_D_DQ(37)   I172 @BASEBOARD_FAB2_LIB.BASEBOARD_FAB2(SCH_1):PAGE26
  DY39 M_D_DQ<36> @BASEBOARD_FAB2_LIB.BASEBOARD_FAB2(SCH_1):M_D_DQ(36)   I172 @BASEBOARD_FAB2_LIB.BASEBOARD_FAB2(SCH_1):PAGE26
  EC36 M_D_DQ<35> @BASEBOARD_FAB2_LIB.BASEBOARD_FAB2(SCH_1):M_D_DQ(35)   I172 @BASEBOARD_FAB2_LIB.BASEBOARD_FAB2(SCH_1):PAGE26
  EA36 M_D_DQ<34> @BASEBOARD_FAB2_LIB.BASEBOARD_FAB2(SCH_1):M_D_DQ(34)   I172 @BASEBOARD_FAB2_LIB.BASEBOARD_FAB2(SCH_1):PAGE26
  ED39 M_D_DQ<33> @BASEBOARD_FAB2_LIB.BASEBOARD_FAB2(SCH_1):M_D_DQ(33)   I172 @BASEBOARD_FAB2_LIB.BASEBOARD_FAB2(SCH_1):PAGE26
  EC40 M_D_DQ<32> @BASEBOARD_FAB2_LIB.BASEBOARD_FAB2(SCH_1):M_D_DQ(32)   I172 @BASEBOARD_FAB2_LIB.BASEBOARD_FAB2(SCH_1):PAGE26
  DU74 M_D_DQ<31> @BASEBOARD_FAB2_LIB.BASEBOARD_FAB2(SCH_1):M_D_DQ(31)   I172 @BASEBOARD_FAB2_LIB.BASEBOARD_FAB2(SCH_1):PAGE26
  DN74 M_D_DQ<30> @BASEBOARD_FAB2_LIB.BASEBOARD_FAB2(SCH_1):M_D_DQ(30)   I172 @BASEBOARD_FAB2_LIB.BASEBOARD_FAB2(SCH_1):PAGE26
  DT77 M_D_DQ<29> @BASEBOARD_FAB2_LIB.BASEBOARD_FAB2(SCH_1):M_D_DQ(29)   I172 @BASEBOARD_FAB2_LIB.BASEBOARD_FAB2(SCH_1):PAGE26
  DP77 M_D_DQ<28> @BASEBOARD_FAB2_LIB.BASEBOARD_FAB2(SCH_1):M_D_DQ(28)   I172 @BASEBOARD_FAB2_LIB.BASEBOARD_FAB2(SCH_1):PAGE26
  DT73 M_D_DQ<27> @BASEBOARD_FAB2_LIB.BASEBOARD_FAB2(SCH_1):M_D_DQ(27)   I172 @BASEBOARD_FAB2_LIB.BASEBOARD_FAB2(SCH_1):PAGE26
  DP73 M_D_DQ<26> @BASEBOARD_FAB2_LIB.BASEBOARD_FAB2(SCH_1):M_D_DQ(26)   I172 @BASEBOARD_FAB2_LIB.BASEBOARD_FAB2(SCH_1):PAGE26
  DU76 M_D_DQ<25> @BASEBOARD_FAB2_LIB.BASEBOARD_FAB2(SCH_1):M_D_DQ(25)   I172 @BASEBOARD_FAB2_LIB.BASEBOARD_FAB2(SCH_1):PAGE26
  DN76 M_D_DQ<24> @BASEBOARD_FAB2_LIB.BASEBOARD_FAB2(SCH_1):M_D_DQ(24)   I172 @BASEBOARD_FAB2_LIB.BASEBOARD_FAB2(SCH_1):PAGE26
  DN82 M_D_DQ<23> @BASEBOARD_FAB2_LIB.BASEBOARD_FAB2(SCH_1):M_D_DQ(23)   I172 @BASEBOARD_FAB2_LIB.BASEBOARD_FAB2(SCH_1):PAGE26
  DR80 M_D_DQ<22> @BASEBOARD_FAB2_LIB.BASEBOARD_FAB2(SCH_1):M_D_DQ(22)   I172 @BASEBOARD_FAB2_LIB.BASEBOARD_FAB2(SCH_1):PAGE26
  DJ80 M_D_DQ<21> @BASEBOARD_FAB2_LIB.BASEBOARD_FAB2(SCH_1):M_D_DQ(21)   I172 @BASEBOARD_FAB2_LIB.BASEBOARD_FAB2(SCH_1):PAGE26
  DK79 M_D_DQ<20> @BASEBOARD_FAB2_LIB.BASEBOARD_FAB2(SCH_1):M_D_DQ(20)   I172 @BASEBOARD_FAB2_LIB.BASEBOARD_FAB2(SCH_1):PAGE26
  DR82 M_D_DQ<19> @BASEBOARD_FAB2_LIB.BASEBOARD_FAB2(SCH_1):M_D_DQ(19)   I172 @BASEBOARD_FAB2_LIB.BASEBOARD_FAB2(SCH_1):PAGE26
  DT81 M_D_DQ<18> @BASEBOARD_FAB2_LIB.BASEBOARD_FAB2(SCH_1):M_D_DQ(18)   I172 @BASEBOARD_FAB2_LIB.BASEBOARD_FAB2(SCH_1):PAGE26
  DK81 M_D_DQ<17> @BASEBOARD_FAB2_LIB.BASEBOARD_FAB2(SCH_1):M_D_DQ(17)   I172 @BASEBOARD_FAB2_LIB.BASEBOARD_FAB2(SCH_1):PAGE26
  DM79 M_D_DQ<16> @BASEBOARD_FAB2_LIB.BASEBOARD_FAB2(SCH_1):M_D_DQ(16)   I172 @BASEBOARD_FAB2_LIB.BASEBOARD_FAB2(SCH_1):PAGE26
  DV85 M_D_DQ<15> @BASEBOARD_FAB2_LIB.BASEBOARD_FAB2(SCH_1):M_D_DQ(15)   I172 @BASEBOARD_FAB2_LIB.BASEBOARD_FAB2(SCH_1):PAGE26
  DR84 M_D_DQ<14> @BASEBOARD_FAB2_LIB.BASEBOARD_FAB2(SCH_1):M_D_DQ(14)   I172 @BASEBOARD_FAB2_LIB.BASEBOARD_FAB2(SCH_1):PAGE26
  DE84 M_D_DQ<13> @BASEBOARD_FAB2_LIB.BASEBOARD_FAB2(SCH_1):M_D_DQ(13)   I172 @BASEBOARD_FAB2_LIB.BASEBOARD_FAB2(SCH_1):PAGE26
  DD85 M_D_DQ<12> @BASEBOARD_FAB2_LIB.BASEBOARD_FAB2(SCH_1):M_D_DQ(12)   I172 @BASEBOARD_FAB2_LIB.BASEBOARD_FAB2(SCH_1):PAGE26
  DY83 M_D_DQ<11> @BASEBOARD_FAB2_LIB.BASEBOARD_FAB2(SCH_1):M_D_DQ(11)   I172 @BASEBOARD_FAB2_LIB.BASEBOARD_FAB2(SCH_1):PAGE26
  DV83 M_D_DQ<10> @BASEBOARD_FAB2_LIB.BASEBOARD_FAB2(SCH_1):M_D_DQ(10)   I172 @BASEBOARD_FAB2_LIB.BASEBOARD_FAB2(SCH_1):PAGE26
  DH85 M_D_DQ<9> @BASEBOARD_FAB2_LIB.BASEBOARD_FAB2(SCH_1):M_D_DQ(9)   I172 @BASEBOARD_FAB2_LIB.BASEBOARD_FAB2(SCH_1):PAGE26
  DG84 M_D_DQ<8> @BASEBOARD_FAB2_LIB.BASEBOARD_FAB2(SCH_1):M_D_DQ(8)   I172 @BASEBOARD_FAB2_LIB.BASEBOARD_FAB2(SCH_1):PAGE26
  CW84 M_D_DQ<7> @BASEBOARD_FAB2_LIB.BASEBOARD_FAB2(SCH_1):M_D_DQ(7)   I172 @BASEBOARD_FAB2_LIB.BASEBOARD_FAB2(SCH_1):PAGE26
  CW86 M_D_DQ<6> @BASEBOARD_FAB2_LIB.BASEBOARD_FAB2(SCH_1):M_D_DQ(6)   I172 @BASEBOARD_FAB2_LIB.BASEBOARD_FAB2(SCH_1):PAGE26
  CL86 M_D_DQ<5> @BASEBOARD_FAB2_LIB.BASEBOARD_FAB2(SCH_1):M_D_DQ(5)   I172 @BASEBOARD_FAB2_LIB.BASEBOARD_FAB2(SCH_1):PAGE26
  CL84 M_D_DQ<4> @BASEBOARD_FAB2_LIB.BASEBOARD_FAB2(SCH_1):M_D_DQ(4)   I172 @BASEBOARD_FAB2_LIB.BASEBOARD_FAB2(SCH_1):PAGE26
  DA84 M_D_DQ<3> @BASEBOARD_FAB2_LIB.BASEBOARD_FAB2(SCH_1):M_D_DQ(3)   I172 @BASEBOARD_FAB2_LIB.BASEBOARD_FAB2(SCH_1):PAGE26
  DA86 M_D_DQ<2> @BASEBOARD_FAB2_LIB.BASEBOARD_FAB2(SCH_1):M_D_DQ(2)   I172 @BASEBOARD_FAB2_LIB.BASEBOARD_FAB2(SCH_1):PAGE26
  CN86 M_D_DQ<1> @BASEBOARD_FAB2_LIB.BASEBOARD_FAB2(SCH_1):M_D_DQ(1)   I172 @BASEBOARD_FAB2_LIB.BASEBOARD_FAB2(SCH_1):PAGE26
  CN84 M_D_DQ<0> @BASEBOARD_FAB2_LIB.BASEBOARD_FAB2(SCH_1):M_D_DQ(0)   I172 @BASEBOARD_FAB2_LIB.BASEBOARD_FAB2(SCH_1):PAGE26
  DB67 M_D_DQS_DN<17> @BASEBOARD_FAB2_LIB.BASEBOARD_FAB2(SCH_1):M_D_DQS_DN(17)   I172 @BASEBOARD_FAB2_LIB.BASEBOARD_FAB2(SCH_1):PAGE26
  DM23 M_D_DQS_DN<16> @BASEBOARD_FAB2_LIB.BASEBOARD_FAB2(SCH_1):M_D_DQS_DN(16)   I172 @BASEBOARD_FAB2_LIB.BASEBOARD_FAB2(SCH_1):PAGE26
  DM29 M_D_DQS_DN<15> @BASEBOARD_FAB2_LIB.BASEBOARD_FAB2(SCH_1):M_D_DQS_DN(15)   I172 @BASEBOARD_FAB2_LIB.BASEBOARD_FAB2(SCH_1):PAGE26
  DP35 M_D_DQS_DN<14> @BASEBOARD_FAB2_LIB.BASEBOARD_FAB2(SCH_1):M_D_DQS_DN(14)   I172 @BASEBOARD_FAB2_LIB.BASEBOARD_FAB2(SCH_1):PAGE26
  EA38 M_D_DQS_DN<13> @BASEBOARD_FAB2_LIB.BASEBOARD_FAB2(SCH_1):M_D_DQS_DN(13)   I172 @BASEBOARD_FAB2_LIB.BASEBOARD_FAB2(SCH_1):PAGE26
  DP75 M_D_DQS_DN<12> @BASEBOARD_FAB2_LIB.BASEBOARD_FAB2(SCH_1):M_D_DQS_DN(12)   I172 @BASEBOARD_FAB2_LIB.BASEBOARD_FAB2(SCH_1):PAGE26
  DN80 M_D_DQS_DN<11> @BASEBOARD_FAB2_LIB.BASEBOARD_FAB2(SCH_1):M_D_DQS_DN(11)   I172 @BASEBOARD_FAB2_LIB.BASEBOARD_FAB2(SCH_1):PAGE26
  DM85 M_D_DQS_DN<10> @BASEBOARD_FAB2_LIB.BASEBOARD_FAB2(SCH_1):M_D_DQS_DN(10)   I172 @BASEBOARD_FAB2_LIB.BASEBOARD_FAB2(SCH_1):PAGE26
  CR84 M_D_DQS_DN<9> @BASEBOARD_FAB2_LIB.BASEBOARD_FAB2(SCH_1):M_D_DQS_DN(9)   I172 @BASEBOARD_FAB2_LIB.BASEBOARD_FAB2(SCH_1):PAGE26
  DF67 M_D_DQS_DN<8> @BASEBOARD_FAB2_LIB.BASEBOARD_FAB2(SCH_1):M_D_DQS_DN(8)   I172 @BASEBOARD_FAB2_LIB.BASEBOARD_FAB2(SCH_1):PAGE26
  DV23 M_D_DQS_DN<7> @BASEBOARD_FAB2_LIB.BASEBOARD_FAB2(SCH_1):M_D_DQS_DN(7)   I172 @BASEBOARD_FAB2_LIB.BASEBOARD_FAB2(SCH_1):PAGE26
  DV29 M_D_DQS_DN<6> @BASEBOARD_FAB2_LIB.BASEBOARD_FAB2(SCH_1):M_D_DQS_DN(6)   I172 @BASEBOARD_FAB2_LIB.BASEBOARD_FAB2(SCH_1):PAGE26
  DV35 M_D_DQS_DN<5> @BASEBOARD_FAB2_LIB.BASEBOARD_FAB2(SCH_1):M_D_DQS_DN(5)   I172 @BASEBOARD_FAB2_LIB.BASEBOARD_FAB2(SCH_1):PAGE26
  EE38 M_D_DQS_DN<4> @BASEBOARD_FAB2_LIB.BASEBOARD_FAB2(SCH_1):M_D_DQS_DN(4)   I172 @BASEBOARD_FAB2_LIB.BASEBOARD_FAB2(SCH_1):PAGE26
  DV75 M_D_DQS_DN<3> @BASEBOARD_FAB2_LIB.BASEBOARD_FAB2(SCH_1):M_D_DQS_DN(3)   I172 @BASEBOARD_FAB2_LIB.BASEBOARD_FAB2(SCH_1):PAGE26
  DL82 M_D_DQS_DN<2> @BASEBOARD_FAB2_LIB.BASEBOARD_FAB2(SCH_1):M_D_DQS_DN(2)   I172 @BASEBOARD_FAB2_LIB.BASEBOARD_FAB2(SCH_1):PAGE26
  DN84 M_D_DQS_DN<1> @BASEBOARD_FAB2_LIB.BASEBOARD_FAB2(SCH_1):M_D_DQS_DN(1)   I172 @BASEBOARD_FAB2_LIB.BASEBOARD_FAB2(SCH_1):PAGE26
  CU84 M_D_DQS_DN<0> @BASEBOARD_FAB2_LIB.BASEBOARD_FAB2(SCH_1):M_D_DQS_DN(0)   I172 @BASEBOARD_FAB2_LIB.BASEBOARD_FAB2(SCH_1):PAGE26
  CY67 M_D_DQS_DP<17> @BASEBOARD_FAB2_LIB.BASEBOARD_FAB2(SCH_1):M_D_DQS_DP(17)   I172 @BASEBOARD_FAB2_LIB.BASEBOARD_FAB2(SCH_1):PAGE26
  DP23 M_D_DQS_DP<16> @BASEBOARD_FAB2_LIB.BASEBOARD_FAB2(SCH_1):M_D_DQS_DP(16)   I172 @BASEBOARD_FAB2_LIB.BASEBOARD_FAB2(SCH_1):PAGE26
  DP29 M_D_DQS_DP<15> @BASEBOARD_FAB2_LIB.BASEBOARD_FAB2(SCH_1):M_D_DQS_DP(15)   I172 @BASEBOARD_FAB2_LIB.BASEBOARD_FAB2(SCH_1):PAGE26
  DM35 M_D_DQS_DP<14> @BASEBOARD_FAB2_LIB.BASEBOARD_FAB2(SCH_1):M_D_DQS_DP(14)   I172 @BASEBOARD_FAB2_LIB.BASEBOARD_FAB2(SCH_1):PAGE26
  DW38 M_D_DQS_DP<13> @BASEBOARD_FAB2_LIB.BASEBOARD_FAB2(SCH_1):M_D_DQS_DP(13)   I172 @BASEBOARD_FAB2_LIB.BASEBOARD_FAB2(SCH_1):PAGE26
  DM75 M_D_DQS_DP<12> @BASEBOARD_FAB2_LIB.BASEBOARD_FAB2(SCH_1):M_D_DQS_DP(12)   I172 @BASEBOARD_FAB2_LIB.BASEBOARD_FAB2(SCH_1):PAGE26
  DP79 M_D_DQS_DP<11> @BASEBOARD_FAB2_LIB.BASEBOARD_FAB2(SCH_1):M_D_DQS_DP(11)   I172 @BASEBOARD_FAB2_LIB.BASEBOARD_FAB2(SCH_1):PAGE26
  DL84 M_D_DQS_DP<10> @BASEBOARD_FAB2_LIB.BASEBOARD_FAB2(SCH_1):M_D_DQS_DP(10)   I172 @BASEBOARD_FAB2_LIB.BASEBOARD_FAB2(SCH_1):PAGE26
  CP85 M_D_DQS_DP<9> @BASEBOARD_FAB2_LIB.BASEBOARD_FAB2(SCH_1):M_D_DQS_DP(9)   I172 @BASEBOARD_FAB2_LIB.BASEBOARD_FAB2(SCH_1):PAGE26
  DD67 M_D_DQS_DP<8> @BASEBOARD_FAB2_LIB.BASEBOARD_FAB2(SCH_1):M_D_DQS_DP(8)   I172 @BASEBOARD_FAB2_LIB.BASEBOARD_FAB2(SCH_1):PAGE26
  DT23 M_D_DQS_DP<7> @BASEBOARD_FAB2_LIB.BASEBOARD_FAB2(SCH_1):M_D_DQS_DP(7)   I172 @BASEBOARD_FAB2_LIB.BASEBOARD_FAB2(SCH_1):PAGE26
  DT29 M_D_DQS_DP<6> @BASEBOARD_FAB2_LIB.BASEBOARD_FAB2(SCH_1):M_D_DQS_DP(6)   I172 @BASEBOARD_FAB2_LIB.BASEBOARD_FAB2(SCH_1):PAGE26
  DT35 M_D_DQS_DP<5> @BASEBOARD_FAB2_LIB.BASEBOARD_FAB2(SCH_1):M_D_DQS_DP(5)   I172 @BASEBOARD_FAB2_LIB.BASEBOARD_FAB2(SCH_1):PAGE26
  EC38 M_D_DQS_DP<4> @BASEBOARD_FAB2_LIB.BASEBOARD_FAB2(SCH_1):M_D_DQS_DP(4)   I172 @BASEBOARD_FAB2_LIB.BASEBOARD_FAB2(SCH_1):PAGE26
  DT75 M_D_DQS_DP<3> @BASEBOARD_FAB2_LIB.BASEBOARD_FAB2(SCH_1):M_D_DQS_DP(3)   I172 @BASEBOARD_FAB2_LIB.BASEBOARD_FAB2(SCH_1):PAGE26
  DM81 M_D_DQS_DP<2> @BASEBOARD_FAB2_LIB.BASEBOARD_FAB2(SCH_1):M_D_DQS_DP(2)   I172 @BASEBOARD_FAB2_LIB.BASEBOARD_FAB2(SCH_1):PAGE26
  DP85 M_D_DQS_DP<1> @BASEBOARD_FAB2_LIB.BASEBOARD_FAB2(SCH_1):M_D_DQS_DP(1)   I172 @BASEBOARD_FAB2_LIB.BASEBOARD_FAB2(SCH_1):PAGE26
  CV85 M_D_DQS_DP<0> @BASEBOARD_FAB2_LIB.BASEBOARD_FAB2(SCH_1):M_D_DQS_DP(0)   I172 @BASEBOARD_FAB2_LIB.BASEBOARD_FAB2(SCH_1):PAGE26
  DE66 M_D_ECC<7> @BASEBOARD_FAB2_LIB.BASEBOARD_FAB2(SCH_1):M_D_ECC(7)   I172 @BASEBOARD_FAB2_LIB.BASEBOARD_FAB2(SCH_1):PAGE26
  DA66 M_D_ECC<6> @BASEBOARD_FAB2_LIB.BASEBOARD_FAB2(SCH_1):M_D_ECC(6)   I172 @BASEBOARD_FAB2_LIB.BASEBOARD_FAB2(SCH_1):PAGE26
  DD69 M_D_ECC<5> @BASEBOARD_FAB2_LIB.BASEBOARD_FAB2(SCH_1):M_D_ECC(5)   I172 @BASEBOARD_FAB2_LIB.BASEBOARD_FAB2(SCH_1):PAGE26
  DB69 M_D_ECC<4> @BASEBOARD_FAB2_LIB.BASEBOARD_FAB2(SCH_1):M_D_ECC(4)   I172 @BASEBOARD_FAB2_LIB.BASEBOARD_FAB2(SCH_1):PAGE26
  DD65 M_D_ECC<3> @BASEBOARD_FAB2_LIB.BASEBOARD_FAB2(SCH_1):M_D_ECC(3)   I172 @BASEBOARD_FAB2_LIB.BASEBOARD_FAB2(SCH_1):PAGE26
  DB65 M_D_ECC<2> @BASEBOARD_FAB2_LIB.BASEBOARD_FAB2(SCH_1):M_D_ECC(2)   I172 @BASEBOARD_FAB2_LIB.BASEBOARD_FAB2(SCH_1):PAGE26
  DE68 M_D_ECC<1> @BASEBOARD_FAB2_LIB.BASEBOARD_FAB2(SCH_1):M_D_ECC(1)   I172 @BASEBOARD_FAB2_LIB.BASEBOARD_FAB2(SCH_1):PAGE26
  DA68 M_D_ECC<0> @BASEBOARD_FAB2_LIB.BASEBOARD_FAB2(SCH_1):M_D_ECC(0)   I172 @BASEBOARD_FAB2_LIB.BASEBOARD_FAB2(SCH_1):PAGE26
  EA46 M_D_MA<17> @BASEBOARD_FAB2_LIB.BASEBOARD_FAB2(SCH_1):M_D_MA(17)   I172 @BASEBOARD_FAB2_LIB.BASEBOARD_FAB2(SCH_1):PAGE26
  EA52 M_D_MA<16> @BASEBOARD_FAB2_LIB.BASEBOARD_FAB2(SCH_1):M_D_MA(16)   I172 @BASEBOARD_FAB2_LIB.BASEBOARD_FAB2(SCH_1):PAGE26
  DV49 M_D_MA<15> @BASEBOARD_FAB2_LIB.BASEBOARD_FAB2(SCH_1):M_D_MA(15)   I172 @BASEBOARD_FAB2_LIB.BASEBOARD_FAB2(SCH_1):PAGE26
  ED51 M_D_MA<14> @BASEBOARD_FAB2_LIB.BASEBOARD_FAB2(SCH_1):M_D_MA(14)   I172 @BASEBOARD_FAB2_LIB.BASEBOARD_FAB2(SCH_1):PAGE26
  DW48 M_D_MA<13> @BASEBOARD_FAB2_LIB.BASEBOARD_FAB2(SCH_1):M_D_MA(13)   I172 @BASEBOARD_FAB2_LIB.BASEBOARD_FAB2(SCH_1):PAGE26
  DT63 M_D_MA<12> @BASEBOARD_FAB2_LIB.BASEBOARD_FAB2(SCH_1):M_D_MA(12)   I172 @BASEBOARD_FAB2_LIB.BASEBOARD_FAB2(SCH_1):PAGE26
  EB61 M_D_MA<11> @BASEBOARD_FAB2_LIB.BASEBOARD_FAB2(SCH_1):M_D_MA(11)   I172 @BASEBOARD_FAB2_LIB.BASEBOARD_FAB2(SCH_1):PAGE26
  DW54 M_D_MA<10> @BASEBOARD_FAB2_LIB.BASEBOARD_FAB2(SCH_1):M_D_MA(10)   I172 @BASEBOARD_FAB2_LIB.BASEBOARD_FAB2(SCH_1):PAGE26
  EF61 M_D_MA<9> @BASEBOARD_FAB2_LIB.BASEBOARD_FAB2(SCH_1):M_D_MA(9)   I172 @BASEBOARD_FAB2_LIB.BASEBOARD_FAB2(SCH_1):PAGE26
  EB59 M_D_MA<8> @BASEBOARD_FAB2_LIB.BASEBOARD_FAB2(SCH_1):M_D_MA(8)   I172 @BASEBOARD_FAB2_LIB.BASEBOARD_FAB2(SCH_1):PAGE26
  EA60 M_D_MA<7> @BASEBOARD_FAB2_LIB.BASEBOARD_FAB2(SCH_1):M_D_MA(7)   I172 @BASEBOARD_FAB2_LIB.BASEBOARD_FAB2(SCH_1):PAGE26
  EE60 M_D_MA<6> @BASEBOARD_FAB2_LIB.BASEBOARD_FAB2(SCH_1):M_D_MA(6)   I172 @BASEBOARD_FAB2_LIB.BASEBOARD_FAB2(SCH_1):PAGE26
  EA58 M_D_MA<5> @BASEBOARD_FAB2_LIB.BASEBOARD_FAB2(SCH_1):M_D_MA(5)   I172 @BASEBOARD_FAB2_LIB.BASEBOARD_FAB2(SCH_1):PAGE26
  ED59 M_D_MA<4> @BASEBOARD_FAB2_LIB.BASEBOARD_FAB2(SCH_1):M_D_MA(4)   I172 @BASEBOARD_FAB2_LIB.BASEBOARD_FAB2(SCH_1):PAGE26
  EB57 M_D_MA<3> @BASEBOARD_FAB2_LIB.BASEBOARD_FAB2(SCH_1):M_D_MA(3)   I172 @BASEBOARD_FAB2_LIB.BASEBOARD_FAB2(SCH_1):PAGE26
  EE58 M_D_MA<2> @BASEBOARD_FAB2_LIB.BASEBOARD_FAB2(SCH_1):M_D_MA(2)   I172 @BASEBOARD_FAB2_LIB.BASEBOARD_FAB2(SCH_1):PAGE26
  ED57 M_D_MA<1> @BASEBOARD_FAB2_LIB.BASEBOARD_FAB2(SCH_1):M_D_MA(1)   I172 @BASEBOARD_FAB2_LIB.BASEBOARD_FAB2(SCH_1):PAGE26
  EB53 M_D_MA<0> @BASEBOARD_FAB2_LIB.BASEBOARD_FAB2(SCH_1):M_D_MA(0)   I172 @BASEBOARD_FAB2_LIB.BASEBOARD_FAB2(SCH_1):PAGE26
  EA48 M_D_ODT<3> @BASEBOARD_FAB2_LIB.BASEBOARD_FAB2(SCH_1):M_D_ODT(3)   I172 @BASEBOARD_FAB2_LIB.BASEBOARD_FAB2(SCH_1):PAGE26
  EA50 M_D_ODT<2> @BASEBOARD_FAB2_LIB.BASEBOARD_FAB2(SCH_1):M_D_ODT(2)   I172 @BASEBOARD_FAB2_LIB.BASEBOARD_FAB2(SCH_1):PAGE26
  EE48 M_D_ODT<1> @BASEBOARD_FAB2_LIB.BASEBOARD_FAB2(SCH_1):M_D_ODT(1)   I172 @BASEBOARD_FAB2_LIB.BASEBOARD_FAB2(SCH_1):PAGE26
  EE50 M_D_ODT<0> @BASEBOARD_FAB2_LIB.BASEBOARD_FAB2(SCH_1):M_D_ODT(0)   I172 @BASEBOARD_FAB2_LIB.BASEBOARD_FAB2(SCH_1):PAGE26
  ED53 M_D_PAR @BASEBOARD_FAB2_LIB.BASEBOARD_FAB2(SCH_1):M_D_PAR   I172 @BASEBOARD_FAB2_LIB.BASEBOARD_FAB2(SCH_1):PAGE26
  DR62 M_E_ACT_N @BASEBOARD_FAB2_LIB.BASEBOARD_FAB2(SCH_1):M_E_ACT_N   I172 @BASEBOARD_FAB2_LIB.BASEBOARD_FAB2(SCH_1):PAGE27
  DT61 M_E_ALERT_N @BASEBOARD_FAB2_LIB.BASEBOARD_FAB2(SCH_1):M_E_ALERT_N   I172 @BASEBOARD_FAB2_LIB.BASEBOARD_FAB2(SCH_1):PAGE27
  DV55 M_E_BA<1> @BASEBOARD_FAB2_LIB.BASEBOARD_FAB2(SCH_1):M_E_BA(1)   I172 @BASEBOARD_FAB2_LIB.BASEBOARD_FAB2(SCH_1):PAGE27
  DM53 M_E_BA<0> @BASEBOARD_FAB2_LIB.BASEBOARD_FAB2(SCH_1):M_E_BA(0)   I172 @BASEBOARD_FAB2_LIB.BASEBOARD_FAB2(SCH_1):PAGE27
  DM61 M_E_BG<1> @BASEBOARD_FAB2_LIB.BASEBOARD_FAB2(SCH_1):M_E_BG(1)   I172 @BASEBOARD_FAB2_LIB.BASEBOARD_FAB2(SCH_1):PAGE27
  DJ62 M_E_BG<0> @BASEBOARD_FAB2_LIB.BASEBOARD_FAB2(SCH_1):M_E_BG(0)   I172 @BASEBOARD_FAB2_LIB.BASEBOARD_FAB2(SCH_1):PAGE27
  DT47 M_E_C<2> @BASEBOARD_FAB2_LIB.BASEBOARD_FAB2(SCH_1):M_E_C(2)   I172 @BASEBOARD_FAB2_LIB.BASEBOARD_FAB2(SCH_1):PAGE27
  DR64 M_E_CKE<3> @BASEBOARD_FAB2_LIB.BASEBOARD_FAB2(SCH_1):M_E_CKE(3)   I172 @BASEBOARD_FAB2_LIB.BASEBOARD_FAB2(SCH_1):PAGE27
  DL64 M_E_CKE<2> @BASEBOARD_FAB2_LIB.BASEBOARD_FAB2(SCH_1):M_E_CKE(2)   I172 @BASEBOARD_FAB2_LIB.BASEBOARD_FAB2(SCH_1):PAGE27
  DN64 M_E_CKE<1> @BASEBOARD_FAB2_LIB.BASEBOARD_FAB2(SCH_1):M_E_CKE(1)   I172 @BASEBOARD_FAB2_LIB.BASEBOARD_FAB2(SCH_1):PAGE27
  DM63 M_E_CKE<0> @BASEBOARD_FAB2_LIB.BASEBOARD_FAB2(SCH_1):M_E_CKE(0)   I172 @BASEBOARD_FAB2_LIB.BASEBOARD_FAB2(SCH_1):PAGE27
  DT57 M_E_CLK_DN<3> @BASEBOARD_FAB2_LIB.BASEBOARD_FAB2(SCH_1):M_E_CLK_DN(3)   I172 @BASEBOARD_FAB2_LIB.BASEBOARD_FAB2(SCH_1):PAGE27
  DM57 M_E_CLK_DN<2> @BASEBOARD_FAB2_LIB.BASEBOARD_FAB2(SCH_1):M_E_CLK_DN(2)   I172 @BASEBOARD_FAB2_LIB.BASEBOARD_FAB2(SCH_1):PAGE27
  DR54 M_E_CLK_DN<1> @BASEBOARD_FAB2_LIB.BASEBOARD_FAB2(SCH_1):M_E_CLK_DN(1)   I172 @BASEBOARD_FAB2_LIB.BASEBOARD_FAB2(SCH_1):PAGE27
  DM55 M_E_CLK_DN<0> @BASEBOARD_FAB2_LIB.BASEBOARD_FAB2(SCH_1):M_E_CLK_DN(0)   I172 @BASEBOARD_FAB2_LIB.BASEBOARD_FAB2(SCH_1):PAGE27
  DR56 M_E_CLK_DP<3> @BASEBOARD_FAB2_LIB.BASEBOARD_FAB2(SCH_1):M_E_CLK_DP(3)   I172 @BASEBOARD_FAB2_LIB.BASEBOARD_FAB2(SCH_1):PAGE27
  DN56 M_E_CLK_DP<2> @BASEBOARD_FAB2_LIB.BASEBOARD_FAB2(SCH_1):M_E_CLK_DP(2)   I172 @BASEBOARD_FAB2_LIB.BASEBOARD_FAB2(SCH_1):PAGE27
  DT53 M_E_CLK_DP<1> @BASEBOARD_FAB2_LIB.BASEBOARD_FAB2(SCH_1):M_E_CLK_DP(1)   I172 @BASEBOARD_FAB2_LIB.BASEBOARD_FAB2(SCH_1):PAGE27
  DN54 M_E_CLK_DP<0> @BASEBOARD_FAB2_LIB.BASEBOARD_FAB2(SCH_1):M_E_CLK_DP(0)   I172 @BASEBOARD_FAB2_LIB.BASEBOARD_FAB2(SCH_1):PAGE27
  DN46 M_E_CS_N<7> @BASEBOARD_FAB2_LIB.BASEBOARD_FAB2(SCH_1):M_E_CS_N(7)   I172 @BASEBOARD_FAB2_LIB.BASEBOARD_FAB2(SCH_1):PAGE27
  DT45 M_E_CS_N<6> @BASEBOARD_FAB2_LIB.BASEBOARD_FAB2(SCH_1):M_E_CS_N(6)   I172 @BASEBOARD_FAB2_LIB.BASEBOARD_FAB2(SCH_1):PAGE27
  DM49 M_E_CS_N<5> @BASEBOARD_FAB2_LIB.BASEBOARD_FAB2(SCH_1):M_E_CS_N(5)   I172 @BASEBOARD_FAB2_LIB.BASEBOARD_FAB2(SCH_1):PAGE27
  DW50 M_E_CS_N<4> @BASEBOARD_FAB2_LIB.BASEBOARD_FAB2(SCH_1):M_E_CS_N(4)   I172 @BASEBOARD_FAB2_LIB.BASEBOARD_FAB2(SCH_1):PAGE27
  DK47 M_E_CS_N<3> @BASEBOARD_FAB2_LIB.BASEBOARD_FAB2(SCH_1):M_E_CS_N(3)   I172 @BASEBOARD_FAB2_LIB.BASEBOARD_FAB2(SCH_1):PAGE27
  DR46 M_E_CS_N<2> @BASEBOARD_FAB2_LIB.BASEBOARD_FAB2(SCH_1):M_E_CS_N(2)   I172 @BASEBOARD_FAB2_LIB.BASEBOARD_FAB2(SCH_1):PAGE27
  DN50 M_E_CS_N<1> @BASEBOARD_FAB2_LIB.BASEBOARD_FAB2(SCH_1):M_E_CS_N(1)   I172 @BASEBOARD_FAB2_LIB.BASEBOARD_FAB2(SCH_1):PAGE27
  DV51 M_E_CS_N<0> @BASEBOARD_FAB2_LIB.BASEBOARD_FAB2(SCH_1):M_E_CS_N(0)   I172 @BASEBOARD_FAB2_LIB.BASEBOARD_FAB2(SCH_1):PAGE27
  DK25 M_E_DQ<63> @BASEBOARD_FAB2_LIB.BASEBOARD_FAB2(SCH_1):M_E_DQ(63)   I172 @BASEBOARD_FAB2_LIB.BASEBOARD_FAB2(SCH_1):PAGE27
  DF25 M_E_DQ<62> @BASEBOARD_FAB2_LIB.BASEBOARD_FAB2(SCH_1):M_E_DQ(62)   I172 @BASEBOARD_FAB2_LIB.BASEBOARD_FAB2(SCH_1):PAGE27
  DJ28 M_E_DQ<61> @BASEBOARD_FAB2_LIB.BASEBOARD_FAB2(SCH_1):M_E_DQ(61)   I172 @BASEBOARD_FAB2_LIB.BASEBOARD_FAB2(SCH_1):PAGE27
  DG28 M_E_DQ<60> @BASEBOARD_FAB2_LIB.BASEBOARD_FAB2(SCH_1):M_E_DQ(60)   I172 @BASEBOARD_FAB2_LIB.BASEBOARD_FAB2(SCH_1):PAGE27
  DJ24 M_E_DQ<59> @BASEBOARD_FAB2_LIB.BASEBOARD_FAB2(SCH_1):M_E_DQ(59)   I172 @BASEBOARD_FAB2_LIB.BASEBOARD_FAB2(SCH_1):PAGE27
  DD25 M_E_DQ<58> @BASEBOARD_FAB2_LIB.BASEBOARD_FAB2(SCH_1):M_E_DQ(58)   I172 @BASEBOARD_FAB2_LIB.BASEBOARD_FAB2(SCH_1):PAGE27
  DK27 M_E_DQ<57> @BASEBOARD_FAB2_LIB.BASEBOARD_FAB2(SCH_1):M_E_DQ(57)   I172 @BASEBOARD_FAB2_LIB.BASEBOARD_FAB2(SCH_1):PAGE27
  DF27 M_E_DQ<56> @BASEBOARD_FAB2_LIB.BASEBOARD_FAB2(SCH_1):M_E_DQ(56)   I172 @BASEBOARD_FAB2_LIB.BASEBOARD_FAB2(SCH_1):PAGE27
  ED25 M_E_DQ<55> @BASEBOARD_FAB2_LIB.BASEBOARD_FAB2(SCH_1):M_E_DQ(55)   I172 @BASEBOARD_FAB2_LIB.BASEBOARD_FAB2(SCH_1):PAGE27
  DY25 M_E_DQ<54> @BASEBOARD_FAB2_LIB.BASEBOARD_FAB2(SCH_1):M_E_DQ(54)   I172 @BASEBOARD_FAB2_LIB.BASEBOARD_FAB2(SCH_1):PAGE27
  EA28 M_E_DQ<53> @BASEBOARD_FAB2_LIB.BASEBOARD_FAB2(SCH_1):M_E_DQ(53)   I172 @BASEBOARD_FAB2_LIB.BASEBOARD_FAB2(SCH_1):PAGE27
  DY27 M_E_DQ<52> @BASEBOARD_FAB2_LIB.BASEBOARD_FAB2(SCH_1):M_E_DQ(52)   I172 @BASEBOARD_FAB2_LIB.BASEBOARD_FAB2(SCH_1):PAGE27
  EC24 M_E_DQ<51> @BASEBOARD_FAB2_LIB.BASEBOARD_FAB2(SCH_1):M_E_DQ(51)   I172 @BASEBOARD_FAB2_LIB.BASEBOARD_FAB2(SCH_1):PAGE27
  EA24 M_E_DQ<50> @BASEBOARD_FAB2_LIB.BASEBOARD_FAB2(SCH_1):M_E_DQ(50)   I172 @BASEBOARD_FAB2_LIB.BASEBOARD_FAB2(SCH_1):PAGE27
  ED27 M_E_DQ<49> @BASEBOARD_FAB2_LIB.BASEBOARD_FAB2(SCH_1):M_E_DQ(49)   I172 @BASEBOARD_FAB2_LIB.BASEBOARD_FAB2(SCH_1):PAGE27
  EC28 M_E_DQ<48> @BASEBOARD_FAB2_LIB.BASEBOARD_FAB2(SCH_1):M_E_DQ(48)   I172 @BASEBOARD_FAB2_LIB.BASEBOARD_FAB2(SCH_1):PAGE27
  ED31 M_E_DQ<47> @BASEBOARD_FAB2_LIB.BASEBOARD_FAB2(SCH_1):M_E_DQ(47)   I172 @BASEBOARD_FAB2_LIB.BASEBOARD_FAB2(SCH_1):PAGE27
  DY31 M_E_DQ<46> @BASEBOARD_FAB2_LIB.BASEBOARD_FAB2(SCH_1):M_E_DQ(46)   I172 @BASEBOARD_FAB2_LIB.BASEBOARD_FAB2(SCH_1):PAGE27
  EA34 M_E_DQ<45> @BASEBOARD_FAB2_LIB.BASEBOARD_FAB2(SCH_1):M_E_DQ(45)   I172 @BASEBOARD_FAB2_LIB.BASEBOARD_FAB2(SCH_1):PAGE27
  DY33 M_E_DQ<44> @BASEBOARD_FAB2_LIB.BASEBOARD_FAB2(SCH_1):M_E_DQ(44)   I172 @BASEBOARD_FAB2_LIB.BASEBOARD_FAB2(SCH_1):PAGE27
  EC30 M_E_DQ<43> @BASEBOARD_FAB2_LIB.BASEBOARD_FAB2(SCH_1):M_E_DQ(43)   I172 @BASEBOARD_FAB2_LIB.BASEBOARD_FAB2(SCH_1):PAGE27
  EA30 M_E_DQ<42> @BASEBOARD_FAB2_LIB.BASEBOARD_FAB2(SCH_1):M_E_DQ(42)   I172 @BASEBOARD_FAB2_LIB.BASEBOARD_FAB2(SCH_1):PAGE27
  ED33 M_E_DQ<41> @BASEBOARD_FAB2_LIB.BASEBOARD_FAB2(SCH_1):M_E_DQ(41)   I172 @BASEBOARD_FAB2_LIB.BASEBOARD_FAB2(SCH_1):PAGE27
  EC34 M_E_DQ<40> @BASEBOARD_FAB2_LIB.BASEBOARD_FAB2(SCH_1):M_E_DQ(40)   I172 @BASEBOARD_FAB2_LIB.BASEBOARD_FAB2(SCH_1):PAGE27
  DU40 M_E_DQ<39> @BASEBOARD_FAB2_LIB.BASEBOARD_FAB2(SCH_1):M_E_DQ(39)   I172 @BASEBOARD_FAB2_LIB.BASEBOARD_FAB2(SCH_1):PAGE27
  DN40 M_E_DQ<38> @BASEBOARD_FAB2_LIB.BASEBOARD_FAB2(SCH_1):M_E_DQ(38)   I172 @BASEBOARD_FAB2_LIB.BASEBOARD_FAB2(SCH_1):PAGE27
  DN42 M_E_DQ<37> @BASEBOARD_FAB2_LIB.BASEBOARD_FAB2(SCH_1):M_E_DQ(37)   I172 @BASEBOARD_FAB2_LIB.BASEBOARD_FAB2(SCH_1):PAGE27
  DL42 M_E_DQ<36> @BASEBOARD_FAB2_LIB.BASEBOARD_FAB2(SCH_1):M_E_DQ(36)   I172 @BASEBOARD_FAB2_LIB.BASEBOARD_FAB2(SCH_1):PAGE27
  DT39 M_E_DQ<35> @BASEBOARD_FAB2_LIB.BASEBOARD_FAB2(SCH_1):M_E_DQ(35)   I172 @BASEBOARD_FAB2_LIB.BASEBOARD_FAB2(SCH_1):PAGE27
  DP39 M_E_DQ<34> @BASEBOARD_FAB2_LIB.BASEBOARD_FAB2(SCH_1):M_E_DQ(34)   I172 @BASEBOARD_FAB2_LIB.BASEBOARD_FAB2(SCH_1):PAGE27
  DW42 M_E_DQ<33> @BASEBOARD_FAB2_LIB.BASEBOARD_FAB2(SCH_1):M_E_DQ(33)   I172 @BASEBOARD_FAB2_LIB.BASEBOARD_FAB2(SCH_1):PAGE27
  DU42 M_E_DQ<32> @BASEBOARD_FAB2_LIB.BASEBOARD_FAB2(SCH_1):M_E_DQ(32)   I172 @BASEBOARD_FAB2_LIB.BASEBOARD_FAB2(SCH_1):PAGE27
  EE72 M_E_DQ<31> @BASEBOARD_FAB2_LIB.BASEBOARD_FAB2(SCH_1):M_E_DQ(31)   I172 @BASEBOARD_FAB2_LIB.BASEBOARD_FAB2(SCH_1):PAGE27
  EA72 M_E_DQ<30> @BASEBOARD_FAB2_LIB.BASEBOARD_FAB2(SCH_1):M_E_DQ(30)   I172 @BASEBOARD_FAB2_LIB.BASEBOARD_FAB2(SCH_1):PAGE27
  EB75 M_E_DQ<29> @BASEBOARD_FAB2_LIB.BASEBOARD_FAB2(SCH_1):M_E_DQ(29)   I172 @BASEBOARD_FAB2_LIB.BASEBOARD_FAB2(SCH_1):PAGE27
  EA74 M_E_DQ<28> @BASEBOARD_FAB2_LIB.BASEBOARD_FAB2(SCH_1):M_E_DQ(28)   I172 @BASEBOARD_FAB2_LIB.BASEBOARD_FAB2(SCH_1):PAGE27
  ED71 M_E_DQ<27> @BASEBOARD_FAB2_LIB.BASEBOARD_FAB2(SCH_1):M_E_DQ(27)   I172 @BASEBOARD_FAB2_LIB.BASEBOARD_FAB2(SCH_1):PAGE27
  EB71 M_E_DQ<26> @BASEBOARD_FAB2_LIB.BASEBOARD_FAB2(SCH_1):M_E_DQ(26)   I172 @BASEBOARD_FAB2_LIB.BASEBOARD_FAB2(SCH_1):PAGE27
  EE74 M_E_DQ<25> @BASEBOARD_FAB2_LIB.BASEBOARD_FAB2(SCH_1):M_E_DQ(25)   I172 @BASEBOARD_FAB2_LIB.BASEBOARD_FAB2(SCH_1):PAGE27
  ED75 M_E_DQ<24> @BASEBOARD_FAB2_LIB.BASEBOARD_FAB2(SCH_1):M_E_DQ(24)   I172 @BASEBOARD_FAB2_LIB.BASEBOARD_FAB2(SCH_1):PAGE27
  EC78 M_E_DQ<23> @BASEBOARD_FAB2_LIB.BASEBOARD_FAB2(SCH_1):M_E_DQ(23)   I172 @BASEBOARD_FAB2_LIB.BASEBOARD_FAB2(SCH_1):PAGE27
  DW78 M_E_DQ<22> @BASEBOARD_FAB2_LIB.BASEBOARD_FAB2(SCH_1):M_E_DQ(22)   I172 @BASEBOARD_FAB2_LIB.BASEBOARD_FAB2(SCH_1):PAGE27
  EB81 M_E_DQ<21> @BASEBOARD_FAB2_LIB.BASEBOARD_FAB2(SCH_1):M_E_DQ(21)   I172 @BASEBOARD_FAB2_LIB.BASEBOARD_FAB2(SCH_1):PAGE27
  DY81 M_E_DQ<20> @BASEBOARD_FAB2_LIB.BASEBOARD_FAB2(SCH_1):M_E_DQ(20)   I172 @BASEBOARD_FAB2_LIB.BASEBOARD_FAB2(SCH_1):PAGE27
  EB77 M_E_DQ<19> @BASEBOARD_FAB2_LIB.BASEBOARD_FAB2(SCH_1):M_E_DQ(19)   I172 @BASEBOARD_FAB2_LIB.BASEBOARD_FAB2(SCH_1):PAGE27
  DY77 M_E_DQ<18> @BASEBOARD_FAB2_LIB.BASEBOARD_FAB2(SCH_1):M_E_DQ(18)   I172 @BASEBOARD_FAB2_LIB.BASEBOARD_FAB2(SCH_1):PAGE27
  EC80 M_E_DQ<17> @BASEBOARD_FAB2_LIB.BASEBOARD_FAB2(SCH_1):M_E_DQ(17)   I172 @BASEBOARD_FAB2_LIB.BASEBOARD_FAB2(SCH_1):PAGE27
  DW80 M_E_DQ<16> @BASEBOARD_FAB2_LIB.BASEBOARD_FAB2(SCH_1):M_E_DQ(16)   I172 @BASEBOARD_FAB2_LIB.BASEBOARD_FAB2(SCH_1):PAGE27
  DE82 M_E_DQ<15> @BASEBOARD_FAB2_LIB.BASEBOARD_FAB2(SCH_1):M_E_DQ(15)   I172 @BASEBOARD_FAB2_LIB.BASEBOARD_FAB2(SCH_1):PAGE27
  DC82 M_E_DQ<14> @BASEBOARD_FAB2_LIB.BASEBOARD_FAB2(SCH_1):M_E_DQ(14)   I172 @BASEBOARD_FAB2_LIB.BASEBOARD_FAB2(SCH_1):PAGE27
  CW80 M_E_DQ<13> @BASEBOARD_FAB2_LIB.BASEBOARD_FAB2(SCH_1):M_E_DQ(13)   I172 @BASEBOARD_FAB2_LIB.BASEBOARD_FAB2(SCH_1):PAGE27
  CY79 M_E_DQ<12> @BASEBOARD_FAB2_LIB.BASEBOARD_FAB2(SCH_1):M_E_DQ(12)   I172 @BASEBOARD_FAB2_LIB.BASEBOARD_FAB2(SCH_1):PAGE27
  DF81 M_E_DQ<11> @BASEBOARD_FAB2_LIB.BASEBOARD_FAB2(SCH_1):M_E_DQ(11)   I172 @BASEBOARD_FAB2_LIB.BASEBOARD_FAB2(SCH_1):PAGE27
  DE80 M_E_DQ<10> @BASEBOARD_FAB2_LIB.BASEBOARD_FAB2(SCH_1):M_E_DQ(10)   I172 @BASEBOARD_FAB2_LIB.BASEBOARD_FAB2(SCH_1):PAGE27
  CY81 M_E_DQ<9> @BASEBOARD_FAB2_LIB.BASEBOARD_FAB2(SCH_1):M_E_DQ(9)   I172 @BASEBOARD_FAB2_LIB.BASEBOARD_FAB2(SCH_1):PAGE27
  DB79 M_E_DQ<8> @BASEBOARD_FAB2_LIB.BASEBOARD_FAB2(SCH_1):M_E_DQ(8)   I172 @BASEBOARD_FAB2_LIB.BASEBOARD_FAB2(SCH_1):PAGE27
  CN82 M_E_DQ<7> @BASEBOARD_FAB2_LIB.BASEBOARD_FAB2(SCH_1):M_E_DQ(7)   I172 @BASEBOARD_FAB2_LIB.BASEBOARD_FAB2(SCH_1):PAGE27
  CR80 M_E_DQ<6> @BASEBOARD_FAB2_LIB.BASEBOARD_FAB2(SCH_1):M_E_DQ(6)   I172 @BASEBOARD_FAB2_LIB.BASEBOARD_FAB2(SCH_1):PAGE27
  CJ80 M_E_DQ<5> @BASEBOARD_FAB2_LIB.BASEBOARD_FAB2(SCH_1):M_E_DQ(5)   I172 @BASEBOARD_FAB2_LIB.BASEBOARD_FAB2(SCH_1):PAGE27
  CK79 M_E_DQ<4> @BASEBOARD_FAB2_LIB.BASEBOARD_FAB2(SCH_1):M_E_DQ(4)   I172 @BASEBOARD_FAB2_LIB.BASEBOARD_FAB2(SCH_1):PAGE27
  CR82 M_E_DQ<3> @BASEBOARD_FAB2_LIB.BASEBOARD_FAB2(SCH_1):M_E_DQ(3)   I172 @BASEBOARD_FAB2_LIB.BASEBOARD_FAB2(SCH_1):PAGE27
  CT81 M_E_DQ<2> @BASEBOARD_FAB2_LIB.BASEBOARD_FAB2(SCH_1):M_E_DQ(2)   I172 @BASEBOARD_FAB2_LIB.BASEBOARD_FAB2(SCH_1):PAGE27
  CK81 M_E_DQ<1> @BASEBOARD_FAB2_LIB.BASEBOARD_FAB2(SCH_1):M_E_DQ(1)   I172 @BASEBOARD_FAB2_LIB.BASEBOARD_FAB2(SCH_1):PAGE27
  CM79 M_E_DQ<0> @BASEBOARD_FAB2_LIB.BASEBOARD_FAB2(SCH_1):M_E_DQ(0)   I172 @BASEBOARD_FAB2_LIB.BASEBOARD_FAB2(SCH_1):PAGE27
  DV67 M_E_DQS_DN<17> @BASEBOARD_FAB2_LIB.BASEBOARD_FAB2(SCH_1):M_E_DQS_DN(17)   I172 @BASEBOARD_FAB2_LIB.BASEBOARD_FAB2(SCH_1):PAGE27
  DG26 M_E_DQS_DN<16> @BASEBOARD_FAB2_LIB.BASEBOARD_FAB2(SCH_1):M_E_DQS_DN(16)   I172 @BASEBOARD_FAB2_LIB.BASEBOARD_FAB2(SCH_1):PAGE27
  EA26 M_E_DQS_DN<15> @BASEBOARD_FAB2_LIB.BASEBOARD_FAB2(SCH_1):M_E_DQS_DN(15)   I172 @BASEBOARD_FAB2_LIB.BASEBOARD_FAB2(SCH_1):PAGE27
  EA32 M_E_DQS_DN<14> @BASEBOARD_FAB2_LIB.BASEBOARD_FAB2(SCH_1):M_E_DQS_DN(14)   I172 @BASEBOARD_FAB2_LIB.BASEBOARD_FAB2(SCH_1):PAGE27
  DP41 M_E_DQS_DN<13> @BASEBOARD_FAB2_LIB.BASEBOARD_FAB2(SCH_1):M_E_DQS_DN(13)   I172 @BASEBOARD_FAB2_LIB.BASEBOARD_FAB2(SCH_1):PAGE27
  EB73 M_E_DQS_DN<12> @BASEBOARD_FAB2_LIB.BASEBOARD_FAB2(SCH_1):M_E_DQS_DN(12)   I172 @BASEBOARD_FAB2_LIB.BASEBOARD_FAB2(SCH_1):PAGE27
  DY79 M_E_DQS_DN<11> @BASEBOARD_FAB2_LIB.BASEBOARD_FAB2(SCH_1):M_E_DQS_DN(11)   I172 @BASEBOARD_FAB2_LIB.BASEBOARD_FAB2(SCH_1):PAGE27
  DC80 M_E_DQS_DN<10> @BASEBOARD_FAB2_LIB.BASEBOARD_FAB2(SCH_1):M_E_DQS_DN(10)   I172 @BASEBOARD_FAB2_LIB.BASEBOARD_FAB2(SCH_1):PAGE27
  CN80 M_E_DQS_DN<9> @BASEBOARD_FAB2_LIB.BASEBOARD_FAB2(SCH_1):M_E_DQS_DN(9)   I172 @BASEBOARD_FAB2_LIB.BASEBOARD_FAB2(SCH_1):PAGE27
  EB67 M_E_DQS_DN<8> @BASEBOARD_FAB2_LIB.BASEBOARD_FAB2(SCH_1):M_E_DQS_DN(8)   I172 @BASEBOARD_FAB2_LIB.BASEBOARD_FAB2(SCH_1):PAGE27
  DL26 M_E_DQS_DN<7> @BASEBOARD_FAB2_LIB.BASEBOARD_FAB2(SCH_1):M_E_DQS_DN(7)   I172 @BASEBOARD_FAB2_LIB.BASEBOARD_FAB2(SCH_1):PAGE27
  EE26 M_E_DQS_DN<6> @BASEBOARD_FAB2_LIB.BASEBOARD_FAB2(SCH_1):M_E_DQS_DN(6)   I172 @BASEBOARD_FAB2_LIB.BASEBOARD_FAB2(SCH_1):PAGE27
  EE32 M_E_DQS_DN<5> @BASEBOARD_FAB2_LIB.BASEBOARD_FAB2(SCH_1):M_E_DQS_DN(5)   I172 @BASEBOARD_FAB2_LIB.BASEBOARD_FAB2(SCH_1):PAGE27
  DV41 M_E_DQS_DN<4> @BASEBOARD_FAB2_LIB.BASEBOARD_FAB2(SCH_1):M_E_DQS_DN(4)   I172 @BASEBOARD_FAB2_LIB.BASEBOARD_FAB2(SCH_1):PAGE27
  EF73 M_E_DQS_DN<3> @BASEBOARD_FAB2_LIB.BASEBOARD_FAB2(SCH_1):M_E_DQS_DN(3)   I172 @BASEBOARD_FAB2_LIB.BASEBOARD_FAB2(SCH_1):PAGE27
  ED79 M_E_DQS_DN<2> @BASEBOARD_FAB2_LIB.BASEBOARD_FAB2(SCH_1):M_E_DQS_DN(2)   I172 @BASEBOARD_FAB2_LIB.BASEBOARD_FAB2(SCH_1):PAGE27
  DA82 M_E_DQS_DN<1> @BASEBOARD_FAB2_LIB.BASEBOARD_FAB2(SCH_1):M_E_DQS_DN(1)   I172 @BASEBOARD_FAB2_LIB.BASEBOARD_FAB2(SCH_1):PAGE27
  CL82 M_E_DQS_DN<0> @BASEBOARD_FAB2_LIB.BASEBOARD_FAB2(SCH_1):M_E_DQS_DN(0)   I172 @BASEBOARD_FAB2_LIB.BASEBOARD_FAB2(SCH_1):PAGE27
  DT67 M_E_DQS_DP<17> @BASEBOARD_FAB2_LIB.BASEBOARD_FAB2(SCH_1):M_E_DQS_DP(17)   I172 @BASEBOARD_FAB2_LIB.BASEBOARD_FAB2(SCH_1):PAGE27
  DE26 M_E_DQS_DP<16> @BASEBOARD_FAB2_LIB.BASEBOARD_FAB2(SCH_1):M_E_DQS_DP(16)   I172 @BASEBOARD_FAB2_LIB.BASEBOARD_FAB2(SCH_1):PAGE27
  DW26 M_E_DQS_DP<15> @BASEBOARD_FAB2_LIB.BASEBOARD_FAB2(SCH_1):M_E_DQS_DP(15)   I172 @BASEBOARD_FAB2_LIB.BASEBOARD_FAB2(SCH_1):PAGE27
  DW32 M_E_DQS_DP<14> @BASEBOARD_FAB2_LIB.BASEBOARD_FAB2(SCH_1):M_E_DQS_DP(14)   I172 @BASEBOARD_FAB2_LIB.BASEBOARD_FAB2(SCH_1):PAGE27
  DM41 M_E_DQS_DP<13> @BASEBOARD_FAB2_LIB.BASEBOARD_FAB2(SCH_1):M_E_DQS_DP(13)   I172 @BASEBOARD_FAB2_LIB.BASEBOARD_FAB2(SCH_1):PAGE27
  DY73 M_E_DQS_DP<12> @BASEBOARD_FAB2_LIB.BASEBOARD_FAB2(SCH_1):M_E_DQS_DP(12)   I172 @BASEBOARD_FAB2_LIB.BASEBOARD_FAB2(SCH_1):PAGE27
  DV79 M_E_DQS_DP<11> @BASEBOARD_FAB2_LIB.BASEBOARD_FAB2(SCH_1):M_E_DQS_DP(11)   I172 @BASEBOARD_FAB2_LIB.BASEBOARD_FAB2(SCH_1):PAGE27
  DD79 M_E_DQS_DP<10> @BASEBOARD_FAB2_LIB.BASEBOARD_FAB2(SCH_1):M_E_DQS_DP(10)   I172 @BASEBOARD_FAB2_LIB.BASEBOARD_FAB2(SCH_1):PAGE27
  CP79 M_E_DQS_DP<9> @BASEBOARD_FAB2_LIB.BASEBOARD_FAB2(SCH_1):M_E_DQS_DP(9)   I172 @BASEBOARD_FAB2_LIB.BASEBOARD_FAB2(SCH_1):PAGE27
  DY67 M_E_DQS_DP<8> @BASEBOARD_FAB2_LIB.BASEBOARD_FAB2(SCH_1):M_E_DQS_DP(8)   I172 @BASEBOARD_FAB2_LIB.BASEBOARD_FAB2(SCH_1):PAGE27
  DJ26 M_E_DQS_DP<7> @BASEBOARD_FAB2_LIB.BASEBOARD_FAB2(SCH_1):M_E_DQS_DP(7)   I172 @BASEBOARD_FAB2_LIB.BASEBOARD_FAB2(SCH_1):PAGE27
  EC26 M_E_DQS_DP<6> @BASEBOARD_FAB2_LIB.BASEBOARD_FAB2(SCH_1):M_E_DQS_DP(6)   I172 @BASEBOARD_FAB2_LIB.BASEBOARD_FAB2(SCH_1):PAGE27
  EC32 M_E_DQS_DP<5> @BASEBOARD_FAB2_LIB.BASEBOARD_FAB2(SCH_1):M_E_DQS_DP(5)   I172 @BASEBOARD_FAB2_LIB.BASEBOARD_FAB2(SCH_1):PAGE27
  DT41 M_E_DQS_DP<4> @BASEBOARD_FAB2_LIB.BASEBOARD_FAB2(SCH_1):M_E_DQS_DP(4)   I172 @BASEBOARD_FAB2_LIB.BASEBOARD_FAB2(SCH_1):PAGE27
  ED73 M_E_DQS_DP<3> @BASEBOARD_FAB2_LIB.BASEBOARD_FAB2(SCH_1):M_E_DQS_DP(3)   I172 @BASEBOARD_FAB2_LIB.BASEBOARD_FAB2(SCH_1):PAGE27
  EB79 M_E_DQS_DP<2> @BASEBOARD_FAB2_LIB.BASEBOARD_FAB2(SCH_1):M_E_DQS_DP(2)   I172 @BASEBOARD_FAB2_LIB.BASEBOARD_FAB2(SCH_1):PAGE27
  DB81 M_E_DQS_DP<1> @BASEBOARD_FAB2_LIB.BASEBOARD_FAB2(SCH_1):M_E_DQS_DP(1)   I172 @BASEBOARD_FAB2_LIB.BASEBOARD_FAB2(SCH_1):PAGE27
  CM81 M_E_DQS_DP<0> @BASEBOARD_FAB2_LIB.BASEBOARD_FAB2(SCH_1):M_E_DQS_DP(0)   I172 @BASEBOARD_FAB2_LIB.BASEBOARD_FAB2(SCH_1):PAGE27
  EA66 M_E_ECC<7> @BASEBOARD_FAB2_LIB.BASEBOARD_FAB2(SCH_1):M_E_ECC(7)   I172 @BASEBOARD_FAB2_LIB.BASEBOARD_FAB2(SCH_1):PAGE27
  DU66 M_E_ECC<6> @BASEBOARD_FAB2_LIB.BASEBOARD_FAB2(SCH_1):M_E_ECC(6)   I172 @BASEBOARD_FAB2_LIB.BASEBOARD_FAB2(SCH_1):PAGE27
  DV69 M_E_ECC<5> @BASEBOARD_FAB2_LIB.BASEBOARD_FAB2(SCH_1):M_E_ECC(5)   I172 @BASEBOARD_FAB2_LIB.BASEBOARD_FAB2(SCH_1):PAGE27
  DU68 M_E_ECC<4> @BASEBOARD_FAB2_LIB.BASEBOARD_FAB2(SCH_1):M_E_ECC(4)   I172 @BASEBOARD_FAB2_LIB.BASEBOARD_FAB2(SCH_1):PAGE27
  DY65 M_E_ECC<3> @BASEBOARD_FAB2_LIB.BASEBOARD_FAB2(SCH_1):M_E_ECC(3)   I172 @BASEBOARD_FAB2_LIB.BASEBOARD_FAB2(SCH_1):PAGE27
  DV65 M_E_ECC<2> @BASEBOARD_FAB2_LIB.BASEBOARD_FAB2(SCH_1):M_E_ECC(2)   I172 @BASEBOARD_FAB2_LIB.BASEBOARD_FAB2(SCH_1):PAGE27
  EA68 M_E_ECC<1> @BASEBOARD_FAB2_LIB.BASEBOARD_FAB2(SCH_1):M_E_ECC(1)   I172 @BASEBOARD_FAB2_LIB.BASEBOARD_FAB2(SCH_1):PAGE27
  DY69 M_E_ECC<0> @BASEBOARD_FAB2_LIB.BASEBOARD_FAB2(SCH_1):M_E_ECC(0)   I172 @BASEBOARD_FAB2_LIB.BASEBOARD_FAB2(SCH_1):PAGE27
  DR48 M_E_MA<17> @BASEBOARD_FAB2_LIB.BASEBOARD_FAB2(SCH_1):M_E_MA(17)   I172 @BASEBOARD_FAB2_LIB.BASEBOARD_FAB2(SCH_1):PAGE27
  DN52 M_E_MA<16> @BASEBOARD_FAB2_LIB.BASEBOARD_FAB2(SCH_1):M_E_MA(16)   I172 @BASEBOARD_FAB2_LIB.BASEBOARD_FAB2(SCH_1):PAGE27
  DR52 M_E_MA<15> @BASEBOARD_FAB2_LIB.BASEBOARD_FAB2(SCH_1):M_E_MA(15)   I172 @BASEBOARD_FAB2_LIB.BASEBOARD_FAB2(SCH_1):PAGE27
  DM51 M_E_MA<14> @BASEBOARD_FAB2_LIB.BASEBOARD_FAB2(SCH_1):M_E_MA(14)   I172 @BASEBOARD_FAB2_LIB.BASEBOARD_FAB2(SCH_1):PAGE27
  DT51 M_E_MA<13> @BASEBOARD_FAB2_LIB.BASEBOARD_FAB2(SCH_1):M_E_MA(13)   I172 @BASEBOARD_FAB2_LIB.BASEBOARD_FAB2(SCH_1):PAGE27
  DN60 M_E_MA<12> @BASEBOARD_FAB2_LIB.BASEBOARD_FAB2(SCH_1):M_E_MA(12)   I172 @BASEBOARD_FAB2_LIB.BASEBOARD_FAB2(SCH_1):PAGE27
  DR60 M_E_MA<11> @BASEBOARD_FAB2_LIB.BASEBOARD_FAB2(SCH_1):M_E_MA(11)   I172 @BASEBOARD_FAB2_LIB.BASEBOARD_FAB2(SCH_1):PAGE27
  DT55 M_E_MA<10> @BASEBOARD_FAB2_LIB.BASEBOARD_FAB2(SCH_1):M_E_MA(10)   I172 @BASEBOARD_FAB2_LIB.BASEBOARD_FAB2(SCH_1):PAGE27
  DV59 M_E_MA<9> @BASEBOARD_FAB2_LIB.BASEBOARD_FAB2(SCH_1):M_E_MA(9)   I172 @BASEBOARD_FAB2_LIB.BASEBOARD_FAB2(SCH_1):PAGE27
  DJ60 M_E_MA<8> @BASEBOARD_FAB2_LIB.BASEBOARD_FAB2(SCH_1):M_E_MA(8)   I172 @BASEBOARD_FAB2_LIB.BASEBOARD_FAB2(SCH_1):PAGE27
  DK61 M_E_MA<7> @BASEBOARD_FAB2_LIB.BASEBOARD_FAB2(SCH_1):M_E_MA(7)   I172 @BASEBOARD_FAB2_LIB.BASEBOARD_FAB2(SCH_1):PAGE27
  DM59 M_E_MA<6> @BASEBOARD_FAB2_LIB.BASEBOARD_FAB2(SCH_1):M_E_MA(6)   I172 @BASEBOARD_FAB2_LIB.BASEBOARD_FAB2(SCH_1):PAGE27
  DN58 M_E_MA<5> @BASEBOARD_FAB2_LIB.BASEBOARD_FAB2(SCH_1):M_E_MA(5)   I172 @BASEBOARD_FAB2_LIB.BASEBOARD_FAB2(SCH_1):PAGE27
  DT59 M_E_MA<4> @BASEBOARD_FAB2_LIB.BASEBOARD_FAB2(SCH_1):M_E_MA(4)   I172 @BASEBOARD_FAB2_LIB.BASEBOARD_FAB2(SCH_1):PAGE27
  DR58 M_E_MA<3> @BASEBOARD_FAB2_LIB.BASEBOARD_FAB2(SCH_1):M_E_MA(3)   I172 @BASEBOARD_FAB2_LIB.BASEBOARD_FAB2(SCH_1):PAGE27
  DV57 M_E_MA<2> @BASEBOARD_FAB2_LIB.BASEBOARD_FAB2(SCH_1):M_E_MA(2)   I172 @BASEBOARD_FAB2_LIB.BASEBOARD_FAB2(SCH_1):PAGE27
  DW58 M_E_MA<1> @BASEBOARD_FAB2_LIB.BASEBOARD_FAB2(SCH_1):M_E_MA(1)   I172 @BASEBOARD_FAB2_LIB.BASEBOARD_FAB2(SCH_1):PAGE27
  DW52 M_E_MA<0> @BASEBOARD_FAB2_LIB.BASEBOARD_FAB2(SCH_1):M_E_MA(0)   I172 @BASEBOARD_FAB2_LIB.BASEBOARD_FAB2(SCH_1):PAGE27
  DM47 M_E_ODT<3> @BASEBOARD_FAB2_LIB.BASEBOARD_FAB2(SCH_1):M_E_ODT(3)   I172 @BASEBOARD_FAB2_LIB.BASEBOARD_FAB2(SCH_1):PAGE27
  DT49 M_E_ODT<2> @BASEBOARD_FAB2_LIB.BASEBOARD_FAB2(SCH_1):M_E_ODT(2)   I172 @BASEBOARD_FAB2_LIB.BASEBOARD_FAB2(SCH_1):PAGE27
  DN48 M_E_ODT<1> @BASEBOARD_FAB2_LIB.BASEBOARD_FAB2(SCH_1):M_E_ODT(1)   I172 @BASEBOARD_FAB2_LIB.BASEBOARD_FAB2(SCH_1):PAGE27
  DR50 M_E_ODT<0> @BASEBOARD_FAB2_LIB.BASEBOARD_FAB2(SCH_1):M_E_ODT(0)   I172 @BASEBOARD_FAB2_LIB.BASEBOARD_FAB2(SCH_1):PAGE27
  DV53 M_E_PAR @BASEBOARD_FAB2_LIB.BASEBOARD_FAB2(SCH_1):M_E_PAR   I172 @BASEBOARD_FAB2_LIB.BASEBOARD_FAB2(SCH_1):PAGE27
  DC62 M_F_ACT_N @BASEBOARD_FAB2_LIB.BASEBOARD_FAB2(SCH_1):M_F_ACT_N   I172 @BASEBOARD_FAB2_LIB.BASEBOARD_FAB2(SCH_1):PAGE28
  DD61 M_F_ALERT_N @BASEBOARD_FAB2_LIB.BASEBOARD_FAB2(SCH_1):M_F_ALERT_N   I172 @BASEBOARD_FAB2_LIB.BASEBOARD_FAB2(SCH_1):PAGE28
  DC56 M_F_BA<1> @BASEBOARD_FAB2_LIB.BASEBOARD_FAB2(SCH_1):M_F_BA(1)   I172 @BASEBOARD_FAB2_LIB.BASEBOARD_FAB2(SCH_1):PAGE28
  DJ52 M_F_BA<0> @BASEBOARD_FAB2_LIB.BASEBOARD_FAB2(SCH_1):M_F_BA(0)   I172 @BASEBOARD_FAB2_LIB.BASEBOARD_FAB2(SCH_1):PAGE28
  DF61 M_F_BG<1> @BASEBOARD_FAB2_LIB.BASEBOARD_FAB2(SCH_1):M_F_BG(1)   I172 @BASEBOARD_FAB2_LIB.BASEBOARD_FAB2(SCH_1):PAGE28
  DA62 M_F_BG<0> @BASEBOARD_FAB2_LIB.BASEBOARD_FAB2(SCH_1):M_F_BG(0)   I172 @BASEBOARD_FAB2_LIB.BASEBOARD_FAB2(SCH_1):PAGE28
  DF45 M_F_C<2> @BASEBOARD_FAB2_LIB.BASEBOARD_FAB2(SCH_1):M_F_C(2)   I172 @BASEBOARD_FAB2_LIB.BASEBOARD_FAB2(SCH_1):PAGE28
  DF63 M_F_CKE<3> @BASEBOARD_FAB2_LIB.BASEBOARD_FAB2(SCH_1):M_F_CKE(3)   I172 @BASEBOARD_FAB2_LIB.BASEBOARD_FAB2(SCH_1):PAGE28
  DK63 M_F_CKE<2> @BASEBOARD_FAB2_LIB.BASEBOARD_FAB2(SCH_1):M_F_CKE(2)   I172 @BASEBOARD_FAB2_LIB.BASEBOARD_FAB2(SCH_1):PAGE28
  DD63 M_F_CKE<1> @BASEBOARD_FAB2_LIB.BASEBOARD_FAB2(SCH_1):M_F_CKE(1)   I172 @BASEBOARD_FAB2_LIB.BASEBOARD_FAB2(SCH_1):PAGE28
  DG62 M_F_CKE<0> @BASEBOARD_FAB2_LIB.BASEBOARD_FAB2(SCH_1):M_F_CKE(0)   I172 @BASEBOARD_FAB2_LIB.BASEBOARD_FAB2(SCH_1):PAGE28
  DF57 M_F_CLK_DN<3> @BASEBOARD_FAB2_LIB.BASEBOARD_FAB2(SCH_1):M_F_CLK_DN(3)   I172 @BASEBOARD_FAB2_LIB.BASEBOARD_FAB2(SCH_1):PAGE28
  DK57 M_F_CLK_DN<2> @BASEBOARD_FAB2_LIB.BASEBOARD_FAB2(SCH_1):M_F_CLK_DN(2)   I172 @BASEBOARD_FAB2_LIB.BASEBOARD_FAB2(SCH_1):PAGE28
  DF55 M_F_CLK_DN<1> @BASEBOARD_FAB2_LIB.BASEBOARD_FAB2(SCH_1):M_F_CLK_DN(1)   I172 @BASEBOARD_FAB2_LIB.BASEBOARD_FAB2(SCH_1):PAGE28
  DK55 M_F_CLK_DN<0> @BASEBOARD_FAB2_LIB.BASEBOARD_FAB2(SCH_1):M_F_CLK_DN(0)   I172 @BASEBOARD_FAB2_LIB.BASEBOARD_FAB2(SCH_1):PAGE28
  DG56 M_F_CLK_DP<3> @BASEBOARD_FAB2_LIB.BASEBOARD_FAB2(SCH_1):M_F_CLK_DP(3)   I172 @BASEBOARD_FAB2_LIB.BASEBOARD_FAB2(SCH_1):PAGE28
  DJ56 M_F_CLK_DP<2> @BASEBOARD_FAB2_LIB.BASEBOARD_FAB2(SCH_1):M_F_CLK_DP(2)   I172 @BASEBOARD_FAB2_LIB.BASEBOARD_FAB2(SCH_1):PAGE28
  DG54 M_F_CLK_DP<1> @BASEBOARD_FAB2_LIB.BASEBOARD_FAB2(SCH_1):M_F_CLK_DP(1)   I172 @BASEBOARD_FAB2_LIB.BASEBOARD_FAB2(SCH_1):PAGE28
  DJ54 M_F_CLK_DP<0> @BASEBOARD_FAB2_LIB.BASEBOARD_FAB2(SCH_1):M_F_CLK_DP(0)   I172 @BASEBOARD_FAB2_LIB.BASEBOARD_FAB2(SCH_1):PAGE28
  DK45 M_F_CS_N<7> @BASEBOARD_FAB2_LIB.BASEBOARD_FAB2(SCH_1):M_F_CS_N(7)   I172 @BASEBOARD_FAB2_LIB.BASEBOARD_FAB2(SCH_1):PAGE28
  DM45 M_F_CS_N<6> @BASEBOARD_FAB2_LIB.BASEBOARD_FAB2(SCH_1):M_F_CS_N(6)   I172 @BASEBOARD_FAB2_LIB.BASEBOARD_FAB2(SCH_1):PAGE28
  DJ48 M_F_CS_N<5> @BASEBOARD_FAB2_LIB.BASEBOARD_FAB2(SCH_1):M_F_CS_N(5)   I172 @BASEBOARD_FAB2_LIB.BASEBOARD_FAB2(SCH_1):PAGE28
  DF51 M_F_CS_N<4> @BASEBOARD_FAB2_LIB.BASEBOARD_FAB2(SCH_1):M_F_CS_N(4)   I172 @BASEBOARD_FAB2_LIB.BASEBOARD_FAB2(SCH_1):PAGE28
  DG46 M_F_CS_N<3> @BASEBOARD_FAB2_LIB.BASEBOARD_FAB2(SCH_1):M_F_CS_N(3)   I172 @BASEBOARD_FAB2_LIB.BASEBOARD_FAB2(SCH_1):PAGE28
  DJ46 M_F_CS_N<2> @BASEBOARD_FAB2_LIB.BASEBOARD_FAB2(SCH_1):M_F_CS_N(2)   I172 @BASEBOARD_FAB2_LIB.BASEBOARD_FAB2(SCH_1):PAGE28
  DF49 M_F_CS_N<1> @BASEBOARD_FAB2_LIB.BASEBOARD_FAB2(SCH_1):M_F_CS_N(1)   I172 @BASEBOARD_FAB2_LIB.BASEBOARD_FAB2(SCH_1):PAGE28
  DK51 M_F_CS_N<0> @BASEBOARD_FAB2_LIB.BASEBOARD_FAB2(SCH_1):M_F_CS_N(0)   I172 @BASEBOARD_FAB2_LIB.BASEBOARD_FAB2(SCH_1):PAGE28
  DC28 M_F_DQ<63> @BASEBOARD_FAB2_LIB.BASEBOARD_FAB2(SCH_1):M_F_DQ(63)   I172 @BASEBOARD_FAB2_LIB.BASEBOARD_FAB2(SCH_1):PAGE28
  CW28 M_F_DQ<62> @BASEBOARD_FAB2_LIB.BASEBOARD_FAB2(SCH_1):M_F_DQ(62)   I172 @BASEBOARD_FAB2_LIB.BASEBOARD_FAB2(SCH_1):PAGE28
  DB31 M_F_DQ<61> @BASEBOARD_FAB2_LIB.BASEBOARD_FAB2(SCH_1):M_F_DQ(61)   I172 @BASEBOARD_FAB2_LIB.BASEBOARD_FAB2(SCH_1):PAGE28
  CY31 M_F_DQ<60> @BASEBOARD_FAB2_LIB.BASEBOARD_FAB2(SCH_1):M_F_DQ(60)   I172 @BASEBOARD_FAB2_LIB.BASEBOARD_FAB2(SCH_1):PAGE28
  DB27 M_F_DQ<59> @BASEBOARD_FAB2_LIB.BASEBOARD_FAB2(SCH_1):M_F_DQ(59)   I172 @BASEBOARD_FAB2_LIB.BASEBOARD_FAB2(SCH_1):PAGE28
  CY27 M_F_DQ<58> @BASEBOARD_FAB2_LIB.BASEBOARD_FAB2(SCH_1):M_F_DQ(58)   I172 @BASEBOARD_FAB2_LIB.BASEBOARD_FAB2(SCH_1):PAGE28
  DC30 M_F_DQ<57> @BASEBOARD_FAB2_LIB.BASEBOARD_FAB2(SCH_1):M_F_DQ(57)   I172 @BASEBOARD_FAB2_LIB.BASEBOARD_FAB2(SCH_1):PAGE28
  CW30 M_F_DQ<56> @BASEBOARD_FAB2_LIB.BASEBOARD_FAB2(SCH_1):M_F_DQ(56)   I172 @BASEBOARD_FAB2_LIB.BASEBOARD_FAB2(SCH_1):PAGE28
  DC34 M_F_DQ<55> @BASEBOARD_FAB2_LIB.BASEBOARD_FAB2(SCH_1):M_F_DQ(55)   I172 @BASEBOARD_FAB2_LIB.BASEBOARD_FAB2(SCH_1):PAGE28
  CW34 M_F_DQ<54> @BASEBOARD_FAB2_LIB.BASEBOARD_FAB2(SCH_1):M_F_DQ(54)   I172 @BASEBOARD_FAB2_LIB.BASEBOARD_FAB2(SCH_1):PAGE28
  DB37 M_F_DQ<53> @BASEBOARD_FAB2_LIB.BASEBOARD_FAB2(SCH_1):M_F_DQ(53)   I172 @BASEBOARD_FAB2_LIB.BASEBOARD_FAB2(SCH_1):PAGE28
  CY37 M_F_DQ<52> @BASEBOARD_FAB2_LIB.BASEBOARD_FAB2(SCH_1):M_F_DQ(52)   I172 @BASEBOARD_FAB2_LIB.BASEBOARD_FAB2(SCH_1):PAGE28
  DB33 M_F_DQ<51> @BASEBOARD_FAB2_LIB.BASEBOARD_FAB2(SCH_1):M_F_DQ(51)   I172 @BASEBOARD_FAB2_LIB.BASEBOARD_FAB2(SCH_1):PAGE28
  CY33 M_F_DQ<50> @BASEBOARD_FAB2_LIB.BASEBOARD_FAB2(SCH_1):M_F_DQ(50)   I172 @BASEBOARD_FAB2_LIB.BASEBOARD_FAB2(SCH_1):PAGE28
  DC36 M_F_DQ<49> @BASEBOARD_FAB2_LIB.BASEBOARD_FAB2(SCH_1):M_F_DQ(49)   I172 @BASEBOARD_FAB2_LIB.BASEBOARD_FAB2(SCH_1):PAGE28
  CW36 M_F_DQ<48> @BASEBOARD_FAB2_LIB.BASEBOARD_FAB2(SCH_1):M_F_DQ(48)   I172 @BASEBOARD_FAB2_LIB.BASEBOARD_FAB2(SCH_1):PAGE28
  DK31 M_F_DQ<47> @BASEBOARD_FAB2_LIB.BASEBOARD_FAB2(SCH_1):M_F_DQ(47)   I172 @BASEBOARD_FAB2_LIB.BASEBOARD_FAB2(SCH_1):PAGE28
  DF31 M_F_DQ<46> @BASEBOARD_FAB2_LIB.BASEBOARD_FAB2(SCH_1):M_F_DQ(46)   I172 @BASEBOARD_FAB2_LIB.BASEBOARD_FAB2(SCH_1):PAGE28
  DJ34 M_F_DQ<45> @BASEBOARD_FAB2_LIB.BASEBOARD_FAB2(SCH_1):M_F_DQ(45)   I172 @BASEBOARD_FAB2_LIB.BASEBOARD_FAB2(SCH_1):PAGE28
  DG34 M_F_DQ<44> @BASEBOARD_FAB2_LIB.BASEBOARD_FAB2(SCH_1):M_F_DQ(44)   I172 @BASEBOARD_FAB2_LIB.BASEBOARD_FAB2(SCH_1):PAGE28
  DJ30 M_F_DQ<43> @BASEBOARD_FAB2_LIB.BASEBOARD_FAB2(SCH_1):M_F_DQ(43)   I172 @BASEBOARD_FAB2_LIB.BASEBOARD_FAB2(SCH_1):PAGE28
  DG30 M_F_DQ<42> @BASEBOARD_FAB2_LIB.BASEBOARD_FAB2(SCH_1):M_F_DQ(42)   I172 @BASEBOARD_FAB2_LIB.BASEBOARD_FAB2(SCH_1):PAGE28
  DK33 M_F_DQ<41> @BASEBOARD_FAB2_LIB.BASEBOARD_FAB2(SCH_1):M_F_DQ(41)   I172 @BASEBOARD_FAB2_LIB.BASEBOARD_FAB2(SCH_1):PAGE28
  DF33 M_F_DQ<40> @BASEBOARD_FAB2_LIB.BASEBOARD_FAB2(SCH_1):M_F_DQ(40)   I172 @BASEBOARD_FAB2_LIB.BASEBOARD_FAB2(SCH_1):PAGE28
  DH39 M_F_DQ<39> @BASEBOARD_FAB2_LIB.BASEBOARD_FAB2(SCH_1):M_F_DQ(39)   I172 @BASEBOARD_FAB2_LIB.BASEBOARD_FAB2(SCH_1):PAGE28
  DD39 M_F_DQ<38> @BASEBOARD_FAB2_LIB.BASEBOARD_FAB2(SCH_1):M_F_DQ(38)   I172 @BASEBOARD_FAB2_LIB.BASEBOARD_FAB2(SCH_1):PAGE28
  DE42 M_F_DQ<37> @BASEBOARD_FAB2_LIB.BASEBOARD_FAB2(SCH_1):M_F_DQ(37)   I172 @BASEBOARD_FAB2_LIB.BASEBOARD_FAB2(SCH_1):PAGE28
  DA42 M_F_DQ<36> @BASEBOARD_FAB2_LIB.BASEBOARD_FAB2(SCH_1):M_F_DQ(36)   I172 @BASEBOARD_FAB2_LIB.BASEBOARD_FAB2(SCH_1):PAGE28
  DG38 M_F_DQ<35> @BASEBOARD_FAB2_LIB.BASEBOARD_FAB2(SCH_1):M_F_DQ(35)   I172 @BASEBOARD_FAB2_LIB.BASEBOARD_FAB2(SCH_1):PAGE28
  DE38 M_F_DQ<34> @BASEBOARD_FAB2_LIB.BASEBOARD_FAB2(SCH_1):M_F_DQ(34)   I172 @BASEBOARD_FAB2_LIB.BASEBOARD_FAB2(SCH_1):PAGE28
  DG42 M_F_DQ<33> @BASEBOARD_FAB2_LIB.BASEBOARD_FAB2(SCH_1):M_F_DQ(33)   I172 @BASEBOARD_FAB2_LIB.BASEBOARD_FAB2(SCH_1):PAGE28
  DD41 M_F_DQ<32> @BASEBOARD_FAB2_LIB.BASEBOARD_FAB2(SCH_1):M_F_DQ(32)   I172 @BASEBOARD_FAB2_LIB.BASEBOARD_FAB2(SCH_1):PAGE28
  CU64 M_F_DQ<31> @BASEBOARD_FAB2_LIB.BASEBOARD_FAB2(SCH_1):M_F_DQ(31)   I172 @BASEBOARD_FAB2_LIB.BASEBOARD_FAB2(SCH_1):PAGE28
  CN64 M_F_DQ<30> @BASEBOARD_FAB2_LIB.BASEBOARD_FAB2(SCH_1):M_F_DQ(30)   I172 @BASEBOARD_FAB2_LIB.BASEBOARD_FAB2(SCH_1):PAGE28
  CT67 M_F_DQ<29> @BASEBOARD_FAB2_LIB.BASEBOARD_FAB2(SCH_1):M_F_DQ(29)   I172 @BASEBOARD_FAB2_LIB.BASEBOARD_FAB2(SCH_1):PAGE28
  CP67 M_F_DQ<28> @BASEBOARD_FAB2_LIB.BASEBOARD_FAB2(SCH_1):M_F_DQ(28)   I172 @BASEBOARD_FAB2_LIB.BASEBOARD_FAB2(SCH_1):PAGE28
  CT63 M_F_DQ<27> @BASEBOARD_FAB2_LIB.BASEBOARD_FAB2(SCH_1):M_F_DQ(27)   I172 @BASEBOARD_FAB2_LIB.BASEBOARD_FAB2(SCH_1):PAGE28
  CP63 M_F_DQ<26> @BASEBOARD_FAB2_LIB.BASEBOARD_FAB2(SCH_1):M_F_DQ(26)   I172 @BASEBOARD_FAB2_LIB.BASEBOARD_FAB2(SCH_1):PAGE28
  CU66 M_F_DQ<25> @BASEBOARD_FAB2_LIB.BASEBOARD_FAB2(SCH_1):M_F_DQ(25)   I172 @BASEBOARD_FAB2_LIB.BASEBOARD_FAB2(SCH_1):PAGE28
  CN66 M_F_DQ<24> @BASEBOARD_FAB2_LIB.BASEBOARD_FAB2(SCH_1):M_F_DQ(24)   I172 @BASEBOARD_FAB2_LIB.BASEBOARD_FAB2(SCH_1):PAGE28
  DM71 M_F_DQ<23> @BASEBOARD_FAB2_LIB.BASEBOARD_FAB2(SCH_1):M_F_DQ(23)   I172 @BASEBOARD_FAB2_LIB.BASEBOARD_FAB2(SCH_1):PAGE28
  DK69 M_F_DQ<22> @BASEBOARD_FAB2_LIB.BASEBOARD_FAB2(SCH_1):M_F_DQ(22)   I172 @BASEBOARD_FAB2_LIB.BASEBOARD_FAB2(SCH_1):PAGE28
  DG72 M_F_DQ<21> @BASEBOARD_FAB2_LIB.BASEBOARD_FAB2(SCH_1):M_F_DQ(21)   I172 @BASEBOARD_FAB2_LIB.BASEBOARD_FAB2(SCH_1):PAGE28
  DF71 M_F_DQ<20> @BASEBOARD_FAB2_LIB.BASEBOARD_FAB2(SCH_1):M_F_DQ(20)   I172 @BASEBOARD_FAB2_LIB.BASEBOARD_FAB2(SCH_1):PAGE28
  DN70 M_F_DQ<19> @BASEBOARD_FAB2_LIB.BASEBOARD_FAB2(SCH_1):M_F_DQ(19)   I172 @BASEBOARD_FAB2_LIB.BASEBOARD_FAB2(SCH_1):PAGE28
  DM69 M_F_DQ<18> @BASEBOARD_FAB2_LIB.BASEBOARD_FAB2(SCH_1):M_F_DQ(18)   I172 @BASEBOARD_FAB2_LIB.BASEBOARD_FAB2(SCH_1):PAGE28
  DJ72 M_F_DQ<17> @BASEBOARD_FAB2_LIB.BASEBOARD_FAB2(SCH_1):M_F_DQ(17)   I172 @BASEBOARD_FAB2_LIB.BASEBOARD_FAB2(SCH_1):PAGE28
  DG70 M_F_DQ<16> @BASEBOARD_FAB2_LIB.BASEBOARD_FAB2(SCH_1):M_F_DQ(16)   I172 @BASEBOARD_FAB2_LIB.BASEBOARD_FAB2(SCH_1):PAGE28
  DH77 M_F_DQ<15> @BASEBOARD_FAB2_LIB.BASEBOARD_FAB2(SCH_1):M_F_DQ(15)   I172 @BASEBOARD_FAB2_LIB.BASEBOARD_FAB2(SCH_1):PAGE28
  DF77 M_F_DQ<14> @BASEBOARD_FAB2_LIB.BASEBOARD_FAB2(SCH_1):M_F_DQ(14)   I172 @BASEBOARD_FAB2_LIB.BASEBOARD_FAB2(SCH_1):PAGE28
  DB75 M_F_DQ<13> @BASEBOARD_FAB2_LIB.BASEBOARD_FAB2(SCH_1):M_F_DQ(13)   I172 @BASEBOARD_FAB2_LIB.BASEBOARD_FAB2(SCH_1):PAGE28
  DC74 M_F_DQ<12> @BASEBOARD_FAB2_LIB.BASEBOARD_FAB2(SCH_1):M_F_DQ(12)   I172 @BASEBOARD_FAB2_LIB.BASEBOARD_FAB2(SCH_1):PAGE28
  DJ76 M_F_DQ<11> @BASEBOARD_FAB2_LIB.BASEBOARD_FAB2(SCH_1):M_F_DQ(11)   I172 @BASEBOARD_FAB2_LIB.BASEBOARD_FAB2(SCH_1):PAGE28
  DH75 M_F_DQ<10> @BASEBOARD_FAB2_LIB.BASEBOARD_FAB2(SCH_1):M_F_DQ(10)   I172 @BASEBOARD_FAB2_LIB.BASEBOARD_FAB2(SCH_1):PAGE28
  DC76 M_F_DQ<9> @BASEBOARD_FAB2_LIB.BASEBOARD_FAB2(SCH_1):M_F_DQ(9)   I172 @BASEBOARD_FAB2_LIB.BASEBOARD_FAB2(SCH_1):PAGE28
  DE74 M_F_DQ<8> @BASEBOARD_FAB2_LIB.BASEBOARD_FAB2(SCH_1):M_F_DQ(8)   I172 @BASEBOARD_FAB2_LIB.BASEBOARD_FAB2(SCH_1):PAGE28
  CT77 M_F_DQ<7> @BASEBOARD_FAB2_LIB.BASEBOARD_FAB2(SCH_1):M_F_DQ(7)   I172 @BASEBOARD_FAB2_LIB.BASEBOARD_FAB2(SCH_1):PAGE28
  CV75 M_F_DQ<6> @BASEBOARD_FAB2_LIB.BASEBOARD_FAB2(SCH_1):M_F_DQ(6)   I172 @BASEBOARD_FAB2_LIB.BASEBOARD_FAB2(SCH_1):PAGE28
  CM75 M_F_DQ<5> @BASEBOARD_FAB2_LIB.BASEBOARD_FAB2(SCH_1):M_F_DQ(5)   I172 @BASEBOARD_FAB2_LIB.BASEBOARD_FAB2(SCH_1):PAGE28
  CN74 M_F_DQ<4> @BASEBOARD_FAB2_LIB.BASEBOARD_FAB2(SCH_1):M_F_DQ(4)   I172 @BASEBOARD_FAB2_LIB.BASEBOARD_FAB2(SCH_1):PAGE28
  CV77 M_F_DQ<3> @BASEBOARD_FAB2_LIB.BASEBOARD_FAB2(SCH_1):M_F_DQ(3)   I172 @BASEBOARD_FAB2_LIB.BASEBOARD_FAB2(SCH_1):PAGE28
  CW76 M_F_DQ<2> @BASEBOARD_FAB2_LIB.BASEBOARD_FAB2(SCH_1):M_F_DQ(2)   I172 @BASEBOARD_FAB2_LIB.BASEBOARD_FAB2(SCH_1):PAGE28
  CN76 M_F_DQ<1> @BASEBOARD_FAB2_LIB.BASEBOARD_FAB2(SCH_1):M_F_DQ(1)   I172 @BASEBOARD_FAB2_LIB.BASEBOARD_FAB2(SCH_1):PAGE28
  CR74 M_F_DQ<0> @BASEBOARD_FAB2_LIB.BASEBOARD_FAB2(SCH_1):M_F_DQ(0)   I172 @BASEBOARD_FAB2_LIB.BASEBOARD_FAB2(SCH_1):PAGE28
  CJ70 M_F_DQS_DN<17> @BASEBOARD_FAB2_LIB.BASEBOARD_FAB2(SCH_1):M_F_DQS_DN(17)   I172 @BASEBOARD_FAB2_LIB.BASEBOARD_FAB2(SCH_1):PAGE28
  CY29 M_F_DQS_DN<16> @BASEBOARD_FAB2_LIB.BASEBOARD_FAB2(SCH_1):M_F_DQS_DN(16)   I172 @BASEBOARD_FAB2_LIB.BASEBOARD_FAB2(SCH_1):PAGE28
  CY35 M_F_DQS_DN<15> @BASEBOARD_FAB2_LIB.BASEBOARD_FAB2(SCH_1):M_F_DQS_DN(15)   I172 @BASEBOARD_FAB2_LIB.BASEBOARD_FAB2(SCH_1):PAGE28
  DG32 M_F_DQS_DN<14> @BASEBOARD_FAB2_LIB.BASEBOARD_FAB2(SCH_1):M_F_DQS_DN(14)   I172 @BASEBOARD_FAB2_LIB.BASEBOARD_FAB2(SCH_1):PAGE28
  DE40 M_F_DQS_DN<13> @BASEBOARD_FAB2_LIB.BASEBOARD_FAB2(SCH_1):M_F_DQS_DN(13)   I172 @BASEBOARD_FAB2_LIB.BASEBOARD_FAB2(SCH_1):PAGE28
  CP65 M_F_DQS_DN<12> @BASEBOARD_FAB2_LIB.BASEBOARD_FAB2(SCH_1):M_F_DQS_DN(12)   I172 @BASEBOARD_FAB2_LIB.BASEBOARD_FAB2(SCH_1):PAGE28
  DJ70 M_F_DQS_DN<11> @BASEBOARD_FAB2_LIB.BASEBOARD_FAB2(SCH_1):M_F_DQS_DN(11)   I172 @BASEBOARD_FAB2_LIB.BASEBOARD_FAB2(SCH_1):PAGE28
  DF75 M_F_DQS_DN<10> @BASEBOARD_FAB2_LIB.BASEBOARD_FAB2(SCH_1):M_F_DQS_DN(10)   I172 @BASEBOARD_FAB2_LIB.BASEBOARD_FAB2(SCH_1):PAGE28
  CT75 M_F_DQS_DN<9> @BASEBOARD_FAB2_LIB.BASEBOARD_FAB2(SCH_1):M_F_DQS_DN(9)   I172 @BASEBOARD_FAB2_LIB.BASEBOARD_FAB2(SCH_1):PAGE28
  CN70 M_F_DQS_DN<8> @BASEBOARD_FAB2_LIB.BASEBOARD_FAB2(SCH_1):M_F_DQS_DN(8)   I172 @BASEBOARD_FAB2_LIB.BASEBOARD_FAB2(SCH_1):PAGE28
  DD29 M_F_DQS_DN<7> @BASEBOARD_FAB2_LIB.BASEBOARD_FAB2(SCH_1):M_F_DQS_DN(7)   I172 @BASEBOARD_FAB2_LIB.BASEBOARD_FAB2(SCH_1):PAGE28
  DD35 M_F_DQS_DN<6> @BASEBOARD_FAB2_LIB.BASEBOARD_FAB2(SCH_1):M_F_DQS_DN(6)   I172 @BASEBOARD_FAB2_LIB.BASEBOARD_FAB2(SCH_1):PAGE28
  DL32 M_F_DQS_DN<5> @BASEBOARD_FAB2_LIB.BASEBOARD_FAB2(SCH_1):M_F_DQS_DN(5)   I172 @BASEBOARD_FAB2_LIB.BASEBOARD_FAB2(SCH_1):PAGE28
  DG40 M_F_DQS_DN<4> @BASEBOARD_FAB2_LIB.BASEBOARD_FAB2(SCH_1):M_F_DQS_DN(4)   I172 @BASEBOARD_FAB2_LIB.BASEBOARD_FAB2(SCH_1):PAGE28
  CV65 M_F_DQS_DN<3> @BASEBOARD_FAB2_LIB.BASEBOARD_FAB2(SCH_1):M_F_DQS_DN(3)   I172 @BASEBOARD_FAB2_LIB.BASEBOARD_FAB2(SCH_1):PAGE28
  DL72 M_F_DQS_DN<2> @BASEBOARD_FAB2_LIB.BASEBOARD_FAB2(SCH_1):M_F_DQS_DN(2)   I172 @BASEBOARD_FAB2_LIB.BASEBOARD_FAB2(SCH_1):PAGE28
  DD77 M_F_DQS_DN<1> @BASEBOARD_FAB2_LIB.BASEBOARD_FAB2(SCH_1):M_F_DQS_DN(1)   I172 @BASEBOARD_FAB2_LIB.BASEBOARD_FAB2(SCH_1):PAGE28
  CP77 M_F_DQS_DN<0> @BASEBOARD_FAB2_LIB.BASEBOARD_FAB2(SCH_1):M_F_DQS_DN(0)   I172 @BASEBOARD_FAB2_LIB.BASEBOARD_FAB2(SCH_1):PAGE28
  CG70 M_F_DQS_DP<17> @BASEBOARD_FAB2_LIB.BASEBOARD_FAB2(SCH_1):M_F_DQS_DP(17)   I172 @BASEBOARD_FAB2_LIB.BASEBOARD_FAB2(SCH_1):PAGE28
  CV29 M_F_DQS_DP<16> @BASEBOARD_FAB2_LIB.BASEBOARD_FAB2(SCH_1):M_F_DQS_DP(16)   I172 @BASEBOARD_FAB2_LIB.BASEBOARD_FAB2(SCH_1):PAGE28
  CV35 M_F_DQS_DP<15> @BASEBOARD_FAB2_LIB.BASEBOARD_FAB2(SCH_1):M_F_DQS_DP(15)   I172 @BASEBOARD_FAB2_LIB.BASEBOARD_FAB2(SCH_1):PAGE28
  DE32 M_F_DQS_DP<14> @BASEBOARD_FAB2_LIB.BASEBOARD_FAB2(SCH_1):M_F_DQS_DP(14)   I172 @BASEBOARD_FAB2_LIB.BASEBOARD_FAB2(SCH_1):PAGE28
  DC40 M_F_DQS_DP<13> @BASEBOARD_FAB2_LIB.BASEBOARD_FAB2(SCH_1):M_F_DQS_DP(13)   I172 @BASEBOARD_FAB2_LIB.BASEBOARD_FAB2(SCH_1):PAGE28
  CM65 M_F_DQS_DP<12> @BASEBOARD_FAB2_LIB.BASEBOARD_FAB2(SCH_1):M_F_DQS_DP(12)   I172 @BASEBOARD_FAB2_LIB.BASEBOARD_FAB2(SCH_1):PAGE28
  DH69 M_F_DQS_DP<11> @BASEBOARD_FAB2_LIB.BASEBOARD_FAB2(SCH_1):M_F_DQS_DP(11)   I172 @BASEBOARD_FAB2_LIB.BASEBOARD_FAB2(SCH_1):PAGE28
  DG74 M_F_DQS_DP<10> @BASEBOARD_FAB2_LIB.BASEBOARD_FAB2(SCH_1):M_F_DQS_DP(10)   I172 @BASEBOARD_FAB2_LIB.BASEBOARD_FAB2(SCH_1):PAGE28
  CU74 M_F_DQS_DP<9> @BASEBOARD_FAB2_LIB.BASEBOARD_FAB2(SCH_1):M_F_DQS_DP(9)   I172 @BASEBOARD_FAB2_LIB.BASEBOARD_FAB2(SCH_1):PAGE28
  CL70 M_F_DQS_DP<8> @BASEBOARD_FAB2_LIB.BASEBOARD_FAB2(SCH_1):M_F_DQS_DP(8)   I172 @BASEBOARD_FAB2_LIB.BASEBOARD_FAB2(SCH_1):PAGE28
  DB29 M_F_DQS_DP<7> @BASEBOARD_FAB2_LIB.BASEBOARD_FAB2(SCH_1):M_F_DQS_DP(7)   I172 @BASEBOARD_FAB2_LIB.BASEBOARD_FAB2(SCH_1):PAGE28
  DB35 M_F_DQS_DP<6> @BASEBOARD_FAB2_LIB.BASEBOARD_FAB2(SCH_1):M_F_DQS_DP(6)   I172 @BASEBOARD_FAB2_LIB.BASEBOARD_FAB2(SCH_1):PAGE28
  DJ32 M_F_DQS_DP<5> @BASEBOARD_FAB2_LIB.BASEBOARD_FAB2(SCH_1):M_F_DQS_DP(5)   I172 @BASEBOARD_FAB2_LIB.BASEBOARD_FAB2(SCH_1):PAGE28
  DJ40 M_F_DQS_DP<4> @BASEBOARD_FAB2_LIB.BASEBOARD_FAB2(SCH_1):M_F_DQS_DP(4)   I172 @BASEBOARD_FAB2_LIB.BASEBOARD_FAB2(SCH_1):PAGE28
  CT65 M_F_DQS_DP<3> @BASEBOARD_FAB2_LIB.BASEBOARD_FAB2(SCH_1):M_F_DQS_DP(3)   I172 @BASEBOARD_FAB2_LIB.BASEBOARD_FAB2(SCH_1):PAGE28
  DK71 M_F_DQS_DP<2> @BASEBOARD_FAB2_LIB.BASEBOARD_FAB2(SCH_1):M_F_DQS_DP(2)   I172 @BASEBOARD_FAB2_LIB.BASEBOARD_FAB2(SCH_1):PAGE28
  DE76 M_F_DQS_DP<1> @BASEBOARD_FAB2_LIB.BASEBOARD_FAB2(SCH_1):M_F_DQS_DP(1)   I172 @BASEBOARD_FAB2_LIB.BASEBOARD_FAB2(SCH_1):PAGE28
  CR76 M_F_DQS_DP<0> @BASEBOARD_FAB2_LIB.BASEBOARD_FAB2(SCH_1):M_F_DQS_DP(0)   I172 @BASEBOARD_FAB2_LIB.BASEBOARD_FAB2(SCH_1):PAGE28
  CM69 M_F_ECC<7> @BASEBOARD_FAB2_LIB.BASEBOARD_FAB2(SCH_1):M_F_ECC(7)   I172 @BASEBOARD_FAB2_LIB.BASEBOARD_FAB2(SCH_1):PAGE28
  CH69 M_F_ECC<6> @BASEBOARD_FAB2_LIB.BASEBOARD_FAB2(SCH_1):M_F_ECC(6)   I172 @BASEBOARD_FAB2_LIB.BASEBOARD_FAB2(SCH_1):PAGE28
  CL72 M_F_ECC<5> @BASEBOARD_FAB2_LIB.BASEBOARD_FAB2(SCH_1):M_F_ECC(5)   I172 @BASEBOARD_FAB2_LIB.BASEBOARD_FAB2(SCH_1):PAGE28
  CJ72 M_F_ECC<4> @BASEBOARD_FAB2_LIB.BASEBOARD_FAB2(SCH_1):M_F_ECC(4)   I172 @BASEBOARD_FAB2_LIB.BASEBOARD_FAB2(SCH_1):PAGE28
  CL68 M_F_ECC<3> @BASEBOARD_FAB2_LIB.BASEBOARD_FAB2(SCH_1):M_F_ECC(3)   I172 @BASEBOARD_FAB2_LIB.BASEBOARD_FAB2(SCH_1):PAGE28
  CJ68 M_F_ECC<2> @BASEBOARD_FAB2_LIB.BASEBOARD_FAB2(SCH_1):M_F_ECC(2)   I172 @BASEBOARD_FAB2_LIB.BASEBOARD_FAB2(SCH_1):PAGE28
  CM71 M_F_ECC<1> @BASEBOARD_FAB2_LIB.BASEBOARD_FAB2(SCH_1):M_F_ECC(1)   I172 @BASEBOARD_FAB2_LIB.BASEBOARD_FAB2(SCH_1):PAGE28
  CH71 M_F_ECC<0> @BASEBOARD_FAB2_LIB.BASEBOARD_FAB2(SCH_1):M_F_ECC(0)   I172 @BASEBOARD_FAB2_LIB.BASEBOARD_FAB2(SCH_1):PAGE28
  DE46 M_F_MA<17> @BASEBOARD_FAB2_LIB.BASEBOARD_FAB2(SCH_1):M_F_MA(17)   I172 @BASEBOARD_FAB2_LIB.BASEBOARD_FAB2(SCH_1):PAGE28
  DG52 M_F_MA<16> @BASEBOARD_FAB2_LIB.BASEBOARD_FAB2(SCH_1):M_F_MA(16)   I172 @BASEBOARD_FAB2_LIB.BASEBOARD_FAB2(SCH_1):PAGE28
  DC54 M_F_MA<15> @BASEBOARD_FAB2_LIB.BASEBOARD_FAB2(SCH_1):M_F_MA(15)   I172 @BASEBOARD_FAB2_LIB.BASEBOARD_FAB2(SCH_1):PAGE28
  DJ50 M_F_MA<14> @BASEBOARD_FAB2_LIB.BASEBOARD_FAB2(SCH_1):M_F_MA(14)   I172 @BASEBOARD_FAB2_LIB.BASEBOARD_FAB2(SCH_1):PAGE28
  DD53 M_F_MA<13> @BASEBOARD_FAB2_LIB.BASEBOARD_FAB2(SCH_1):M_F_MA(13)   I172 @BASEBOARD_FAB2_LIB.BASEBOARD_FAB2(SCH_1):PAGE28
  DG60 M_F_MA<12> @BASEBOARD_FAB2_LIB.BASEBOARD_FAB2(SCH_1):M_F_MA(12)   I172 @BASEBOARD_FAB2_LIB.BASEBOARD_FAB2(SCH_1):PAGE28
  DA60 M_F_MA<11> @BASEBOARD_FAB2_LIB.BASEBOARD_FAB2(SCH_1):M_F_MA(11)   I172 @BASEBOARD_FAB2_LIB.BASEBOARD_FAB2(SCH_1):PAGE28
  DD55 M_F_MA<10> @BASEBOARD_FAB2_LIB.BASEBOARD_FAB2(SCH_1):M_F_MA(10)   I172 @BASEBOARD_FAB2_LIB.BASEBOARD_FAB2(SCH_1):PAGE28
  DA58 M_F_MA<9> @BASEBOARD_FAB2_LIB.BASEBOARD_FAB2(SCH_1):M_F_MA(9)   I172 @BASEBOARD_FAB2_LIB.BASEBOARD_FAB2(SCH_1):PAGE28
  DD59 M_F_MA<8> @BASEBOARD_FAB2_LIB.BASEBOARD_FAB2(SCH_1):M_F_MA(8)   I172 @BASEBOARD_FAB2_LIB.BASEBOARD_FAB2(SCH_1):PAGE28
  DC60 M_F_MA<7> @BASEBOARD_FAB2_LIB.BASEBOARD_FAB2(SCH_1):M_F_MA(7)   I172 @BASEBOARD_FAB2_LIB.BASEBOARD_FAB2(SCH_1):PAGE28
  DK59 M_F_MA<6> @BASEBOARD_FAB2_LIB.BASEBOARD_FAB2(SCH_1):M_F_MA(6)   I172 @BASEBOARD_FAB2_LIB.BASEBOARD_FAB2(SCH_1):PAGE28
  DF59 M_F_MA<5> @BASEBOARD_FAB2_LIB.BASEBOARD_FAB2(SCH_1):M_F_MA(5)   I172 @BASEBOARD_FAB2_LIB.BASEBOARD_FAB2(SCH_1):PAGE28
  DJ58 M_F_MA<4> @BASEBOARD_FAB2_LIB.BASEBOARD_FAB2(SCH_1):M_F_MA(4)   I172 @BASEBOARD_FAB2_LIB.BASEBOARD_FAB2(SCH_1):PAGE28
  DG58 M_F_MA<3> @BASEBOARD_FAB2_LIB.BASEBOARD_FAB2(SCH_1):M_F_MA(3)   I172 @BASEBOARD_FAB2_LIB.BASEBOARD_FAB2(SCH_1):PAGE28
  DD57 M_F_MA<2> @BASEBOARD_FAB2_LIB.BASEBOARD_FAB2(SCH_1):M_F_MA(2)   I172 @BASEBOARD_FAB2_LIB.BASEBOARD_FAB2(SCH_1):PAGE28
  DC58 M_F_MA<1> @BASEBOARD_FAB2_LIB.BASEBOARD_FAB2(SCH_1):M_F_MA(1)   I172 @BASEBOARD_FAB2_LIB.BASEBOARD_FAB2(SCH_1):PAGE28
  DF53 M_F_MA<0> @BASEBOARD_FAB2_LIB.BASEBOARD_FAB2(SCH_1):M_F_MA(0)   I172 @BASEBOARD_FAB2_LIB.BASEBOARD_FAB2(SCH_1):PAGE28
  DF47 M_F_ODT<3> @BASEBOARD_FAB2_LIB.BASEBOARD_FAB2(SCH_1):M_F_ODT(3)   I172 @BASEBOARD_FAB2_LIB.BASEBOARD_FAB2(SCH_1):PAGE28
  DK49 M_F_ODT<2> @BASEBOARD_FAB2_LIB.BASEBOARD_FAB2(SCH_1):M_F_ODT(2)   I172 @BASEBOARD_FAB2_LIB.BASEBOARD_FAB2(SCH_1):PAGE28
  DG48 M_F_ODT<1> @BASEBOARD_FAB2_LIB.BASEBOARD_FAB2(SCH_1):M_F_ODT(1)   I172 @BASEBOARD_FAB2_LIB.BASEBOARD_FAB2(SCH_1):PAGE28
  DG50 M_F_ODT<0> @BASEBOARD_FAB2_LIB.BASEBOARD_FAB2(SCH_1):M_F_ODT(0)   I172 @BASEBOARD_FAB2_LIB.BASEBOARD_FAB2(SCH_1):PAGE28
  DK53 M_F_PAR @BASEBOARD_FAB2_LIB.BASEBOARD_FAB2(SCH_1):M_F_PAR   I172 @BASEBOARD_FAB2_LIB.BASEBOARD_FAB2(SCH_1):PAGE28
  BN22 SMB_HFI0_CPU0_LVC2_SCL @BASEBOARD_FAB2_LIB.BASEBOARD_FAB2(SCH_1):SMB_HFI0_CPU0_LVC2_SCL    I61 @BASEBOARD_FAB2_LIB.BASEBOARD_FAB2(SCH_1):PAGE29
  BP23 SMB_HFI0_CPU0_LVC2_SDA @BASEBOARD_FAB2_LIB.BASEBOARD_FAB2(SCH_1):SMB_HFI0_CPU0_LVC2_SDA    I61 @BASEBOARD_FAB2_LIB.BASEBOARD_FAB2(SCH_1):PAGE29
  BP19 IRQ_HFI0_CPU0_LVT2_N @BASEBOARD_FAB2_LIB.BASEBOARD_FAB2(SCH_1):IRQ_HFI0_CPU0_LVT2_N    I61 @BASEBOARD_FAB2_LIB.BASEBOARD_FAB2(SCH_1):PAGE29
  BK21 LED_HFI0_CPU0_N @BASEBOARD_FAB2_LIB.BASEBOARD_FAB2(SCH_1):LED_HFI0_CPU0_N    I61 @BASEBOARD_FAB2_LIB.BASEBOARD_FAB2(SCH_1):PAGE29
  BR20 FM_MODPRST_HFI0_CPU0_LVT2_N @BASEBOARD_FAB2_LIB.BASEBOARD_FAB2(SCH_1):FM_MODPRST_HFI0_CPU0_LVT2_N    I61 @BASEBOARD_FAB2_LIB.BASEBOARD_FAB2(SCH_1):PAGE29
  BN24 RST_HFI0_CPU0_LVT2_N @BASEBOARD_FAB2_LIB.BASEBOARD_FAB2(SCH_1):RST_HFI0_CPU0_LVT2_N    I61 @BASEBOARD_FAB2_LIB.BASEBOARD_FAB2(SCH_1):PAGE29
  BJ22 SMB_HFI1_CPU0_LVC2_SCL @BASEBOARD_FAB2_LIB.BASEBOARD_FAB2(SCH_1):SMB_HFI1_CPU0_LVC2_SCL    I61 @BASEBOARD_FAB2_LIB.BASEBOARD_FAB2(SCH_1):PAGE29
  BH23 SMB_HFI1_CPU0_LVC2_SDA @BASEBOARD_FAB2_LIB.BASEBOARD_FAB2(SCH_1):SMB_HFI1_CPU0_LVC2_SDA    I61 @BASEBOARD_FAB2_LIB.BASEBOARD_FAB2(SCH_1):PAGE29
  BM21 IRQ_HFI1_CPU0_LVT2_N @BASEBOARD_FAB2_LIB.BASEBOARD_FAB2(SCH_1):IRQ_HFI1_CPU0_LVT2_N    I61 @BASEBOARD_FAB2_LIB.BASEBOARD_FAB2(SCH_1):PAGE29
  BM23 LED_HFI1_CPU0_N @BASEBOARD_FAB2_LIB.BASEBOARD_FAB2(SCH_1):LED_HFI1_CPU0_N    I61 @BASEBOARD_FAB2_LIB.BASEBOARD_FAB2(SCH_1):PAGE29
  BT19 FM_MODPRST_HFI1_CPU0_LVT2_N @BASEBOARD_FAB2_LIB.BASEBOARD_FAB2(SCH_1):FM_MODPRST_HFI1_CPU0_LVT2_N    I61 @BASEBOARD_FAB2_LIB.BASEBOARD_FAB2(SCH_1):PAGE29
  BK23 RST_HFI1_CPU0_LVT2_N @BASEBOARD_FAB2_LIB.BASEBOARD_FAB2(SCH_1):RST_HFI1_CPU0_LVT2_N    I61 @BASEBOARD_FAB2_LIB.BASEBOARD_FAB2(SCH_1):PAGE29
  BE16 CLK_156M_OSC_CPU0_HFI_DN @BASEBOARD_FAB2_LIB.BASEBOARD_FAB2(SCH_1):CLK_156M_OSC_CPU0_HFI_DN    I61 @BASEBOARD_FAB2_LIB.BASEBOARD_FAB2(SCH_1):PAGE29
  BG16 CLK_156M_OSC_CPU0_HFI_DP @BASEBOARD_FAB2_LIB.BASEBOARD_FAB2(SCH_1):CLK_156M_OSC_CPU0_HFI_DP    I61 @BASEBOARD_FAB2_LIB.BASEBOARD_FAB2(SCH_1):PAGE29
  BU24 CLK_100M_CPU0_PE_REFCLK_DN @BASEBOARD_FAB2_LIB.BASEBOARD_FAB2(SCH_1):CLK_100M_CPU0_PE_REFCLK_DN    I61 @BASEBOARD_FAB2_LIB.BASEBOARD_FAB2(SCH_1):PAGE29
  BW24 CLK_100M_CPU0_PE_REFCLK_DP @BASEBOARD_FAB2_LIB.BASEBOARD_FAB2(SCH_1):CLK_100M_CPU0_PE_REFCLK_DP    I61 @BASEBOARD_FAB2_LIB.BASEBOARD_FAB2(SCH_1):PAGE29
  CF25 RST_CD_CPU0_POR_N @BASEBOARD_FAB2_LIB.BASEBOARD_FAB2(SCH_1):RST_CD_CPU0_POR_N    I61 @BASEBOARD_FAB2_LIB.BASEBOARD_FAB2(SCH_1):PAGE29
  CB23 JTAG_MCP_TCK @BASEBOARD_FAB2_LIB.BASEBOARD_FAB2(SCH_1):JTAG_MCP_TCK    I61 @BASEBOARD_FAB2_LIB.BASEBOARD_FAB2(SCH_1):PAGE29
  BY21 JTAG_MCP_CPU0_TDI @BASEBOARD_FAB2_LIB.BASEBOARD_FAB2(SCH_1):JTAG_MCP_CPU0_TDI    I61 @BASEBOARD_FAB2_LIB.BASEBOARD_FAB2(SCH_1):PAGE29
  CC22 JTAG_MCP_CPU0_TDO @BASEBOARD_FAB2_LIB.BASEBOARD_FAB2(SCH_1):JTAG_MCP_CPU0_TDO    I61 @BASEBOARD_FAB2_LIB.BASEBOARD_FAB2(SCH_1):PAGE29
  CE24 JTAG_MCP_TMS @BASEBOARD_FAB2_LIB.BASEBOARD_FAB2(SCH_1):JTAG_MCP_TMS    I61 @BASEBOARD_FAB2_LIB.BASEBOARD_FAB2(SCH_1):PAGE29
  CD23 JTAG_MCP_TRST_N @BASEBOARD_FAB2_LIB.BASEBOARD_FAB2(SCH_1):JTAG_MCP_TRST_N    I61 @BASEBOARD_FAB2_LIB.BASEBOARD_FAB2(SCH_1):PAGE29
  CT11 DMI_CPU0_PCH_RX_C_DN<3> @BASEBOARD_FAB2_LIB.BASEBOARD_FAB2(SCH_1):DMI_CPU0_PCH_RX_C_DN(3)    I61 @BASEBOARD_FAB2_LIB.BASEBOARD_FAB2(SCH_1):PAGE29
  CR12 DMI_CPU0_PCH_RX_C_DN<2> @BASEBOARD_FAB2_LIB.BASEBOARD_FAB2(SCH_1):DMI_CPU0_PCH_RX_C_DN(2)    I61 @BASEBOARD_FAB2_LIB.BASEBOARD_FAB2(SCH_1):PAGE29
  CM11 DMI_CPU0_PCH_RX_C_DN<1> @BASEBOARD_FAB2_LIB.BASEBOARD_FAB2(SCH_1):DMI_CPU0_PCH_RX_C_DN(1)    I61 @BASEBOARD_FAB2_LIB.BASEBOARD_FAB2(SCH_1):PAGE29
   CK9 DMI_CPU0_PCH_RX_C_DN<0> @BASEBOARD_FAB2_LIB.BASEBOARD_FAB2(SCH_1):DMI_CPU0_PCH_RX_C_DN(0)    I61 @BASEBOARD_FAB2_LIB.BASEBOARD_FAB2(SCH_1):PAGE29
  CV11 DMI_CPU0_PCH_RX_C_DP<3> @BASEBOARD_FAB2_LIB.BASEBOARD_FAB2(SCH_1):DMI_CPU0_PCH_RX_C_DP(3)    I61 @BASEBOARD_FAB2_LIB.BASEBOARD_FAB2(SCH_1):PAGE29
  CP11 DMI_CPU0_PCH_RX_C_DP<2> @BASEBOARD_FAB2_LIB.BASEBOARD_FAB2(SCH_1):DMI_CPU0_PCH_RX_C_DP(2)    I61 @BASEBOARD_FAB2_LIB.BASEBOARD_FAB2(SCH_1):PAGE29
  CN10 DMI_CPU0_PCH_RX_C_DP<1> @BASEBOARD_FAB2_LIB.BASEBOARD_FAB2(SCH_1):DMI_CPU0_PCH_RX_C_DP(1)    I61 @BASEBOARD_FAB2_LIB.BASEBOARD_FAB2(SCH_1):PAGE29
  CL10 DMI_CPU0_PCH_RX_C_DP<0> @BASEBOARD_FAB2_LIB.BASEBOARD_FAB2(SCH_1):DMI_CPU0_PCH_RX_C_DP(0)    I61 @BASEBOARD_FAB2_LIB.BASEBOARD_FAB2(SCH_1):PAGE29
   CP5 DMI_CPU0_PCH_TX_DN<3> @BASEBOARD_FAB2_LIB.BASEBOARD_FAB2(SCH_1):DMI_CPU0_PCH_TX_DN(3)    I61 @BASEBOARD_FAB2_LIB.BASEBOARD_FAB2(SCH_1):PAGE29
   CN4 DMI_CPU0_PCH_TX_DN<2> @BASEBOARD_FAB2_LIB.BASEBOARD_FAB2(SCH_1):DMI_CPU0_PCH_TX_DN(2)    I61 @BASEBOARD_FAB2_LIB.BASEBOARD_FAB2(SCH_1):PAGE29
   CJ4 DMI_CPU0_PCH_TX_DN<1> @BASEBOARD_FAB2_LIB.BASEBOARD_FAB2(SCH_1):DMI_CPU0_PCH_TX_DN(1)    I61 @BASEBOARD_FAB2_LIB.BASEBOARD_FAB2(SCH_1):PAGE29
   CG4 DMI_CPU0_PCH_TX_DN<0> @BASEBOARD_FAB2_LIB.BASEBOARD_FAB2(SCH_1):DMI_CPU0_PCH_TX_DN(0)    I61 @BASEBOARD_FAB2_LIB.BASEBOARD_FAB2(SCH_1):PAGE29
   CR4 DMI_CPU0_PCH_TX_DP<3> @BASEBOARD_FAB2_LIB.BASEBOARD_FAB2(SCH_1):DMI_CPU0_PCH_TX_DP(3)    I61 @BASEBOARD_FAB2_LIB.BASEBOARD_FAB2(SCH_1):PAGE29
   CM3 DMI_CPU0_PCH_TX_DP<2> @BASEBOARD_FAB2_LIB.BASEBOARD_FAB2(SCH_1):DMI_CPU0_PCH_TX_DP(2)    I61 @BASEBOARD_FAB2_LIB.BASEBOARD_FAB2(SCH_1):PAGE29
   CL4 DMI_CPU0_PCH_TX_DP<1> @BASEBOARD_FAB2_LIB.BASEBOARD_FAB2(SCH_1):DMI_CPU0_PCH_TX_DP(1)    I61 @BASEBOARD_FAB2_LIB.BASEBOARD_FAB2(SCH_1):PAGE29
   CH5 DMI_CPU0_PCH_TX_DP<0> @BASEBOARD_FAB2_LIB.BASEBOARD_FAB2(SCH_1):DMI_CPU0_PCH_TX_DP(0)    I61 @BASEBOARD_FAB2_LIB.BASEBOARD_FAB2(SCH_1):PAGE29
  AR20 PVCCMCP_CPU0 @BASEBOARD_FAB2_LIB.BASEBOARD_FAB2(SCH_1):PVCCMCP_CPU0    I61 @BASEBOARD_FAB2_LIB.BASEBOARD_FAB2(SCH_1):PAGE29
  AR22 PVCCMCP_CPU0 @BASEBOARD_FAB2_LIB.BASEBOARD_FAB2(SCH_1):PVCCMCP_CPU0    I61 @BASEBOARD_FAB2_LIB.BASEBOARD_FAB2(SCH_1):PAGE29
  AR26 PVCCMCP_CPU0 @BASEBOARD_FAB2_LIB.BASEBOARD_FAB2(SCH_1):PVCCMCP_CPU0    I61 @BASEBOARD_FAB2_LIB.BASEBOARD_FAB2(SCH_1):PAGE29
  AR62 TP_CPU0_RSVD_190 @BASEBOARD_FAB2_LIB.BASEBOARD_FAB2(SCH_1):TP_CPU0_RSVD_190    I61 @BASEBOARD_FAB2_LIB.BASEBOARD_FAB2(SCH_1):PAGE29
  AT13 TP_CPU0_RSVD_189 @BASEBOARD_FAB2_LIB.BASEBOARD_FAB2(SCH_1):TP_CPU0_RSVD_189    I61 @BASEBOARD_FAB2_LIB.BASEBOARD_FAB2(SCH_1):PAGE29
  AT23 PVCCMCP_CPU0 @BASEBOARD_FAB2_LIB.BASEBOARD_FAB2(SCH_1):PVCCMCP_CPU0    I61 @BASEBOARD_FAB2_LIB.BASEBOARD_FAB2(SCH_1):PAGE29
  AT25 PVCCMCP_CPU0 @BASEBOARD_FAB2_LIB.BASEBOARD_FAB2(SCH_1):PVCCMCP_CPU0    I61 @BASEBOARD_FAB2_LIB.BASEBOARD_FAB2(SCH_1):PAGE29
  AV77 TP_CPU0_RSVD_186 @BASEBOARD_FAB2_LIB.BASEBOARD_FAB2(SCH_1):TP_CPU0_RSVD_186    I61 @BASEBOARD_FAB2_LIB.BASEBOARD_FAB2(SCH_1):PAGE29
  AW64 TP_CPU0_RSVD_184 @BASEBOARD_FAB2_LIB.BASEBOARD_FAB2(SCH_1):TP_CPU0_RSVD_184    I61 @BASEBOARD_FAB2_LIB.BASEBOARD_FAB2(SCH_1):PAGE29
  AW76 TP_CPU0_RSVD_183 @BASEBOARD_FAB2_LIB.BASEBOARD_FAB2(SCH_1):TP_CPU0_RSVD_183    I61 @BASEBOARD_FAB2_LIB.BASEBOARD_FAB2(SCH_1):PAGE29
  AY65 TP_CPU0_RSVD_182 @BASEBOARD_FAB2_LIB.BASEBOARD_FAB2(SCH_1):TP_CPU0_RSVD_182    I61 @BASEBOARD_FAB2_LIB.BASEBOARD_FAB2(SCH_1):PAGE29
  AY67 TP_CPU0_RSVD_181 @BASEBOARD_FAB2_LIB.BASEBOARD_FAB2(SCH_1):TP_CPU0_RSVD_181    I61 @BASEBOARD_FAB2_LIB.BASEBOARD_FAB2(SCH_1):PAGE29
  AY75 TP_CPU0_RSVD_180 @BASEBOARD_FAB2_LIB.BASEBOARD_FAB2(SCH_1):TP_CPU0_RSVD_180    I61 @BASEBOARD_FAB2_LIB.BASEBOARD_FAB2(SCH_1):PAGE29
  AY77 TP_CPU0_RSVD_179 @BASEBOARD_FAB2_LIB.BASEBOARD_FAB2(SCH_1):TP_CPU0_RSVD_179    I61 @BASEBOARD_FAB2_LIB.BASEBOARD_FAB2(SCH_1):PAGE29
  BA14 TP_CPU0_RSVD_178 @BASEBOARD_FAB2_LIB.BASEBOARD_FAB2(SCH_1):TP_CPU0_RSVD_178    I61 @BASEBOARD_FAB2_LIB.BASEBOARD_FAB2(SCH_1):PAGE29
  BA16 TP_CPU0_RSVD_177 @BASEBOARD_FAB2_LIB.BASEBOARD_FAB2(SCH_1):TP_CPU0_RSVD_177    I61 @BASEBOARD_FAB2_LIB.BASEBOARD_FAB2(SCH_1):PAGE29
  BA18 TP_CPU0_RSVD_176 @BASEBOARD_FAB2_LIB.BASEBOARD_FAB2(SCH_1):TP_CPU0_RSVD_176    I61 @BASEBOARD_FAB2_LIB.BASEBOARD_FAB2(SCH_1):PAGE29
  BA22 TP_CPU0_RSVD_175 @BASEBOARD_FAB2_LIB.BASEBOARD_FAB2(SCH_1):TP_CPU0_RSVD_175    I61 @BASEBOARD_FAB2_LIB.BASEBOARD_FAB2(SCH_1):PAGE29
  BA64 TP_CPU0_RSVD_174 @BASEBOARD_FAB2_LIB.BASEBOARD_FAB2(SCH_1):TP_CPU0_RSVD_174    I61 @BASEBOARD_FAB2_LIB.BASEBOARD_FAB2(SCH_1):PAGE29
  BA66 TP_CPU0_RSVD_173 @BASEBOARD_FAB2_LIB.BASEBOARD_FAB2(SCH_1):TP_CPU0_RSVD_173    I61 @BASEBOARD_FAB2_LIB.BASEBOARD_FAB2(SCH_1):PAGE29
  BA76 TP_CPU0_RSVD_172 @BASEBOARD_FAB2_LIB.BASEBOARD_FAB2(SCH_1):TP_CPU0_RSVD_172    I61 @BASEBOARD_FAB2_LIB.BASEBOARD_FAB2(SCH_1):PAGE29
  DU16 P3E_CPU0_PE1_PCH_RXN<15> @BASEBOARD_FAB2_LIB.BASEBOARD_FAB2(SCH_1):P3E_CPU0_PE1_PCH_RXN(15)    I84 @BASEBOARD_FAB2_LIB.BASEBOARD_FAB2(SCH_1):PAGE30
  DY15 P3E_CPU0_PE1_PCH_RXN<14> @BASEBOARD_FAB2_LIB.BASEBOARD_FAB2(SCH_1):P3E_CPU0_PE1_PCH_RXN(14)    I84 @BASEBOARD_FAB2_LIB.BASEBOARD_FAB2(SCH_1):PAGE30
  DW14 P3E_CPU0_PE1_PCH_RXN<13> @BASEBOARD_FAB2_LIB.BASEBOARD_FAB2(SCH_1):P3E_CPU0_PE1_PCH_RXN(13)    I84 @BASEBOARD_FAB2_LIB.BASEBOARD_FAB2(SCH_1):PAGE30
  DV13 P3E_CPU0_PE1_PCH_RXN<12> @BASEBOARD_FAB2_LIB.BASEBOARD_FAB2(SCH_1):P3E_CPU0_PE1_PCH_RXN(12)    I84 @BASEBOARD_FAB2_LIB.BASEBOARD_FAB2(SCH_1):PAGE30
  DT13 P3E_CPU0_PE1_PCH_RXN<11> @BASEBOARD_FAB2_LIB.BASEBOARD_FAB2(SCH_1):P3E_CPU0_PE1_PCH_RXN(11)    I84 @BASEBOARD_FAB2_LIB.BASEBOARD_FAB2(SCH_1):PAGE30
  DT11 P3E_CPU0_PE1_PCH_RXN<10> @BASEBOARD_FAB2_LIB.BASEBOARD_FAB2(SCH_1):P3E_CPU0_PE1_PCH_RXN(10)    I84 @BASEBOARD_FAB2_LIB.BASEBOARD_FAB2(SCH_1):PAGE30
  DP11 P3E_CPU0_PE1_PCH_RXN<9> @BASEBOARD_FAB2_LIB.BASEBOARD_FAB2(SCH_1):P3E_CPU0_PE1_PCH_RXN(9)    I84 @BASEBOARD_FAB2_LIB.BASEBOARD_FAB2(SCH_1):PAGE30
  DM11 P3E_CPU0_PE1_PCH_RXN<8> @BASEBOARD_FAB2_LIB.BASEBOARD_FAB2(SCH_1):P3E_CPU0_PE1_PCH_RXN(8)    I84 @BASEBOARD_FAB2_LIB.BASEBOARD_FAB2(SCH_1):PAGE30
   DM9 P3E_CPU0_PE1_SS_RXN<7> @BASEBOARD_FAB2_LIB.BASEBOARD_FAB2(SCH_1):P3E_CPU0_PE1_SS_RXN(7)    I84 @BASEBOARD_FAB2_LIB.BASEBOARD_FAB2(SCH_1):PAGE30
   DK9 P3E_CPU0_PE1_SS_RXN<6> @BASEBOARD_FAB2_LIB.BASEBOARD_FAB2(SCH_1):P3E_CPU0_PE1_SS_RXN(6)    I84 @BASEBOARD_FAB2_LIB.BASEBOARD_FAB2(SCH_1):PAGE30
   DH9 P3E_CPU0_PE1_SS_RXN<5> @BASEBOARD_FAB2_LIB.BASEBOARD_FAB2(SCH_1):P3E_CPU0_PE1_SS_RXN(5)    I84 @BASEBOARD_FAB2_LIB.BASEBOARD_FAB2(SCH_1):PAGE30
  DE10 P3E_CPU0_PE1_SS_RXN<4> @BASEBOARD_FAB2_LIB.BASEBOARD_FAB2(SCH_1):P3E_CPU0_PE1_SS_RXN(4)    I84 @BASEBOARD_FAB2_LIB.BASEBOARD_FAB2(SCH_1):PAGE30
  DC10 P3E_CPU0_PE1_SS_RXN<3> @BASEBOARD_FAB2_LIB.BASEBOARD_FAB2(SCH_1):P3E_CPU0_PE1_SS_RXN(3)    I84 @BASEBOARD_FAB2_LIB.BASEBOARD_FAB2(SCH_1):PAGE30
   DC8 P3E_CPU0_PE1_SS_RXN<2> @BASEBOARD_FAB2_LIB.BASEBOARD_FAB2(SCH_1):P3E_CPU0_PE1_SS_RXN(2)    I84 @BASEBOARD_FAB2_LIB.BASEBOARD_FAB2(SCH_1):PAGE30
   DA8 P3E_CPU0_PE1_SS_RXN<1> @BASEBOARD_FAB2_LIB.BASEBOARD_FAB2(SCH_1):P3E_CPU0_PE1_SS_RXN(1)    I84 @BASEBOARD_FAB2_LIB.BASEBOARD_FAB2(SCH_1):PAGE30
   CW8 P3E_CPU0_PE1_SS_RXN<0> @BASEBOARD_FAB2_LIB.BASEBOARD_FAB2(SCH_1):P3E_CPU0_PE1_SS_RXN(0)    I84 @BASEBOARD_FAB2_LIB.BASEBOARD_FAB2(SCH_1):PAGE30
  DT15 P3E_CPU0_PE1_PCH_RXP<15> @BASEBOARD_FAB2_LIB.BASEBOARD_FAB2(SCH_1):P3E_CPU0_PE1_PCH_RXP(15)    I84 @BASEBOARD_FAB2_LIB.BASEBOARD_FAB2(SCH_1):PAGE30
  DV15 P3E_CPU0_PE1_PCH_RXP<14> @BASEBOARD_FAB2_LIB.BASEBOARD_FAB2(SCH_1):P3E_CPU0_PE1_PCH_RXP(14)    I84 @BASEBOARD_FAB2_LIB.BASEBOARD_FAB2(SCH_1):PAGE30
  DY13 P3E_CPU0_PE1_PCH_RXP<13> @BASEBOARD_FAB2_LIB.BASEBOARD_FAB2(SCH_1):P3E_CPU0_PE1_PCH_RXP(13)    I84 @BASEBOARD_FAB2_LIB.BASEBOARD_FAB2(SCH_1):PAGE30
  DU12 P3E_CPU0_PE1_PCH_RXP<12> @BASEBOARD_FAB2_LIB.BASEBOARD_FAB2(SCH_1):P3E_CPU0_PE1_PCH_RXP(12)    I84 @BASEBOARD_FAB2_LIB.BASEBOARD_FAB2(SCH_1):PAGE30
  DP13 P3E_CPU0_PE1_PCH_RXP<11> @BASEBOARD_FAB2_LIB.BASEBOARD_FAB2(SCH_1):P3E_CPU0_PE1_PCH_RXP(11)    I84 @BASEBOARD_FAB2_LIB.BASEBOARD_FAB2(SCH_1):PAGE30
  DR12 P3E_CPU0_PE1_PCH_RXP<10> @BASEBOARD_FAB2_LIB.BASEBOARD_FAB2(SCH_1):P3E_CPU0_PE1_PCH_RXP(10)    I84 @BASEBOARD_FAB2_LIB.BASEBOARD_FAB2(SCH_1):PAGE30
  DN10 P3E_CPU0_PE1_PCH_RXP<9> @BASEBOARD_FAB2_LIB.BASEBOARD_FAB2(SCH_1):P3E_CPU0_PE1_PCH_RXP(9)    I84 @BASEBOARD_FAB2_LIB.BASEBOARD_FAB2(SCH_1):PAGE30
  DK11 P3E_CPU0_PE1_PCH_RXP<8> @BASEBOARD_FAB2_LIB.BASEBOARD_FAB2(SCH_1):P3E_CPU0_PE1_PCH_RXP(8)    I84 @BASEBOARD_FAB2_LIB.BASEBOARD_FAB2(SCH_1):PAGE30
  DL10 P3E_CPU0_PE1_SS_RXP<7> @BASEBOARD_FAB2_LIB.BASEBOARD_FAB2(SCH_1):P3E_CPU0_PE1_SS_RXP(7)    I84 @BASEBOARD_FAB2_LIB.BASEBOARD_FAB2(SCH_1):PAGE30
   DJ8 P3E_CPU0_PE1_SS_RXP<6> @BASEBOARD_FAB2_LIB.BASEBOARD_FAB2(SCH_1):P3E_CPU0_PE1_SS_RXP(6)    I84 @BASEBOARD_FAB2_LIB.BASEBOARD_FAB2(SCH_1):PAGE30
   DF9 P3E_CPU0_PE1_SS_RXP<5> @BASEBOARD_FAB2_LIB.BASEBOARD_FAB2(SCH_1):P3E_CPU0_PE1_SS_RXP(5)    I84 @BASEBOARD_FAB2_LIB.BASEBOARD_FAB2(SCH_1):PAGE30
   DD9 P3E_CPU0_PE1_SS_RXP<4> @BASEBOARD_FAB2_LIB.BASEBOARD_FAB2(SCH_1):P3E_CPU0_PE1_SS_RXP(4)    I84 @BASEBOARD_FAB2_LIB.BASEBOARD_FAB2(SCH_1):PAGE30
  DA10 P3E_CPU0_PE1_SS_RXP<3> @BASEBOARD_FAB2_LIB.BASEBOARD_FAB2(SCH_1):P3E_CPU0_PE1_SS_RXP(3)    I84 @BASEBOARD_FAB2_LIB.BASEBOARD_FAB2(SCH_1):PAGE30
   DB9 P3E_CPU0_PE1_SS_RXP<2> @BASEBOARD_FAB2_LIB.BASEBOARD_FAB2(SCH_1):P3E_CPU0_PE1_SS_RXP(2)    I84 @BASEBOARD_FAB2_LIB.BASEBOARD_FAB2(SCH_1):PAGE30
   CY7 P3E_CPU0_PE1_SS_RXP<1> @BASEBOARD_FAB2_LIB.BASEBOARD_FAB2(SCH_1):P3E_CPU0_PE1_SS_RXP(1)    I84 @BASEBOARD_FAB2_LIB.BASEBOARD_FAB2(SCH_1):PAGE30
   CU8 P3E_CPU0_PE1_SS_RXP<0> @BASEBOARD_FAB2_LIB.BASEBOARD_FAB2(SCH_1):P3E_CPU0_PE1_SS_RXP(0)    I84 @BASEBOARD_FAB2_LIB.BASEBOARD_FAB2(SCH_1):PAGE30
   ED9 P3E_CPU0_PE1_PCH_TXN<15> @BASEBOARD_FAB2_LIB.BASEBOARD_FAB2(SCH_1):P3E_CPU0_PE1_PCH_TXN(15)    I84 @BASEBOARD_FAB2_LIB.BASEBOARD_FAB2(SCH_1):PAGE30
   EA8 P3E_CPU0_PE1_PCH_TXN<14> @BASEBOARD_FAB2_LIB.BASEBOARD_FAB2(SCH_1):P3E_CPU0_PE1_PCH_TXN(14)    I84 @BASEBOARD_FAB2_LIB.BASEBOARD_FAB2(SCH_1):PAGE30
   DY7 P3E_CPU0_PE1_PCH_TXN<13> @BASEBOARD_FAB2_LIB.BASEBOARD_FAB2(SCH_1):P3E_CPU0_PE1_PCH_TXN(13)    I84 @BASEBOARD_FAB2_LIB.BASEBOARD_FAB2(SCH_1):PAGE30
   DV7 P3E_CPU0_PE1_PCH_TXN<12> @BASEBOARD_FAB2_LIB.BASEBOARD_FAB2(SCH_1):P3E_CPU0_PE1_PCH_TXN(12)    I84 @BASEBOARD_FAB2_LIB.BASEBOARD_FAB2(SCH_1):PAGE30
   DU6 P3E_CPU0_PE1_PCH_TXN<11> @BASEBOARD_FAB2_LIB.BASEBOARD_FAB2(SCH_1):P3E_CPU0_PE1_PCH_TXN(11)    I84 @BASEBOARD_FAB2_LIB.BASEBOARD_FAB2(SCH_1):PAGE30
   DW4 P3E_CPU0_PE1_PCH_TXN<10> @BASEBOARD_FAB2_LIB.BASEBOARD_FAB2(SCH_1):P3E_CPU0_PE1_PCH_TXN(10)    I84 @BASEBOARD_FAB2_LIB.BASEBOARD_FAB2(SCH_1):PAGE30
   DV3 P3E_CPU0_PE1_PCH_TXN<9> @BASEBOARD_FAB2_LIB.BASEBOARD_FAB2(SCH_1):P3E_CPU0_PE1_PCH_TXN(9)    I84 @BASEBOARD_FAB2_LIB.BASEBOARD_FAB2(SCH_1):PAGE30
   DT5 P3E_CPU0_PE1_PCH_TXN<8> @BASEBOARD_FAB2_LIB.BASEBOARD_FAB2(SCH_1):P3E_CPU0_PE1_PCH_TXN(8)    I84 @BASEBOARD_FAB2_LIB.BASEBOARD_FAB2(SCH_1):PAGE30
   DN4 P3E_CPU0_PE1_SS_TXN<7> @BASEBOARD_FAB2_LIB.BASEBOARD_FAB2(SCH_1):P3E_CPU0_PE1_SS_TXN(7)    I84 @BASEBOARD_FAB2_LIB.BASEBOARD_FAB2(SCH_1):PAGE30
   DM3 P3E_CPU0_PE1_SS_TXN<6> @BASEBOARD_FAB2_LIB.BASEBOARD_FAB2(SCH_1):P3E_CPU0_PE1_SS_TXN(6)    I84 @BASEBOARD_FAB2_LIB.BASEBOARD_FAB2(SCH_1):PAGE30
   DK3 P3E_CPU0_PE1_SS_TXN<5> @BASEBOARD_FAB2_LIB.BASEBOARD_FAB2(SCH_1):P3E_CPU0_PE1_SS_TXN(5)    I84 @BASEBOARD_FAB2_LIB.BASEBOARD_FAB2(SCH_1):PAGE30
   DG4 P3E_CPU0_PE1_SS_TXN<4> @BASEBOARD_FAB2_LIB.BASEBOARD_FAB2(SCH_1):P3E_CPU0_PE1_SS_TXN(4)    I84 @BASEBOARD_FAB2_LIB.BASEBOARD_FAB2(SCH_1):PAGE30
   DE4 P3E_CPU0_PE1_SS_TXN<3> @BASEBOARD_FAB2_LIB.BASEBOARD_FAB2(SCH_1):P3E_CPU0_PE1_SS_TXN(3)    I84 @BASEBOARD_FAB2_LIB.BASEBOARD_FAB2(SCH_1):PAGE30
   DE2 P3E_CPU0_PE1_SS_TXN<2> @BASEBOARD_FAB2_LIB.BASEBOARD_FAB2(SCH_1):P3E_CPU0_PE1_SS_TXN(2)    I84 @BASEBOARD_FAB2_LIB.BASEBOARD_FAB2(SCH_1):PAGE30
   DC2 P3E_CPU0_PE1_SS_TXN<1> @BASEBOARD_FAB2_LIB.BASEBOARD_FAB2(SCH_1):P3E_CPU0_PE1_SS_TXN(1)    I84 @BASEBOARD_FAB2_LIB.BASEBOARD_FAB2(SCH_1):PAGE30
   DA2 P3E_CPU0_PE1_SS_TXN<0> @BASEBOARD_FAB2_LIB.BASEBOARD_FAB2(SCH_1):P3E_CPU0_PE1_SS_TXN(0)    I84 @BASEBOARD_FAB2_LIB.BASEBOARD_FAB2(SCH_1):PAGE30
   EC8 P3E_CPU0_PE1_PCH_TXP<15> @BASEBOARD_FAB2_LIB.BASEBOARD_FAB2(SCH_1):P3E_CPU0_PE1_PCH_TXP(15)    I84 @BASEBOARD_FAB2_LIB.BASEBOARD_FAB2(SCH_1):PAGE30
   EB7 P3E_CPU0_PE1_PCH_TXP<14> @BASEBOARD_FAB2_LIB.BASEBOARD_FAB2(SCH_1):P3E_CPU0_PE1_PCH_TXP(14)    I84 @BASEBOARD_FAB2_LIB.BASEBOARD_FAB2(SCH_1):PAGE30
   DW6 P3E_CPU0_PE1_PCH_TXP<13> @BASEBOARD_FAB2_LIB.BASEBOARD_FAB2(SCH_1):P3E_CPU0_PE1_PCH_TXP(13)    I84 @BASEBOARD_FAB2_LIB.BASEBOARD_FAB2(SCH_1):PAGE30
   DT7 P3E_CPU0_PE1_PCH_TXP<12> @BASEBOARD_FAB2_LIB.BASEBOARD_FAB2(SCH_1):P3E_CPU0_PE1_PCH_TXP(12)    I84 @BASEBOARD_FAB2_LIB.BASEBOARD_FAB2(SCH_1):PAGE30
   DV5 P3E_CPU0_PE1_PCH_TXP<11> @BASEBOARD_FAB2_LIB.BASEBOARD_FAB2(SCH_1):P3E_CPU0_PE1_PCH_TXP(11)    I84 @BASEBOARD_FAB2_LIB.BASEBOARD_FAB2(SCH_1):PAGE30
   DU4 P3E_CPU0_PE1_PCH_TXP<10> @BASEBOARD_FAB2_LIB.BASEBOARD_FAB2(SCH_1):P3E_CPU0_PE1_PCH_TXP(10)    I84 @BASEBOARD_FAB2_LIB.BASEBOARD_FAB2(SCH_1):PAGE30
   DU2 P3E_CPU0_PE1_PCH_TXP<9> @BASEBOARD_FAB2_LIB.BASEBOARD_FAB2(SCH_1):P3E_CPU0_PE1_PCH_TXP(9)    I84 @BASEBOARD_FAB2_LIB.BASEBOARD_FAB2(SCH_1):PAGE30
   DR4 P3E_CPU0_PE1_PCH_TXP<8> @BASEBOARD_FAB2_LIB.BASEBOARD_FAB2(SCH_1):P3E_CPU0_PE1_PCH_TXP(8)    I84 @BASEBOARD_FAB2_LIB.BASEBOARD_FAB2(SCH_1):PAGE30
   DP3 P3E_CPU0_PE1_SS_TXP<7> @BASEBOARD_FAB2_LIB.BASEBOARD_FAB2(SCH_1):P3E_CPU0_PE1_SS_TXP(7)    I84 @BASEBOARD_FAB2_LIB.BASEBOARD_FAB2(SCH_1):PAGE30
   DL2 P3E_CPU0_PE1_SS_TXP<6> @BASEBOARD_FAB2_LIB.BASEBOARD_FAB2(SCH_1):P3E_CPU0_PE1_SS_TXP(6)    I84 @BASEBOARD_FAB2_LIB.BASEBOARD_FAB2(SCH_1):PAGE30
   DH3 P3E_CPU0_PE1_SS_TXP<5> @BASEBOARD_FAB2_LIB.BASEBOARD_FAB2(SCH_1):P3E_CPU0_PE1_SS_TXP(5)    I84 @BASEBOARD_FAB2_LIB.BASEBOARD_FAB2(SCH_1):PAGE30
   DF3 P3E_CPU0_PE1_SS_TXP<4> @BASEBOARD_FAB2_LIB.BASEBOARD_FAB2(SCH_1):P3E_CPU0_PE1_SS_TXP(4)    I84 @BASEBOARD_FAB2_LIB.BASEBOARD_FAB2(SCH_1):PAGE30
   DC4 P3E_CPU0_PE1_SS_TXP<3> @BASEBOARD_FAB2_LIB.BASEBOARD_FAB2(SCH_1):P3E_CPU0_PE1_SS_TXP(3)    I84 @BASEBOARD_FAB2_LIB.BASEBOARD_FAB2(SCH_1):PAGE30
   DD3 P3E_CPU0_PE1_SS_TXP<2> @BASEBOARD_FAB2_LIB.BASEBOARD_FAB2(SCH_1):P3E_CPU0_PE1_SS_TXP(2)    I84 @BASEBOARD_FAB2_LIB.BASEBOARD_FAB2(SCH_1):PAGE30
   DB1 P3E_CPU0_PE1_SS_TXP<1> @BASEBOARD_FAB2_LIB.BASEBOARD_FAB2(SCH_1):P3E_CPU0_PE1_SS_TXP(1)    I84 @BASEBOARD_FAB2_LIB.BASEBOARD_FAB2(SCH_1):PAGE30
   CW2 P3E_CPU0_PE1_SS_TXP<0> @BASEBOARD_FAB2_LIB.BASEBOARD_FAB2(SCH_1):P3E_CPU0_PE1_SS_TXP(0)    I84 @BASEBOARD_FAB2_LIB.BASEBOARD_FAB2(SCH_1):PAGE30
   BK9 P3E_CPU0_PE2_SS_RXN<15> @BASEBOARD_FAB2_LIB.BASEBOARD_FAB2(SCH_1):P3E_CPU0_PE2_SS_RXN(15)   I106 @BASEBOARD_FAB2_LIB.BASEBOARD_FAB2(SCH_1):PAGE31
   BL8 P3E_CPU0_PE2_SS_RXN<14> @BASEBOARD_FAB2_LIB.BASEBOARD_FAB2(SCH_1):P3E_CPU0_PE2_SS_RXN(14)   I106 @BASEBOARD_FAB2_LIB.BASEBOARD_FAB2(SCH_1):PAGE31
   BN8 P3E_CPU0_PE2_SS_RXN<13> @BASEBOARD_FAB2_LIB.BASEBOARD_FAB2(SCH_1):P3E_CPU0_PE2_SS_RXN(13)   I106 @BASEBOARD_FAB2_LIB.BASEBOARD_FAB2(SCH_1):PAGE31
   BR8 P3E_CPU0_PE2_SS_RXN<12> @BASEBOARD_FAB2_LIB.BASEBOARD_FAB2(SCH_1):P3E_CPU0_PE2_SS_RXN(12)   I106 @BASEBOARD_FAB2_LIB.BASEBOARD_FAB2(SCH_1):PAGE31
   BT7 P3E_CPU0_PE2_SS_RXN<11> @BASEBOARD_FAB2_LIB.BASEBOARD_FAB2(SCH_1):P3E_CPU0_PE2_SS_RXN(11)   I106 @BASEBOARD_FAB2_LIB.BASEBOARD_FAB2(SCH_1):PAGE31
   BV7 P3E_CPU0_PE2_SS_RXN<10> @BASEBOARD_FAB2_LIB.BASEBOARD_FAB2(SCH_1):P3E_CPU0_PE2_SS_RXN(10)   I106 @BASEBOARD_FAB2_LIB.BASEBOARD_FAB2(SCH_1):PAGE31
   BY7 P3E_CPU0_PE2_SS_RXN<9> @BASEBOARD_FAB2_LIB.BASEBOARD_FAB2(SCH_1):P3E_CPU0_PE2_SS_RXN(9)   I106 @BASEBOARD_FAB2_LIB.BASEBOARD_FAB2(SCH_1):PAGE31
   BY9 P3E_CPU0_PE2_SS_RXN<8> @BASEBOARD_FAB2_LIB.BASEBOARD_FAB2(SCH_1):P3E_CPU0_PE2_SS_RXN(8)   I106 @BASEBOARD_FAB2_LIB.BASEBOARD_FAB2(SCH_1):PAGE31
   CE8 P3E_CPU0_PE2_SS_RXN<7> @BASEBOARD_FAB2_LIB.BASEBOARD_FAB2(SCH_1):P3E_CPU0_PE2_SS_RXN(7)   I106 @BASEBOARD_FAB2_LIB.BASEBOARD_FAB2(SCH_1):PAGE31
   CE6 P3E_CPU0_PE2_SS_RXN<6> @BASEBOARD_FAB2_LIB.BASEBOARD_FAB2(SCH_1):P3E_CPU0_PE2_SS_RXN(6)   I106 @BASEBOARD_FAB2_LIB.BASEBOARD_FAB2(SCH_1):PAGE31
   CG8 P3E_CPU0_PE2_SS_RXN<5> @BASEBOARD_FAB2_LIB.BASEBOARD_FAB2(SCH_1):P3E_CPU0_PE2_SS_RXN(5)   I106 @BASEBOARD_FAB2_LIB.BASEBOARD_FAB2(SCH_1):PAGE31
   CK7 P3E_CPU0_PE2_SS_RXN<4> @BASEBOARD_FAB2_LIB.BASEBOARD_FAB2(SCH_1):P3E_CPU0_PE2_SS_RXN(4)   I106 @BASEBOARD_FAB2_LIB.BASEBOARD_FAB2(SCH_1):PAGE31
   CM7 P3E_CPU0_PE2_SS_RXN<3> @BASEBOARD_FAB2_LIB.BASEBOARD_FAB2(SCH_1):P3E_CPU0_PE2_SS_RXN(3)   I106 @BASEBOARD_FAB2_LIB.BASEBOARD_FAB2(SCH_1):PAGE31
   CP7 P3E_CPU0_PE2_SS_RXN<2> @BASEBOARD_FAB2_LIB.BASEBOARD_FAB2(SCH_1):P3E_CPU0_PE2_SS_RXN(2)   I106 @BASEBOARD_FAB2_LIB.BASEBOARD_FAB2(SCH_1):PAGE31
   CP9 P3E_CPU0_PE2_SS_RXN<1> @BASEBOARD_FAB2_LIB.BASEBOARD_FAB2(SCH_1):P3E_CPU0_PE2_SS_RXN(1)   I106 @BASEBOARD_FAB2_LIB.BASEBOARD_FAB2(SCH_1):PAGE31
   CT9 P3E_CPU0_PE2_SS_RXN<0> @BASEBOARD_FAB2_LIB.BASEBOARD_FAB2(SCH_1):P3E_CPU0_PE2_SS_RXN(0)   I106 @BASEBOARD_FAB2_LIB.BASEBOARD_FAB2(SCH_1):PAGE31
  BJ10 P3E_CPU0_PE2_SS_RXP<15> @BASEBOARD_FAB2_LIB.BASEBOARD_FAB2(SCH_1):P3E_CPU0_PE2_SS_RXP(15)   I106 @BASEBOARD_FAB2_LIB.BASEBOARD_FAB2(SCH_1):PAGE31
   BJ8 P3E_CPU0_PE2_SS_RXP<14> @BASEBOARD_FAB2_LIB.BASEBOARD_FAB2(SCH_1):P3E_CPU0_PE2_SS_RXP(14)   I106 @BASEBOARD_FAB2_LIB.BASEBOARD_FAB2(SCH_1):PAGE31
   BM7 P3E_CPU0_PE2_SS_RXP<13> @BASEBOARD_FAB2_LIB.BASEBOARD_FAB2(SCH_1):P3E_CPU0_PE2_SS_RXP(13)   I106 @BASEBOARD_FAB2_LIB.BASEBOARD_FAB2(SCH_1):PAGE31
   BP9 P3E_CPU0_PE2_SS_RXP<12> @BASEBOARD_FAB2_LIB.BASEBOARD_FAB2(SCH_1):P3E_CPU0_PE2_SS_RXP(12)   I106 @BASEBOARD_FAB2_LIB.BASEBOARD_FAB2(SCH_1):PAGE31
   BP7 P3E_CPU0_PE2_SS_RXP<11> @BASEBOARD_FAB2_LIB.BASEBOARD_FAB2(SCH_1):P3E_CPU0_PE2_SS_RXP(11)   I106 @BASEBOARD_FAB2_LIB.BASEBOARD_FAB2(SCH_1):PAGE31
   BU6 P3E_CPU0_PE2_SS_RXP<10> @BASEBOARD_FAB2_LIB.BASEBOARD_FAB2(SCH_1):P3E_CPU0_PE2_SS_RXP(10)   I106 @BASEBOARD_FAB2_LIB.BASEBOARD_FAB2(SCH_1):PAGE31
   BW8 P3E_CPU0_PE2_SS_RXP<9> @BASEBOARD_FAB2_LIB.BASEBOARD_FAB2(SCH_1):P3E_CPU0_PE2_SS_RXP(9)   I106 @BASEBOARD_FAB2_LIB.BASEBOARD_FAB2(SCH_1):PAGE31
   BV9 P3E_CPU0_PE2_SS_RXP<8> @BASEBOARD_FAB2_LIB.BASEBOARD_FAB2(SCH_1):P3E_CPU0_PE2_SS_RXP(8)   I106 @BASEBOARD_FAB2_LIB.BASEBOARD_FAB2(SCH_1):PAGE31
   CC8 P3E_CPU0_PE2_SS_RXP<7> @BASEBOARD_FAB2_LIB.BASEBOARD_FAB2(SCH_1):P3E_CPU0_PE2_SS_RXP(7)   I106 @BASEBOARD_FAB2_LIB.BASEBOARD_FAB2(SCH_1):PAGE31
   CD7 P3E_CPU0_PE2_SS_RXP<6> @BASEBOARD_FAB2_LIB.BASEBOARD_FAB2(SCH_1):P3E_CPU0_PE2_SS_RXP(6)   I106 @BASEBOARD_FAB2_LIB.BASEBOARD_FAB2(SCH_1):PAGE31
   CF7 P3E_CPU0_PE2_SS_RXP<5> @BASEBOARD_FAB2_LIB.BASEBOARD_FAB2(SCH_1):P3E_CPU0_PE2_SS_RXP(5)   I106 @BASEBOARD_FAB2_LIB.BASEBOARD_FAB2(SCH_1):PAGE31
   CH7 P3E_CPU0_PE2_SS_RXP<4> @BASEBOARD_FAB2_LIB.BASEBOARD_FAB2(SCH_1):P3E_CPU0_PE2_SS_RXP(4)   I106 @BASEBOARD_FAB2_LIB.BASEBOARD_FAB2(SCH_1):PAGE31
   CL6 P3E_CPU0_PE2_SS_RXP<3> @BASEBOARD_FAB2_LIB.BASEBOARD_FAB2(SCH_1):P3E_CPU0_PE2_SS_RXP(3)   I106 @BASEBOARD_FAB2_LIB.BASEBOARD_FAB2(SCH_1):PAGE31
   CN8 P3E_CPU0_PE2_SS_RXP<2> @BASEBOARD_FAB2_LIB.BASEBOARD_FAB2(SCH_1):P3E_CPU0_PE2_SS_RXP(2)   I106 @BASEBOARD_FAB2_LIB.BASEBOARD_FAB2(SCH_1):PAGE31
   CM9 P3E_CPU0_PE2_SS_RXP<1> @BASEBOARD_FAB2_LIB.BASEBOARD_FAB2(SCH_1):P3E_CPU0_PE2_SS_RXP(1)   I106 @BASEBOARD_FAB2_LIB.BASEBOARD_FAB2(SCH_1):PAGE31
   CR8 P3E_CPU0_PE2_SS_RXP<0> @BASEBOARD_FAB2_LIB.BASEBOARD_FAB2(SCH_1):P3E_CPU0_PE2_SS_RXP(0)   I106 @BASEBOARD_FAB2_LIB.BASEBOARD_FAB2(SCH_1):PAGE31
   BM5 P3E_CPU0_PE2_SS_TXN<15> @BASEBOARD_FAB2_LIB.BASEBOARD_FAB2(SCH_1):P3E_CPU0_PE2_SS_TXN(15)   I106 @BASEBOARD_FAB2_LIB.BASEBOARD_FAB2(SCH_1):PAGE31
   BL4 P3E_CPU0_PE2_SS_TXN<14> @BASEBOARD_FAB2_LIB.BASEBOARD_FAB2(SCH_1):P3E_CPU0_PE2_SS_TXN(14)   I106 @BASEBOARD_FAB2_LIB.BASEBOARD_FAB2(SCH_1):PAGE31
   BP5 P3E_CPU0_PE2_SS_TXN<13> @BASEBOARD_FAB2_LIB.BASEBOARD_FAB2(SCH_1):P3E_CPU0_PE2_SS_TXN(13)   I106 @BASEBOARD_FAB2_LIB.BASEBOARD_FAB2(SCH_1):PAGE31
   BU4 P3E_CPU0_PE2_SS_TXN<12> @BASEBOARD_FAB2_LIB.BASEBOARD_FAB2(SCH_1):P3E_CPU0_PE2_SS_TXN(12)   I106 @BASEBOARD_FAB2_LIB.BASEBOARD_FAB2(SCH_1):PAGE31
   BW4 P3E_CPU0_PE2_SS_TXN<11> @BASEBOARD_FAB2_LIB.BASEBOARD_FAB2(SCH_1):P3E_CPU0_PE2_SS_TXN(11)   I106 @BASEBOARD_FAB2_LIB.BASEBOARD_FAB2(SCH_1):PAGE31
   CA4 P3E_CPU0_PE2_SS_TXN<10> @BASEBOARD_FAB2_LIB.BASEBOARD_FAB2(SCH_1):P3E_CPU0_PE2_SS_TXN(10)   I106 @BASEBOARD_FAB2_LIB.BASEBOARD_FAB2(SCH_1):PAGE31
   CB3 P3E_CPU0_PE2_SS_TXN<9> @BASEBOARD_FAB2_LIB.BASEBOARD_FAB2(SCH_1):P3E_CPU0_PE2_SS_TXN(9)   I106 @BASEBOARD_FAB2_LIB.BASEBOARD_FAB2(SCH_1):PAGE31
   CC2 P3E_CPU0_PE2_SS_TXN<8> @BASEBOARD_FAB2_LIB.BASEBOARD_FAB2(SCH_1):P3E_CPU0_PE2_SS_TXN(8)   I106 @BASEBOARD_FAB2_LIB.BASEBOARD_FAB2(SCH_1):PAGE31
   CF3 P3E_CPU0_PE2_SS_TXN<7> @BASEBOARD_FAB2_LIB.BASEBOARD_FAB2(SCH_1):P3E_CPU0_PE2_SS_TXN(7)   I106 @BASEBOARD_FAB2_LIB.BASEBOARD_FAB2(SCH_1):PAGE31
   CG2 P3E_CPU0_PE2_SS_TXN<6> @BASEBOARD_FAB2_LIB.BASEBOARD_FAB2(SCH_1):P3E_CPU0_PE2_SS_TXN(6)   I106 @BASEBOARD_FAB2_LIB.BASEBOARD_FAB2(SCH_1):PAGE31
   CL2 P3E_CPU0_PE2_SS_TXN<5> @BASEBOARD_FAB2_LIB.BASEBOARD_FAB2(SCH_1):P3E_CPU0_PE2_SS_TXN(5)   I106 @BASEBOARD_FAB2_LIB.BASEBOARD_FAB2(SCH_1):PAGE31
   CM1 P3E_CPU0_PE2_SS_TXN<4> @BASEBOARD_FAB2_LIB.BASEBOARD_FAB2(SCH_1):P3E_CPU0_PE2_SS_TXN(4)   I106 @BASEBOARD_FAB2_LIB.BASEBOARD_FAB2(SCH_1):PAGE31
   CT3 P3E_CPU0_PE2_SS_TXN<3> @BASEBOARD_FAB2_LIB.BASEBOARD_FAB2(SCH_1):P3E_CPU0_PE2_SS_TXN(3)   I106 @BASEBOARD_FAB2_LIB.BASEBOARD_FAB2(SCH_1):PAGE31
   CT1 P3E_CPU0_PE2_SS_TXN<2> @BASEBOARD_FAB2_LIB.BASEBOARD_FAB2(SCH_1):P3E_CPU0_PE2_SS_TXN(2)   I106 @BASEBOARD_FAB2_LIB.BASEBOARD_FAB2(SCH_1):PAGE31
   CV3 P3E_CPU0_PE2_SS_TXN<1> @BASEBOARD_FAB2_LIB.BASEBOARD_FAB2(SCH_1):P3E_CPU0_PE2_SS_TXN(1)   I106 @BASEBOARD_FAB2_LIB.BASEBOARD_FAB2(SCH_1):PAGE31
   CY3 P3E_CPU0_PE2_SS_TXN<0> @BASEBOARD_FAB2_LIB.BASEBOARD_FAB2(SCH_1):P3E_CPU0_PE2_SS_TXN(0)   I106 @BASEBOARD_FAB2_LIB.BASEBOARD_FAB2(SCH_1):PAGE31
   BK5 P3E_CPU0_PE2_SS_TXP<15> @BASEBOARD_FAB2_LIB.BASEBOARD_FAB2(SCH_1):P3E_CPU0_PE2_SS_TXP(15)   I106 @BASEBOARD_FAB2_LIB.BASEBOARD_FAB2(SCH_1):PAGE31
   BM3 P3E_CPU0_PE2_SS_TXP<14> @BASEBOARD_FAB2_LIB.BASEBOARD_FAB2(SCH_1):P3E_CPU0_PE2_SS_TXP(14)   I106 @BASEBOARD_FAB2_LIB.BASEBOARD_FAB2(SCH_1):PAGE31
   BN4 P3E_CPU0_PE2_SS_TXP<13> @BASEBOARD_FAB2_LIB.BASEBOARD_FAB2(SCH_1):P3E_CPU0_PE2_SS_TXP(13)   I106 @BASEBOARD_FAB2_LIB.BASEBOARD_FAB2(SCH_1):PAGE31
   BR4 P3E_CPU0_PE2_SS_TXP<12> @BASEBOARD_FAB2_LIB.BASEBOARD_FAB2(SCH_1):P3E_CPU0_PE2_SS_TXP(12)   I106 @BASEBOARD_FAB2_LIB.BASEBOARD_FAB2(SCH_1):PAGE31
   BV3 P3E_CPU0_PE2_SS_TXP<11> @BASEBOARD_FAB2_LIB.BASEBOARD_FAB2(SCH_1):P3E_CPU0_PE2_SS_TXP(11)   I106 @BASEBOARD_FAB2_LIB.BASEBOARD_FAB2(SCH_1):PAGE31
   BY5 P3E_CPU0_PE2_SS_TXP<10> @BASEBOARD_FAB2_LIB.BASEBOARD_FAB2(SCH_1):P3E_CPU0_PE2_SS_TXP(10)   I106 @BASEBOARD_FAB2_LIB.BASEBOARD_FAB2(SCH_1):PAGE31
   BY3 P3E_CPU0_PE2_SS_TXP<9> @BASEBOARD_FAB2_LIB.BASEBOARD_FAB2(SCH_1):P3E_CPU0_PE2_SS_TXP(9)   I106 @BASEBOARD_FAB2_LIB.BASEBOARD_FAB2(SCH_1):PAGE31
   CD3 P3E_CPU0_PE2_SS_TXP<8> @BASEBOARD_FAB2_LIB.BASEBOARD_FAB2(SCH_1):P3E_CPU0_PE2_SS_TXP(8)   I106 @BASEBOARD_FAB2_LIB.BASEBOARD_FAB2(SCH_1):PAGE31
   CE4 P3E_CPU0_PE2_SS_TXP<7> @BASEBOARD_FAB2_LIB.BASEBOARD_FAB2(SCH_1):P3E_CPU0_PE2_SS_TXP(7)   I106 @BASEBOARD_FAB2_LIB.BASEBOARD_FAB2(SCH_1):PAGE31
   CE2 P3E_CPU0_PE2_SS_TXP<6> @BASEBOARD_FAB2_LIB.BASEBOARD_FAB2(SCH_1):P3E_CPU0_PE2_SS_TXP(6)   I106 @BASEBOARD_FAB2_LIB.BASEBOARD_FAB2(SCH_1):PAGE31
   CK3 P3E_CPU0_PE2_SS_TXP<5> @BASEBOARD_FAB2_LIB.BASEBOARD_FAB2(SCH_1):P3E_CPU0_PE2_SS_TXP(5)   I106 @BASEBOARD_FAB2_LIB.BASEBOARD_FAB2(SCH_1):PAGE31
   CK1 P3E_CPU0_PE2_SS_TXP<4> @BASEBOARD_FAB2_LIB.BASEBOARD_FAB2(SCH_1):P3E_CPU0_PE2_SS_TXP(4)   I106 @BASEBOARD_FAB2_LIB.BASEBOARD_FAB2(SCH_1):PAGE31
   CP3 P3E_CPU0_PE2_SS_TXP<3> @BASEBOARD_FAB2_LIB.BASEBOARD_FAB2(SCH_1):P3E_CPU0_PE2_SS_TXP(3)   I106 @BASEBOARD_FAB2_LIB.BASEBOARD_FAB2(SCH_1):PAGE31
   CR2 P3E_CPU0_PE2_SS_TXP<2> @BASEBOARD_FAB2_LIB.BASEBOARD_FAB2(SCH_1):P3E_CPU0_PE2_SS_TXP(2)   I106 @BASEBOARD_FAB2_LIB.BASEBOARD_FAB2(SCH_1):PAGE31
   CU2 P3E_CPU0_PE2_SS_TXP<1> @BASEBOARD_FAB2_LIB.BASEBOARD_FAB2(SCH_1):P3E_CPU0_PE2_SS_TXP(1)   I106 @BASEBOARD_FAB2_LIB.BASEBOARD_FAB2(SCH_1):PAGE31
   CW4 P3E_CPU0_PE2_SS_TXP<0> @BASEBOARD_FAB2_LIB.BASEBOARD_FAB2(SCH_1):P3E_CPU0_PE2_SS_TXP(0)   I106 @BASEBOARD_FAB2_LIB.BASEBOARD_FAB2(SCH_1):PAGE31
   CV9 P3E_CPU0_PE3_OCP_RXN<15> @BASEBOARD_FAB2_LIB.BASEBOARD_FAB2(SCH_1):P3E_CPU0_PE3_OCP_RXN(15)    I89 @BASEBOARD_FAB2_LIB.BASEBOARD_FAB2(SCH_1):PAGE32
  CY11 P3E_CPU0_PE3_OCP_RXN<14> @BASEBOARD_FAB2_LIB.BASEBOARD_FAB2(SCH_1):P3E_CPU0_PE3_OCP_RXN(14)    I89 @BASEBOARD_FAB2_LIB.BASEBOARD_FAB2(SCH_1):PAGE32
  DB11 P3E_CPU0_PE3_OCP_RXN<13> @BASEBOARD_FAB2_LIB.BASEBOARD_FAB2(SCH_1):P3E_CPU0_PE3_OCP_RXN(13)    I89 @BASEBOARD_FAB2_LIB.BASEBOARD_FAB2(SCH_1):PAGE32
  DD13 P3E_CPU0_PE3_OCP_RXN<12> @BASEBOARD_FAB2_LIB.BASEBOARD_FAB2(SCH_1):P3E_CPU0_PE3_OCP_RXN(12)    I89 @BASEBOARD_FAB2_LIB.BASEBOARD_FAB2(SCH_1):PAGE32
  DG10 P3E_CPU0_PE3_OCP_RXN<11> @BASEBOARD_FAB2_LIB.BASEBOARD_FAB2(SCH_1):P3E_CPU0_PE3_OCP_RXN(11)    I89 @BASEBOARD_FAB2_LIB.BASEBOARD_FAB2(SCH_1):PAGE32
  DG12 P3E_CPU0_PE3_OCP_RXN<10> @BASEBOARD_FAB2_LIB.BASEBOARD_FAB2(SCH_1):P3E_CPU0_PE3_OCP_RXN(10)    I89 @BASEBOARD_FAB2_LIB.BASEBOARD_FAB2(SCH_1):PAGE32
  DJ12 P3E_CPU0_PE3_OCP_RXN<9> @BASEBOARD_FAB2_LIB.BASEBOARD_FAB2(SCH_1):P3E_CPU0_PE3_OCP_RXN(9)    I89 @BASEBOARD_FAB2_LIB.BASEBOARD_FAB2(SCH_1):PAGE32
  DL12 P3E_CPU0_PE3_OCP_RXN<8> @BASEBOARD_FAB2_LIB.BASEBOARD_FAB2(SCH_1):P3E_CPU0_PE3_OCP_RXN(8)    I89 @BASEBOARD_FAB2_LIB.BASEBOARD_FAB2(SCH_1):PAGE32
  DL14 P3E_CPU0_PE3_OCP_RXN<7> @BASEBOARD_FAB2_LIB.BASEBOARD_FAB2(SCH_1):P3E_CPU0_PE3_OCP_RXN(7)    I89 @BASEBOARD_FAB2_LIB.BASEBOARD_FAB2(SCH_1):PAGE32
  DN14 P3E_CPU0_PE3_OCP_RXN<6> @BASEBOARD_FAB2_LIB.BASEBOARD_FAB2(SCH_1):P3E_CPU0_PE3_OCP_RXN(6)    I89 @BASEBOARD_FAB2_LIB.BASEBOARD_FAB2(SCH_1):PAGE32
  DR14 P3E_CPU0_PE3_OCP_RXN<5> @BASEBOARD_FAB2_LIB.BASEBOARD_FAB2(SCH_1):P3E_CPU0_PE3_OCP_RXN(5)    I89 @BASEBOARD_FAB2_LIB.BASEBOARD_FAB2(SCH_1):PAGE32
  DR16 P3E_CPU0_PE3_OCP_RXN<4> @BASEBOARD_FAB2_LIB.BASEBOARD_FAB2(SCH_1):P3E_CPU0_PE3_OCP_RXN(4)    I89 @BASEBOARD_FAB2_LIB.BASEBOARD_FAB2(SCH_1):PAGE32
  DT19 P3E_CPU0_PE3_OCP_RXN<3> @BASEBOARD_FAB2_LIB.BASEBOARD_FAB2(SCH_1):P3E_CPU0_PE3_OCP_RXN(3)    I89 @BASEBOARD_FAB2_LIB.BASEBOARD_FAB2(SCH_1):PAGE32
  DW16 P3E_CPU0_PE3_OCP_RXN<2> @BASEBOARD_FAB2_LIB.BASEBOARD_FAB2(SCH_1):P3E_CPU0_PE3_OCP_RXN(2)    I89 @BASEBOARD_FAB2_LIB.BASEBOARD_FAB2(SCH_1):PAGE32
  DW18 P3E_CPU0_PE3_OCP_RXN<1> @BASEBOARD_FAB2_LIB.BASEBOARD_FAB2(SCH_1):P3E_CPU0_PE3_OCP_RXN(1)    I89 @BASEBOARD_FAB2_LIB.BASEBOARD_FAB2(SCH_1):PAGE32
  EA18 P3E_CPU0_PE3_OCP_RXN<0> @BASEBOARD_FAB2_LIB.BASEBOARD_FAB2(SCH_1):P3E_CPU0_PE3_OCP_RXN(0)    I89 @BASEBOARD_FAB2_LIB.BASEBOARD_FAB2(SCH_1):PAGE32
  CU10 P3E_CPU0_PE3_OCP_RXP<15> @BASEBOARD_FAB2_LIB.BASEBOARD_FAB2(SCH_1):P3E_CPU0_PE3_OCP_RXP(15)    I89 @BASEBOARD_FAB2_LIB.BASEBOARD_FAB2(SCH_1):PAGE32
  CW10 P3E_CPU0_PE3_OCP_RXP<14> @BASEBOARD_FAB2_LIB.BASEBOARD_FAB2(SCH_1):P3E_CPU0_PE3_OCP_RXP(14)    I89 @BASEBOARD_FAB2_LIB.BASEBOARD_FAB2(SCH_1):PAGE32
  DA12 P3E_CPU0_PE3_OCP_RXP<13> @BASEBOARD_FAB2_LIB.BASEBOARD_FAB2(SCH_1):P3E_CPU0_PE3_OCP_RXP(13)    I89 @BASEBOARD_FAB2_LIB.BASEBOARD_FAB2(SCH_1):PAGE32
  DC12 P3E_CPU0_PE3_OCP_RXP<12> @BASEBOARD_FAB2_LIB.BASEBOARD_FAB2(SCH_1):P3E_CPU0_PE3_OCP_RXP(12)    I89 @BASEBOARD_FAB2_LIB.BASEBOARD_FAB2(SCH_1):PAGE32
  DF11 P3E_CPU0_PE3_OCP_RXP<11> @BASEBOARD_FAB2_LIB.BASEBOARD_FAB2(SCH_1):P3E_CPU0_PE3_OCP_RXP(11)    I89 @BASEBOARD_FAB2_LIB.BASEBOARD_FAB2(SCH_1):PAGE32
  DE12 P3E_CPU0_PE3_OCP_RXP<10> @BASEBOARD_FAB2_LIB.BASEBOARD_FAB2(SCH_1):P3E_CPU0_PE3_OCP_RXP(10)    I89 @BASEBOARD_FAB2_LIB.BASEBOARD_FAB2(SCH_1):PAGE32
  DH11 P3E_CPU0_PE3_OCP_RXP<9> @BASEBOARD_FAB2_LIB.BASEBOARD_FAB2(SCH_1):P3E_CPU0_PE3_OCP_RXP(9)    I89 @BASEBOARD_FAB2_LIB.BASEBOARD_FAB2(SCH_1):PAGE32
  DK13 P3E_CPU0_PE3_OCP_RXP<8> @BASEBOARD_FAB2_LIB.BASEBOARD_FAB2(SCH_1):P3E_CPU0_PE3_OCP_RXP(8)    I89 @BASEBOARD_FAB2_LIB.BASEBOARD_FAB2(SCH_1):PAGE32
  DJ14 P3E_CPU0_PE3_OCP_RXP<7> @BASEBOARD_FAB2_LIB.BASEBOARD_FAB2(SCH_1):P3E_CPU0_PE3_OCP_RXP(7)    I89 @BASEBOARD_FAB2_LIB.BASEBOARD_FAB2(SCH_1):PAGE32
  DM13 P3E_CPU0_PE3_OCP_RXP<6> @BASEBOARD_FAB2_LIB.BASEBOARD_FAB2(SCH_1):P3E_CPU0_PE3_OCP_RXP(6)    I89 @BASEBOARD_FAB2_LIB.BASEBOARD_FAB2(SCH_1):PAGE32
  DP15 P3E_CPU0_PE3_OCP_RXP<5> @BASEBOARD_FAB2_LIB.BASEBOARD_FAB2(SCH_1):P3E_CPU0_PE3_OCP_RXP(5)    I89 @BASEBOARD_FAB2_LIB.BASEBOARD_FAB2(SCH_1):PAGE32
  DN16 P3E_CPU0_PE3_OCP_RXP<4> @BASEBOARD_FAB2_LIB.BASEBOARD_FAB2(SCH_1):P3E_CPU0_PE3_OCP_RXP(4)    I89 @BASEBOARD_FAB2_LIB.BASEBOARD_FAB2(SCH_1):PAGE32
  DR18 P3E_CPU0_PE3_OCP_RXP<3> @BASEBOARD_FAB2_LIB.BASEBOARD_FAB2(SCH_1):P3E_CPU0_PE3_OCP_RXP(3)    I89 @BASEBOARD_FAB2_LIB.BASEBOARD_FAB2(SCH_1):PAGE32
  DV17 P3E_CPU0_PE3_OCP_RXP<2> @BASEBOARD_FAB2_LIB.BASEBOARD_FAB2(SCH_1):P3E_CPU0_PE3_OCP_RXP(2)    I89 @BASEBOARD_FAB2_LIB.BASEBOARD_FAB2(SCH_1):PAGE32
  DU18 P3E_CPU0_PE3_OCP_RXP<1> @BASEBOARD_FAB2_LIB.BASEBOARD_FAB2(SCH_1):P3E_CPU0_PE3_OCP_RXP(1)    I89 @BASEBOARD_FAB2_LIB.BASEBOARD_FAB2(SCH_1):PAGE32
  DY17 P3E_CPU0_PE3_OCP_RXP<0> @BASEBOARD_FAB2_LIB.BASEBOARD_FAB2(SCH_1):P3E_CPU0_PE3_OCP_RXP(0)    I89 @BASEBOARD_FAB2_LIB.BASEBOARD_FAB2(SCH_1):PAGE32
   CY5 P3E_CPU0_PE3_OCP_TXN<15> @BASEBOARD_FAB2_LIB.BASEBOARD_FAB2(SCH_1):P3E_CPU0_PE3_OCP_TXN(15)    I89 @BASEBOARD_FAB2_LIB.BASEBOARD_FAB2(SCH_1):PAGE32
   DB5 P3E_CPU0_PE3_OCP_TXN<14> @BASEBOARD_FAB2_LIB.BASEBOARD_FAB2(SCH_1):P3E_CPU0_PE3_OCP_TXN(14)    I89 @BASEBOARD_FAB2_LIB.BASEBOARD_FAB2(SCH_1):PAGE32
   DD5 P3E_CPU0_PE3_OCP_TXN<13> @BASEBOARD_FAB2_LIB.BASEBOARD_FAB2(SCH_1):P3E_CPU0_PE3_OCP_TXN(13)    I89 @BASEBOARD_FAB2_LIB.BASEBOARD_FAB2(SCH_1):PAGE32
   DJ6 P3E_CPU0_PE3_OCP_TXN<12> @BASEBOARD_FAB2_LIB.BASEBOARD_FAB2(SCH_1):P3E_CPU0_PE3_OCP_TXN(12)    I89 @BASEBOARD_FAB2_LIB.BASEBOARD_FAB2(SCH_1):PAGE32
   DJ4 P3E_CPU0_PE3_OCP_TXN<11> @BASEBOARD_FAB2_LIB.BASEBOARD_FAB2(SCH_1):P3E_CPU0_PE3_OCP_TXN(11)    I89 @BASEBOARD_FAB2_LIB.BASEBOARD_FAB2(SCH_1):PAGE32
   DL6 P3E_CPU0_PE3_OCP_TXN<10> @BASEBOARD_FAB2_LIB.BASEBOARD_FAB2(SCH_1):P3E_CPU0_PE3_OCP_TXN(10)    I89 @BASEBOARD_FAB2_LIB.BASEBOARD_FAB2(SCH_1):PAGE32
   DP5 P3E_CPU0_PE3_OCP_TXN<9> @BASEBOARD_FAB2_LIB.BASEBOARD_FAB2(SCH_1):P3E_CPU0_PE3_OCP_TXN(9)    I89 @BASEBOARD_FAB2_LIB.BASEBOARD_FAB2(SCH_1):PAGE32
   DM7 P3E_CPU0_PE3_OCP_TXN<8> @BASEBOARD_FAB2_LIB.BASEBOARD_FAB2(SCH_1):P3E_CPU0_PE3_OCP_TXN(8)    I89 @BASEBOARD_FAB2_LIB.BASEBOARD_FAB2(SCH_1):PAGE32
   DR8 P3E_CPU0_PE3_OCP_TXN<7> @BASEBOARD_FAB2_LIB.BASEBOARD_FAB2(SCH_1):P3E_CPU0_PE3_OCP_TXN(7)    I89 @BASEBOARD_FAB2_LIB.BASEBOARD_FAB2(SCH_1):PAGE32
   DU8 P3E_CPU0_PE3_OCP_TXN<6> @BASEBOARD_FAB2_LIB.BASEBOARD_FAB2(SCH_1):P3E_CPU0_PE3_OCP_TXN(6)    I89 @BASEBOARD_FAB2_LIB.BASEBOARD_FAB2(SCH_1):PAGE32
  DW10 P3E_CPU0_PE3_OCP_TXN<5> @BASEBOARD_FAB2_LIB.BASEBOARD_FAB2(SCH_1):P3E_CPU0_PE3_OCP_TXN(5)    I89 @BASEBOARD_FAB2_LIB.BASEBOARD_FAB2(SCH_1):PAGE32
   EB9 P3E_CPU0_PE3_OCP_TXN<4> @BASEBOARD_FAB2_LIB.BASEBOARD_FAB2(SCH_1):P3E_CPU0_PE3_OCP_TXN(4)    I89 @BASEBOARD_FAB2_LIB.BASEBOARD_FAB2(SCH_1):PAGE32
  DY11 P3E_CPU0_PE3_OCP_TXN<3> @BASEBOARD_FAB2_LIB.BASEBOARD_FAB2(SCH_1):P3E_CPU0_PE3_OCP_TXN(3)    I89 @BASEBOARD_FAB2_LIB.BASEBOARD_FAB2(SCH_1):PAGE32
  EC12 P3E_CPU0_PE3_OCP_TXN<2> @BASEBOARD_FAB2_LIB.BASEBOARD_FAB2(SCH_1):P3E_CPU0_PE3_OCP_TXN(2)    I89 @BASEBOARD_FAB2_LIB.BASEBOARD_FAB2(SCH_1):PAGE32
  EE12 P3E_CPU0_PE3_OCP_TXN<1> @BASEBOARD_FAB2_LIB.BASEBOARD_FAB2(SCH_1):P3E_CPU0_PE3_OCP_TXN(1)    I89 @BASEBOARD_FAB2_LIB.BASEBOARD_FAB2(SCH_1):PAGE32
  EE14 P3E_CPU0_PE3_OCP_TXN<0> @BASEBOARD_FAB2_LIB.BASEBOARD_FAB2(SCH_1):P3E_CPU0_PE3_OCP_TXN(0)    I89 @BASEBOARD_FAB2_LIB.BASEBOARD_FAB2(SCH_1):PAGE32
   CV5 P3E_CPU0_PE3_OCP_TXP<15> @BASEBOARD_FAB2_LIB.BASEBOARD_FAB2(SCH_1):P3E_CPU0_PE3_OCP_TXP(15)    I89 @BASEBOARD_FAB2_LIB.BASEBOARD_FAB2(SCH_1):PAGE32
   DA4 P3E_CPU0_PE3_OCP_TXP<14> @BASEBOARD_FAB2_LIB.BASEBOARD_FAB2(SCH_1):P3E_CPU0_PE3_OCP_TXP(14)    I89 @BASEBOARD_FAB2_LIB.BASEBOARD_FAB2(SCH_1):PAGE32
   DC6 P3E_CPU0_PE3_OCP_TXP<13> @BASEBOARD_FAB2_LIB.BASEBOARD_FAB2(SCH_1):P3E_CPU0_PE3_OCP_TXP(13)    I89 @BASEBOARD_FAB2_LIB.BASEBOARD_FAB2(SCH_1):PAGE32
   DG6 P3E_CPU0_PE3_OCP_TXP<12> @BASEBOARD_FAB2_LIB.BASEBOARD_FAB2(SCH_1):P3E_CPU0_PE3_OCP_TXP(12)    I89 @BASEBOARD_FAB2_LIB.BASEBOARD_FAB2(SCH_1):PAGE32
   DH5 P3E_CPU0_PE3_OCP_TXP<11> @BASEBOARD_FAB2_LIB.BASEBOARD_FAB2(SCH_1):P3E_CPU0_PE3_OCP_TXP(11)    I89 @BASEBOARD_FAB2_LIB.BASEBOARD_FAB2(SCH_1):PAGE32
   DK5 P3E_CPU0_PE3_OCP_TXP<10> @BASEBOARD_FAB2_LIB.BASEBOARD_FAB2(SCH_1):P3E_CPU0_PE3_OCP_TXP(10)    I89 @BASEBOARD_FAB2_LIB.BASEBOARD_FAB2(SCH_1):PAGE32
   DM5 P3E_CPU0_PE3_OCP_TXP<9> @BASEBOARD_FAB2_LIB.BASEBOARD_FAB2(SCH_1):P3E_CPU0_PE3_OCP_TXP(9)    I89 @BASEBOARD_FAB2_LIB.BASEBOARD_FAB2(SCH_1):PAGE32
   DN6 P3E_CPU0_PE3_OCP_TXP<8> @BASEBOARD_FAB2_LIB.BASEBOARD_FAB2(SCH_1):P3E_CPU0_PE3_OCP_TXP(8)    I89 @BASEBOARD_FAB2_LIB.BASEBOARD_FAB2(SCH_1):PAGE32
   DP7 P3E_CPU0_PE3_OCP_TXP<7> @BASEBOARD_FAB2_LIB.BASEBOARD_FAB2(SCH_1):P3E_CPU0_PE3_OCP_TXP(7)    I89 @BASEBOARD_FAB2_LIB.BASEBOARD_FAB2(SCH_1):PAGE32
   DT9 P3E_CPU0_PE3_OCP_TXP<6> @BASEBOARD_FAB2_LIB.BASEBOARD_FAB2(SCH_1):P3E_CPU0_PE3_OCP_TXP(6)    I89 @BASEBOARD_FAB2_LIB.BASEBOARD_FAB2(SCH_1):PAGE32
   DV9 P3E_CPU0_PE3_OCP_TXP<5> @BASEBOARD_FAB2_LIB.BASEBOARD_FAB2(SCH_1):P3E_CPU0_PE3_OCP_TXP(5)    I89 @BASEBOARD_FAB2_LIB.BASEBOARD_FAB2(SCH_1):PAGE32
   DY9 P3E_CPU0_PE3_OCP_TXP<4> @BASEBOARD_FAB2_LIB.BASEBOARD_FAB2(SCH_1):P3E_CPU0_PE3_OCP_TXP(4)    I89 @BASEBOARD_FAB2_LIB.BASEBOARD_FAB2(SCH_1):PAGE32
  EA10 P3E_CPU0_PE3_OCP_TXP<3> @BASEBOARD_FAB2_LIB.BASEBOARD_FAB2(SCH_1):P3E_CPU0_PE3_OCP_TXP(3)    I89 @BASEBOARD_FAB2_LIB.BASEBOARD_FAB2(SCH_1):PAGE32
  EB11 P3E_CPU0_PE3_OCP_TXP<2> @BASEBOARD_FAB2_LIB.BASEBOARD_FAB2(SCH_1):P3E_CPU0_PE3_OCP_TXP(2)    I89 @BASEBOARD_FAB2_LIB.BASEBOARD_FAB2(SCH_1):PAGE32
  ED13 P3E_CPU0_PE3_OCP_TXP<1> @BASEBOARD_FAB2_LIB.BASEBOARD_FAB2(SCH_1):P3E_CPU0_PE3_OCP_TXP(1)    I89 @BASEBOARD_FAB2_LIB.BASEBOARD_FAB2(SCH_1):PAGE32
  EC14 P3E_CPU0_PE3_OCP_TXP<0> @BASEBOARD_FAB2_LIB.BASEBOARD_FAB2(SCH_1):P3E_CPU0_PE3_OCP_TXP(0)    I89 @BASEBOARD_FAB2_LIB.BASEBOARD_FAB2(SCH_1):PAGE32
  BB11 UPI_CPU1_CPU0_P0P0_DN<0> @BASEBOARD_FAB2_LIB.BASEBOARD_FAB2(SCH_1):UPI_CPU1_CPU0_P0P0_DN(0)    I86 @BASEBOARD_FAB2_LIB.BASEBOARD_FAB2(SCH_1):PAGE33
   BD9 UPI_CPU1_CPU0_P0P0_DN<1> @BASEBOARD_FAB2_LIB.BASEBOARD_FAB2(SCH_1):UPI_CPU1_CPU0_P0P0_DN(1)    I86 @BASEBOARD_FAB2_LIB.BASEBOARD_FAB2(SCH_1):PAGE33
   AY9 UPI_CPU1_CPU0_P0P0_DN<2> @BASEBOARD_FAB2_LIB.BASEBOARD_FAB2(SCH_1):UPI_CPU1_CPU0_P0P0_DN(2)    I86 @BASEBOARD_FAB2_LIB.BASEBOARD_FAB2(SCH_1):PAGE33
   AW8 UPI_CPU1_CPU0_P0P0_DN<3> @BASEBOARD_FAB2_LIB.BASEBOARD_FAB2(SCH_1):UPI_CPU1_CPU0_P0P0_DN(3)    I86 @BASEBOARD_FAB2_LIB.BASEBOARD_FAB2(SCH_1):PAGE33
   BD7 UPI_CPU1_CPU0_P0P0_DN<4> @BASEBOARD_FAB2_LIB.BASEBOARD_FAB2(SCH_1):UPI_CPU1_CPU0_P0P0_DN(4)    I86 @BASEBOARD_FAB2_LIB.BASEBOARD_FAB2(SCH_1):PAGE33
   BC6 UPI_CPU1_CPU0_P0P0_DN<5> @BASEBOARD_FAB2_LIB.BASEBOARD_FAB2(SCH_1):UPI_CPU1_CPU0_P0P0_DN(5)    I86 @BASEBOARD_FAB2_LIB.BASEBOARD_FAB2(SCH_1):PAGE33
   BA8 UPI_CPU1_CPU0_P0P0_DN<6> @BASEBOARD_FAB2_LIB.BASEBOARD_FAB2(SCH_1):UPI_CPU1_CPU0_P0P0_DN(6)    I86 @BASEBOARD_FAB2_LIB.BASEBOARD_FAB2(SCH_1):PAGE33
  AU10 UPI_CPU1_CPU0_P0P0_DN<7> @BASEBOARD_FAB2_LIB.BASEBOARD_FAB2(SCH_1):UPI_CPU1_CPU0_P0P0_DN(7)    I86 @BASEBOARD_FAB2_LIB.BASEBOARD_FAB2(SCH_1):PAGE33
   AR8 UPI_CPU1_CPU0_P0P0_DN<8> @BASEBOARD_FAB2_LIB.BASEBOARD_FAB2(SCH_1):UPI_CPU1_CPU0_P0P0_DN(8)    I86 @BASEBOARD_FAB2_LIB.BASEBOARD_FAB2(SCH_1):PAGE33
   AP7 UPI_CPU1_CPU0_P0P0_DN<9> @BASEBOARD_FAB2_LIB.BASEBOARD_FAB2(SCH_1):UPI_CPU1_CPU0_P0P0_DN(9)    I86 @BASEBOARD_FAB2_LIB.BASEBOARD_FAB2(SCH_1):PAGE33
   AM9 UPI_CPU1_CPU0_P0P0_DN<10> @BASEBOARD_FAB2_LIB.BASEBOARD_FAB2(SCH_1):UPI_CPU1_CPU0_P0P0_DN(10)    I86 @BASEBOARD_FAB2_LIB.BASEBOARD_FAB2(SCH_1):PAGE33
   AK7 UPI_CPU1_CPU0_P0P0_DN<11> @BASEBOARD_FAB2_LIB.BASEBOARD_FAB2(SCH_1):UPI_CPU1_CPU0_P0P0_DN(11)    I86 @BASEBOARD_FAB2_LIB.BASEBOARD_FAB2(SCH_1):PAGE33
   AL6 UPI_CPU1_CPU0_P0P0_DN<12> @BASEBOARD_FAB2_LIB.BASEBOARD_FAB2(SCH_1):UPI_CPU1_CPU0_P0P0_DN(12)    I86 @BASEBOARD_FAB2_LIB.BASEBOARD_FAB2(SCH_1):PAGE33
   AJ6 UPI_CPU1_CPU0_P0P0_DN<13> @BASEBOARD_FAB2_LIB.BASEBOARD_FAB2(SCH_1):UPI_CPU1_CPU0_P0P0_DN(13)    I86 @BASEBOARD_FAB2_LIB.BASEBOARD_FAB2(SCH_1):PAGE33
   AG8 UPI_CPU1_CPU0_P0P0_DN<14> @BASEBOARD_FAB2_LIB.BASEBOARD_FAB2(SCH_1):UPI_CPU1_CPU0_P0P0_DN(14)    I86 @BASEBOARD_FAB2_LIB.BASEBOARD_FAB2(SCH_1):PAGE33
   AE6 UPI_CPU1_CPU0_P0P0_DN<15> @BASEBOARD_FAB2_LIB.BASEBOARD_FAB2(SCH_1):UPI_CPU1_CPU0_P0P0_DN(15)    I86 @BASEBOARD_FAB2_LIB.BASEBOARD_FAB2(SCH_1):PAGE33
   AD5 UPI_CPU1_CPU0_P0P0_DN<16> @BASEBOARD_FAB2_LIB.BASEBOARD_FAB2(SCH_1):UPI_CPU1_CPU0_P0P0_DN(16)    I86 @BASEBOARD_FAB2_LIB.BASEBOARD_FAB2(SCH_1):PAGE33
   AB7 UPI_CPU1_CPU0_P0P0_DN<17> @BASEBOARD_FAB2_LIB.BASEBOARD_FAB2(SCH_1):UPI_CPU1_CPU0_P0P0_DN(17)    I86 @BASEBOARD_FAB2_LIB.BASEBOARD_FAB2(SCH_1):PAGE33
   AA8 UPI_CPU1_CPU0_P0P0_DN<18> @BASEBOARD_FAB2_LIB.BASEBOARD_FAB2(SCH_1):UPI_CPU1_CPU0_P0P0_DN(18)    I86 @BASEBOARD_FAB2_LIB.BASEBOARD_FAB2(SCH_1):PAGE33
  AC10 UPI_CPU1_CPU0_P0P0_DN<19> @BASEBOARD_FAB2_LIB.BASEBOARD_FAB2(SCH_1):UPI_CPU1_CPU0_P0P0_DN(19)    I86 @BASEBOARD_FAB2_LIB.BASEBOARD_FAB2(SCH_1):PAGE33
  BA10 UPI_CPU1_CPU0_P0P0_DP<0> @BASEBOARD_FAB2_LIB.BASEBOARD_FAB2(SCH_1):UPI_CPU1_CPU0_P0P0_DP(0)    I86 @BASEBOARD_FAB2_LIB.BASEBOARD_FAB2(SCH_1):PAGE33
  BC10 UPI_CPU1_CPU0_P0P0_DP<1> @BASEBOARD_FAB2_LIB.BASEBOARD_FAB2(SCH_1):UPI_CPU1_CPU0_P0P0_DP(1)    I86 @BASEBOARD_FAB2_LIB.BASEBOARD_FAB2(SCH_1):PAGE33
   BB9 UPI_CPU1_CPU0_P0P0_DP<2> @BASEBOARD_FAB2_LIB.BASEBOARD_FAB2(SCH_1):UPI_CPU1_CPU0_P0P0_DP(2)    I86 @BASEBOARD_FAB2_LIB.BASEBOARD_FAB2(SCH_1):PAGE33
   AV9 UPI_CPU1_CPU0_P0P0_DP<3> @BASEBOARD_FAB2_LIB.BASEBOARD_FAB2(SCH_1):UPI_CPU1_CPU0_P0P0_DP(3)    I86 @BASEBOARD_FAB2_LIB.BASEBOARD_FAB2(SCH_1):PAGE33
   BF7 UPI_CPU1_CPU0_P0P0_DP<4> @BASEBOARD_FAB2_LIB.BASEBOARD_FAB2(SCH_1):UPI_CPU1_CPU0_P0P0_DP(4)    I86 @BASEBOARD_FAB2_LIB.BASEBOARD_FAB2(SCH_1):PAGE33
   BB7 UPI_CPU1_CPU0_P0P0_DP<5> @BASEBOARD_FAB2_LIB.BASEBOARD_FAB2(SCH_1):UPI_CPU1_CPU0_P0P0_DP(5)    I86 @BASEBOARD_FAB2_LIB.BASEBOARD_FAB2(SCH_1):PAGE33
   AY7 UPI_CPU1_CPU0_P0P0_DP<6> @BASEBOARD_FAB2_LIB.BASEBOARD_FAB2(SCH_1):UPI_CPU1_CPU0_P0P0_DP(6)    I86 @BASEBOARD_FAB2_LIB.BASEBOARD_FAB2(SCH_1):PAGE33
   AT9 UPI_CPU1_CPU0_P0P0_DP<7> @BASEBOARD_FAB2_LIB.BASEBOARD_FAB2(SCH_1):UPI_CPU1_CPU0_P0P0_DP(7)    I86 @BASEBOARD_FAB2_LIB.BASEBOARD_FAB2(SCH_1):PAGE33
   AU8 UPI_CPU1_CPU0_P0P0_DP<8> @BASEBOARD_FAB2_LIB.BASEBOARD_FAB2(SCH_1):UPI_CPU1_CPU0_P0P0_DP(8)    I86 @BASEBOARD_FAB2_LIB.BASEBOARD_FAB2(SCH_1):PAGE33
   AN8 UPI_CPU1_CPU0_P0P0_DP<9> @BASEBOARD_FAB2_LIB.BASEBOARD_FAB2(SCH_1):UPI_CPU1_CPU0_P0P0_DP(9)    I86 @BASEBOARD_FAB2_LIB.BASEBOARD_FAB2(SCH_1):PAGE33
   AL8 UPI_CPU1_CPU0_P0P0_DP<10> @BASEBOARD_FAB2_LIB.BASEBOARD_FAB2(SCH_1):UPI_CPU1_CPU0_P0P0_DP(10)    I86 @BASEBOARD_FAB2_LIB.BASEBOARD_FAB2(SCH_1):PAGE33
   AM7 UPI_CPU1_CPU0_P0P0_DP<11> @BASEBOARD_FAB2_LIB.BASEBOARD_FAB2(SCH_1):UPI_CPU1_CPU0_P0P0_DP(11)    I86 @BASEBOARD_FAB2_LIB.BASEBOARD_FAB2(SCH_1):PAGE33
   AK5 UPI_CPU1_CPU0_P0P0_DP<12> @BASEBOARD_FAB2_LIB.BASEBOARD_FAB2(SCH_1):UPI_CPU1_CPU0_P0P0_DP(12)    I86 @BASEBOARD_FAB2_LIB.BASEBOARD_FAB2(SCH_1):PAGE33
   AH7 UPI_CPU1_CPU0_P0P0_DP<13> @BASEBOARD_FAB2_LIB.BASEBOARD_FAB2(SCH_1):UPI_CPU1_CPU0_P0P0_DP(13)    I86 @BASEBOARD_FAB2_LIB.BASEBOARD_FAB2(SCH_1):PAGE33
   AF7 UPI_CPU1_CPU0_P0P0_DP<14> @BASEBOARD_FAB2_LIB.BASEBOARD_FAB2(SCH_1):UPI_CPU1_CPU0_P0P0_DP(14)    I86 @BASEBOARD_FAB2_LIB.BASEBOARD_FAB2(SCH_1):PAGE33
   AG6 UPI_CPU1_CPU0_P0P0_DP<15> @BASEBOARD_FAB2_LIB.BASEBOARD_FAB2(SCH_1):UPI_CPU1_CPU0_P0P0_DP(15)    I86 @BASEBOARD_FAB2_LIB.BASEBOARD_FAB2(SCH_1):PAGE33
   AC6 UPI_CPU1_CPU0_P0P0_DP<16> @BASEBOARD_FAB2_LIB.BASEBOARD_FAB2(SCH_1):UPI_CPU1_CPU0_P0P0_DP(16)    I86 @BASEBOARD_FAB2_LIB.BASEBOARD_FAB2(SCH_1):PAGE33
   AA6 UPI_CPU1_CPU0_P0P0_DP<17> @BASEBOARD_FAB2_LIB.BASEBOARD_FAB2(SCH_1):UPI_CPU1_CPU0_P0P0_DP(17)    I86 @BASEBOARD_FAB2_LIB.BASEBOARD_FAB2(SCH_1):PAGE33
   AC8 UPI_CPU1_CPU0_P0P0_DP<18> @BASEBOARD_FAB2_LIB.BASEBOARD_FAB2(SCH_1):UPI_CPU1_CPU0_P0P0_DP(18)    I86 @BASEBOARD_FAB2_LIB.BASEBOARD_FAB2(SCH_1):PAGE33
   AB9 UPI_CPU1_CPU0_P0P0_DP<19> @BASEBOARD_FAB2_LIB.BASEBOARD_FAB2(SCH_1):UPI_CPU1_CPU0_P0P0_DP(19)    I86 @BASEBOARD_FAB2_LIB.BASEBOARD_FAB2(SCH_1):PAGE33
   BG4 UPI_CPU0_CPU1_P0P0_DN<0> @BASEBOARD_FAB2_LIB.BASEBOARD_FAB2(SCH_1):UPI_CPU0_CPU1_P0P0_DN(0)    I86 @BASEBOARD_FAB2_LIB.BASEBOARD_FAB2(SCH_1):PAGE33
   BF3 UPI_CPU0_CPU1_P0P0_DN<1> @BASEBOARD_FAB2_LIB.BASEBOARD_FAB2(SCH_1):UPI_CPU0_CPU1_P0P0_DN(1)    I86 @BASEBOARD_FAB2_LIB.BASEBOARD_FAB2(SCH_1):PAGE33
   BB3 UPI_CPU0_CPU1_P0P0_DN<2> @BASEBOARD_FAB2_LIB.BASEBOARD_FAB2(SCH_1):UPI_CPU0_CPU1_P0P0_DN(2)    I86 @BASEBOARD_FAB2_LIB.BASEBOARD_FAB2(SCH_1):PAGE33
   BA4 UPI_CPU0_CPU1_P0P0_DN<3> @BASEBOARD_FAB2_LIB.BASEBOARD_FAB2(SCH_1):UPI_CPU0_CPU1_P0P0_DN(3)    I86 @BASEBOARD_FAB2_LIB.BASEBOARD_FAB2(SCH_1):PAGE33
   AV5 UPI_CPU0_CPU1_P0P0_DN<4> @BASEBOARD_FAB2_LIB.BASEBOARD_FAB2(SCH_1):UPI_CPU0_CPU1_P0P0_DN(4)    I86 @BASEBOARD_FAB2_LIB.BASEBOARD_FAB2(SCH_1):PAGE33
   AU4 UPI_CPU0_CPU1_P0P0_DN<5> @BASEBOARD_FAB2_LIB.BASEBOARD_FAB2(SCH_1):UPI_CPU0_CPU1_P0P0_DN(5)    I86 @BASEBOARD_FAB2_LIB.BASEBOARD_FAB2(SCH_1):PAGE33
   AT3 UPI_CPU0_CPU1_P0P0_DN<6> @BASEBOARD_FAB2_LIB.BASEBOARD_FAB2(SCH_1):UPI_CPU0_CPU1_P0P0_DN(6)    I86 @BASEBOARD_FAB2_LIB.BASEBOARD_FAB2(SCH_1):PAGE33
   AT1 UPI_CPU0_CPU1_P0P0_DN<7> @BASEBOARD_FAB2_LIB.BASEBOARD_FAB2(SCH_1):UPI_CPU0_CPU1_P0P0_DN(7)    I86 @BASEBOARD_FAB2_LIB.BASEBOARD_FAB2(SCH_1):PAGE33
   AN4 UPI_CPU0_CPU1_P0P0_DN<8> @BASEBOARD_FAB2_LIB.BASEBOARD_FAB2(SCH_1):UPI_CPU0_CPU1_P0P0_DN(8)    I86 @BASEBOARD_FAB2_LIB.BASEBOARD_FAB2(SCH_1):PAGE33
   AM3 UPI_CPU0_CPU1_P0P0_DN<9> @BASEBOARD_FAB2_LIB.BASEBOARD_FAB2(SCH_1):UPI_CPU0_CPU1_P0P0_DN(9)    I86 @BASEBOARD_FAB2_LIB.BASEBOARD_FAB2(SCH_1):PAGE33
   AL2 UPI_CPU0_CPU1_P0P0_DN<10> @BASEBOARD_FAB2_LIB.BASEBOARD_FAB2(SCH_1):UPI_CPU0_CPU1_P0P0_DN(10)    I86 @BASEBOARD_FAB2_LIB.BASEBOARD_FAB2(SCH_1):PAGE33
   AH3 UPI_CPU0_CPU1_P0P0_DN<11> @BASEBOARD_FAB2_LIB.BASEBOARD_FAB2(SCH_1):UPI_CPU0_CPU1_P0P0_DN(11)    I86 @BASEBOARD_FAB2_LIB.BASEBOARD_FAB2(SCH_1):PAGE33
   AE2 UPI_CPU0_CPU1_P0P0_DN<12> @BASEBOARD_FAB2_LIB.BASEBOARD_FAB2(SCH_1):UPI_CPU0_CPU1_P0P0_DN(12)    I86 @BASEBOARD_FAB2_LIB.BASEBOARD_FAB2(SCH_1):PAGE33
   AG4 UPI_CPU0_CPU1_P0P0_DN<13> @BASEBOARD_FAB2_LIB.BASEBOARD_FAB2(SCH_1):UPI_CPU0_CPU1_P0P0_DN(13)    I86 @BASEBOARD_FAB2_LIB.BASEBOARD_FAB2(SCH_1):PAGE33
   AC2 UPI_CPU0_CPU1_P0P0_DN<14> @BASEBOARD_FAB2_LIB.BASEBOARD_FAB2(SCH_1):UPI_CPU0_CPU1_P0P0_DN(14)    I86 @BASEBOARD_FAB2_LIB.BASEBOARD_FAB2(SCH_1):PAGE33
   AB3 UPI_CPU0_CPU1_P0P0_DN<15> @BASEBOARD_FAB2_LIB.BASEBOARD_FAB2(SCH_1):UPI_CPU0_CPU1_P0P0_DN(15)    I86 @BASEBOARD_FAB2_LIB.BASEBOARD_FAB2(SCH_1):PAGE33
    Y1 UPI_CPU0_CPU1_P0P0_DN<16> @BASEBOARD_FAB2_LIB.BASEBOARD_FAB2(SCH_1):UPI_CPU0_CPU1_P0P0_DN(16)    I86 @BASEBOARD_FAB2_LIB.BASEBOARD_FAB2(SCH_1):PAGE33
    V3 UPI_CPU0_CPU1_P0P0_DN<17> @BASEBOARD_FAB2_LIB.BASEBOARD_FAB2(SCH_1):UPI_CPU0_CPU1_P0P0_DN(17)    I86 @BASEBOARD_FAB2_LIB.BASEBOARD_FAB2(SCH_1):PAGE33
    P1 UPI_CPU0_CPU1_P0P0_DN<18> @BASEBOARD_FAB2_LIB.BASEBOARD_FAB2(SCH_1):UPI_CPU0_CPU1_P0P0_DN(18)    I86 @BASEBOARD_FAB2_LIB.BASEBOARD_FAB2(SCH_1):PAGE33
    N2 UPI_CPU0_CPU1_P0P0_DN<19> @BASEBOARD_FAB2_LIB.BASEBOARD_FAB2(SCH_1):UPI_CPU0_CPU1_P0P0_DN(19)    I86 @BASEBOARD_FAB2_LIB.BASEBOARD_FAB2(SCH_1):PAGE33
   BH3 UPI_CPU0_CPU1_P0P0_DP<0> @BASEBOARD_FAB2_LIB.BASEBOARD_FAB2(SCH_1):UPI_CPU0_CPU1_P0P0_DP(0)    I86 @BASEBOARD_FAB2_LIB.BASEBOARD_FAB2(SCH_1):PAGE33
   BD3 UPI_CPU0_CPU1_P0P0_DP<1> @BASEBOARD_FAB2_LIB.BASEBOARD_FAB2(SCH_1):UPI_CPU0_CPU1_P0P0_DP(1)    I86 @BASEBOARD_FAB2_LIB.BASEBOARD_FAB2(SCH_1):PAGE33
   BC2 UPI_CPU0_CPU1_P0P0_DP<2> @BASEBOARD_FAB2_LIB.BASEBOARD_FAB2(SCH_1):UPI_CPU0_CPU1_P0P0_DP(2)    I86 @BASEBOARD_FAB2_LIB.BASEBOARD_FAB2(SCH_1):PAGE33
   AY3 UPI_CPU0_CPU1_P0P0_DP<3> @BASEBOARD_FAB2_LIB.BASEBOARD_FAB2(SCH_1):UPI_CPU0_CPU1_P0P0_DP(3)    I86 @BASEBOARD_FAB2_LIB.BASEBOARD_FAB2(SCH_1):PAGE33
   AW4 UPI_CPU0_CPU1_P0P0_DP<4> @BASEBOARD_FAB2_LIB.BASEBOARD_FAB2(SCH_1):UPI_CPU0_CPU1_P0P0_DP(4)    I86 @BASEBOARD_FAB2_LIB.BASEBOARD_FAB2(SCH_1):PAGE33
   AR4 UPI_CPU0_CPU1_P0P0_DP<5> @BASEBOARD_FAB2_LIB.BASEBOARD_FAB2(SCH_1):UPI_CPU0_CPU1_P0P0_DP(5)    I86 @BASEBOARD_FAB2_LIB.BASEBOARD_FAB2(SCH_1):PAGE33
   AR2 UPI_CPU0_CPU1_P0P0_DP<6> @BASEBOARD_FAB2_LIB.BASEBOARD_FAB2(SCH_1):UPI_CPU0_CPU1_P0P0_DP(6)    I86 @BASEBOARD_FAB2_LIB.BASEBOARD_FAB2(SCH_1):PAGE33
   AP1 UPI_CPU0_CPU1_P0P0_DP<7> @BASEBOARD_FAB2_LIB.BASEBOARD_FAB2(SCH_1):UPI_CPU0_CPU1_P0P0_DP(7)    I86 @BASEBOARD_FAB2_LIB.BASEBOARD_FAB2(SCH_1):PAGE33
   AP3 UPI_CPU0_CPU1_P0P0_DP<8> @BASEBOARD_FAB2_LIB.BASEBOARD_FAB2(SCH_1):UPI_CPU0_CPU1_P0P0_DP(8)    I86 @BASEBOARD_FAB2_LIB.BASEBOARD_FAB2(SCH_1):PAGE33
   AK3 UPI_CPU0_CPU1_P0P0_DP<9> @BASEBOARD_FAB2_LIB.BASEBOARD_FAB2(SCH_1):UPI_CPU0_CPU1_P0P0_DP(9)    I86 @BASEBOARD_FAB2_LIB.BASEBOARD_FAB2(SCH_1):PAGE33
   AK1 UPI_CPU0_CPU1_P0P0_DP<10> @BASEBOARD_FAB2_LIB.BASEBOARD_FAB2(SCH_1):UPI_CPU0_CPU1_P0P0_DP(10)    I86 @BASEBOARD_FAB2_LIB.BASEBOARD_FAB2(SCH_1):PAGE33
   AJ2 UPI_CPU0_CPU1_P0P0_DP<11> @BASEBOARD_FAB2_LIB.BASEBOARD_FAB2(SCH_1):UPI_CPU0_CPU1_P0P0_DP(11)    I86 @BASEBOARD_FAB2_LIB.BASEBOARD_FAB2(SCH_1):PAGE33
   AG2 UPI_CPU0_CPU1_P0P0_DP<12> @BASEBOARD_FAB2_LIB.BASEBOARD_FAB2(SCH_1):UPI_CPU0_CPU1_P0P0_DP(12)    I86 @BASEBOARD_FAB2_LIB.BASEBOARD_FAB2(SCH_1):PAGE33
   AF3 UPI_CPU0_CPU1_P0P0_DP<13> @BASEBOARD_FAB2_LIB.BASEBOARD_FAB2(SCH_1):UPI_CPU0_CPU1_P0P0_DP(13)    I86 @BASEBOARD_FAB2_LIB.BASEBOARD_FAB2(SCH_1):PAGE33
   AD1 UPI_CPU0_CPU1_P0P0_DP<14> @BASEBOARD_FAB2_LIB.BASEBOARD_FAB2(SCH_1):UPI_CPU0_CPU1_P0P0_DP(14)    I86 @BASEBOARD_FAB2_LIB.BASEBOARD_FAB2(SCH_1):PAGE33
   AA2 UPI_CPU0_CPU1_P0P0_DP<15> @BASEBOARD_FAB2_LIB.BASEBOARD_FAB2(SCH_1):UPI_CPU0_CPU1_P0P0_DP(15)    I86 @BASEBOARD_FAB2_LIB.BASEBOARD_FAB2(SCH_1):PAGE33
    W2 UPI_CPU0_CPU1_P0P0_DP<16> @BASEBOARD_FAB2_LIB.BASEBOARD_FAB2(SCH_1):UPI_CPU0_CPU1_P0P0_DP(16)    I86 @BASEBOARD_FAB2_LIB.BASEBOARD_FAB2(SCH_1):PAGE33
    Y3 UPI_CPU0_CPU1_P0P0_DP<17> @BASEBOARD_FAB2_LIB.BASEBOARD_FAB2(SCH_1):UPI_CPU0_CPU1_P0P0_DP(17)    I86 @BASEBOARD_FAB2_LIB.BASEBOARD_FAB2(SCH_1):PAGE33
    T1 UPI_CPU0_CPU1_P0P0_DP<18> @BASEBOARD_FAB2_LIB.BASEBOARD_FAB2(SCH_1):UPI_CPU0_CPU1_P0P0_DP(18)    I86 @BASEBOARD_FAB2_LIB.BASEBOARD_FAB2(SCH_1):PAGE33
    M1 UPI_CPU0_CPU1_P0P0_DP<19> @BASEBOARD_FAB2_LIB.BASEBOARD_FAB2(SCH_1):UPI_CPU0_CPU1_P0P0_DP(19)    I86 @BASEBOARD_FAB2_LIB.BASEBOARD_FAB2(SCH_1):PAGE33
  AB19 UPI_CPU1_CPU0_P1P1_DN<0> @BASEBOARD_FAB2_LIB.BASEBOARD_FAB2(SCH_1):UPI_CPU1_CPU0_P1P1_DN(0)    I86 @BASEBOARD_FAB2_LIB.BASEBOARD_FAB2(SCH_1):PAGE34
   Y21 UPI_CPU1_CPU0_P1P1_DN<1> @BASEBOARD_FAB2_LIB.BASEBOARD_FAB2(SCH_1):UPI_CPU1_CPU0_P1P1_DN(1)    I86 @BASEBOARD_FAB2_LIB.BASEBOARD_FAB2(SCH_1):PAGE34
   V19 UPI_CPU1_CPU0_P1P1_DN<2> @BASEBOARD_FAB2_LIB.BASEBOARD_FAB2(SCH_1):UPI_CPU1_CPU0_P1P1_DN(2)    I86 @BASEBOARD_FAB2_LIB.BASEBOARD_FAB2(SCH_1):PAGE34
   P21 UPI_CPU1_CPU0_P1P1_DN<3> @BASEBOARD_FAB2_LIB.BASEBOARD_FAB2(SCH_1):UPI_CPU1_CPU0_P1P1_DN(3)    I86 @BASEBOARD_FAB2_LIB.BASEBOARD_FAB2(SCH_1):PAGE34
   U18 UPI_CPU1_CPU0_P1P1_DN<4> @BASEBOARD_FAB2_LIB.BASEBOARD_FAB2(SCH_1):UPI_CPU1_CPU0_P1P1_DN(4)    I86 @BASEBOARD_FAB2_LIB.BASEBOARD_FAB2(SCH_1):PAGE34
   R20 UPI_CPU1_CPU0_P1P1_DN<5> @BASEBOARD_FAB2_LIB.BASEBOARD_FAB2(SCH_1):UPI_CPU1_CPU0_P1P1_DN(5)    I86 @BASEBOARD_FAB2_LIB.BASEBOARD_FAB2(SCH_1):PAGE34
   W18 UPI_CPU1_CPU0_P1P1_DN<6> @BASEBOARD_FAB2_LIB.BASEBOARD_FAB2(SCH_1):UPI_CPU1_CPU0_P1P1_DN(6)    I86 @BASEBOARD_FAB2_LIB.BASEBOARD_FAB2(SCH_1):PAGE34
   U16 UPI_CPU1_CPU0_P1P1_DN<7> @BASEBOARD_FAB2_LIB.BASEBOARD_FAB2(SCH_1):UPI_CPU1_CPU0_P1P1_DN(7)    I86 @BASEBOARD_FAB2_LIB.BASEBOARD_FAB2(SCH_1):PAGE34
   P17 UPI_CPU1_CPU0_P1P1_DN<8> @BASEBOARD_FAB2_LIB.BASEBOARD_FAB2(SCH_1):UPI_CPU1_CPU0_P1P1_DN(8)    I86 @BASEBOARD_FAB2_LIB.BASEBOARD_FAB2(SCH_1):PAGE34
   R16 UPI_CPU1_CPU0_P1P1_DN<9> @BASEBOARD_FAB2_LIB.BASEBOARD_FAB2(SCH_1):UPI_CPU1_CPU0_P1P1_DN(9)    I86 @BASEBOARD_FAB2_LIB.BASEBOARD_FAB2(SCH_1):PAGE34
   R12 UPI_CPU1_CPU0_P1P1_DN<10> @BASEBOARD_FAB2_LIB.BASEBOARD_FAB2(SCH_1):UPI_CPU1_CPU0_P1P1_DN(10)    I86 @BASEBOARD_FAB2_LIB.BASEBOARD_FAB2(SCH_1):PAGE34
   N14 UPI_CPU1_CPU0_P1P1_DN<11> @BASEBOARD_FAB2_LIB.BASEBOARD_FAB2(SCH_1):UPI_CPU1_CPU0_P1P1_DN(11)    I86 @BASEBOARD_FAB2_LIB.BASEBOARD_FAB2(SCH_1):PAGE34
   L12 UPI_CPU1_CPU0_P1P1_DN<12> @BASEBOARD_FAB2_LIB.BASEBOARD_FAB2(SCH_1):UPI_CPU1_CPU0_P1P1_DN(12)    I86 @BASEBOARD_FAB2_LIB.BASEBOARD_FAB2(SCH_1):PAGE34
   U12 UPI_CPU1_CPU0_P1P1_DN<13> @BASEBOARD_FAB2_LIB.BASEBOARD_FAB2(SCH_1):UPI_CPU1_CPU0_P1P1_DN(13)    I86 @BASEBOARD_FAB2_LIB.BASEBOARD_FAB2(SCH_1):PAGE34
   R10 UPI_CPU1_CPU0_P1P1_DN<14> @BASEBOARD_FAB2_LIB.BASEBOARD_FAB2(SCH_1):UPI_CPU1_CPU0_P1P1_DN(14)    I86 @BASEBOARD_FAB2_LIB.BASEBOARD_FAB2(SCH_1):PAGE34
    P9 UPI_CPU1_CPU0_P1P1_DN<15> @BASEBOARD_FAB2_LIB.BASEBOARD_FAB2(SCH_1):UPI_CPU1_CPU0_P1P1_DN(15)    I86 @BASEBOARD_FAB2_LIB.BASEBOARD_FAB2(SCH_1):PAGE34
    T9 UPI_CPU1_CPU0_P1P1_DN<16> @BASEBOARD_FAB2_LIB.BASEBOARD_FAB2(SCH_1):UPI_CPU1_CPU0_P1P1_DN(16)    I86 @BASEBOARD_FAB2_LIB.BASEBOARD_FAB2(SCH_1):PAGE34
    V7 UPI_CPU1_CPU0_P1P1_DN<17> @BASEBOARD_FAB2_LIB.BASEBOARD_FAB2(SCH_1):UPI_CPU1_CPU0_P1P1_DN(17)    I86 @BASEBOARD_FAB2_LIB.BASEBOARD_FAB2(SCH_1):PAGE34
    P7 UPI_CPU1_CPU0_P1P1_DN<18> @BASEBOARD_FAB2_LIB.BASEBOARD_FAB2(SCH_1):UPI_CPU1_CPU0_P1P1_DN(18)    I86 @BASEBOARD_FAB2_LIB.BASEBOARD_FAB2(SCH_1):PAGE34
    T5 UPI_CPU1_CPU0_P1P1_DN<19> @BASEBOARD_FAB2_LIB.BASEBOARD_FAB2(SCH_1):UPI_CPU1_CPU0_P1P1_DN(19)    I86 @BASEBOARD_FAB2_LIB.BASEBOARD_FAB2(SCH_1):PAGE34
  AA20 UPI_CPU1_CPU0_P1P1_DP<0> @BASEBOARD_FAB2_LIB.BASEBOARD_FAB2(SCH_1):UPI_CPU1_CPU0_P1P1_DP(0)    I86 @BASEBOARD_FAB2_LIB.BASEBOARD_FAB2(SCH_1):PAGE34
   W20 UPI_CPU1_CPU0_P1P1_DP<1> @BASEBOARD_FAB2_LIB.BASEBOARD_FAB2(SCH_1):UPI_CPU1_CPU0_P1P1_DP(1)    I86 @BASEBOARD_FAB2_LIB.BASEBOARD_FAB2(SCH_1):PAGE34
   Y19 UPI_CPU1_CPU0_P1P1_DP<2> @BASEBOARD_FAB2_LIB.BASEBOARD_FAB2(SCH_1):UPI_CPU1_CPU0_P1P1_DP(2)    I86 @BASEBOARD_FAB2_LIB.BASEBOARD_FAB2(SCH_1):PAGE34
   T21 UPI_CPU1_CPU0_P1P1_DP<3> @BASEBOARD_FAB2_LIB.BASEBOARD_FAB2(SCH_1):UPI_CPU1_CPU0_P1P1_DP(3)    I86 @BASEBOARD_FAB2_LIB.BASEBOARD_FAB2(SCH_1):PAGE34
   T19 UPI_CPU1_CPU0_P1P1_DP<4> @BASEBOARD_FAB2_LIB.BASEBOARD_FAB2(SCH_1):UPI_CPU1_CPU0_P1P1_DP(4)    I86 @BASEBOARD_FAB2_LIB.BASEBOARD_FAB2(SCH_1):PAGE34
   P19 UPI_CPU1_CPU0_P1P1_DP<5> @BASEBOARD_FAB2_LIB.BASEBOARD_FAB2(SCH_1):UPI_CPU1_CPU0_P1P1_DP(5)    I86 @BASEBOARD_FAB2_LIB.BASEBOARD_FAB2(SCH_1):PAGE34
   V17 UPI_CPU1_CPU0_P1P1_DP<6> @BASEBOARD_FAB2_LIB.BASEBOARD_FAB2(SCH_1):UPI_CPU1_CPU0_P1P1_DP(6)    I86 @BASEBOARD_FAB2_LIB.BASEBOARD_FAB2(SCH_1):PAGE34
   W16 UPI_CPU1_CPU0_P1P1_DP<7> @BASEBOARD_FAB2_LIB.BASEBOARD_FAB2(SCH_1):UPI_CPU1_CPU0_P1P1_DP(7)    I86 @BASEBOARD_FAB2_LIB.BASEBOARD_FAB2(SCH_1):PAGE34
   N16 UPI_CPU1_CPU0_P1P1_DP<8> @BASEBOARD_FAB2_LIB.BASEBOARD_FAB2(SCH_1):UPI_CPU1_CPU0_P1P1_DP(8)    I86 @BASEBOARD_FAB2_LIB.BASEBOARD_FAB2(SCH_1):PAGE34
   T15 UPI_CPU1_CPU0_P1P1_DP<9> @BASEBOARD_FAB2_LIB.BASEBOARD_FAB2(SCH_1):UPI_CPU1_CPU0_P1P1_DP(9)    I86 @BASEBOARD_FAB2_LIB.BASEBOARD_FAB2(SCH_1):PAGE34
   P13 UPI_CPU1_CPU0_P1P1_DP<10> @BASEBOARD_FAB2_LIB.BASEBOARD_FAB2(SCH_1):UPI_CPU1_CPU0_P1P1_DP(10)    I86 @BASEBOARD_FAB2_LIB.BASEBOARD_FAB2(SCH_1):PAGE34
   M13 UPI_CPU1_CPU0_P1P1_DP<11> @BASEBOARD_FAB2_LIB.BASEBOARD_FAB2(SCH_1):UPI_CPU1_CPU0_P1P1_DP(11)    I86 @BASEBOARD_FAB2_LIB.BASEBOARD_FAB2(SCH_1):PAGE34
   N12 UPI_CPU1_CPU0_P1P1_DP<12> @BASEBOARD_FAB2_LIB.BASEBOARD_FAB2(SCH_1):UPI_CPU1_CPU0_P1P1_DP(12)    I86 @BASEBOARD_FAB2_LIB.BASEBOARD_FAB2(SCH_1):PAGE34
   T11 UPI_CPU1_CPU0_P1P1_DP<13> @BASEBOARD_FAB2_LIB.BASEBOARD_FAB2(SCH_1):UPI_CPU1_CPU0_P1P1_DP(13)    I86 @BASEBOARD_FAB2_LIB.BASEBOARD_FAB2(SCH_1):PAGE34
   U10 UPI_CPU1_CPU0_P1P1_DP<14> @BASEBOARD_FAB2_LIB.BASEBOARD_FAB2(SCH_1):UPI_CPU1_CPU0_P1P1_DP(14)    I86 @BASEBOARD_FAB2_LIB.BASEBOARD_FAB2(SCH_1):PAGE34
   N10 UPI_CPU1_CPU0_P1P1_DP<15> @BASEBOARD_FAB2_LIB.BASEBOARD_FAB2(SCH_1):UPI_CPU1_CPU0_P1P1_DP(15)    I86 @BASEBOARD_FAB2_LIB.BASEBOARD_FAB2(SCH_1):PAGE34
    R8 UPI_CPU1_CPU0_P1P1_DP<16> @BASEBOARD_FAB2_LIB.BASEBOARD_FAB2(SCH_1):UPI_CPU1_CPU0_P1P1_DP(16)    I86 @BASEBOARD_FAB2_LIB.BASEBOARD_FAB2(SCH_1):PAGE34
    U8 UPI_CPU1_CPU0_P1P1_DP<17> @BASEBOARD_FAB2_LIB.BASEBOARD_FAB2(SCH_1):UPI_CPU1_CPU0_P1P1_DP(17)    I86 @BASEBOARD_FAB2_LIB.BASEBOARD_FAB2(SCH_1):PAGE34
    T7 UPI_CPU1_CPU0_P1P1_DP<18> @BASEBOARD_FAB2_LIB.BASEBOARD_FAB2(SCH_1):UPI_CPU1_CPU0_P1P1_DP(18)    I86 @BASEBOARD_FAB2_LIB.BASEBOARD_FAB2(SCH_1):PAGE34
    R6 UPI_CPU1_CPU0_P1P1_DP<19> @BASEBOARD_FAB2_LIB.BASEBOARD_FAB2(SCH_1):UPI_CPU1_CPU0_P1P1_DP(19)    I86 @BASEBOARD_FAB2_LIB.BASEBOARD_FAB2(SCH_1):PAGE34
   H21 UPI_CPU0_CPU1_P1P1_DN<0> @BASEBOARD_FAB2_LIB.BASEBOARD_FAB2(SCH_1):UPI_CPU0_CPU1_P1P1_DN(0)    I86 @BASEBOARD_FAB2_LIB.BASEBOARD_FAB2(SCH_1):PAGE34
   F21 UPI_CPU0_CPU1_P1P1_DN<1> @BASEBOARD_FAB2_LIB.BASEBOARD_FAB2(SCH_1):UPI_CPU0_CPU1_P1P1_DN(1)    I86 @BASEBOARD_FAB2_LIB.BASEBOARD_FAB2(SCH_1):PAGE34
   J20 UPI_CPU0_CPU1_P1P1_DN<2> @BASEBOARD_FAB2_LIB.BASEBOARD_FAB2(SCH_1):UPI_CPU0_CPU1_P1P1_DN(2)    I86 @BASEBOARD_FAB2_LIB.BASEBOARD_FAB2(SCH_1):PAGE34
   G18 UPI_CPU0_CPU1_P1P1_DN<3> @BASEBOARD_FAB2_LIB.BASEBOARD_FAB2(SCH_1):UPI_CPU0_CPU1_P1P1_DN(3)    I86 @BASEBOARD_FAB2_LIB.BASEBOARD_FAB2(SCH_1):PAGE34
   K19 UPI_CPU0_CPU1_P1P1_DN<4> @BASEBOARD_FAB2_LIB.BASEBOARD_FAB2(SCH_1):UPI_CPU0_CPU1_P1P1_DN(4)    I86 @BASEBOARD_FAB2_LIB.BASEBOARD_FAB2(SCH_1):PAGE34
   H17 UPI_CPU0_CPU1_P1P1_DN<5> @BASEBOARD_FAB2_LIB.BASEBOARD_FAB2(SCH_1):UPI_CPU0_CPU1_P1P1_DN(5)    I86 @BASEBOARD_FAB2_LIB.BASEBOARD_FAB2(SCH_1):PAGE34
   F15 UPI_CPU0_CPU1_P1P1_DN<6> @BASEBOARD_FAB2_LIB.BASEBOARD_FAB2(SCH_1):UPI_CPU0_CPU1_P1P1_DN(6)    I86 @BASEBOARD_FAB2_LIB.BASEBOARD_FAB2(SCH_1):PAGE34
   D15 UPI_CPU0_CPU1_P1P1_DN<7> @BASEBOARD_FAB2_LIB.BASEBOARD_FAB2(SCH_1):UPI_CPU0_CPU1_P1P1_DN(7)    I86 @BASEBOARD_FAB2_LIB.BASEBOARD_FAB2(SCH_1):PAGE34
   G14 UPI_CPU0_CPU1_P1P1_DN<8> @BASEBOARD_FAB2_LIB.BASEBOARD_FAB2(SCH_1):UPI_CPU0_CPU1_P1P1_DN(8)    I86 @BASEBOARD_FAB2_LIB.BASEBOARD_FAB2(SCH_1):PAGE34
   E12 UPI_CPU0_CPU1_P1P1_DN<9> @BASEBOARD_FAB2_LIB.BASEBOARD_FAB2(SCH_1):UPI_CPU0_CPU1_P1P1_DN(9)    I86 @BASEBOARD_FAB2_LIB.BASEBOARD_FAB2(SCH_1):PAGE34
   G10 UPI_CPU0_CPU1_P1P1_DN<10> @BASEBOARD_FAB2_LIB.BASEBOARD_FAB2(SCH_1):UPI_CPU0_CPU1_P1P1_DN(10)    I86 @BASEBOARD_FAB2_LIB.BASEBOARD_FAB2(SCH_1):PAGE34
   F11 UPI_CPU0_CPU1_P1P1_DN<11> @BASEBOARD_FAB2_LIB.BASEBOARD_FAB2(SCH_1):UPI_CPU0_CPU1_P1P1_DN(11)    I86 @BASEBOARD_FAB2_LIB.BASEBOARD_FAB2(SCH_1):PAGE34
    D9 UPI_CPU0_CPU1_P1P1_DN<12> @BASEBOARD_FAB2_LIB.BASEBOARD_FAB2(SCH_1):UPI_CPU0_CPU1_P1P1_DN(12)    I86 @BASEBOARD_FAB2_LIB.BASEBOARD_FAB2(SCH_1):PAGE34
    K9 UPI_CPU0_CPU1_P1P1_DN<13> @BASEBOARD_FAB2_LIB.BASEBOARD_FAB2(SCH_1):UPI_CPU0_CPU1_P1P1_DN(13)    I86 @BASEBOARD_FAB2_LIB.BASEBOARD_FAB2(SCH_1):PAGE34
    H7 UPI_CPU0_CPU1_P1P1_DN<14> @BASEBOARD_FAB2_LIB.BASEBOARD_FAB2(SCH_1):UPI_CPU0_CPU1_P1P1_DN(14)    I86 @BASEBOARD_FAB2_LIB.BASEBOARD_FAB2(SCH_1):PAGE34
    G6 UPI_CPU0_CPU1_P1P1_DN<15> @BASEBOARD_FAB2_LIB.BASEBOARD_FAB2(SCH_1):UPI_CPU0_CPU1_P1P1_DN(15)    I86 @BASEBOARD_FAB2_LIB.BASEBOARD_FAB2(SCH_1):PAGE34
    J6 UPI_CPU0_CPU1_P1P1_DN<16> @BASEBOARD_FAB2_LIB.BASEBOARD_FAB2(SCH_1):UPI_CPU0_CPU1_P1P1_DN(16)    I86 @BASEBOARD_FAB2_LIB.BASEBOARD_FAB2(SCH_1):PAGE34
    K5 UPI_CPU0_CPU1_P1P1_DN<17> @BASEBOARD_FAB2_LIB.BASEBOARD_FAB2(SCH_1):UPI_CPU0_CPU1_P1P1_DN(17)    I86 @BASEBOARD_FAB2_LIB.BASEBOARD_FAB2(SCH_1):PAGE34
    L4 UPI_CPU0_CPU1_P1P1_DN<18> @BASEBOARD_FAB2_LIB.BASEBOARD_FAB2(SCH_1):UPI_CPU0_CPU1_P1P1_DN(18)    I86 @BASEBOARD_FAB2_LIB.BASEBOARD_FAB2(SCH_1):PAGE34
    M3 UPI_CPU0_CPU1_P1P1_DN<19> @BASEBOARD_FAB2_LIB.BASEBOARD_FAB2(SCH_1):UPI_CPU0_CPU1_P1P1_DN(19)    I86 @BASEBOARD_FAB2_LIB.BASEBOARD_FAB2(SCH_1):PAGE34
   K21 UPI_CPU0_CPU1_P1P1_DP<0> @BASEBOARD_FAB2_LIB.BASEBOARD_FAB2(SCH_1):UPI_CPU0_CPU1_P1P1_DP(0)    I86 @BASEBOARD_FAB2_LIB.BASEBOARD_FAB2(SCH_1):PAGE34
   G20 UPI_CPU0_CPU1_P1P1_DP<1> @BASEBOARD_FAB2_LIB.BASEBOARD_FAB2(SCH_1):UPI_CPU0_CPU1_P1P1_DP(1)    I86 @BASEBOARD_FAB2_LIB.BASEBOARD_FAB2(SCH_1):PAGE34
   H19 UPI_CPU0_CPU1_P1P1_DP<2> @BASEBOARD_FAB2_LIB.BASEBOARD_FAB2(SCH_1):UPI_CPU0_CPU1_P1P1_DP(2)    I86 @BASEBOARD_FAB2_LIB.BASEBOARD_FAB2(SCH_1):PAGE34
   J18 UPI_CPU0_CPU1_P1P1_DP<3> @BASEBOARD_FAB2_LIB.BASEBOARD_FAB2(SCH_1):UPI_CPU0_CPU1_P1P1_DP(3)    I86 @BASEBOARD_FAB2_LIB.BASEBOARD_FAB2(SCH_1):PAGE34
   L18 UPI_CPU0_CPU1_P1P1_DP<4> @BASEBOARD_FAB2_LIB.BASEBOARD_FAB2(SCH_1):UPI_CPU0_CPU1_P1P1_DP(4)    I86 @BASEBOARD_FAB2_LIB.BASEBOARD_FAB2(SCH_1):PAGE34
   G16 UPI_CPU0_CPU1_P1P1_DP<5> @BASEBOARD_FAB2_LIB.BASEBOARD_FAB2(SCH_1):UPI_CPU0_CPU1_P1P1_DP(5)    I86 @BASEBOARD_FAB2_LIB.BASEBOARD_FAB2(SCH_1):PAGE34
   H15 UPI_CPU0_CPU1_P1P1_DP<6> @BASEBOARD_FAB2_LIB.BASEBOARD_FAB2(SCH_1):UPI_CPU0_CPU1_P1P1_DP(6)    I86 @BASEBOARD_FAB2_LIB.BASEBOARD_FAB2(SCH_1):PAGE34
   E14 UPI_CPU0_CPU1_P1P1_DP<7> @BASEBOARD_FAB2_LIB.BASEBOARD_FAB2(SCH_1):UPI_CPU0_CPU1_P1P1_DP(7)    I86 @BASEBOARD_FAB2_LIB.BASEBOARD_FAB2(SCH_1):PAGE34
   F13 UPI_CPU0_CPU1_P1P1_DP<8> @BASEBOARD_FAB2_LIB.BASEBOARD_FAB2(SCH_1):UPI_CPU0_CPU1_P1P1_DP(8)    I86 @BASEBOARD_FAB2_LIB.BASEBOARD_FAB2(SCH_1):PAGE34
   G12 UPI_CPU0_CPU1_P1P1_DP<9> @BASEBOARD_FAB2_LIB.BASEBOARD_FAB2(SCH_1):UPI_CPU0_CPU1_P1P1_DP(9)    I86 @BASEBOARD_FAB2_LIB.BASEBOARD_FAB2(SCH_1):PAGE34
    H9 UPI_CPU0_CPU1_P1P1_DP<10> @BASEBOARD_FAB2_LIB.BASEBOARD_FAB2(SCH_1):UPI_CPU0_CPU1_P1P1_DP(10)    I86 @BASEBOARD_FAB2_LIB.BASEBOARD_FAB2(SCH_1):PAGE34
   E10 UPI_CPU0_CPU1_P1P1_DP<11> @BASEBOARD_FAB2_LIB.BASEBOARD_FAB2(SCH_1):UPI_CPU0_CPU1_P1P1_DP(11)    I86 @BASEBOARD_FAB2_LIB.BASEBOARD_FAB2(SCH_1):PAGE34
    F9 UPI_CPU0_CPU1_P1P1_DP<12> @BASEBOARD_FAB2_LIB.BASEBOARD_FAB2(SCH_1):UPI_CPU0_CPU1_P1P1_DP(12)    I86 @BASEBOARD_FAB2_LIB.BASEBOARD_FAB2(SCH_1):PAGE34
    J8 UPI_CPU0_CPU1_P1P1_DP<13> @BASEBOARD_FAB2_LIB.BASEBOARD_FAB2(SCH_1):UPI_CPU0_CPU1_P1P1_DP(13)    I86 @BASEBOARD_FAB2_LIB.BASEBOARD_FAB2(SCH_1):PAGE34
    K7 UPI_CPU0_CPU1_P1P1_DP<14> @BASEBOARD_FAB2_LIB.BASEBOARD_FAB2(SCH_1):UPI_CPU0_CPU1_P1P1_DP(14)    I86 @BASEBOARD_FAB2_LIB.BASEBOARD_FAB2(SCH_1):PAGE34
    F7 UPI_CPU0_CPU1_P1P1_DP<15> @BASEBOARD_FAB2_LIB.BASEBOARD_FAB2(SCH_1):UPI_CPU0_CPU1_P1P1_DP(15)    I86 @BASEBOARD_FAB2_LIB.BASEBOARD_FAB2(SCH_1):PAGE34
    H5 UPI_CPU0_CPU1_P1P1_DP<16> @BASEBOARD_FAB2_LIB.BASEBOARD_FAB2(SCH_1):UPI_CPU0_CPU1_P1P1_DP(16)    I86 @BASEBOARD_FAB2_LIB.BASEBOARD_FAB2(SCH_1):PAGE34
    M5 UPI_CPU0_CPU1_P1P1_DP<17> @BASEBOARD_FAB2_LIB.BASEBOARD_FAB2(SCH_1):UPI_CPU0_CPU1_P1P1_DP(17)    I86 @BASEBOARD_FAB2_LIB.BASEBOARD_FAB2(SCH_1):PAGE34
    K3 UPI_CPU0_CPU1_P1P1_DP<18> @BASEBOARD_FAB2_LIB.BASEBOARD_FAB2(SCH_1):UPI_CPU0_CPU1_P1P1_DP(18)    I86 @BASEBOARD_FAB2_LIB.BASEBOARD_FAB2(SCH_1):PAGE34
    P3 UPI_CPU0_CPU1_P1P1_DP<19> @BASEBOARD_FAB2_LIB.BASEBOARD_FAB2(SCH_1):UPI_CPU0_CPU1_P1P1_DP(19)    I86 @BASEBOARD_FAB2_LIB.BASEBOARD_FAB2(SCH_1):PAGE34
  BY17    GND @BASEBOARD_FAB2_LIB.BASEBOARD_FAB2(SCH_1):GND     I3 @BASEBOARD_FAB2_LIB.BASEBOARD_FAB2(SCH_1):PAGE35
  CB15    GND @BASEBOARD_FAB2_LIB.BASEBOARD_FAB2(SCH_1):GND     I3 @BASEBOARD_FAB2_LIB.BASEBOARD_FAB2(SCH_1):PAGE35
  CF17    GND @BASEBOARD_FAB2_LIB.BASEBOARD_FAB2(SCH_1):GND     I3 @BASEBOARD_FAB2_LIB.BASEBOARD_FAB2(SCH_1):PAGE35
  CD15    GND @BASEBOARD_FAB2_LIB.BASEBOARD_FAB2(SCH_1):GND     I3 @BASEBOARD_FAB2_LIB.BASEBOARD_FAB2(SCH_1):PAGE35
  CE16    GND @BASEBOARD_FAB2_LIB.BASEBOARD_FAB2(SCH_1):GND     I3 @BASEBOARD_FAB2_LIB.BASEBOARD_FAB2(SCH_1):PAGE35
  CH17    GND @BASEBOARD_FAB2_LIB.BASEBOARD_FAB2(SCH_1):GND     I3 @BASEBOARD_FAB2_LIB.BASEBOARD_FAB2(SCH_1):PAGE35
  CJ18    GND @BASEBOARD_FAB2_LIB.BASEBOARD_FAB2(SCH_1):GND     I3 @BASEBOARD_FAB2_LIB.BASEBOARD_FAB2(SCH_1):PAGE35
  CL16    GND @BASEBOARD_FAB2_LIB.BASEBOARD_FAB2(SCH_1):GND     I3 @BASEBOARD_FAB2_LIB.BASEBOARD_FAB2(SCH_1):PAGE35
  CP21    GND @BASEBOARD_FAB2_LIB.BASEBOARD_FAB2(SCH_1):GND     I3 @BASEBOARD_FAB2_LIB.BASEBOARD_FAB2(SCH_1):PAGE35
  CN20    GND @BASEBOARD_FAB2_LIB.BASEBOARD_FAB2(SCH_1):GND     I3 @BASEBOARD_FAB2_LIB.BASEBOARD_FAB2(SCH_1):PAGE35
  CR18    GND @BASEBOARD_FAB2_LIB.BASEBOARD_FAB2(SCH_1):GND     I3 @BASEBOARD_FAB2_LIB.BASEBOARD_FAB2(SCH_1):PAGE35
  CT21    GND @BASEBOARD_FAB2_LIB.BASEBOARD_FAB2(SCH_1):GND     I3 @BASEBOARD_FAB2_LIB.BASEBOARD_FAB2(SCH_1):PAGE35
  CV19    GND @BASEBOARD_FAB2_LIB.BASEBOARD_FAB2(SCH_1):GND     I3 @BASEBOARD_FAB2_LIB.BASEBOARD_FAB2(SCH_1):PAGE35
  CW20    GND @BASEBOARD_FAB2_LIB.BASEBOARD_FAB2(SCH_1):GND     I3 @BASEBOARD_FAB2_LIB.BASEBOARD_FAB2(SCH_1):PAGE35
  DA20    GND @BASEBOARD_FAB2_LIB.BASEBOARD_FAB2(SCH_1):GND     I3 @BASEBOARD_FAB2_LIB.BASEBOARD_FAB2(SCH_1):PAGE35
  DD19    GND @BASEBOARD_FAB2_LIB.BASEBOARD_FAB2(SCH_1):GND     I3 @BASEBOARD_FAB2_LIB.BASEBOARD_FAB2(SCH_1):PAGE35
  DB21    GND @BASEBOARD_FAB2_LIB.BASEBOARD_FAB2(SCH_1):GND     I3 @BASEBOARD_FAB2_LIB.BASEBOARD_FAB2(SCH_1):PAGE35
  DC22    GND @BASEBOARD_FAB2_LIB.BASEBOARD_FAB2(SCH_1):GND     I3 @BASEBOARD_FAB2_LIB.BASEBOARD_FAB2(SCH_1):PAGE35
  DE22    GND @BASEBOARD_FAB2_LIB.BASEBOARD_FAB2(SCH_1):GND     I3 @BASEBOARD_FAB2_LIB.BASEBOARD_FAB2(SCH_1):PAGE35
  DF23    GND @BASEBOARD_FAB2_LIB.BASEBOARD_FAB2(SCH_1):GND     I3 @BASEBOARD_FAB2_LIB.BASEBOARD_FAB2(SCH_1):PAGE35
  CA16    GND @BASEBOARD_FAB2_LIB.BASEBOARD_FAB2(SCH_1):GND     I3 @BASEBOARD_FAB2_LIB.BASEBOARD_FAB2(SCH_1):PAGE35
  BY15    GND @BASEBOARD_FAB2_LIB.BASEBOARD_FAB2(SCH_1):GND     I3 @BASEBOARD_FAB2_LIB.BASEBOARD_FAB2(SCH_1):PAGE35
  CD17    GND @BASEBOARD_FAB2_LIB.BASEBOARD_FAB2(SCH_1):GND     I3 @BASEBOARD_FAB2_LIB.BASEBOARD_FAB2(SCH_1):PAGE35
  CC14    GND @BASEBOARD_FAB2_LIB.BASEBOARD_FAB2(SCH_1):GND     I3 @BASEBOARD_FAB2_LIB.BASEBOARD_FAB2(SCH_1):PAGE35
  CF15    GND @BASEBOARD_FAB2_LIB.BASEBOARD_FAB2(SCH_1):GND     I3 @BASEBOARD_FAB2_LIB.BASEBOARD_FAB2(SCH_1):PAGE35
  CG16    GND @BASEBOARD_FAB2_LIB.BASEBOARD_FAB2(SCH_1):GND     I3 @BASEBOARD_FAB2_LIB.BASEBOARD_FAB2(SCH_1):PAGE35
  CK17    GND @BASEBOARD_FAB2_LIB.BASEBOARD_FAB2(SCH_1):GND     I3 @BASEBOARD_FAB2_LIB.BASEBOARD_FAB2(SCH_1):PAGE35
  CJ16    GND @BASEBOARD_FAB2_LIB.BASEBOARD_FAB2(SCH_1):GND     I3 @BASEBOARD_FAB2_LIB.BASEBOARD_FAB2(SCH_1):PAGE35
  CM21    GND @BASEBOARD_FAB2_LIB.BASEBOARD_FAB2(SCH_1):GND     I3 @BASEBOARD_FAB2_LIB.BASEBOARD_FAB2(SCH_1):PAGE35
  CP19    GND @BASEBOARD_FAB2_LIB.BASEBOARD_FAB2(SCH_1):GND     I3 @BASEBOARD_FAB2_LIB.BASEBOARD_FAB2(SCH_1):PAGE35
  CN18    GND @BASEBOARD_FAB2_LIB.BASEBOARD_FAB2(SCH_1):GND     I3 @BASEBOARD_FAB2_LIB.BASEBOARD_FAB2(SCH_1):PAGE35
  CR20    GND @BASEBOARD_FAB2_LIB.BASEBOARD_FAB2(SCH_1):GND     I3 @BASEBOARD_FAB2_LIB.BASEBOARD_FAB2(SCH_1):PAGE35
  CW18    GND @BASEBOARD_FAB2_LIB.BASEBOARD_FAB2(SCH_1):GND     I3 @BASEBOARD_FAB2_LIB.BASEBOARD_FAB2(SCH_1):PAGE35
  CU20    GND @BASEBOARD_FAB2_LIB.BASEBOARD_FAB2(SCH_1):GND     I3 @BASEBOARD_FAB2_LIB.BASEBOARD_FAB2(SCH_1):PAGE35
  CY19    GND @BASEBOARD_FAB2_LIB.BASEBOARD_FAB2(SCH_1):GND     I3 @BASEBOARD_FAB2_LIB.BASEBOARD_FAB2(SCH_1):PAGE35
  DB19    GND @BASEBOARD_FAB2_LIB.BASEBOARD_FAB2(SCH_1):GND     I3 @BASEBOARD_FAB2_LIB.BASEBOARD_FAB2(SCH_1):PAGE35
  DC20    GND @BASEBOARD_FAB2_LIB.BASEBOARD_FAB2(SCH_1):GND     I3 @BASEBOARD_FAB2_LIB.BASEBOARD_FAB2(SCH_1):PAGE35
  DA22    GND @BASEBOARD_FAB2_LIB.BASEBOARD_FAB2(SCH_1):GND     I3 @BASEBOARD_FAB2_LIB.BASEBOARD_FAB2(SCH_1):PAGE35
  DD21    GND @BASEBOARD_FAB2_LIB.BASEBOARD_FAB2(SCH_1):GND     I3 @BASEBOARD_FAB2_LIB.BASEBOARD_FAB2(SCH_1):PAGE35
  DG22    GND @BASEBOARD_FAB2_LIB.BASEBOARD_FAB2(SCH_1):GND     I3 @BASEBOARD_FAB2_LIB.BASEBOARD_FAB2(SCH_1):PAGE35
  CC12 TP_CPU0_UPI2_RSVD_DT21 @BASEBOARD_FAB2_LIB.BASEBOARD_FAB2(SCH_1):TP_CPU0_UPI2_RSVD_DT21     I3 @BASEBOARD_FAB2_LIB.BASEBOARD_FAB2(SCH_1):PAGE35
  CC10 TP_CPU0_UPI2_RSVD_DM21 @BASEBOARD_FAB2_LIB.BASEBOARD_FAB2(SCH_1):TP_CPU0_UPI2_RSVD_DM21     I3 @BASEBOARD_FAB2_LIB.BASEBOARD_FAB2(SCH_1):PAGE35
  CE12 TP_CPU0_UPI2_RSVD_DL20 @BASEBOARD_FAB2_LIB.BASEBOARD_FAB2(SCH_1):TP_CPU0_UPI2_RSVD_DL20     I3 @BASEBOARD_FAB2_LIB.BASEBOARD_FAB2(SCH_1):PAGE35
  CH11 TP_CPU0_UPI2_RSVD_DG20 @BASEBOARD_FAB2_LIB.BASEBOARD_FAB2(SCH_1):TP_CPU0_UPI2_RSVD_DG20     I3 @BASEBOARD_FAB2_LIB.BASEBOARD_FAB2(SCH_1):PAGE35
  CF13 TP_CPU0_UPI2_RSVD_DH19 @BASEBOARD_FAB2_LIB.BASEBOARD_FAB2(SCH_1):TP_CPU0_UPI2_RSVD_DH19     I3 @BASEBOARD_FAB2_LIB.BASEBOARD_FAB2(SCH_1):PAGE35
  CJ14 TP_CPU0_UPI2_RSVD_DK17 @BASEBOARD_FAB2_LIB.BASEBOARD_FAB2(SCH_1):TP_CPU0_UPI2_RSVD_DK17     I3 @BASEBOARD_FAB2_LIB.BASEBOARD_FAB2(SCH_1):PAGE35
  CM13 TP_CPU0_UPI2_RSVD_DG18 @BASEBOARD_FAB2_LIB.BASEBOARD_FAB2(SCH_1):TP_CPU0_UPI2_RSVD_DG18     I3 @BASEBOARD_FAB2_LIB.BASEBOARD_FAB2(SCH_1):PAGE35
  CU14 TP_CPU0_UPI2_RSVD_DD17 @BASEBOARD_FAB2_LIB.BASEBOARD_FAB2(SCH_1):TP_CPU0_UPI2_RSVD_DD17     I3 @BASEBOARD_FAB2_LIB.BASEBOARD_FAB2(SCH_1):PAGE35
  CW14 TP_CPU0_UPI2_RSVD_DF15 @BASEBOARD_FAB2_LIB.BASEBOARD_FAB2(SCH_1):TP_CPU0_UPI2_RSVD_DF15     I3 @BASEBOARD_FAB2_LIB.BASEBOARD_FAB2(SCH_1):PAGE35
  DA16 TP_CPU0_UPI2_RSVD_DC16 @BASEBOARD_FAB2_LIB.BASEBOARD_FAB2(SCH_1):TP_CPU0_UPI2_RSVD_DC16     I3 @BASEBOARD_FAB2_LIB.BASEBOARD_FAB2(SCH_1):PAGE35
  DC16 TP_CPU0_UPI2_RSVD_DA16 @BASEBOARD_FAB2_LIB.BASEBOARD_FAB2(SCH_1):TP_CPU0_UPI2_RSVD_DA16     I3 @BASEBOARD_FAB2_LIB.BASEBOARD_FAB2(SCH_1):PAGE35
  DF15 TP_CPU0_UPI2_RSVD_CW14 @BASEBOARD_FAB2_LIB.BASEBOARD_FAB2(SCH_1):TP_CPU0_UPI2_RSVD_CW14     I3 @BASEBOARD_FAB2_LIB.BASEBOARD_FAB2(SCH_1):PAGE35
  DD17 TP_CPU0_UPI2_RSVD_CU14 @BASEBOARD_FAB2_LIB.BASEBOARD_FAB2(SCH_1):TP_CPU0_UPI2_RSVD_CU14     I3 @BASEBOARD_FAB2_LIB.BASEBOARD_FAB2(SCH_1):PAGE35
  DG18 TP_CPU0_UPI2_RSVD_CM13 @BASEBOARD_FAB2_LIB.BASEBOARD_FAB2(SCH_1):TP_CPU0_UPI2_RSVD_CM13     I3 @BASEBOARD_FAB2_LIB.BASEBOARD_FAB2(SCH_1):PAGE35
  DK17 TP_CPU0_UPI2_RSVD_CJ14 @BASEBOARD_FAB2_LIB.BASEBOARD_FAB2(SCH_1):TP_CPU0_UPI2_RSVD_CJ14     I3 @BASEBOARD_FAB2_LIB.BASEBOARD_FAB2(SCH_1):PAGE35
  DH19 TP_CPU0_UPI2_RSVD_CF13 @BASEBOARD_FAB2_LIB.BASEBOARD_FAB2(SCH_1):TP_CPU0_UPI2_RSVD_CF13     I3 @BASEBOARD_FAB2_LIB.BASEBOARD_FAB2(SCH_1):PAGE35
  DG20 TP_CPU0_UPI2_RSVD_CH11 @BASEBOARD_FAB2_LIB.BASEBOARD_FAB2(SCH_1):TP_CPU0_UPI2_RSVD_CH11     I3 @BASEBOARD_FAB2_LIB.BASEBOARD_FAB2(SCH_1):PAGE35
  DL20 TP_CPU0_UPI2_RSVD_CE12 @BASEBOARD_FAB2_LIB.BASEBOARD_FAB2(SCH_1):TP_CPU0_UPI2_RSVD_CE12     I3 @BASEBOARD_FAB2_LIB.BASEBOARD_FAB2(SCH_1):PAGE35
  DM21 TP_CPU0_UPI2_RSVD_CC10 @BASEBOARD_FAB2_LIB.BASEBOARD_FAB2(SCH_1):TP_CPU0_UPI2_RSVD_CC10     I3 @BASEBOARD_FAB2_LIB.BASEBOARD_FAB2(SCH_1):PAGE35
  DT21 TP_CPU0_UPI2_RSVD_CC12 @BASEBOARD_FAB2_LIB.BASEBOARD_FAB2(SCH_1):TP_CPU0_UPI2_RSVD_CC12     I3 @BASEBOARD_FAB2_LIB.BASEBOARD_FAB2(SCH_1):PAGE35
  CA12 TP_CPU0_UPI2_RSVD_DP21 @BASEBOARD_FAB2_LIB.BASEBOARD_FAB2(SCH_1):TP_CPU0_UPI2_RSVD_DP21     I3 @BASEBOARD_FAB2_LIB.BASEBOARD_FAB2(SCH_1):PAGE35
  CB11 TP_CPU0_UPI2_RSVD_DN20 @BASEBOARD_FAB2_LIB.BASEBOARD_FAB2(SCH_1):TP_CPU0_UPI2_RSVD_DN20     I3 @BASEBOARD_FAB2_LIB.BASEBOARD_FAB2(SCH_1):PAGE35
  CD11 TP_CPU0_UPI2_RSVD_DK19 @BASEBOARD_FAB2_LIB.BASEBOARD_FAB2(SCH_1):TP_CPU0_UPI2_RSVD_DK19     I3 @BASEBOARD_FAB2_LIB.BASEBOARD_FAB2(SCH_1):PAGE35
  CF11 TP_CPU0_UPI2_RSVD_DJ20 @BASEBOARD_FAB2_LIB.BASEBOARD_FAB2(SCH_1):TP_CPU0_UPI2_RSVD_DJ20     I3 @BASEBOARD_FAB2_LIB.BASEBOARD_FAB2(SCH_1):PAGE35
  CG12 TP_CPU0_UPI2_RSVD_DJ18 @BASEBOARD_FAB2_LIB.BASEBOARD_FAB2(SCH_1):TP_CPU0_UPI2_RSVD_DJ18     I3 @BASEBOARD_FAB2_LIB.BASEBOARD_FAB2(SCH_1):PAGE35
  CH13 TP_CPU0_UPI2_RSVD_DH17 @BASEBOARD_FAB2_LIB.BASEBOARD_FAB2(SCH_1):TP_CPU0_UPI2_RSVD_DH17     I3 @BASEBOARD_FAB2_LIB.BASEBOARD_FAB2(SCH_1):PAGE35
  CK13 TP_CPU0_UPI2_RSVD_DF17 @BASEBOARD_FAB2_LIB.BASEBOARD_FAB2(SCH_1):TP_CPU0_UPI2_RSVD_DF17     I3 @BASEBOARD_FAB2_LIB.BASEBOARD_FAB2(SCH_1):PAGE35
  CR14 TP_CPU0_UPI2_RSVD_DE16 @BASEBOARD_FAB2_LIB.BASEBOARD_FAB2(SCH_1):TP_CPU0_UPI2_RSVD_DE16     I3 @BASEBOARD_FAB2_LIB.BASEBOARD_FAB2(SCH_1):PAGE35
  CV13 TP_CPU0_UPI2_RSVD_DD15 @BASEBOARD_FAB2_LIB.BASEBOARD_FAB2(SCH_1):TP_CPU0_UPI2_RSVD_DD15     I3 @BASEBOARD_FAB2_LIB.BASEBOARD_FAB2(SCH_1):PAGE35
  CW16 TP_CPU0_UPI2_RSVD_DB15 @BASEBOARD_FAB2_LIB.BASEBOARD_FAB2(SCH_1):TP_CPU0_UPI2_RSVD_DB15     I3 @BASEBOARD_FAB2_LIB.BASEBOARD_FAB2(SCH_1):PAGE35
  DB15 TP_CPU0_UPI2_RSVD_CW16 @BASEBOARD_FAB2_LIB.BASEBOARD_FAB2(SCH_1):TP_CPU0_UPI2_RSVD_CW16     I3 @BASEBOARD_FAB2_LIB.BASEBOARD_FAB2(SCH_1):PAGE35
  DD15 TP_CPU0_UPI2_RSVD_CV13 @BASEBOARD_FAB2_LIB.BASEBOARD_FAB2(SCH_1):TP_CPU0_UPI2_RSVD_CV13     I3 @BASEBOARD_FAB2_LIB.BASEBOARD_FAB2(SCH_1):PAGE35
  DE16 TP_CPU0_UPI2_RSVD_CR14 @BASEBOARD_FAB2_LIB.BASEBOARD_FAB2(SCH_1):TP_CPU0_UPI2_RSVD_CR14     I3 @BASEBOARD_FAB2_LIB.BASEBOARD_FAB2(SCH_1):PAGE35
  DF17 TP_CPU0_UPI2_RSVD_CK13 @BASEBOARD_FAB2_LIB.BASEBOARD_FAB2(SCH_1):TP_CPU0_UPI2_RSVD_CK13     I3 @BASEBOARD_FAB2_LIB.BASEBOARD_FAB2(SCH_1):PAGE35
  DH17 TP_CPU0_UPI2_RSVD_CH13 @BASEBOARD_FAB2_LIB.BASEBOARD_FAB2(SCH_1):TP_CPU0_UPI2_RSVD_CH13     I3 @BASEBOARD_FAB2_LIB.BASEBOARD_FAB2(SCH_1):PAGE35
  DJ18 TP_CPU0_UPI2_RSVD_CG12 @BASEBOARD_FAB2_LIB.BASEBOARD_FAB2(SCH_1):TP_CPU0_UPI2_RSVD_CG12     I3 @BASEBOARD_FAB2_LIB.BASEBOARD_FAB2(SCH_1):PAGE35
  DJ20 TP_CPU0_UPI2_RSVD_CF11 @BASEBOARD_FAB2_LIB.BASEBOARD_FAB2(SCH_1):TP_CPU0_UPI2_RSVD_CF11     I3 @BASEBOARD_FAB2_LIB.BASEBOARD_FAB2(SCH_1):PAGE35
  DK19 TP_CPU0_UPI2_RSVD_CD11 @BASEBOARD_FAB2_LIB.BASEBOARD_FAB2(SCH_1):TP_CPU0_UPI2_RSVD_CD11     I3 @BASEBOARD_FAB2_LIB.BASEBOARD_FAB2(SCH_1):PAGE35
  DN20 TP_CPU0_UPI2_RSVD_CB11 @BASEBOARD_FAB2_LIB.BASEBOARD_FAB2(SCH_1):TP_CPU0_UPI2_RSVD_CB11     I3 @BASEBOARD_FAB2_LIB.BASEBOARD_FAB2(SCH_1):PAGE35
  DP21 TP_CPU0_UPI2_RSVD_CA12 @BASEBOARD_FAB2_LIB.BASEBOARD_FAB2(SCH_1):TP_CPU0_UPI2_RSVD_CA12     I3 @BASEBOARD_FAB2_LIB.BASEBOARD_FAB2(SCH_1):PAGE35
  AY83 TP_CPU0_RSVD_255 @BASEBOARD_FAB2_LIB.BASEBOARD_FAB2(SCH_1):TP_CPU0_RSVD_255    I15 @BASEBOARD_FAB2_LIB.BASEBOARD_FAB2(SCH_1):PAGE36
  BA78 TP_CPU0_RSVD_171 @BASEBOARD_FAB2_LIB.BASEBOARD_FAB2(SCH_1):TP_CPU0_RSVD_171    I15 @BASEBOARD_FAB2_LIB.BASEBOARD_FAB2(SCH_1):PAGE36
  BA82 TP_CPU0_RSVD_170 @BASEBOARD_FAB2_LIB.BASEBOARD_FAB2(SCH_1):TP_CPU0_RSVD_170    I15 @BASEBOARD_FAB2_LIB.BASEBOARD_FAB2(SCH_1):PAGE36
  BB13 TP_CPU0_RSVD_169 @BASEBOARD_FAB2_LIB.BASEBOARD_FAB2(SCH_1):TP_CPU0_RSVD_169    I15 @BASEBOARD_FAB2_LIB.BASEBOARD_FAB2(SCH_1):PAGE36
  BB15 TP_CPU0_RSVD_168 @BASEBOARD_FAB2_LIB.BASEBOARD_FAB2(SCH_1):TP_CPU0_RSVD_168    I15 @BASEBOARD_FAB2_LIB.BASEBOARD_FAB2(SCH_1):PAGE36
  BB17 TP_CPU0_RSVD_167 @BASEBOARD_FAB2_LIB.BASEBOARD_FAB2(SCH_1):TP_CPU0_RSVD_167    I15 @BASEBOARD_FAB2_LIB.BASEBOARD_FAB2(SCH_1):PAGE36
  BB21 TP_CPU0_RSVD_166 @BASEBOARD_FAB2_LIB.BASEBOARD_FAB2(SCH_1):TP_CPU0_RSVD_166    I15 @BASEBOARD_FAB2_LIB.BASEBOARD_FAB2(SCH_1):PAGE36
  BB25 CLK_100M_CPU0_RC_REFCLK1_DN @BASEBOARD_FAB2_LIB.BASEBOARD_FAB2(SCH_1):CLK_100M_CPU0_RC_REFCLK1_DN    I15 @BASEBOARD_FAB2_LIB.BASEBOARD_FAB2(SCH_1):PAGE36
  BB65 TP_CPU0_RSVD_164 @BASEBOARD_FAB2_LIB.BASEBOARD_FAB2(SCH_1):TP_CPU0_RSVD_164    I15 @BASEBOARD_FAB2_LIB.BASEBOARD_FAB2(SCH_1):PAGE36
  BB67 TP_CPU0_RSVD_163 @BASEBOARD_FAB2_LIB.BASEBOARD_FAB2(SCH_1):TP_CPU0_RSVD_163    I15 @BASEBOARD_FAB2_LIB.BASEBOARD_FAB2(SCH_1):PAGE36
  BC14 TP_CPU0_RSVD_162 @BASEBOARD_FAB2_LIB.BASEBOARD_FAB2(SCH_1):TP_CPU0_RSVD_162    I15 @BASEBOARD_FAB2_LIB.BASEBOARD_FAB2(SCH_1):PAGE36
  BC18 TP_CPU0_RSVD_161 @BASEBOARD_FAB2_LIB.BASEBOARD_FAB2(SCH_1):TP_CPU0_RSVD_161    I15 @BASEBOARD_FAB2_LIB.BASEBOARD_FAB2(SCH_1):PAGE36
  BC20 TP_CPU0_RSVD_160 @BASEBOARD_FAB2_LIB.BASEBOARD_FAB2(SCH_1):TP_CPU0_RSVD_160    I15 @BASEBOARD_FAB2_LIB.BASEBOARD_FAB2(SCH_1):PAGE36
  BC22 TP_CPU0_RSVD_159 @BASEBOARD_FAB2_LIB.BASEBOARD_FAB2(SCH_1):TP_CPU0_RSVD_159    I15 @BASEBOARD_FAB2_LIB.BASEBOARD_FAB2(SCH_1):PAGE36
  BC64 TP_CPU0_RSVD_158 @BASEBOARD_FAB2_LIB.BASEBOARD_FAB2(SCH_1):TP_CPU0_RSVD_158    I15 @BASEBOARD_FAB2_LIB.BASEBOARD_FAB2(SCH_1):PAGE36
  BC66 TP_CPU0_RSVD_157 @BASEBOARD_FAB2_LIB.BASEBOARD_FAB2(SCH_1):TP_CPU0_RSVD_157    I15 @BASEBOARD_FAB2_LIB.BASEBOARD_FAB2(SCH_1):PAGE36
  BC68 TP_CPU0_RSVD_156 @BASEBOARD_FAB2_LIB.BASEBOARD_FAB2(SCH_1):TP_CPU0_RSVD_156    I15 @BASEBOARD_FAB2_LIB.BASEBOARD_FAB2(SCH_1):PAGE36
  BD17 TP_CPU0_RSVD_155 @BASEBOARD_FAB2_LIB.BASEBOARD_FAB2(SCH_1):TP_CPU0_RSVD_155    I15 @BASEBOARD_FAB2_LIB.BASEBOARD_FAB2(SCH_1):PAGE36
  BD19 TP_CPU0_RSVD_154 @BASEBOARD_FAB2_LIB.BASEBOARD_FAB2(SCH_1):TP_CPU0_RSVD_154    I15 @BASEBOARD_FAB2_LIB.BASEBOARD_FAB2(SCH_1):PAGE36
  BD25 CLK_100M_CPU0_RC_REFCLK1_DP @BASEBOARD_FAB2_LIB.BASEBOARD_FAB2(SCH_1):CLK_100M_CPU0_RC_REFCLK1_DP    I15 @BASEBOARD_FAB2_LIB.BASEBOARD_FAB2(SCH_1):PAGE36
  BD65 TP_CPU0_RSVD_152 @BASEBOARD_FAB2_LIB.BASEBOARD_FAB2(SCH_1):TP_CPU0_RSVD_152    I15 @BASEBOARD_FAB2_LIB.BASEBOARD_FAB2(SCH_1):PAGE36
  BD67 TP_CPU0_RSVD_151 @BASEBOARD_FAB2_LIB.BASEBOARD_FAB2(SCH_1):TP_CPU0_RSVD_151    I15 @BASEBOARD_FAB2_LIB.BASEBOARD_FAB2(SCH_1):PAGE36
  BD69 TP_CPU0_RSVD_150 @BASEBOARD_FAB2_LIB.BASEBOARD_FAB2(SCH_1):TP_CPU0_RSVD_150    I15 @BASEBOARD_FAB2_LIB.BASEBOARD_FAB2(SCH_1):PAGE36
  BE18 TP_CPU0_RSVD_149 @BASEBOARD_FAB2_LIB.BASEBOARD_FAB2(SCH_1):TP_CPU0_RSVD_149    I15 @BASEBOARD_FAB2_LIB.BASEBOARD_FAB2(SCH_1):PAGE36
  BE20 TP_CPU0_RSVD_148 @BASEBOARD_FAB2_LIB.BASEBOARD_FAB2(SCH_1):TP_CPU0_RSVD_148    I15 @BASEBOARD_FAB2_LIB.BASEBOARD_FAB2(SCH_1):PAGE36
  BE22 TP_CPU0_RSVD_147 @BASEBOARD_FAB2_LIB.BASEBOARD_FAB2(SCH_1):TP_CPU0_RSVD_147    I15 @BASEBOARD_FAB2_LIB.BASEBOARD_FAB2(SCH_1):PAGE36
  BF21 TP_CPU0_RSVD_146 @BASEBOARD_FAB2_LIB.BASEBOARD_FAB2(SCH_1):TP_CPU0_RSVD_146    I15 @BASEBOARD_FAB2_LIB.BASEBOARD_FAB2(SCH_1):PAGE36
  BG18 TP_CPU0_RSVD_145 @BASEBOARD_FAB2_LIB.BASEBOARD_FAB2(SCH_1):TP_CPU0_RSVD_145    I15 @BASEBOARD_FAB2_LIB.BASEBOARD_FAB2(SCH_1):PAGE36
  BG20 TP_CPU0_RSVD_144 @BASEBOARD_FAB2_LIB.BASEBOARD_FAB2(SCH_1):TP_CPU0_RSVD_144    I15 @BASEBOARD_FAB2_LIB.BASEBOARD_FAB2(SCH_1):PAGE36
  BH19 PVCCMCP_CPU0 @BASEBOARD_FAB2_LIB.BASEBOARD_FAB2(SCH_1):PVCCMCP_CPU0    I15 @BASEBOARD_FAB2_LIB.BASEBOARD_FAB2(SCH_1):PAGE36
  BJ16 PVCCMCP_CPU0 @BASEBOARD_FAB2_LIB.BASEBOARD_FAB2(SCH_1):PVCCMCP_CPU0    I15 @BASEBOARD_FAB2_LIB.BASEBOARD_FAB2(SCH_1):PAGE36
  BJ18 PVCCMCP_CPU0 @BASEBOARD_FAB2_LIB.BASEBOARD_FAB2(SCH_1):PVCCMCP_CPU0    I15 @BASEBOARD_FAB2_LIB.BASEBOARD_FAB2(SCH_1):PAGE36
  BJ20 PVCCMCP_CPU0 @BASEBOARD_FAB2_LIB.BASEBOARD_FAB2(SCH_1):PVCCMCP_CPU0    I15 @BASEBOARD_FAB2_LIB.BASEBOARD_FAB2(SCH_1):PAGE36
  BK17 PVCCMCP_CPU0 @BASEBOARD_FAB2_LIB.BASEBOARD_FAB2(SCH_1):PVCCMCP_CPU0    I15 @BASEBOARD_FAB2_LIB.BASEBOARD_FAB2(SCH_1):PAGE36
  BL18 PVCCIOMCP_CPU0 @BASEBOARD_FAB2_LIB.BASEBOARD_FAB2(SCH_1):PVCCIOMCP_CPU0    I15 @BASEBOARD_FAB2_LIB.BASEBOARD_FAB2(SCH_1):PAGE36
  BL20 PVCCMCP_CPU0 @BASEBOARD_FAB2_LIB.BASEBOARD_FAB2(SCH_1):PVCCMCP_CPU0    I15 @BASEBOARD_FAB2_LIB.BASEBOARD_FAB2(SCH_1):PAGE36
  BM17 PVCCIOMCP_CPU0 @BASEBOARD_FAB2_LIB.BASEBOARD_FAB2(SCH_1):PVCCIOMCP_CPU0    I15 @BASEBOARD_FAB2_LIB.BASEBOARD_FAB2(SCH_1):PAGE36
  BM19 PVCCMCP_CPU0 @BASEBOARD_FAB2_LIB.BASEBOARD_FAB2(SCH_1):PVCCMCP_CPU0    I15 @BASEBOARD_FAB2_LIB.BASEBOARD_FAB2(SCH_1):PAGE36
  BN18 PVCCIOMCP_CPU0 @BASEBOARD_FAB2_LIB.BASEBOARD_FAB2(SCH_1):PVCCIOMCP_CPU0    I15 @BASEBOARD_FAB2_LIB.BASEBOARD_FAB2(SCH_1):PAGE36
  BP17 PVCCIOMCP_CPU0 @BASEBOARD_FAB2_LIB.BASEBOARD_FAB2(SCH_1):PVCCIOMCP_CPU0    I15 @BASEBOARD_FAB2_LIB.BASEBOARD_FAB2(SCH_1):PAGE36
  BP21 PVCCMCP_CPU0 @BASEBOARD_FAB2_LIB.BASEBOARD_FAB2(SCH_1):PVCCMCP_CPU0    I15 @BASEBOARD_FAB2_LIB.BASEBOARD_FAB2(SCH_1):PAGE36
  BR22 PVCCMCP_CPU0 @BASEBOARD_FAB2_LIB.BASEBOARD_FAB2(SCH_1):PVCCMCP_CPU0    I15 @BASEBOARD_FAB2_LIB.BASEBOARD_FAB2(SCH_1):PAGE36
  BR24 PVCCMCP_CPU0 @BASEBOARD_FAB2_LIB.BASEBOARD_FAB2(SCH_1):PVCCMCP_CPU0    I15 @BASEBOARD_FAB2_LIB.BASEBOARD_FAB2(SCH_1):PAGE36
  BU18 PVCCIOMCP_CPU0 @BASEBOARD_FAB2_LIB.BASEBOARD_FAB2(SCH_1):PVCCIOMCP_CPU0    I15 @BASEBOARD_FAB2_LIB.BASEBOARD_FAB2(SCH_1):PAGE36
  BU20 PVCCMCP_CPU0 @BASEBOARD_FAB2_LIB.BASEBOARD_FAB2(SCH_1):PVCCMCP_CPU0    I15 @BASEBOARD_FAB2_LIB.BASEBOARD_FAB2(SCH_1):PAGE36
  BU22 PVCCMCP_CPU0 @BASEBOARD_FAB2_LIB.BASEBOARD_FAB2(SCH_1):PVCCMCP_CPU0    I15 @BASEBOARD_FAB2_LIB.BASEBOARD_FAB2(SCH_1):PAGE36
  BV19 PVCCMCP_CPU0 @BASEBOARD_FAB2_LIB.BASEBOARD_FAB2(SCH_1):PVCCMCP_CPU0    I15 @BASEBOARD_FAB2_LIB.BASEBOARD_FAB2(SCH_1):PAGE36
  BV21 PVCCMCP_CPU0 @BASEBOARD_FAB2_LIB.BASEBOARD_FAB2(SCH_1):PVCCMCP_CPU0    I15 @BASEBOARD_FAB2_LIB.BASEBOARD_FAB2(SCH_1):PAGE36
  BV23 TP_CPU0_RSVD_124 @BASEBOARD_FAB2_LIB.BASEBOARD_FAB2(SCH_1):TP_CPU0_RSVD_124    I15 @BASEBOARD_FAB2_LIB.BASEBOARD_FAB2(SCH_1):PAGE36
  BW10 TP_CPU0_RSVD_123 @BASEBOARD_FAB2_LIB.BASEBOARD_FAB2(SCH_1):TP_CPU0_RSVD_123    I15 @BASEBOARD_FAB2_LIB.BASEBOARD_FAB2(SCH_1):PAGE36
  BW20 PVCCMCP_CPU0 @BASEBOARD_FAB2_LIB.BASEBOARD_FAB2(SCH_1):PVCCMCP_CPU0    I15 @BASEBOARD_FAB2_LIB.BASEBOARD_FAB2(SCH_1):PAGE36
  BW22 TP_CPU0_RSVD_121 @BASEBOARD_FAB2_LIB.BASEBOARD_FAB2(SCH_1):TP_CPU0_RSVD_121    I15 @BASEBOARD_FAB2_LIB.BASEBOARD_FAB2(SCH_1):PAGE36
  BY19 PVCCMCP_CPU0 @BASEBOARD_FAB2_LIB.BASEBOARD_FAB2(SCH_1):PVCCMCP_CPU0    I15 @BASEBOARD_FAB2_LIB.BASEBOARD_FAB2(SCH_1):PAGE36
  BY25 TP_CPU0_RSVD_119 @BASEBOARD_FAB2_LIB.BASEBOARD_FAB2(SCH_1):TP_CPU0_RSVD_119    I15 @BASEBOARD_FAB2_LIB.BASEBOARD_FAB2(SCH_1):PAGE36
  CA22 PVCCMCP_CPU0 @BASEBOARD_FAB2_LIB.BASEBOARD_FAB2(SCH_1):PVCCMCP_CPU0    I15 @BASEBOARD_FAB2_LIB.BASEBOARD_FAB2(SCH_1):PAGE36
  CA24 TP_CPU0_RSVD_117 @BASEBOARD_FAB2_LIB.BASEBOARD_FAB2(SCH_1):TP_CPU0_RSVD_117    I15 @BASEBOARD_FAB2_LIB.BASEBOARD_FAB2(SCH_1):PAGE36
  CB19 PVCCMCP_CPU0 @BASEBOARD_FAB2_LIB.BASEBOARD_FAB2(SCH_1):PVCCMCP_CPU0    I15 @BASEBOARD_FAB2_LIB.BASEBOARD_FAB2(SCH_1):PAGE36
  CB21 PVCCMCP_CPU0 @BASEBOARD_FAB2_LIB.BASEBOARD_FAB2(SCH_1):PVCCMCP_CPU0    I15 @BASEBOARD_FAB2_LIB.BASEBOARD_FAB2(SCH_1):PAGE36
  CB25 TP_CPU0_RSVD_114 @BASEBOARD_FAB2_LIB.BASEBOARD_FAB2(SCH_1):TP_CPU0_RSVD_114    I15 @BASEBOARD_FAB2_LIB.BASEBOARD_FAB2(SCH_1):PAGE36
   CB5 TP_CPU0_RSVD_113 @BASEBOARD_FAB2_LIB.BASEBOARD_FAB2(SCH_1):TP_CPU0_RSVD_113    I15 @BASEBOARD_FAB2_LIB.BASEBOARD_FAB2(SCH_1):PAGE36
  CC20 PVCCMCP_CPU0 @BASEBOARD_FAB2_LIB.BASEBOARD_FAB2(SCH_1):PVCCMCP_CPU0    I15 @BASEBOARD_FAB2_LIB.BASEBOARD_FAB2(SCH_1):PAGE36
   CC6 TP_CPU0_RSVD_111 @BASEBOARD_FAB2_LIB.BASEBOARD_FAB2(SCH_1):TP_CPU0_RSVD_111    I15 @BASEBOARD_FAB2_LIB.BASEBOARD_FAB2(SCH_1):PAGE36
  CD19 PVCCMCP_CPU0 @BASEBOARD_FAB2_LIB.BASEBOARD_FAB2(SCH_1):PVCCMCP_CPU0    I15 @BASEBOARD_FAB2_LIB.BASEBOARD_FAB2(SCH_1):PAGE36
  CD21 PVCCMCP_CPU0 @BASEBOARD_FAB2_LIB.BASEBOARD_FAB2(SCH_1):PVCCMCP_CPU0    I15 @BASEBOARD_FAB2_LIB.BASEBOARD_FAB2(SCH_1):PAGE36
  CD25 TP_CPU0_RSVD_108 @BASEBOARD_FAB2_LIB.BASEBOARD_FAB2(SCH_1):TP_CPU0_RSVD_108    I15 @BASEBOARD_FAB2_LIB.BASEBOARD_FAB2(SCH_1):PAGE36
  CE22 PVCCMCP_CPU0 @BASEBOARD_FAB2_LIB.BASEBOARD_FAB2(SCH_1):PVCCMCP_CPU0    I15 @BASEBOARD_FAB2_LIB.BASEBOARD_FAB2(SCH_1):PAGE36
  CE78 TP_CPU0_RSVD_106 @BASEBOARD_FAB2_LIB.BASEBOARD_FAB2(SCH_1):TP_CPU0_RSVD_106    I15 @BASEBOARD_FAB2_LIB.BASEBOARD_FAB2(SCH_1):PAGE36
  CE80 TP_CPU0_RSVD_105 @BASEBOARD_FAB2_LIB.BASEBOARD_FAB2(SCH_1):TP_CPU0_RSVD_105    I15 @BASEBOARD_FAB2_LIB.BASEBOARD_FAB2(SCH_1):PAGE36
  CF19 PVCCMCP_CPU0 @BASEBOARD_FAB2_LIB.BASEBOARD_FAB2(SCH_1):PVCCMCP_CPU0    I15 @BASEBOARD_FAB2_LIB.BASEBOARD_FAB2(SCH_1):PAGE36
  CF21 PVCCMCP_CPU0 @BASEBOARD_FAB2_LIB.BASEBOARD_FAB2(SCH_1):PVCCMCP_CPU0    I15 @BASEBOARD_FAB2_LIB.BASEBOARD_FAB2(SCH_1):PAGE36
  CF23 PVCCMCP_CPU0 @BASEBOARD_FAB2_LIB.BASEBOARD_FAB2(SCH_1):PVCCMCP_CPU0    I15 @BASEBOARD_FAB2_LIB.BASEBOARD_FAB2(SCH_1):PAGE36
  CF79 TP_CPU0_RSVD_101 @BASEBOARD_FAB2_LIB.BASEBOARD_FAB2(SCH_1):TP_CPU0_RSVD_101    I15 @BASEBOARD_FAB2_LIB.BASEBOARD_FAB2(SCH_1):PAGE36
  CF81 TP_CPU0_RSVD_100 @BASEBOARD_FAB2_LIB.BASEBOARD_FAB2(SCH_1):TP_CPU0_RSVD_100    I15 @BASEBOARD_FAB2_LIB.BASEBOARD_FAB2(SCH_1):PAGE36
  CG10 TP_CPU0_RSVD_99 @BASEBOARD_FAB2_LIB.BASEBOARD_FAB2(SCH_1):TP_CPU0_RSVD_99    I15 @BASEBOARD_FAB2_LIB.BASEBOARD_FAB2(SCH_1):PAGE36
  CG20 PVCCMCP_CPU0 @BASEBOARD_FAB2_LIB.BASEBOARD_FAB2(SCH_1):PVCCMCP_CPU0    I15 @BASEBOARD_FAB2_LIB.BASEBOARD_FAB2(SCH_1):PAGE36
  CG24 TP_CPU0_RSVD_97 @BASEBOARD_FAB2_LIB.BASEBOARD_FAB2(SCH_1):TP_CPU0_RSVD_97    I15 @BASEBOARD_FAB2_LIB.BASEBOARD_FAB2(SCH_1):PAGE36
  CG26 PVCCMCP_CPU0 @BASEBOARD_FAB2_LIB.BASEBOARD_FAB2(SCH_1):PVCCMCP_CPU0    I15 @BASEBOARD_FAB2_LIB.BASEBOARD_FAB2(SCH_1):PAGE36
  CG78 TP_CPU0_RSVD_95 @BASEBOARD_FAB2_LIB.BASEBOARD_FAB2(SCH_1):TP_CPU0_RSVD_95    I15 @BASEBOARD_FAB2_LIB.BASEBOARD_FAB2(SCH_1):PAGE36
  CG82 TP_CPU0_RSVD_94 @BASEBOARD_FAB2_LIB.BASEBOARD_FAB2(SCH_1):TP_CPU0_RSVD_94    I15 @BASEBOARD_FAB2_LIB.BASEBOARD_FAB2(SCH_1):PAGE36
  CH21 PVCCMCP_CPU0 @BASEBOARD_FAB2_LIB.BASEBOARD_FAB2(SCH_1):PVCCMCP_CPU0    I15 @BASEBOARD_FAB2_LIB.BASEBOARD_FAB2(SCH_1):PAGE36
  CH23 PVCCMCP_CPU0 @BASEBOARD_FAB2_LIB.BASEBOARD_FAB2(SCH_1):PVCCMCP_CPU0    I15 @BASEBOARD_FAB2_LIB.BASEBOARD_FAB2(SCH_1):PAGE36
  CH25 TP_CPU0_RSVD_91 @BASEBOARD_FAB2_LIB.BASEBOARD_FAB2(SCH_1):TP_CPU0_RSVD_91    I16 @BASEBOARD_FAB2_LIB.BASEBOARD_FAB2(SCH_1):PAGE36
  CH77 TP_CPU0_RSVD_90 @BASEBOARD_FAB2_LIB.BASEBOARD_FAB2(SCH_1):TP_CPU0_RSVD_90    I16 @BASEBOARD_FAB2_LIB.BASEBOARD_FAB2(SCH_1):PAGE36
  CJ20 PVCCMCP_CPU0 @BASEBOARD_FAB2_LIB.BASEBOARD_FAB2(SCH_1):PVCCMCP_CPU0    I16 @BASEBOARD_FAB2_LIB.BASEBOARD_FAB2(SCH_1):PAGE36
  CJ22 PVCCMCP_CPU0 @BASEBOARD_FAB2_LIB.BASEBOARD_FAB2(SCH_1):PVCCMCP_CPU0    I16 @BASEBOARD_FAB2_LIB.BASEBOARD_FAB2(SCH_1):PAGE36
  CJ24 PVCCMCP_CPU0 @BASEBOARD_FAB2_LIB.BASEBOARD_FAB2(SCH_1):PVCCMCP_CPU0    I16 @BASEBOARD_FAB2_LIB.BASEBOARD_FAB2(SCH_1):PAGE36
  CJ26 PVCCMCP_CPU0 @BASEBOARD_FAB2_LIB.BASEBOARD_FAB2(SCH_1):PVCCMCP_CPU0    I16 @BASEBOARD_FAB2_LIB.BASEBOARD_FAB2(SCH_1):PAGE36
  CK19 TP_CPU0_RSVD_85 @BASEBOARD_FAB2_LIB.BASEBOARD_FAB2(SCH_1):TP_CPU0_RSVD_85    I16 @BASEBOARD_FAB2_LIB.BASEBOARD_FAB2(SCH_1):PAGE36
  CK23 PVCCMCP_CPU0 @BASEBOARD_FAB2_LIB.BASEBOARD_FAB2(SCH_1):PVCCMCP_CPU0    I16 @BASEBOARD_FAB2_LIB.BASEBOARD_FAB2(SCH_1):PAGE36
  CK25 PVCCMCP_CPU0 @BASEBOARD_FAB2_LIB.BASEBOARD_FAB2(SCH_1):PVCCMCP_CPU0    I16 @BASEBOARD_FAB2_LIB.BASEBOARD_FAB2(SCH_1):PAGE36
  CK77 TP_CPU0_RSVD_82 @BASEBOARD_FAB2_LIB.BASEBOARD_FAB2(SCH_1):TP_CPU0_RSVD_82    I16 @BASEBOARD_FAB2_LIB.BASEBOARD_FAB2(SCH_1):PAGE36
  CL24 PVCCMCP_CPU0 @BASEBOARD_FAB2_LIB.BASEBOARD_FAB2(SCH_1):PVCCMCP_CPU0    I16 @BASEBOARD_FAB2_LIB.BASEBOARD_FAB2(SCH_1):PAGE36
  AW22 TP_CPU0_TEST_10 @BASEBOARD_FAB2_LIB.BASEBOARD_FAB2(SCH_1):TP_CPU0_TEST_10    I16 @BASEBOARD_FAB2_LIB.BASEBOARD_FAB2(SCH_1):PAGE36
  AR16 TP_CPU0_TEST_6 @BASEBOARD_FAB2_LIB.BASEBOARD_FAB2(SCH_1):TP_CPU0_TEST_6    I16 @BASEBOARD_FAB2_LIB.BASEBOARD_FAB2(SCH_1):PAGE36
  AU18 TP_CPU0_TEST_7 @BASEBOARD_FAB2_LIB.BASEBOARD_FAB2(SCH_1):TP_CPU0_TEST_7    I16 @BASEBOARD_FAB2_LIB.BASEBOARD_FAB2(SCH_1):PAGE36
  AW16 TP_CPU0_TEST_8 @BASEBOARD_FAB2_LIB.BASEBOARD_FAB2(SCH_1):TP_CPU0_TEST_8    I16 @BASEBOARD_FAB2_LIB.BASEBOARD_FAB2(SCH_1):PAGE36
  AW20 TP_CPU0_TEST_9 @BASEBOARD_FAB2_LIB.BASEBOARD_FAB2(SCH_1):TP_CPU0_TEST_9    I16 @BASEBOARD_FAB2_LIB.BASEBOARD_FAB2(SCH_1):PAGE36
  AF43 PVCCIN_CPU0 @BASEBOARD_FAB2_LIB.BASEBOARD_FAB2(SCH_1):PVCCIN_CPU0   I310 @BASEBOARD_FAB2_LIB.BASEBOARD_FAB2(SCH_1):PAGE37
  AG38 PVCCIN_CPU0 @BASEBOARD_FAB2_LIB.BASEBOARD_FAB2(SCH_1):PVCCIN_CPU0   I310 @BASEBOARD_FAB2_LIB.BASEBOARD_FAB2(SCH_1):PAGE37
  AG40 PVCCIN_CPU0 @BASEBOARD_FAB2_LIB.BASEBOARD_FAB2(SCH_1):PVCCIN_CPU0   I310 @BASEBOARD_FAB2_LIB.BASEBOARD_FAB2(SCH_1):PAGE37
  AG42 PVCCIN_CPU0 @BASEBOARD_FAB2_LIB.BASEBOARD_FAB2(SCH_1):PVCCIN_CPU0   I310 @BASEBOARD_FAB2_LIB.BASEBOARD_FAB2(SCH_1):PAGE37
  AH37 PVCCIN_CPU0 @BASEBOARD_FAB2_LIB.BASEBOARD_FAB2(SCH_1):PVCCIN_CPU0   I310 @BASEBOARD_FAB2_LIB.BASEBOARD_FAB2(SCH_1):PAGE37
  AH39 PVCCIN_CPU0 @BASEBOARD_FAB2_LIB.BASEBOARD_FAB2(SCH_1):PVCCIN_CPU0   I310 @BASEBOARD_FAB2_LIB.BASEBOARD_FAB2(SCH_1):PAGE37
  AH41 PVCCIN_CPU0 @BASEBOARD_FAB2_LIB.BASEBOARD_FAB2(SCH_1):PVCCIN_CPU0   I310 @BASEBOARD_FAB2_LIB.BASEBOARD_FAB2(SCH_1):PAGE37
  AJ36 PVCCIN_CPU0 @BASEBOARD_FAB2_LIB.BASEBOARD_FAB2(SCH_1):PVCCIN_CPU0   I310 @BASEBOARD_FAB2_LIB.BASEBOARD_FAB2(SCH_1):PAGE37
  AK35 PVCCIN_CPU0 @BASEBOARD_FAB2_LIB.BASEBOARD_FAB2(SCH_1):PVCCIN_CPU0   I310 @BASEBOARD_FAB2_LIB.BASEBOARD_FAB2(SCH_1):PAGE37
  AK45 PVCCIN_CPU0 @BASEBOARD_FAB2_LIB.BASEBOARD_FAB2(SCH_1):PVCCIN_CPU0   I310 @BASEBOARD_FAB2_LIB.BASEBOARD_FAB2(SCH_1):PAGE37
  AK47 PVCCIN_CPU0 @BASEBOARD_FAB2_LIB.BASEBOARD_FAB2(SCH_1):PVCCIN_CPU0   I310 @BASEBOARD_FAB2_LIB.BASEBOARD_FAB2(SCH_1):PAGE37
  AK49 PVCCIN_CPU0 @BASEBOARD_FAB2_LIB.BASEBOARD_FAB2(SCH_1):PVCCIN_CPU0   I310 @BASEBOARD_FAB2_LIB.BASEBOARD_FAB2(SCH_1):PAGE37
  AK51 PVCCIN_CPU0 @BASEBOARD_FAB2_LIB.BASEBOARD_FAB2(SCH_1):PVCCIN_CPU0   I310 @BASEBOARD_FAB2_LIB.BASEBOARD_FAB2(SCH_1):PAGE37
  AK53 PVCCIN_CPU0 @BASEBOARD_FAB2_LIB.BASEBOARD_FAB2(SCH_1):PVCCIN_CPU0   I310 @BASEBOARD_FAB2_LIB.BASEBOARD_FAB2(SCH_1):PAGE37
  AL34 PVCCIN_CPU0 @BASEBOARD_FAB2_LIB.BASEBOARD_FAB2(SCH_1):PVCCIN_CPU0   I310 @BASEBOARD_FAB2_LIB.BASEBOARD_FAB2(SCH_1):PAGE37
  AL46 PVCCIN_CPU0 @BASEBOARD_FAB2_LIB.BASEBOARD_FAB2(SCH_1):PVCCIN_CPU0   I310 @BASEBOARD_FAB2_LIB.BASEBOARD_FAB2(SCH_1):PAGE37
  AL48 PVCCIN_CPU0 @BASEBOARD_FAB2_LIB.BASEBOARD_FAB2(SCH_1):PVCCIN_CPU0   I310 @BASEBOARD_FAB2_LIB.BASEBOARD_FAB2(SCH_1):PAGE37
  AL50 PVCCIN_CPU0 @BASEBOARD_FAB2_LIB.BASEBOARD_FAB2(SCH_1):PVCCIN_CPU0   I310 @BASEBOARD_FAB2_LIB.BASEBOARD_FAB2(SCH_1):PAGE37
  AL52 PVCCIN_CPU0 @BASEBOARD_FAB2_LIB.BASEBOARD_FAB2(SCH_1):PVCCIN_CPU0   I310 @BASEBOARD_FAB2_LIB.BASEBOARD_FAB2(SCH_1):PAGE37
  AL54 PVCCIN_CPU0 @BASEBOARD_FAB2_LIB.BASEBOARD_FAB2(SCH_1):PVCCIN_CPU0   I310 @BASEBOARD_FAB2_LIB.BASEBOARD_FAB2(SCH_1):PAGE37
  AM33 PVCCIN_CPU0 @BASEBOARD_FAB2_LIB.BASEBOARD_FAB2(SCH_1):PVCCIN_CPU0   I310 @BASEBOARD_FAB2_LIB.BASEBOARD_FAB2(SCH_1):PAGE37
  AM53 PVCCIN_CPU0 @BASEBOARD_FAB2_LIB.BASEBOARD_FAB2(SCH_1):PVCCIN_CPU0   I310 @BASEBOARD_FAB2_LIB.BASEBOARD_FAB2(SCH_1):PAGE37
  AM55 PVCCIN_CPU0 @BASEBOARD_FAB2_LIB.BASEBOARD_FAB2(SCH_1):PVCCIN_CPU0   I310 @BASEBOARD_FAB2_LIB.BASEBOARD_FAB2(SCH_1):PAGE37
  AN32 PVCCIN_CPU0 @BASEBOARD_FAB2_LIB.BASEBOARD_FAB2(SCH_1):PVCCIN_CPU0   I310 @BASEBOARD_FAB2_LIB.BASEBOARD_FAB2(SCH_1):PAGE37
  AN54 PVCCIN_CPU0 @BASEBOARD_FAB2_LIB.BASEBOARD_FAB2(SCH_1):PVCCIN_CPU0   I310 @BASEBOARD_FAB2_LIB.BASEBOARD_FAB2(SCH_1):PAGE37
  AN56 PVCCIN_CPU0 @BASEBOARD_FAB2_LIB.BASEBOARD_FAB2(SCH_1):PVCCIN_CPU0   I310 @BASEBOARD_FAB2_LIB.BASEBOARD_FAB2(SCH_1):PAGE37
  AP55 PVCCIN_CPU0 @BASEBOARD_FAB2_LIB.BASEBOARD_FAB2(SCH_1):PVCCIN_CPU0   I310 @BASEBOARD_FAB2_LIB.BASEBOARD_FAB2(SCH_1):PAGE37
  AP57 PVCCIN_CPU0 @BASEBOARD_FAB2_LIB.BASEBOARD_FAB2(SCH_1):PVCCIN_CPU0   I310 @BASEBOARD_FAB2_LIB.BASEBOARD_FAB2(SCH_1):PAGE37
  AR56 PVCCIN_CPU0 @BASEBOARD_FAB2_LIB.BASEBOARD_FAB2(SCH_1):PVCCIN_CPU0   I310 @BASEBOARD_FAB2_LIB.BASEBOARD_FAB2(SCH_1):PAGE37
  AR58 PVCCIN_CPU0 @BASEBOARD_FAB2_LIB.BASEBOARD_FAB2(SCH_1):PVCCIN_CPU0   I310 @BASEBOARD_FAB2_LIB.BASEBOARD_FAB2(SCH_1):PAGE37
  AT57 PVCCIN_CPU0 @BASEBOARD_FAB2_LIB.BASEBOARD_FAB2(SCH_1):PVCCIN_CPU0   I310 @BASEBOARD_FAB2_LIB.BASEBOARD_FAB2(SCH_1):PAGE37
  AT59 PVCCIN_CPU0 @BASEBOARD_FAB2_LIB.BASEBOARD_FAB2(SCH_1):PVCCIN_CPU0   I310 @BASEBOARD_FAB2_LIB.BASEBOARD_FAB2(SCH_1):PAGE37
  AU58 PVCCIN_CPU0 @BASEBOARD_FAB2_LIB.BASEBOARD_FAB2(SCH_1):PVCCIN_CPU0   I310 @BASEBOARD_FAB2_LIB.BASEBOARD_FAB2(SCH_1):PAGE37
  AU60 PVCCIN_CPU0 @BASEBOARD_FAB2_LIB.BASEBOARD_FAB2(SCH_1):PVCCIN_CPU0   I310 @BASEBOARD_FAB2_LIB.BASEBOARD_FAB2(SCH_1):PAGE37
  AV59 PVCCIN_CPU0 @BASEBOARD_FAB2_LIB.BASEBOARD_FAB2(SCH_1):PVCCIN_CPU0   I310 @BASEBOARD_FAB2_LIB.BASEBOARD_FAB2(SCH_1):PAGE37
  AV61 PVCCIN_CPU0 @BASEBOARD_FAB2_LIB.BASEBOARD_FAB2(SCH_1):PVCCIN_CPU0   I310 @BASEBOARD_FAB2_LIB.BASEBOARD_FAB2(SCH_1):PAGE37
  AW60 PVCCIN_CPU0 @BASEBOARD_FAB2_LIB.BASEBOARD_FAB2(SCH_1):PVCCIN_CPU0   I310 @BASEBOARD_FAB2_LIB.BASEBOARD_FAB2(SCH_1):PAGE37
  AY61 PVCCIN_CPU0 @BASEBOARD_FAB2_LIB.BASEBOARD_FAB2(SCH_1):PVCCIN_CPU0   I310 @BASEBOARD_FAB2_LIB.BASEBOARD_FAB2(SCH_1):PAGE37
  BA60 PVCCIN_CPU0 @BASEBOARD_FAB2_LIB.BASEBOARD_FAB2(SCH_1):PVCCIN_CPU0   I310 @BASEBOARD_FAB2_LIB.BASEBOARD_FAB2(SCH_1):PAGE37
  BB61 PVCCIN_CPU0 @BASEBOARD_FAB2_LIB.BASEBOARD_FAB2(SCH_1):PVCCIN_CPU0   I310 @BASEBOARD_FAB2_LIB.BASEBOARD_FAB2(SCH_1):PAGE37
  BB85 PVCCIN_CPU0 @BASEBOARD_FAB2_LIB.BASEBOARD_FAB2(SCH_1):PVCCIN_CPU0   I310 @BASEBOARD_FAB2_LIB.BASEBOARD_FAB2(SCH_1):PAGE37
  BC60 PVCCIN_CPU0 @BASEBOARD_FAB2_LIB.BASEBOARD_FAB2(SCH_1):PVCCIN_CPU0   I310 @BASEBOARD_FAB2_LIB.BASEBOARD_FAB2(SCH_1):PAGE37
  BC62 PVCCIN_CPU0 @BASEBOARD_FAB2_LIB.BASEBOARD_FAB2(SCH_1):PVCCIN_CPU0   I310 @BASEBOARD_FAB2_LIB.BASEBOARD_FAB2(SCH_1):PAGE37
  BC84 PVCCIN_CPU0 @BASEBOARD_FAB2_LIB.BASEBOARD_FAB2(SCH_1):PVCCIN_CPU0   I310 @BASEBOARD_FAB2_LIB.BASEBOARD_FAB2(SCH_1):PAGE37
  BD61 PVCCIN_CPU0 @BASEBOARD_FAB2_LIB.BASEBOARD_FAB2(SCH_1):PVCCIN_CPU0   I310 @BASEBOARD_FAB2_LIB.BASEBOARD_FAB2(SCH_1):PAGE37
  BD73 PVCCIN_CPU0 @BASEBOARD_FAB2_LIB.BASEBOARD_FAB2(SCH_1):PVCCIN_CPU0   I310 @BASEBOARD_FAB2_LIB.BASEBOARD_FAB2(SCH_1):PAGE37
  BD75 PVCCIN_CPU0 @BASEBOARD_FAB2_LIB.BASEBOARD_FAB2(SCH_1):PVCCIN_CPU0   I310 @BASEBOARD_FAB2_LIB.BASEBOARD_FAB2(SCH_1):PAGE37
  BD77 PVCCIN_CPU0 @BASEBOARD_FAB2_LIB.BASEBOARD_FAB2(SCH_1):PVCCIN_CPU0   I310 @BASEBOARD_FAB2_LIB.BASEBOARD_FAB2(SCH_1):PAGE37
  BD79 PVCCIN_CPU0 @BASEBOARD_FAB2_LIB.BASEBOARD_FAB2(SCH_1):PVCCIN_CPU0   I310 @BASEBOARD_FAB2_LIB.BASEBOARD_FAB2(SCH_1):PAGE37
  BD81 PVCCIN_CPU0 @BASEBOARD_FAB2_LIB.BASEBOARD_FAB2(SCH_1):PVCCIN_CPU0   I310 @BASEBOARD_FAB2_LIB.BASEBOARD_FAB2(SCH_1):PAGE37
  BD83 PVCCIN_CPU0 @BASEBOARD_FAB2_LIB.BASEBOARD_FAB2(SCH_1):PVCCIN_CPU0   I310 @BASEBOARD_FAB2_LIB.BASEBOARD_FAB2(SCH_1):PAGE37
  BD85 PVCCIN_CPU0 @BASEBOARD_FAB2_LIB.BASEBOARD_FAB2(SCH_1):PVCCIN_CPU0   I310 @BASEBOARD_FAB2_LIB.BASEBOARD_FAB2(SCH_1):PAGE37
  BE60 PVCCIN_CPU0 @BASEBOARD_FAB2_LIB.BASEBOARD_FAB2(SCH_1):PVCCIN_CPU0   I310 @BASEBOARD_FAB2_LIB.BASEBOARD_FAB2(SCH_1):PAGE37
  BE62 PVCCIN_CPU0 @BASEBOARD_FAB2_LIB.BASEBOARD_FAB2(SCH_1):PVCCIN_CPU0   I310 @BASEBOARD_FAB2_LIB.BASEBOARD_FAB2(SCH_1):PAGE37
  BE72 PVCCIN_CPU0 @BASEBOARD_FAB2_LIB.BASEBOARD_FAB2(SCH_1):PVCCIN_CPU0   I310 @BASEBOARD_FAB2_LIB.BASEBOARD_FAB2(SCH_1):PAGE37
  BE74 PVCCIN_CPU0 @BASEBOARD_FAB2_LIB.BASEBOARD_FAB2(SCH_1):PVCCIN_CPU0   I310 @BASEBOARD_FAB2_LIB.BASEBOARD_FAB2(SCH_1):PAGE37
  BE76 PVCCIN_CPU0 @BASEBOARD_FAB2_LIB.BASEBOARD_FAB2(SCH_1):PVCCIN_CPU0   I310 @BASEBOARD_FAB2_LIB.BASEBOARD_FAB2(SCH_1):PAGE37
  BE78 PVCCIN_CPU0 @BASEBOARD_FAB2_LIB.BASEBOARD_FAB2(SCH_1):PVCCIN_CPU0   I310 @BASEBOARD_FAB2_LIB.BASEBOARD_FAB2(SCH_1):PAGE37
  BE80 PVCCIN_CPU0 @BASEBOARD_FAB2_LIB.BASEBOARD_FAB2(SCH_1):PVCCIN_CPU0   I310 @BASEBOARD_FAB2_LIB.BASEBOARD_FAB2(SCH_1):PAGE37
  BE82 PVCCIN_CPU0 @BASEBOARD_FAB2_LIB.BASEBOARD_FAB2(SCH_1):PVCCIN_CPU0   I310 @BASEBOARD_FAB2_LIB.BASEBOARD_FAB2(SCH_1):PAGE37
  BE84 PVCCIN_CPU0 @BASEBOARD_FAB2_LIB.BASEBOARD_FAB2(SCH_1):PVCCIN_CPU0   I310 @BASEBOARD_FAB2_LIB.BASEBOARD_FAB2(SCH_1):PAGE37
  BF61 PVCCIN_CPU0 @BASEBOARD_FAB2_LIB.BASEBOARD_FAB2(SCH_1):PVCCIN_CPU0   I310 @BASEBOARD_FAB2_LIB.BASEBOARD_FAB2(SCH_1):PAGE37
  BF73 PVCCIN_CPU0 @BASEBOARD_FAB2_LIB.BASEBOARD_FAB2(SCH_1):PVCCIN_CPU0   I310 @BASEBOARD_FAB2_LIB.BASEBOARD_FAB2(SCH_1):PAGE37
  BF75 PVCCIN_CPU0 @BASEBOARD_FAB2_LIB.BASEBOARD_FAB2(SCH_1):PVCCIN_CPU0   I310 @BASEBOARD_FAB2_LIB.BASEBOARD_FAB2(SCH_1):PAGE37
  BF77 PVCCIN_CPU0 @BASEBOARD_FAB2_LIB.BASEBOARD_FAB2(SCH_1):PVCCIN_CPU0   I310 @BASEBOARD_FAB2_LIB.BASEBOARD_FAB2(SCH_1):PAGE37
  BF79 PVCCIN_CPU0 @BASEBOARD_FAB2_LIB.BASEBOARD_FAB2(SCH_1):PVCCIN_CPU0   I310 @BASEBOARD_FAB2_LIB.BASEBOARD_FAB2(SCH_1):PAGE37
  BF81 PVCCIN_CPU0 @BASEBOARD_FAB2_LIB.BASEBOARD_FAB2(SCH_1):PVCCIN_CPU0   I310 @BASEBOARD_FAB2_LIB.BASEBOARD_FAB2(SCH_1):PAGE37
  BF83 PVCCIN_CPU0 @BASEBOARD_FAB2_LIB.BASEBOARD_FAB2(SCH_1):PVCCIN_CPU0   I310 @BASEBOARD_FAB2_LIB.BASEBOARD_FAB2(SCH_1):PAGE37
  BF85 PVCCIN_CPU0 @BASEBOARD_FAB2_LIB.BASEBOARD_FAB2(SCH_1):PVCCIN_CPU0   I310 @BASEBOARD_FAB2_LIB.BASEBOARD_FAB2(SCH_1):PAGE37
  BG60 PVCCIN_CPU0 @BASEBOARD_FAB2_LIB.BASEBOARD_FAB2(SCH_1):PVCCIN_CPU0   I310 @BASEBOARD_FAB2_LIB.BASEBOARD_FAB2(SCH_1):PAGE37
  BG62 PVCCIN_CPU0 @BASEBOARD_FAB2_LIB.BASEBOARD_FAB2(SCH_1):PVCCIN_CPU0   I310 @BASEBOARD_FAB2_LIB.BASEBOARD_FAB2(SCH_1):PAGE37
  BG64 PVCCIN_CPU0 @BASEBOARD_FAB2_LIB.BASEBOARD_FAB2(SCH_1):PVCCIN_CPU0   I310 @BASEBOARD_FAB2_LIB.BASEBOARD_FAB2(SCH_1):PAGE37
  BG66 PVCCIN_CPU0 @BASEBOARD_FAB2_LIB.BASEBOARD_FAB2(SCH_1):PVCCIN_CPU0   I310 @BASEBOARD_FAB2_LIB.BASEBOARD_FAB2(SCH_1):PAGE37
  BG68 PVCCIN_CPU0 @BASEBOARD_FAB2_LIB.BASEBOARD_FAB2(SCH_1):PVCCIN_CPU0   I310 @BASEBOARD_FAB2_LIB.BASEBOARD_FAB2(SCH_1):PAGE37
  BG70 PVCCIN_CPU0 @BASEBOARD_FAB2_LIB.BASEBOARD_FAB2(SCH_1):PVCCIN_CPU0   I310 @BASEBOARD_FAB2_LIB.BASEBOARD_FAB2(SCH_1):PAGE37
  BG84 PVCCIN_CPU0 @BASEBOARD_FAB2_LIB.BASEBOARD_FAB2(SCH_1):PVCCIN_CPU0   I310 @BASEBOARD_FAB2_LIB.BASEBOARD_FAB2(SCH_1):PAGE37
  BH61 PVCCIN_CPU0 @BASEBOARD_FAB2_LIB.BASEBOARD_FAB2(SCH_1):PVCCIN_CPU0   I310 @BASEBOARD_FAB2_LIB.BASEBOARD_FAB2(SCH_1):PAGE37
  BH63 PVCCIN_CPU0 @BASEBOARD_FAB2_LIB.BASEBOARD_FAB2(SCH_1):PVCCIN_CPU0   I310 @BASEBOARD_FAB2_LIB.BASEBOARD_FAB2(SCH_1):PAGE37
  BH65 PVCCIN_CPU0 @BASEBOARD_FAB2_LIB.BASEBOARD_FAB2(SCH_1):PVCCIN_CPU0   I310 @BASEBOARD_FAB2_LIB.BASEBOARD_FAB2(SCH_1):PAGE37
  BH67 PVCCIN_CPU0 @BASEBOARD_FAB2_LIB.BASEBOARD_FAB2(SCH_1):PVCCIN_CPU0   I310 @BASEBOARD_FAB2_LIB.BASEBOARD_FAB2(SCH_1):PAGE37
  BH69 PVCCIN_CPU0 @BASEBOARD_FAB2_LIB.BASEBOARD_FAB2(SCH_1):PVCCIN_CPU0   I310 @BASEBOARD_FAB2_LIB.BASEBOARD_FAB2(SCH_1):PAGE37
  BH71 PVCCIN_CPU0 @BASEBOARD_FAB2_LIB.BASEBOARD_FAB2(SCH_1):PVCCIN_CPU0   I310 @BASEBOARD_FAB2_LIB.BASEBOARD_FAB2(SCH_1):PAGE37
  BH73 PVCCIN_CPU0 @BASEBOARD_FAB2_LIB.BASEBOARD_FAB2(SCH_1):PVCCIN_CPU0   I310 @BASEBOARD_FAB2_LIB.BASEBOARD_FAB2(SCH_1):PAGE37
  BH75 PVCCIN_CPU0 @BASEBOARD_FAB2_LIB.BASEBOARD_FAB2(SCH_1):PVCCIN_CPU0   I310 @BASEBOARD_FAB2_LIB.BASEBOARD_FAB2(SCH_1):PAGE37
  BH77 PVCCIN_CPU0 @BASEBOARD_FAB2_LIB.BASEBOARD_FAB2(SCH_1):PVCCIN_CPU0   I310 @BASEBOARD_FAB2_LIB.BASEBOARD_FAB2(SCH_1):PAGE37
  BH79 PVCCIN_CPU0 @BASEBOARD_FAB2_LIB.BASEBOARD_FAB2(SCH_1):PVCCIN_CPU0   I310 @BASEBOARD_FAB2_LIB.BASEBOARD_FAB2(SCH_1):PAGE37
  BH81 PVCCIN_CPU0 @BASEBOARD_FAB2_LIB.BASEBOARD_FAB2(SCH_1):PVCCIN_CPU0   I310 @BASEBOARD_FAB2_LIB.BASEBOARD_FAB2(SCH_1):PAGE37
  BH83 PVCCIN_CPU0 @BASEBOARD_FAB2_LIB.BASEBOARD_FAB2(SCH_1):PVCCIN_CPU0   I310 @BASEBOARD_FAB2_LIB.BASEBOARD_FAB2(SCH_1):PAGE37
  BJ60 PVCCIN_CPU0 @BASEBOARD_FAB2_LIB.BASEBOARD_FAB2(SCH_1):PVCCIN_CPU0   I310 @BASEBOARD_FAB2_LIB.BASEBOARD_FAB2(SCH_1):PAGE37
  BJ62 PVCCIN_CPU0 @BASEBOARD_FAB2_LIB.BASEBOARD_FAB2(SCH_1):PVCCIN_CPU0   I310 @BASEBOARD_FAB2_LIB.BASEBOARD_FAB2(SCH_1):PAGE37
  BJ64 PVCCIN_CPU0 @BASEBOARD_FAB2_LIB.BASEBOARD_FAB2(SCH_1):PVCCIN_CPU0   I310 @BASEBOARD_FAB2_LIB.BASEBOARD_FAB2(SCH_1):PAGE37
  BJ66 PVCCIN_CPU0 @BASEBOARD_FAB2_LIB.BASEBOARD_FAB2(SCH_1):PVCCIN_CPU0   I310 @BASEBOARD_FAB2_LIB.BASEBOARD_FAB2(SCH_1):PAGE37
  BJ68 PVCCIN_CPU0 @BASEBOARD_FAB2_LIB.BASEBOARD_FAB2(SCH_1):PVCCIN_CPU0   I310 @BASEBOARD_FAB2_LIB.BASEBOARD_FAB2(SCH_1):PAGE37
  BJ70 PVCCIN_CPU0 @BASEBOARD_FAB2_LIB.BASEBOARD_FAB2(SCH_1):PVCCIN_CPU0   I310 @BASEBOARD_FAB2_LIB.BASEBOARD_FAB2(SCH_1):PAGE37
  BJ72 PVCCIN_CPU0 @BASEBOARD_FAB2_LIB.BASEBOARD_FAB2(SCH_1):PVCCIN_CPU0   I310 @BASEBOARD_FAB2_LIB.BASEBOARD_FAB2(SCH_1):PAGE37
  BJ74 PVCCIN_CPU0 @BASEBOARD_FAB2_LIB.BASEBOARD_FAB2(SCH_1):PVCCIN_CPU0   I310 @BASEBOARD_FAB2_LIB.BASEBOARD_FAB2(SCH_1):PAGE37
  BJ76 PVCCIN_CPU0 @BASEBOARD_FAB2_LIB.BASEBOARD_FAB2(SCH_1):PVCCIN_CPU0   I310 @BASEBOARD_FAB2_LIB.BASEBOARD_FAB2(SCH_1):PAGE37
  BJ78 PVCCIN_CPU0 @BASEBOARD_FAB2_LIB.BASEBOARD_FAB2(SCH_1):PVCCIN_CPU0   I310 @BASEBOARD_FAB2_LIB.BASEBOARD_FAB2(SCH_1):PAGE37
  BJ80 PVCCIN_CPU0 @BASEBOARD_FAB2_LIB.BASEBOARD_FAB2(SCH_1):PVCCIN_CPU0   I310 @BASEBOARD_FAB2_LIB.BASEBOARD_FAB2(SCH_1):PAGE37
  BJ82 PVCCIN_CPU0 @BASEBOARD_FAB2_LIB.BASEBOARD_FAB2(SCH_1):PVCCIN_CPU0   I310 @BASEBOARD_FAB2_LIB.BASEBOARD_FAB2(SCH_1):PAGE37
  BJ84 PVCCIN_CPU0 @BASEBOARD_FAB2_LIB.BASEBOARD_FAB2(SCH_1):PVCCIN_CPU0   I310 @BASEBOARD_FAB2_LIB.BASEBOARD_FAB2(SCH_1):PAGE37
  BK61 PVCCIN_CPU0 @BASEBOARD_FAB2_LIB.BASEBOARD_FAB2(SCH_1):PVCCIN_CPU0   I310 @BASEBOARD_FAB2_LIB.BASEBOARD_FAB2(SCH_1):PAGE37
  BK63 PVCCIN_CPU0 @BASEBOARD_FAB2_LIB.BASEBOARD_FAB2(SCH_1):PVCCIN_CPU0   I310 @BASEBOARD_FAB2_LIB.BASEBOARD_FAB2(SCH_1):PAGE37
  BK65 PVCCIN_CPU0 @BASEBOARD_FAB2_LIB.BASEBOARD_FAB2(SCH_1):PVCCIN_CPU0   I310 @BASEBOARD_FAB2_LIB.BASEBOARD_FAB2(SCH_1):PAGE37
  BK67 PVCCIN_CPU0 @BASEBOARD_FAB2_LIB.BASEBOARD_FAB2(SCH_1):PVCCIN_CPU0   I310 @BASEBOARD_FAB2_LIB.BASEBOARD_FAB2(SCH_1):PAGE37
  BK69 PVCCIN_CPU0 @BASEBOARD_FAB2_LIB.BASEBOARD_FAB2(SCH_1):PVCCIN_CPU0   I310 @BASEBOARD_FAB2_LIB.BASEBOARD_FAB2(SCH_1):PAGE37
  BK71 PVCCIN_CPU0 @BASEBOARD_FAB2_LIB.BASEBOARD_FAB2(SCH_1):PVCCIN_CPU0   I310 @BASEBOARD_FAB2_LIB.BASEBOARD_FAB2(SCH_1):PAGE37
  BK73 PVCCIN_CPU0 @BASEBOARD_FAB2_LIB.BASEBOARD_FAB2(SCH_1):PVCCIN_CPU0   I310 @BASEBOARD_FAB2_LIB.BASEBOARD_FAB2(SCH_1):PAGE37
  BK75 PVCCIN_CPU0 @BASEBOARD_FAB2_LIB.BASEBOARD_FAB2(SCH_1):PVCCIN_CPU0   I310 @BASEBOARD_FAB2_LIB.BASEBOARD_FAB2(SCH_1):PAGE37
  BK77 PVCCIN_CPU0 @BASEBOARD_FAB2_LIB.BASEBOARD_FAB2(SCH_1):PVCCIN_CPU0   I310 @BASEBOARD_FAB2_LIB.BASEBOARD_FAB2(SCH_1):PAGE37
  BK79 PVCCIN_CPU0 @BASEBOARD_FAB2_LIB.BASEBOARD_FAB2(SCH_1):PVCCIN_CPU0   I310 @BASEBOARD_FAB2_LIB.BASEBOARD_FAB2(SCH_1):PAGE37
  BK81 PVCCIN_CPU0 @BASEBOARD_FAB2_LIB.BASEBOARD_FAB2(SCH_1):PVCCIN_CPU0   I310 @BASEBOARD_FAB2_LIB.BASEBOARD_FAB2(SCH_1):PAGE37
  BK83 PVCCIN_CPU0 @BASEBOARD_FAB2_LIB.BASEBOARD_FAB2(SCH_1):PVCCIN_CPU0   I310 @BASEBOARD_FAB2_LIB.BASEBOARD_FAB2(SCH_1):PAGE37
  BL60 PVCCIN_CPU0 @BASEBOARD_FAB2_LIB.BASEBOARD_FAB2(SCH_1):PVCCIN_CPU0   I310 @BASEBOARD_FAB2_LIB.BASEBOARD_FAB2(SCH_1):PAGE37
  BL62 PVCCIN_CPU0 @BASEBOARD_FAB2_LIB.BASEBOARD_FAB2(SCH_1):PVCCIN_CPU0   I310 @BASEBOARD_FAB2_LIB.BASEBOARD_FAB2(SCH_1):PAGE37
  BL84 PVCCIN_CPU0 @BASEBOARD_FAB2_LIB.BASEBOARD_FAB2(SCH_1):PVCCIN_CPU0   I310 @BASEBOARD_FAB2_LIB.BASEBOARD_FAB2(SCH_1):PAGE37
  BM61 PVCCIN_CPU0 @BASEBOARD_FAB2_LIB.BASEBOARD_FAB2(SCH_1):PVCCIN_CPU0   I310 @BASEBOARD_FAB2_LIB.BASEBOARD_FAB2(SCH_1):PAGE37
  BM63 PVCCIN_CPU0 @BASEBOARD_FAB2_LIB.BASEBOARD_FAB2(SCH_1):PVCCIN_CPU0   I310 @BASEBOARD_FAB2_LIB.BASEBOARD_FAB2(SCH_1):PAGE37
  BM65 PVCCIN_CPU0 @BASEBOARD_FAB2_LIB.BASEBOARD_FAB2(SCH_1):PVCCIN_CPU0   I310 @BASEBOARD_FAB2_LIB.BASEBOARD_FAB2(SCH_1):PAGE37
  BM67 PVCCIN_CPU0 @BASEBOARD_FAB2_LIB.BASEBOARD_FAB2(SCH_1):PVCCIN_CPU0   I310 @BASEBOARD_FAB2_LIB.BASEBOARD_FAB2(SCH_1):PAGE37
  BM69 PVCCIN_CPU0 @BASEBOARD_FAB2_LIB.BASEBOARD_FAB2(SCH_1):PVCCIN_CPU0   I310 @BASEBOARD_FAB2_LIB.BASEBOARD_FAB2(SCH_1):PAGE37
  BM71 PVCCIN_CPU0 @BASEBOARD_FAB2_LIB.BASEBOARD_FAB2(SCH_1):PVCCIN_CPU0   I310 @BASEBOARD_FAB2_LIB.BASEBOARD_FAB2(SCH_1):PAGE37
  BM73 PVCCIN_CPU0 @BASEBOARD_FAB2_LIB.BASEBOARD_FAB2(SCH_1):PVCCIN_CPU0   I310 @BASEBOARD_FAB2_LIB.BASEBOARD_FAB2(SCH_1):PAGE37
  BM75 PVCCIN_CPU0 @BASEBOARD_FAB2_LIB.BASEBOARD_FAB2(SCH_1):PVCCIN_CPU0   I310 @BASEBOARD_FAB2_LIB.BASEBOARD_FAB2(SCH_1):PAGE37
  BM77 PVCCIN_CPU0 @BASEBOARD_FAB2_LIB.BASEBOARD_FAB2(SCH_1):PVCCIN_CPU0   I310 @BASEBOARD_FAB2_LIB.BASEBOARD_FAB2(SCH_1):PAGE37
  BM79 PVCCIN_CPU0 @BASEBOARD_FAB2_LIB.BASEBOARD_FAB2(SCH_1):PVCCIN_CPU0   I310 @BASEBOARD_FAB2_LIB.BASEBOARD_FAB2(SCH_1):PAGE37
  BM81 PVCCIN_CPU0 @BASEBOARD_FAB2_LIB.BASEBOARD_FAB2(SCH_1):PVCCIN_CPU0   I310 @BASEBOARD_FAB2_LIB.BASEBOARD_FAB2(SCH_1):PAGE37
  BM83 PVCCIN_CPU0 @BASEBOARD_FAB2_LIB.BASEBOARD_FAB2(SCH_1):PVCCIN_CPU0   I310 @BASEBOARD_FAB2_LIB.BASEBOARD_FAB2(SCH_1):PAGE37
  BN60 PVCCIN_CPU0 @BASEBOARD_FAB2_LIB.BASEBOARD_FAB2(SCH_1):PVCCIN_CPU0   I310 @BASEBOARD_FAB2_LIB.BASEBOARD_FAB2(SCH_1):PAGE37
  BN62 PVCCIN_CPU0 @BASEBOARD_FAB2_LIB.BASEBOARD_FAB2(SCH_1):PVCCIN_CPU0   I310 @BASEBOARD_FAB2_LIB.BASEBOARD_FAB2(SCH_1):PAGE37
  BN64 PVCCIN_CPU0 @BASEBOARD_FAB2_LIB.BASEBOARD_FAB2(SCH_1):PVCCIN_CPU0   I310 @BASEBOARD_FAB2_LIB.BASEBOARD_FAB2(SCH_1):PAGE37
  BN66 PVCCIN_CPU0 @BASEBOARD_FAB2_LIB.BASEBOARD_FAB2(SCH_1):PVCCIN_CPU0   I310 @BASEBOARD_FAB2_LIB.BASEBOARD_FAB2(SCH_1):PAGE37
  BN68 PVCCIN_CPU0 @BASEBOARD_FAB2_LIB.BASEBOARD_FAB2(SCH_1):PVCCIN_CPU0   I310 @BASEBOARD_FAB2_LIB.BASEBOARD_FAB2(SCH_1):PAGE37
  BN70 PVCCIN_CPU0 @BASEBOARD_FAB2_LIB.BASEBOARD_FAB2(SCH_1):PVCCIN_CPU0   I310 @BASEBOARD_FAB2_LIB.BASEBOARD_FAB2(SCH_1):PAGE37
  BN72 PVCCIN_CPU0 @BASEBOARD_FAB2_LIB.BASEBOARD_FAB2(SCH_1):PVCCIN_CPU0   I310 @BASEBOARD_FAB2_LIB.BASEBOARD_FAB2(SCH_1):PAGE37
  BN74 PVCCIN_CPU0 @BASEBOARD_FAB2_LIB.BASEBOARD_FAB2(SCH_1):PVCCIN_CPU0   I310 @BASEBOARD_FAB2_LIB.BASEBOARD_FAB2(SCH_1):PAGE37
  BN76 PVCCIN_CPU0 @BASEBOARD_FAB2_LIB.BASEBOARD_FAB2(SCH_1):PVCCIN_CPU0   I310 @BASEBOARD_FAB2_LIB.BASEBOARD_FAB2(SCH_1):PAGE37
  BN78 PVCCIN_CPU0 @BASEBOARD_FAB2_LIB.BASEBOARD_FAB2(SCH_1):PVCCIN_CPU0   I310 @BASEBOARD_FAB2_LIB.BASEBOARD_FAB2(SCH_1):PAGE37
  BN80 PVCCIN_CPU0 @BASEBOARD_FAB2_LIB.BASEBOARD_FAB2(SCH_1):PVCCIN_CPU0   I311 @BASEBOARD_FAB2_LIB.BASEBOARD_FAB2(SCH_1):PAGE37
  BN82 PVCCIN_CPU0 @BASEBOARD_FAB2_LIB.BASEBOARD_FAB2(SCH_1):PVCCIN_CPU0   I311 @BASEBOARD_FAB2_LIB.BASEBOARD_FAB2(SCH_1):PAGE37
  BN84 PVCCIN_CPU0 @BASEBOARD_FAB2_LIB.BASEBOARD_FAB2(SCH_1):PVCCIN_CPU0   I311 @BASEBOARD_FAB2_LIB.BASEBOARD_FAB2(SCH_1):PAGE37
  BP61 PVCCIN_CPU0 @BASEBOARD_FAB2_LIB.BASEBOARD_FAB2(SCH_1):PVCCIN_CPU0   I311 @BASEBOARD_FAB2_LIB.BASEBOARD_FAB2(SCH_1):PAGE37
  BP63 PVCCIN_CPU0 @BASEBOARD_FAB2_LIB.BASEBOARD_FAB2(SCH_1):PVCCIN_CPU0   I311 @BASEBOARD_FAB2_LIB.BASEBOARD_FAB2(SCH_1):PAGE37
  BP65 PVCCIN_CPU0 @BASEBOARD_FAB2_LIB.BASEBOARD_FAB2(SCH_1):PVCCIN_CPU0   I311 @BASEBOARD_FAB2_LIB.BASEBOARD_FAB2(SCH_1):PAGE37
  BP67 PVCCIN_CPU0 @BASEBOARD_FAB2_LIB.BASEBOARD_FAB2(SCH_1):PVCCIN_CPU0   I311 @BASEBOARD_FAB2_LIB.BASEBOARD_FAB2(SCH_1):PAGE37
  BP69 PVCCIN_CPU0 @BASEBOARD_FAB2_LIB.BASEBOARD_FAB2(SCH_1):PVCCIN_CPU0   I311 @BASEBOARD_FAB2_LIB.BASEBOARD_FAB2(SCH_1):PAGE37
  BP71 PVCCIN_CPU0 @BASEBOARD_FAB2_LIB.BASEBOARD_FAB2(SCH_1):PVCCIN_CPU0   I311 @BASEBOARD_FAB2_LIB.BASEBOARD_FAB2(SCH_1):PAGE37
  BP73 PVCCIN_CPU0 @BASEBOARD_FAB2_LIB.BASEBOARD_FAB2(SCH_1):PVCCIN_CPU0   I311 @BASEBOARD_FAB2_LIB.BASEBOARD_FAB2(SCH_1):PAGE37
  BP75 PVCCIN_CPU0 @BASEBOARD_FAB2_LIB.BASEBOARD_FAB2(SCH_1):PVCCIN_CPU0   I311 @BASEBOARD_FAB2_LIB.BASEBOARD_FAB2(SCH_1):PAGE37
  BP77 PVCCIN_CPU0 @BASEBOARD_FAB2_LIB.BASEBOARD_FAB2(SCH_1):PVCCIN_CPU0   I311 @BASEBOARD_FAB2_LIB.BASEBOARD_FAB2(SCH_1):PAGE37
  BP79 PVCCIN_CPU0 @BASEBOARD_FAB2_LIB.BASEBOARD_FAB2(SCH_1):PVCCIN_CPU0   I311 @BASEBOARD_FAB2_LIB.BASEBOARD_FAB2(SCH_1):PAGE37
  BP81 PVCCIN_CPU0 @BASEBOARD_FAB2_LIB.BASEBOARD_FAB2(SCH_1):PVCCIN_CPU0   I311 @BASEBOARD_FAB2_LIB.BASEBOARD_FAB2(SCH_1):PAGE37
  BP83 PVCCIN_CPU0 @BASEBOARD_FAB2_LIB.BASEBOARD_FAB2(SCH_1):PVCCIN_CPU0   I311 @BASEBOARD_FAB2_LIB.BASEBOARD_FAB2(SCH_1):PAGE37
  BR60 PVCCIN_CPU0 @BASEBOARD_FAB2_LIB.BASEBOARD_FAB2(SCH_1):PVCCIN_CPU0   I311 @BASEBOARD_FAB2_LIB.BASEBOARD_FAB2(SCH_1):PAGE37
  BR62 PVCCIN_CPU0 @BASEBOARD_FAB2_LIB.BASEBOARD_FAB2(SCH_1):PVCCIN_CPU0   I311 @BASEBOARD_FAB2_LIB.BASEBOARD_FAB2(SCH_1):PAGE37
  BR84 PVCCIN_CPU0 @BASEBOARD_FAB2_LIB.BASEBOARD_FAB2(SCH_1):PVCCIN_CPU0   I311 @BASEBOARD_FAB2_LIB.BASEBOARD_FAB2(SCH_1):PAGE37
  BT61 PVCCIN_CPU0 @BASEBOARD_FAB2_LIB.BASEBOARD_FAB2(SCH_1):PVCCIN_CPU0   I311 @BASEBOARD_FAB2_LIB.BASEBOARD_FAB2(SCH_1):PAGE37
  BT63 PVCCIN_CPU0 @BASEBOARD_FAB2_LIB.BASEBOARD_FAB2(SCH_1):PVCCIN_CPU0   I311 @BASEBOARD_FAB2_LIB.BASEBOARD_FAB2(SCH_1):PAGE37
  BT65 PVCCIN_CPU0 @BASEBOARD_FAB2_LIB.BASEBOARD_FAB2(SCH_1):PVCCIN_CPU0   I311 @BASEBOARD_FAB2_LIB.BASEBOARD_FAB2(SCH_1):PAGE37
  BT67 PVCCIN_CPU0 @BASEBOARD_FAB2_LIB.BASEBOARD_FAB2(SCH_1):PVCCIN_CPU0   I311 @BASEBOARD_FAB2_LIB.BASEBOARD_FAB2(SCH_1):PAGE37
  BT69 PVCCIN_CPU0 @BASEBOARD_FAB2_LIB.BASEBOARD_FAB2(SCH_1):PVCCIN_CPU0   I311 @BASEBOARD_FAB2_LIB.BASEBOARD_FAB2(SCH_1):PAGE37
  BT71 PVCCIN_CPU0 @BASEBOARD_FAB2_LIB.BASEBOARD_FAB2(SCH_1):PVCCIN_CPU0   I311 @BASEBOARD_FAB2_LIB.BASEBOARD_FAB2(SCH_1):PAGE37
  BT73 PVCCIN_CPU0 @BASEBOARD_FAB2_LIB.BASEBOARD_FAB2(SCH_1):PVCCIN_CPU0   I311 @BASEBOARD_FAB2_LIB.BASEBOARD_FAB2(SCH_1):PAGE37
  BT75 PVCCIN_CPU0 @BASEBOARD_FAB2_LIB.BASEBOARD_FAB2(SCH_1):PVCCIN_CPU0   I311 @BASEBOARD_FAB2_LIB.BASEBOARD_FAB2(SCH_1):PAGE37
  BT77 PVCCIN_CPU0 @BASEBOARD_FAB2_LIB.BASEBOARD_FAB2(SCH_1):PVCCIN_CPU0   I311 @BASEBOARD_FAB2_LIB.BASEBOARD_FAB2(SCH_1):PAGE37
  BT79 PVCCIN_CPU0 @BASEBOARD_FAB2_LIB.BASEBOARD_FAB2(SCH_1):PVCCIN_CPU0   I311 @BASEBOARD_FAB2_LIB.BASEBOARD_FAB2(SCH_1):PAGE37
  BT81 PVCCIN_CPU0 @BASEBOARD_FAB2_LIB.BASEBOARD_FAB2(SCH_1):PVCCIN_CPU0   I311 @BASEBOARD_FAB2_LIB.BASEBOARD_FAB2(SCH_1):PAGE37
  BT83 PVCCIN_CPU0 @BASEBOARD_FAB2_LIB.BASEBOARD_FAB2(SCH_1):PVCCIN_CPU0   I311 @BASEBOARD_FAB2_LIB.BASEBOARD_FAB2(SCH_1):PAGE37
  BU60 PVCCIN_CPU0 @BASEBOARD_FAB2_LIB.BASEBOARD_FAB2(SCH_1):PVCCIN_CPU0   I311 @BASEBOARD_FAB2_LIB.BASEBOARD_FAB2(SCH_1):PAGE37
  BU62 PVCCIN_CPU0 @BASEBOARD_FAB2_LIB.BASEBOARD_FAB2(SCH_1):PVCCIN_CPU0   I311 @BASEBOARD_FAB2_LIB.BASEBOARD_FAB2(SCH_1):PAGE37
  BU64 PVCCIN_CPU0 @BASEBOARD_FAB2_LIB.BASEBOARD_FAB2(SCH_1):PVCCIN_CPU0   I311 @BASEBOARD_FAB2_LIB.BASEBOARD_FAB2(SCH_1):PAGE37
  BU66 PVCCIN_CPU0 @BASEBOARD_FAB2_LIB.BASEBOARD_FAB2(SCH_1):PVCCIN_CPU0   I311 @BASEBOARD_FAB2_LIB.BASEBOARD_FAB2(SCH_1):PAGE37
  BU68 PVCCIN_CPU0 @BASEBOARD_FAB2_LIB.BASEBOARD_FAB2(SCH_1):PVCCIN_CPU0   I311 @BASEBOARD_FAB2_LIB.BASEBOARD_FAB2(SCH_1):PAGE37
  BU70 PVCCIN_CPU0 @BASEBOARD_FAB2_LIB.BASEBOARD_FAB2(SCH_1):PVCCIN_CPU0   I311 @BASEBOARD_FAB2_LIB.BASEBOARD_FAB2(SCH_1):PAGE37
  BU72 PVCCIN_CPU0 @BASEBOARD_FAB2_LIB.BASEBOARD_FAB2(SCH_1):PVCCIN_CPU0   I311 @BASEBOARD_FAB2_LIB.BASEBOARD_FAB2(SCH_1):PAGE37
  BU74 PVCCIN_CPU0 @BASEBOARD_FAB2_LIB.BASEBOARD_FAB2(SCH_1):PVCCIN_CPU0   I311 @BASEBOARD_FAB2_LIB.BASEBOARD_FAB2(SCH_1):PAGE37
  BU76 PVCCIN_CPU0 @BASEBOARD_FAB2_LIB.BASEBOARD_FAB2(SCH_1):PVCCIN_CPU0   I311 @BASEBOARD_FAB2_LIB.BASEBOARD_FAB2(SCH_1):PAGE37
  BU78 PVCCIN_CPU0 @BASEBOARD_FAB2_LIB.BASEBOARD_FAB2(SCH_1):PVCCIN_CPU0   I311 @BASEBOARD_FAB2_LIB.BASEBOARD_FAB2(SCH_1):PAGE37
  BU80 PVCCIN_CPU0 @BASEBOARD_FAB2_LIB.BASEBOARD_FAB2(SCH_1):PVCCIN_CPU0   I311 @BASEBOARD_FAB2_LIB.BASEBOARD_FAB2(SCH_1):PAGE37
  BU82 PVCCIN_CPU0 @BASEBOARD_FAB2_LIB.BASEBOARD_FAB2(SCH_1):PVCCIN_CPU0   I311 @BASEBOARD_FAB2_LIB.BASEBOARD_FAB2(SCH_1):PAGE37
  BU84 PVCCIN_CPU0 @BASEBOARD_FAB2_LIB.BASEBOARD_FAB2(SCH_1):PVCCIN_CPU0   I311 @BASEBOARD_FAB2_LIB.BASEBOARD_FAB2(SCH_1):PAGE37
  BV61 PVCCIN_CPU0 @BASEBOARD_FAB2_LIB.BASEBOARD_FAB2(SCH_1):PVCCIN_CPU0   I311 @BASEBOARD_FAB2_LIB.BASEBOARD_FAB2(SCH_1):PAGE37
  BV63 PVCCIN_CPU0 @BASEBOARD_FAB2_LIB.BASEBOARD_FAB2(SCH_1):PVCCIN_CPU0   I311 @BASEBOARD_FAB2_LIB.BASEBOARD_FAB2(SCH_1):PAGE37
  BV65 PVCCIN_CPU0 @BASEBOARD_FAB2_LIB.BASEBOARD_FAB2(SCH_1):PVCCIN_CPU0   I311 @BASEBOARD_FAB2_LIB.BASEBOARD_FAB2(SCH_1):PAGE37
  BV67 PVCCIN_CPU0 @BASEBOARD_FAB2_LIB.BASEBOARD_FAB2(SCH_1):PVCCIN_CPU0   I311 @BASEBOARD_FAB2_LIB.BASEBOARD_FAB2(SCH_1):PAGE37
  BV69 PVCCIN_CPU0 @BASEBOARD_FAB2_LIB.BASEBOARD_FAB2(SCH_1):PVCCIN_CPU0   I311 @BASEBOARD_FAB2_LIB.BASEBOARD_FAB2(SCH_1):PAGE37
  BV71 PVCCIN_CPU0 @BASEBOARD_FAB2_LIB.BASEBOARD_FAB2(SCH_1):PVCCIN_CPU0   I311 @BASEBOARD_FAB2_LIB.BASEBOARD_FAB2(SCH_1):PAGE37
  BV73 PVCCIN_CPU0 @BASEBOARD_FAB2_LIB.BASEBOARD_FAB2(SCH_1):PVCCIN_CPU0   I311 @BASEBOARD_FAB2_LIB.BASEBOARD_FAB2(SCH_1):PAGE37
  BV75 PVCCIN_CPU0 @BASEBOARD_FAB2_LIB.BASEBOARD_FAB2(SCH_1):PVCCIN_CPU0   I311 @BASEBOARD_FAB2_LIB.BASEBOARD_FAB2(SCH_1):PAGE37
  BV77 PVCCIN_CPU0 @BASEBOARD_FAB2_LIB.BASEBOARD_FAB2(SCH_1):PVCCIN_CPU0   I311 @BASEBOARD_FAB2_LIB.BASEBOARD_FAB2(SCH_1):PAGE37
  BV79 PVCCIN_CPU0 @BASEBOARD_FAB2_LIB.BASEBOARD_FAB2(SCH_1):PVCCIN_CPU0   I311 @BASEBOARD_FAB2_LIB.BASEBOARD_FAB2(SCH_1):PAGE37
  BV81 PVCCIN_CPU0 @BASEBOARD_FAB2_LIB.BASEBOARD_FAB2(SCH_1):PVCCIN_CPU0   I311 @BASEBOARD_FAB2_LIB.BASEBOARD_FAB2(SCH_1):PAGE37
  BV83 PVCCIN_CPU0 @BASEBOARD_FAB2_LIB.BASEBOARD_FAB2(SCH_1):PVCCIN_CPU0   I311 @BASEBOARD_FAB2_LIB.BASEBOARD_FAB2(SCH_1):PAGE37
  BW60 PVCCIN_CPU0 @BASEBOARD_FAB2_LIB.BASEBOARD_FAB2(SCH_1):PVCCIN_CPU0   I311 @BASEBOARD_FAB2_LIB.BASEBOARD_FAB2(SCH_1):PAGE37
  BW62 PVCCIN_CPU0 @BASEBOARD_FAB2_LIB.BASEBOARD_FAB2(SCH_1):PVCCIN_CPU0   I311 @BASEBOARD_FAB2_LIB.BASEBOARD_FAB2(SCH_1):PAGE37
  BW64 PVCCIN_CPU0 @BASEBOARD_FAB2_LIB.BASEBOARD_FAB2(SCH_1):PVCCIN_CPU0   I311 @BASEBOARD_FAB2_LIB.BASEBOARD_FAB2(SCH_1):PAGE37
  BW66 PVCCIN_CPU0 @BASEBOARD_FAB2_LIB.BASEBOARD_FAB2(SCH_1):PVCCIN_CPU0   I311 @BASEBOARD_FAB2_LIB.BASEBOARD_FAB2(SCH_1):PAGE37
  BW68 PVCCIN_CPU0 @BASEBOARD_FAB2_LIB.BASEBOARD_FAB2(SCH_1):PVCCIN_CPU0   I311 @BASEBOARD_FAB2_LIB.BASEBOARD_FAB2(SCH_1):PAGE37
  BW70 PVCCIN_CPU0 @BASEBOARD_FAB2_LIB.BASEBOARD_FAB2(SCH_1):PVCCIN_CPU0   I311 @BASEBOARD_FAB2_LIB.BASEBOARD_FAB2(SCH_1):PAGE37
  BW84 PVCCIN_CPU0 @BASEBOARD_FAB2_LIB.BASEBOARD_FAB2(SCH_1):PVCCIN_CPU0   I311 @BASEBOARD_FAB2_LIB.BASEBOARD_FAB2(SCH_1):PAGE37
  BY61 PVCCIN_CPU0 @BASEBOARD_FAB2_LIB.BASEBOARD_FAB2(SCH_1):PVCCIN_CPU0   I311 @BASEBOARD_FAB2_LIB.BASEBOARD_FAB2(SCH_1):PAGE37
  BY73 PVCCIN_CPU0 @BASEBOARD_FAB2_LIB.BASEBOARD_FAB2(SCH_1):PVCCIN_CPU0   I311 @BASEBOARD_FAB2_LIB.BASEBOARD_FAB2(SCH_1):PAGE37
  BY75 PVCCIN_CPU0 @BASEBOARD_FAB2_LIB.BASEBOARD_FAB2(SCH_1):PVCCIN_CPU0   I311 @BASEBOARD_FAB2_LIB.BASEBOARD_FAB2(SCH_1):PAGE37
  BY77 PVCCIN_CPU0 @BASEBOARD_FAB2_LIB.BASEBOARD_FAB2(SCH_1):PVCCIN_CPU0   I311 @BASEBOARD_FAB2_LIB.BASEBOARD_FAB2(SCH_1):PAGE37
  BY79 PVCCIN_CPU0 @BASEBOARD_FAB2_LIB.BASEBOARD_FAB2(SCH_1):PVCCIN_CPU0   I311 @BASEBOARD_FAB2_LIB.BASEBOARD_FAB2(SCH_1):PAGE37
  BY81 PVCCIN_CPU0 @BASEBOARD_FAB2_LIB.BASEBOARD_FAB2(SCH_1):PVCCIN_CPU0   I311 @BASEBOARD_FAB2_LIB.BASEBOARD_FAB2(SCH_1):PAGE37
  BY83 PVCCIN_CPU0 @BASEBOARD_FAB2_LIB.BASEBOARD_FAB2(SCH_1):PVCCIN_CPU0   I311 @BASEBOARD_FAB2_LIB.BASEBOARD_FAB2(SCH_1):PAGE37
  CA60 PVCCIN_CPU0 @BASEBOARD_FAB2_LIB.BASEBOARD_FAB2(SCH_1):PVCCIN_CPU0   I311 @BASEBOARD_FAB2_LIB.BASEBOARD_FAB2(SCH_1):PAGE37
  CA62 PVCCIN_CPU0 @BASEBOARD_FAB2_LIB.BASEBOARD_FAB2(SCH_1):PVCCIN_CPU0   I311 @BASEBOARD_FAB2_LIB.BASEBOARD_FAB2(SCH_1):PAGE37
  CA72 PVCCIN_CPU0 @BASEBOARD_FAB2_LIB.BASEBOARD_FAB2(SCH_1):PVCCIN_CPU0   I311 @BASEBOARD_FAB2_LIB.BASEBOARD_FAB2(SCH_1):PAGE37
  CA74 PVCCIN_CPU0 @BASEBOARD_FAB2_LIB.BASEBOARD_FAB2(SCH_1):PVCCIN_CPU0   I311 @BASEBOARD_FAB2_LIB.BASEBOARD_FAB2(SCH_1):PAGE37
  CA76 PVCCIN_CPU0 @BASEBOARD_FAB2_LIB.BASEBOARD_FAB2(SCH_1):PVCCIN_CPU0   I311 @BASEBOARD_FAB2_LIB.BASEBOARD_FAB2(SCH_1):PAGE37
  CA78 PVCCIN_CPU0 @BASEBOARD_FAB2_LIB.BASEBOARD_FAB2(SCH_1):PVCCIN_CPU0   I311 @BASEBOARD_FAB2_LIB.BASEBOARD_FAB2(SCH_1):PAGE37
  CA80 PVCCIN_CPU0 @BASEBOARD_FAB2_LIB.BASEBOARD_FAB2(SCH_1):PVCCIN_CPU0   I311 @BASEBOARD_FAB2_LIB.BASEBOARD_FAB2(SCH_1):PAGE37
  CA82 PVCCIN_CPU0 @BASEBOARD_FAB2_LIB.BASEBOARD_FAB2(SCH_1):PVCCIN_CPU0   I311 @BASEBOARD_FAB2_LIB.BASEBOARD_FAB2(SCH_1):PAGE37
  CA84 PVCCIN_CPU0 @BASEBOARD_FAB2_LIB.BASEBOARD_FAB2(SCH_1):PVCCIN_CPU0   I311 @BASEBOARD_FAB2_LIB.BASEBOARD_FAB2(SCH_1):PAGE37
  CB61 PVCCIN_CPU0 @BASEBOARD_FAB2_LIB.BASEBOARD_FAB2(SCH_1):PVCCIN_CPU0   I311 @BASEBOARD_FAB2_LIB.BASEBOARD_FAB2(SCH_1):PAGE37
  CB73 PVCCIN_CPU0 @BASEBOARD_FAB2_LIB.BASEBOARD_FAB2(SCH_1):PVCCIN_CPU0   I311 @BASEBOARD_FAB2_LIB.BASEBOARD_FAB2(SCH_1):PAGE37
  CB75 PVCCIN_CPU0 @BASEBOARD_FAB2_LIB.BASEBOARD_FAB2(SCH_1):PVCCIN_CPU0   I311 @BASEBOARD_FAB2_LIB.BASEBOARD_FAB2(SCH_1):PAGE37
  CB77 PVCCIN_CPU0 @BASEBOARD_FAB2_LIB.BASEBOARD_FAB2(SCH_1):PVCCIN_CPU0   I311 @BASEBOARD_FAB2_LIB.BASEBOARD_FAB2(SCH_1):PAGE37
  CB79 PVCCIN_CPU0 @BASEBOARD_FAB2_LIB.BASEBOARD_FAB2(SCH_1):PVCCIN_CPU0   I311 @BASEBOARD_FAB2_LIB.BASEBOARD_FAB2(SCH_1):PAGE37
  CB81 PVCCIN_CPU0 @BASEBOARD_FAB2_LIB.BASEBOARD_FAB2(SCH_1):PVCCIN_CPU0   I311 @BASEBOARD_FAB2_LIB.BASEBOARD_FAB2(SCH_1):PAGE37
  CB83 PVCCIN_CPU0 @BASEBOARD_FAB2_LIB.BASEBOARD_FAB2(SCH_1):PVCCIN_CPU0   I311 @BASEBOARD_FAB2_LIB.BASEBOARD_FAB2(SCH_1):PAGE37
  CC60 PVCCIN_CPU0 @BASEBOARD_FAB2_LIB.BASEBOARD_FAB2(SCH_1):PVCCIN_CPU0   I311 @BASEBOARD_FAB2_LIB.BASEBOARD_FAB2(SCH_1):PAGE37
  CC62 PVCCIN_CPU0 @BASEBOARD_FAB2_LIB.BASEBOARD_FAB2(SCH_1):PVCCIN_CPU0   I311 @BASEBOARD_FAB2_LIB.BASEBOARD_FAB2(SCH_1):PAGE37
  CC84 PVCCIN_CPU0 @BASEBOARD_FAB2_LIB.BASEBOARD_FAB2(SCH_1):PVCCIN_CPU0   I311 @BASEBOARD_FAB2_LIB.BASEBOARD_FAB2(SCH_1):PAGE37
  CD61 PVCCIN_CPU0 @BASEBOARD_FAB2_LIB.BASEBOARD_FAB2(SCH_1):PVCCIN_CPU0   I311 @BASEBOARD_FAB2_LIB.BASEBOARD_FAB2(SCH_1):PAGE37
  CD83 PVCCIN_CPU0 @BASEBOARD_FAB2_LIB.BASEBOARD_FAB2(SCH_1):PVCCIN_CPU0   I311 @BASEBOARD_FAB2_LIB.BASEBOARD_FAB2(SCH_1):PAGE37
  CD85 PVCCIN_CPU0 @BASEBOARD_FAB2_LIB.BASEBOARD_FAB2(SCH_1):PVCCIN_CPU0   I311 @BASEBOARD_FAB2_LIB.BASEBOARD_FAB2(SCH_1):PAGE37
  CE60 PVCCIN_CPU0 @BASEBOARD_FAB2_LIB.BASEBOARD_FAB2(SCH_1):PVCCIN_CPU0   I311 @BASEBOARD_FAB2_LIB.BASEBOARD_FAB2(SCH_1):PAGE37
  CE84 PVCCIN_CPU0 @BASEBOARD_FAB2_LIB.BASEBOARD_FAB2(SCH_1):PVCCIN_CPU0   I311 @BASEBOARD_FAB2_LIB.BASEBOARD_FAB2(SCH_1):PAGE37
  CF61 PVCCIN_CPU0 @BASEBOARD_FAB2_LIB.BASEBOARD_FAB2(SCH_1):PVCCIN_CPU0   I311 @BASEBOARD_FAB2_LIB.BASEBOARD_FAB2(SCH_1):PAGE37
  CF85 PVCCIN_CPU0 @BASEBOARD_FAB2_LIB.BASEBOARD_FAB2(SCH_1):PVCCIN_CPU0   I311 @BASEBOARD_FAB2_LIB.BASEBOARD_FAB2(SCH_1):PAGE37
  CG60 PVCCIN_CPU0 @BASEBOARD_FAB2_LIB.BASEBOARD_FAB2(SCH_1):PVCCIN_CPU0   I311 @BASEBOARD_FAB2_LIB.BASEBOARD_FAB2(SCH_1):PAGE37
  CG84 PVCCIN_CPU0 @BASEBOARD_FAB2_LIB.BASEBOARD_FAB2(SCH_1):PVCCIN_CPU0   I311 @BASEBOARD_FAB2_LIB.BASEBOARD_FAB2(SCH_1):PAGE37
  CH61 PVCCIN_CPU0 @BASEBOARD_FAB2_LIB.BASEBOARD_FAB2(SCH_1):PVCCIN_CPU0   I311 @BASEBOARD_FAB2_LIB.BASEBOARD_FAB2(SCH_1):PAGE37
  CH85 PVCCIN_CPU0 @BASEBOARD_FAB2_LIB.BASEBOARD_FAB2(SCH_1):PVCCIN_CPU0   I311 @BASEBOARD_FAB2_LIB.BASEBOARD_FAB2(SCH_1):PAGE37
  CJ60 PVCCIN_CPU0 @BASEBOARD_FAB2_LIB.BASEBOARD_FAB2(SCH_1):PVCCIN_CPU0   I311 @BASEBOARD_FAB2_LIB.BASEBOARD_FAB2(SCH_1):PAGE37
  CK59 PVCCIN_CPU0 @BASEBOARD_FAB2_LIB.BASEBOARD_FAB2(SCH_1):PVCCIN_CPU0   I311 @BASEBOARD_FAB2_LIB.BASEBOARD_FAB2(SCH_1):PAGE37
  CK61 PVCCIN_CPU0 @BASEBOARD_FAB2_LIB.BASEBOARD_FAB2(SCH_1):PVCCIN_CPU0   I311 @BASEBOARD_FAB2_LIB.BASEBOARD_FAB2(SCH_1):PAGE37
  CL58 PVCCIN_CPU0 @BASEBOARD_FAB2_LIB.BASEBOARD_FAB2(SCH_1):PVCCIN_CPU0   I311 @BASEBOARD_FAB2_LIB.BASEBOARD_FAB2(SCH_1):PAGE37
  CL60 PVCCIN_CPU0 @BASEBOARD_FAB2_LIB.BASEBOARD_FAB2(SCH_1):PVCCIN_CPU0   I311 @BASEBOARD_FAB2_LIB.BASEBOARD_FAB2(SCH_1):PAGE37
  CM57 PVCCIN_CPU0 @BASEBOARD_FAB2_LIB.BASEBOARD_FAB2(SCH_1):PVCCIN_CPU0   I311 @BASEBOARD_FAB2_LIB.BASEBOARD_FAB2(SCH_1):PAGE37
  CM59 PVCCIN_CPU0 @BASEBOARD_FAB2_LIB.BASEBOARD_FAB2(SCH_1):PVCCIN_CPU0   I311 @BASEBOARD_FAB2_LIB.BASEBOARD_FAB2(SCH_1):PAGE37
  CN56 PVCCIN_CPU0 @BASEBOARD_FAB2_LIB.BASEBOARD_FAB2(SCH_1):PVCCIN_CPU0   I311 @BASEBOARD_FAB2_LIB.BASEBOARD_FAB2(SCH_1):PAGE37
  CN58 PVCCIN_CPU0 @BASEBOARD_FAB2_LIB.BASEBOARD_FAB2(SCH_1):PVCCIN_CPU0   I311 @BASEBOARD_FAB2_LIB.BASEBOARD_FAB2(SCH_1):PAGE37
  CP33 PVCCIN_CPU0 @BASEBOARD_FAB2_LIB.BASEBOARD_FAB2(SCH_1):PVCCIN_CPU0   I311 @BASEBOARD_FAB2_LIB.BASEBOARD_FAB2(SCH_1):PAGE37
  CP55 PVCCIN_CPU0 @BASEBOARD_FAB2_LIB.BASEBOARD_FAB2(SCH_1):PVCCIN_CPU0   I311 @BASEBOARD_FAB2_LIB.BASEBOARD_FAB2(SCH_1):PAGE37
  CP57 PVCCIN_CPU0 @BASEBOARD_FAB2_LIB.BASEBOARD_FAB2(SCH_1):PVCCIN_CPU0   I311 @BASEBOARD_FAB2_LIB.BASEBOARD_FAB2(SCH_1):PAGE37
  CR34 PVCCIN_CPU0 @BASEBOARD_FAB2_LIB.BASEBOARD_FAB2(SCH_1):PVCCIN_CPU0   I311 @BASEBOARD_FAB2_LIB.BASEBOARD_FAB2(SCH_1):PAGE37
  CR54 PVCCIN_CPU0 @BASEBOARD_FAB2_LIB.BASEBOARD_FAB2(SCH_1):PVCCIN_CPU0   I311 @BASEBOARD_FAB2_LIB.BASEBOARD_FAB2(SCH_1):PAGE37
  CR56 PVCCIN_CPU0 @BASEBOARD_FAB2_LIB.BASEBOARD_FAB2(SCH_1):PVCCIN_CPU0   I311 @BASEBOARD_FAB2_LIB.BASEBOARD_FAB2(SCH_1):PAGE37
  CT37 PVCCIN_CPU0 @BASEBOARD_FAB2_LIB.BASEBOARD_FAB2(SCH_1):PVCCIN_CPU0   I311 @BASEBOARD_FAB2_LIB.BASEBOARD_FAB2(SCH_1):PAGE37
  CT39 PVCCIN_CPU0 @BASEBOARD_FAB2_LIB.BASEBOARD_FAB2(SCH_1):PVCCIN_CPU0   I311 @BASEBOARD_FAB2_LIB.BASEBOARD_FAB2(SCH_1):PAGE37
  CT41 PVCCIN_CPU0 @BASEBOARD_FAB2_LIB.BASEBOARD_FAB2(SCH_1):PVCCIN_CPU0   I311 @BASEBOARD_FAB2_LIB.BASEBOARD_FAB2(SCH_1):PAGE37
  CT53 PVCCIN_CPU0 @BASEBOARD_FAB2_LIB.BASEBOARD_FAB2(SCH_1):PVCCIN_CPU0   I311 @BASEBOARD_FAB2_LIB.BASEBOARD_FAB2(SCH_1):PAGE37
  CT55 PVCCIN_CPU0 @BASEBOARD_FAB2_LIB.BASEBOARD_FAB2(SCH_1):PVCCIN_CPU0   I311 @BASEBOARD_FAB2_LIB.BASEBOARD_FAB2(SCH_1):PAGE37
  CU38 PVCCIN_CPU0 @BASEBOARD_FAB2_LIB.BASEBOARD_FAB2(SCH_1):PVCCIN_CPU0   I311 @BASEBOARD_FAB2_LIB.BASEBOARD_FAB2(SCH_1):PAGE37
  CU40 PVCCIN_CPU0 @BASEBOARD_FAB2_LIB.BASEBOARD_FAB2(SCH_1):PVCCIN_CPU0   I311 @BASEBOARD_FAB2_LIB.BASEBOARD_FAB2(SCH_1):PAGE37
  CU42 PVCCIN_CPU0 @BASEBOARD_FAB2_LIB.BASEBOARD_FAB2(SCH_1):PVCCIN_CPU0   I311 @BASEBOARD_FAB2_LIB.BASEBOARD_FAB2(SCH_1):PAGE37
  CU52 PVCCIN_CPU0 @BASEBOARD_FAB2_LIB.BASEBOARD_FAB2(SCH_1):PVCCIN_CPU0   I311 @BASEBOARD_FAB2_LIB.BASEBOARD_FAB2(SCH_1):PAGE37
  CU54 PVCCIN_CPU0 @BASEBOARD_FAB2_LIB.BASEBOARD_FAB2(SCH_1):PVCCIN_CPU0   I311 @BASEBOARD_FAB2_LIB.BASEBOARD_FAB2(SCH_1):PAGE37
  CV51 PVCCIN_CPU0 @BASEBOARD_FAB2_LIB.BASEBOARD_FAB2(SCH_1):PVCCIN_CPU0   I311 @BASEBOARD_FAB2_LIB.BASEBOARD_FAB2(SCH_1):PAGE37
  CW46 PVCCIN_CPU0 @BASEBOARD_FAB2_LIB.BASEBOARD_FAB2(SCH_1):PVCCIN_CPU0   I311 @BASEBOARD_FAB2_LIB.BASEBOARD_FAB2(SCH_1):PAGE37
  CW48 PVCCIN_CPU0 @BASEBOARD_FAB2_LIB.BASEBOARD_FAB2(SCH_1):PVCCIN_CPU0   I311 @BASEBOARD_FAB2_LIB.BASEBOARD_FAB2(SCH_1):PAGE37
  CW50 PVCCIN_CPU0 @BASEBOARD_FAB2_LIB.BASEBOARD_FAB2(SCH_1):PVCCIN_CPU0   I311 @BASEBOARD_FAB2_LIB.BASEBOARD_FAB2(SCH_1):PAGE37
  CY47 PVCCIN_CPU0 @BASEBOARD_FAB2_LIB.BASEBOARD_FAB2(SCH_1):PVCCIN_CPU0   I311 @BASEBOARD_FAB2_LIB.BASEBOARD_FAB2(SCH_1):PAGE37
  CY49 PVCCIN_CPU0 @BASEBOARD_FAB2_LIB.BASEBOARD_FAB2(SCH_1):PVCCIN_CPU0   I311 @BASEBOARD_FAB2_LIB.BASEBOARD_FAB2(SCH_1):PAGE37
  AV85 VSENSE_VCCINR2PMAX_CPU0 @BASEBOARD_FAB2_LIB.BASEBOARD_FAB2(SCH_1):VSENSE_VCCINR2PMAX_CPU0   I311 @BASEBOARD_FAB2_LIB.BASEBOARD_FAB2(SCH_1):PAGE37
  AW86 VSENSE_VCCINR2PMAX_CPU0 @BASEBOARD_FAB2_LIB.BASEBOARD_FAB2(SCH_1):VSENSE_VCCINR2PMAX_CPU0   I311 @BASEBOARD_FAB2_LIB.BASEBOARD_FAB2(SCH_1):PAGE37
  BA86 VSENSE_PVCCIN_CPU0_SKT_VSEN @BASEBOARD_FAB2_LIB.BASEBOARD_FAB2(SCH_1):VSENSE_PVCCIN_CPU0_SKT_VSEN   I311 @BASEBOARD_FAB2_LIB.BASEBOARD_FAB2(SCH_1):PAGE37
  AD41 VSENSE_PMAX_CPU0 @BASEBOARD_FAB2_LIB.BASEBOARD_FAB2(SCH_1):VSENSE_PMAX_CPU0   I311 @BASEBOARD_FAB2_LIB.BASEBOARD_FAB2(SCH_1):PAGE37
  AY85 VSENSE_PVCCIN_CPU0_SKT_VRTN @BASEBOARD_FAB2_LIB.BASEBOARD_FAB2(SCH_1):VSENSE_PVCCIN_CPU0_SKT_VRTN   I311 @BASEBOARD_FAB2_LIB.BASEBOARD_FAB2(SCH_1):PAGE37
   B47 PVDDQ_ABC @BASEBOARD_FAB2_LIB.BASEBOARD_FAB2(SCH_1):PVDDQ_ABC    I33 @BASEBOARD_FAB2_LIB.BASEBOARD_FAB2(SCH_1):PAGE38
   C46 PVDDQ_ABC @BASEBOARD_FAB2_LIB.BASEBOARD_FAB2(SCH_1):PVDDQ_ABC    I33 @BASEBOARD_FAB2_LIB.BASEBOARD_FAB2(SCH_1):PAGE38
   D45 PVDDQ_ABC @BASEBOARD_FAB2_LIB.BASEBOARD_FAB2(SCH_1):PVDDQ_ABC    I33 @BASEBOARD_FAB2_LIB.BASEBOARD_FAB2(SCH_1):PAGE38
  AF63 PVDDQ_ABC @BASEBOARD_FAB2_LIB.BASEBOARD_FAB2(SCH_1):PVDDQ_ABC    I33 @BASEBOARD_FAB2_LIB.BASEBOARD_FAB2(SCH_1):PAGE38
  AF61 PVDDQ_ABC @BASEBOARD_FAB2_LIB.BASEBOARD_FAB2(SCH_1):PVDDQ_ABC    I33 @BASEBOARD_FAB2_LIB.BASEBOARD_FAB2(SCH_1):PAGE38
  AF59 PVDDQ_ABC @BASEBOARD_FAB2_LIB.BASEBOARD_FAB2(SCH_1):PVDDQ_ABC    I33 @BASEBOARD_FAB2_LIB.BASEBOARD_FAB2(SCH_1):PAGE38
  AF57 PVDDQ_ABC @BASEBOARD_FAB2_LIB.BASEBOARD_FAB2(SCH_1):PVDDQ_ABC    I33 @BASEBOARD_FAB2_LIB.BASEBOARD_FAB2(SCH_1):PAGE38
  AF55 PVDDQ_ABC @BASEBOARD_FAB2_LIB.BASEBOARD_FAB2(SCH_1):PVDDQ_ABC    I33 @BASEBOARD_FAB2_LIB.BASEBOARD_FAB2(SCH_1):PAGE38
  AD45 PVDDQ_ABC @BASEBOARD_FAB2_LIB.BASEBOARD_FAB2(SCH_1):PVDDQ_ABC    I33 @BASEBOARD_FAB2_LIB.BASEBOARD_FAB2(SCH_1):PAGE38
   Y63 PVDDQ_ABC @BASEBOARD_FAB2_LIB.BASEBOARD_FAB2(SCH_1):PVDDQ_ABC    I33 @BASEBOARD_FAB2_LIB.BASEBOARD_FAB2(SCH_1):PAGE38
   Y61 PVDDQ_ABC @BASEBOARD_FAB2_LIB.BASEBOARD_FAB2(SCH_1):PVDDQ_ABC    I33 @BASEBOARD_FAB2_LIB.BASEBOARD_FAB2(SCH_1):PAGE38
   Y59 PVDDQ_ABC @BASEBOARD_FAB2_LIB.BASEBOARD_FAB2(SCH_1):PVDDQ_ABC    I33 @BASEBOARD_FAB2_LIB.BASEBOARD_FAB2(SCH_1):PAGE38
   Y57 PVDDQ_ABC @BASEBOARD_FAB2_LIB.BASEBOARD_FAB2(SCH_1):PVDDQ_ABC    I33 @BASEBOARD_FAB2_LIB.BASEBOARD_FAB2(SCH_1):PAGE38
   Y55 PVDDQ_ABC @BASEBOARD_FAB2_LIB.BASEBOARD_FAB2(SCH_1):PVDDQ_ABC    I33 @BASEBOARD_FAB2_LIB.BASEBOARD_FAB2(SCH_1):PAGE38
   Y53 PVDDQ_ABC @BASEBOARD_FAB2_LIB.BASEBOARD_FAB2(SCH_1):PVDDQ_ABC    I33 @BASEBOARD_FAB2_LIB.BASEBOARD_FAB2(SCH_1):PAGE38
   Y51 PVDDQ_ABC @BASEBOARD_FAB2_LIB.BASEBOARD_FAB2(SCH_1):PVDDQ_ABC    I33 @BASEBOARD_FAB2_LIB.BASEBOARD_FAB2(SCH_1):PAGE38
   Y49 PVDDQ_ABC @BASEBOARD_FAB2_LIB.BASEBOARD_FAB2(SCH_1):PVDDQ_ABC    I33 @BASEBOARD_FAB2_LIB.BASEBOARD_FAB2(SCH_1):PAGE38
   Y47 PVDDQ_ABC @BASEBOARD_FAB2_LIB.BASEBOARD_FAB2(SCH_1):PVDDQ_ABC    I33 @BASEBOARD_FAB2_LIB.BASEBOARD_FAB2(SCH_1):PAGE38
   Y45 PVDDQ_ABC @BASEBOARD_FAB2_LIB.BASEBOARD_FAB2(SCH_1):PVDDQ_ABC    I33 @BASEBOARD_FAB2_LIB.BASEBOARD_FAB2(SCH_1):PAGE38
   W64 PVDDQ_ABC @BASEBOARD_FAB2_LIB.BASEBOARD_FAB2(SCH_1):PVDDQ_ABC    I33 @BASEBOARD_FAB2_LIB.BASEBOARD_FAB2(SCH_1):PAGE38
   U62 PVDDQ_ABC @BASEBOARD_FAB2_LIB.BASEBOARD_FAB2(SCH_1):PVDDQ_ABC    I33 @BASEBOARD_FAB2_LIB.BASEBOARD_FAB2(SCH_1):PAGE38
   U60 PVDDQ_ABC @BASEBOARD_FAB2_LIB.BASEBOARD_FAB2(SCH_1):PVDDQ_ABC    I33 @BASEBOARD_FAB2_LIB.BASEBOARD_FAB2(SCH_1):PAGE38
   U58 PVDDQ_ABC @BASEBOARD_FAB2_LIB.BASEBOARD_FAB2(SCH_1):PVDDQ_ABC    I33 @BASEBOARD_FAB2_LIB.BASEBOARD_FAB2(SCH_1):PAGE38
   U56 PVDDQ_ABC @BASEBOARD_FAB2_LIB.BASEBOARD_FAB2(SCH_1):PVDDQ_ABC    I33 @BASEBOARD_FAB2_LIB.BASEBOARD_FAB2(SCH_1):PAGE38
   U54 PVDDQ_ABC @BASEBOARD_FAB2_LIB.BASEBOARD_FAB2(SCH_1):PVDDQ_ABC    I33 @BASEBOARD_FAB2_LIB.BASEBOARD_FAB2(SCH_1):PAGE38
   U52 PVDDQ_ABC @BASEBOARD_FAB2_LIB.BASEBOARD_FAB2(SCH_1):PVDDQ_ABC    I33 @BASEBOARD_FAB2_LIB.BASEBOARD_FAB2(SCH_1):PAGE38
   U50 PVDDQ_ABC @BASEBOARD_FAB2_LIB.BASEBOARD_FAB2(SCH_1):PVDDQ_ABC    I33 @BASEBOARD_FAB2_LIB.BASEBOARD_FAB2(SCH_1):PAGE38
   U48 PVDDQ_ABC @BASEBOARD_FAB2_LIB.BASEBOARD_FAB2(SCH_1):PVDDQ_ABC    I33 @BASEBOARD_FAB2_LIB.BASEBOARD_FAB2(SCH_1):PAGE38
   U46 PVDDQ_ABC @BASEBOARD_FAB2_LIB.BASEBOARD_FAB2(SCH_1):PVDDQ_ABC    I33 @BASEBOARD_FAB2_LIB.BASEBOARD_FAB2(SCH_1):PAGE38
   N64 PVDDQ_ABC @BASEBOARD_FAB2_LIB.BASEBOARD_FAB2(SCH_1):PVDDQ_ABC    I33 @BASEBOARD_FAB2_LIB.BASEBOARD_FAB2(SCH_1):PAGE38
   L62 PVDDQ_ABC @BASEBOARD_FAB2_LIB.BASEBOARD_FAB2(SCH_1):PVDDQ_ABC    I33 @BASEBOARD_FAB2_LIB.BASEBOARD_FAB2(SCH_1):PAGE38
   L60 PVDDQ_ABC @BASEBOARD_FAB2_LIB.BASEBOARD_FAB2(SCH_1):PVDDQ_ABC    I33 @BASEBOARD_FAB2_LIB.BASEBOARD_FAB2(SCH_1):PAGE38
   L58 PVDDQ_ABC @BASEBOARD_FAB2_LIB.BASEBOARD_FAB2(SCH_1):PVDDQ_ABC    I33 @BASEBOARD_FAB2_LIB.BASEBOARD_FAB2(SCH_1):PAGE38
   L56 PVDDQ_ABC @BASEBOARD_FAB2_LIB.BASEBOARD_FAB2(SCH_1):PVDDQ_ABC    I33 @BASEBOARD_FAB2_LIB.BASEBOARD_FAB2(SCH_1):PAGE38
   L54 PVDDQ_ABC @BASEBOARD_FAB2_LIB.BASEBOARD_FAB2(SCH_1):PVDDQ_ABC    I33 @BASEBOARD_FAB2_LIB.BASEBOARD_FAB2(SCH_1):PAGE38
   L52 PVDDQ_ABC @BASEBOARD_FAB2_LIB.BASEBOARD_FAB2(SCH_1):PVDDQ_ABC    I33 @BASEBOARD_FAB2_LIB.BASEBOARD_FAB2(SCH_1):PAGE38
   L50 PVDDQ_ABC @BASEBOARD_FAB2_LIB.BASEBOARD_FAB2(SCH_1):PVDDQ_ABC    I33 @BASEBOARD_FAB2_LIB.BASEBOARD_FAB2(SCH_1):PAGE38
   L48 PVDDQ_ABC @BASEBOARD_FAB2_LIB.BASEBOARD_FAB2(SCH_1):PVDDQ_ABC    I33 @BASEBOARD_FAB2_LIB.BASEBOARD_FAB2(SCH_1):PAGE38
   L46 PVDDQ_ABC @BASEBOARD_FAB2_LIB.BASEBOARD_FAB2(SCH_1):PVDDQ_ABC    I33 @BASEBOARD_FAB2_LIB.BASEBOARD_FAB2(SCH_1):PAGE38
   E64 PVDDQ_ABC @BASEBOARD_FAB2_LIB.BASEBOARD_FAB2(SCH_1):PVDDQ_ABC    I33 @BASEBOARD_FAB2_LIB.BASEBOARD_FAB2(SCH_1):PAGE38
   E62 PVDDQ_ABC @BASEBOARD_FAB2_LIB.BASEBOARD_FAB2(SCH_1):PVDDQ_ABC    I33 @BASEBOARD_FAB2_LIB.BASEBOARD_FAB2(SCH_1):PAGE38
   E60 PVDDQ_ABC @BASEBOARD_FAB2_LIB.BASEBOARD_FAB2(SCH_1):PVDDQ_ABC    I33 @BASEBOARD_FAB2_LIB.BASEBOARD_FAB2(SCH_1):PAGE38
   E58 PVDDQ_ABC @BASEBOARD_FAB2_LIB.BASEBOARD_FAB2(SCH_1):PVDDQ_ABC    I33 @BASEBOARD_FAB2_LIB.BASEBOARD_FAB2(SCH_1):PAGE38
   E56 PVDDQ_ABC @BASEBOARD_FAB2_LIB.BASEBOARD_FAB2(SCH_1):PVDDQ_ABC    I33 @BASEBOARD_FAB2_LIB.BASEBOARD_FAB2(SCH_1):PAGE38
   E54 PVDDQ_ABC @BASEBOARD_FAB2_LIB.BASEBOARD_FAB2(SCH_1):PVDDQ_ABC    I33 @BASEBOARD_FAB2_LIB.BASEBOARD_FAB2(SCH_1):PAGE38
   E52 PVDDQ_ABC @BASEBOARD_FAB2_LIB.BASEBOARD_FAB2(SCH_1):PVDDQ_ABC    I33 @BASEBOARD_FAB2_LIB.BASEBOARD_FAB2(SCH_1):PAGE38
   E50 PVDDQ_ABC @BASEBOARD_FAB2_LIB.BASEBOARD_FAB2(SCH_1):PVDDQ_ABC    I33 @BASEBOARD_FAB2_LIB.BASEBOARD_FAB2(SCH_1):PAGE38
   E48 PVDDQ_ABC @BASEBOARD_FAB2_LIB.BASEBOARD_FAB2(SCH_1):PVDDQ_ABC    I33 @BASEBOARD_FAB2_LIB.BASEBOARD_FAB2(SCH_1):PAGE38
   E46 PVDDQ_ABC @BASEBOARD_FAB2_LIB.BASEBOARD_FAB2(SCH_1):PVDDQ_ABC    I33 @BASEBOARD_FAB2_LIB.BASEBOARD_FAB2(SCH_1):PAGE38
   B59 PVDDQ_ABC @BASEBOARD_FAB2_LIB.BASEBOARD_FAB2(SCH_1):PVDDQ_ABC    I33 @BASEBOARD_FAB2_LIB.BASEBOARD_FAB2(SCH_1):PAGE38
   B53 PVDDQ_ABC @BASEBOARD_FAB2_LIB.BASEBOARD_FAB2(SCH_1):PVDDQ_ABC    I33 @BASEBOARD_FAB2_LIB.BASEBOARD_FAB2(SCH_1):PAGE38
   B49 PVDDQ_ABC @BASEBOARD_FAB2_LIB.BASEBOARD_FAB2(SCH_1):PVDDQ_ABC    I33 @BASEBOARD_FAB2_LIB.BASEBOARD_FAB2(SCH_1):PAGE38
  EE44 PVDDQ_DEF @BASEBOARD_FAB2_LIB.BASEBOARD_FAB2(SCH_1):PVDDQ_DEF    I33 @BASEBOARD_FAB2_LIB.BASEBOARD_FAB2(SCH_1):PAGE38
  EF45 PVDDQ_DEF @BASEBOARD_FAB2_LIB.BASEBOARD_FAB2(SCH_1):PVDDQ_DEF    I33 @BASEBOARD_FAB2_LIB.BASEBOARD_FAB2(SCH_1):PAGE38
  DB53 PVDDQ_DEF @BASEBOARD_FAB2_LIB.BASEBOARD_FAB2(SCH_1):PVDDQ_DEF    I33 @BASEBOARD_FAB2_LIB.BASEBOARD_FAB2(SCH_1):PAGE38
  DB55 PVDDQ_DEF @BASEBOARD_FAB2_LIB.BASEBOARD_FAB2(SCH_1):PVDDQ_DEF    I33 @BASEBOARD_FAB2_LIB.BASEBOARD_FAB2(SCH_1):PAGE38
  DB57 PVDDQ_DEF @BASEBOARD_FAB2_LIB.BASEBOARD_FAB2(SCH_1):PVDDQ_DEF    I33 @BASEBOARD_FAB2_LIB.BASEBOARD_FAB2(SCH_1):PAGE38
  DB59 PVDDQ_DEF @BASEBOARD_FAB2_LIB.BASEBOARD_FAB2(SCH_1):PVDDQ_DEF    I33 @BASEBOARD_FAB2_LIB.BASEBOARD_FAB2(SCH_1):PAGE38
  DB61 PVDDQ_DEF @BASEBOARD_FAB2_LIB.BASEBOARD_FAB2(SCH_1):PVDDQ_DEF    I33 @BASEBOARD_FAB2_LIB.BASEBOARD_FAB2(SCH_1):PAGE38
  DB63 PVDDQ_DEF @BASEBOARD_FAB2_LIB.BASEBOARD_FAB2(SCH_1):PVDDQ_DEF    I33 @BASEBOARD_FAB2_LIB.BASEBOARD_FAB2(SCH_1):PAGE38
  DD45 PVDDQ_DEF @BASEBOARD_FAB2_LIB.BASEBOARD_FAB2(SCH_1):PVDDQ_DEF    I33 @BASEBOARD_FAB2_LIB.BASEBOARD_FAB2(SCH_1):PAGE38
  DH45 PVDDQ_DEF @BASEBOARD_FAB2_LIB.BASEBOARD_FAB2(SCH_1):PVDDQ_DEF    I33 @BASEBOARD_FAB2_LIB.BASEBOARD_FAB2(SCH_1):PAGE38
  DH47 PVDDQ_DEF @BASEBOARD_FAB2_LIB.BASEBOARD_FAB2(SCH_1):PVDDQ_DEF    I33 @BASEBOARD_FAB2_LIB.BASEBOARD_FAB2(SCH_1):PAGE38
  DH49 PVDDQ_DEF @BASEBOARD_FAB2_LIB.BASEBOARD_FAB2(SCH_1):PVDDQ_DEF    I33 @BASEBOARD_FAB2_LIB.BASEBOARD_FAB2(SCH_1):PAGE38
  DH51 PVDDQ_DEF @BASEBOARD_FAB2_LIB.BASEBOARD_FAB2(SCH_1):PVDDQ_DEF    I33 @BASEBOARD_FAB2_LIB.BASEBOARD_FAB2(SCH_1):PAGE38
  DH53 PVDDQ_DEF @BASEBOARD_FAB2_LIB.BASEBOARD_FAB2(SCH_1):PVDDQ_DEF    I33 @BASEBOARD_FAB2_LIB.BASEBOARD_FAB2(SCH_1):PAGE38
  DH55 PVDDQ_DEF @BASEBOARD_FAB2_LIB.BASEBOARD_FAB2(SCH_1):PVDDQ_DEF    I33 @BASEBOARD_FAB2_LIB.BASEBOARD_FAB2(SCH_1):PAGE38
  DH57 PVDDQ_DEF @BASEBOARD_FAB2_LIB.BASEBOARD_FAB2(SCH_1):PVDDQ_DEF    I33 @BASEBOARD_FAB2_LIB.BASEBOARD_FAB2(SCH_1):PAGE38
  DH59 PVDDQ_DEF @BASEBOARD_FAB2_LIB.BASEBOARD_FAB2(SCH_1):PVDDQ_DEF    I33 @BASEBOARD_FAB2_LIB.BASEBOARD_FAB2(SCH_1):PAGE38
  DH61 PVDDQ_DEF @BASEBOARD_FAB2_LIB.BASEBOARD_FAB2(SCH_1):PVDDQ_DEF    I33 @BASEBOARD_FAB2_LIB.BASEBOARD_FAB2(SCH_1):PAGE38
  DH63 PVDDQ_DEF @BASEBOARD_FAB2_LIB.BASEBOARD_FAB2(SCH_1):PVDDQ_DEF    I33 @BASEBOARD_FAB2_LIB.BASEBOARD_FAB2(SCH_1):PAGE38
  DJ64 PVDDQ_DEF @BASEBOARD_FAB2_LIB.BASEBOARD_FAB2(SCH_1):PVDDQ_DEF    I33 @BASEBOARD_FAB2_LIB.BASEBOARD_FAB2(SCH_1):PAGE38
  DL46 PVDDQ_DEF @BASEBOARD_FAB2_LIB.BASEBOARD_FAB2(SCH_1):PVDDQ_DEF    I33 @BASEBOARD_FAB2_LIB.BASEBOARD_FAB2(SCH_1):PAGE38
  DL48 PVDDQ_DEF @BASEBOARD_FAB2_LIB.BASEBOARD_FAB2(SCH_1):PVDDQ_DEF    I33 @BASEBOARD_FAB2_LIB.BASEBOARD_FAB2(SCH_1):PAGE38
  DL50 PVDDQ_DEF @BASEBOARD_FAB2_LIB.BASEBOARD_FAB2(SCH_1):PVDDQ_DEF    I33 @BASEBOARD_FAB2_LIB.BASEBOARD_FAB2(SCH_1):PAGE38
  DL52 PVDDQ_DEF @BASEBOARD_FAB2_LIB.BASEBOARD_FAB2(SCH_1):PVDDQ_DEF    I33 @BASEBOARD_FAB2_LIB.BASEBOARD_FAB2(SCH_1):PAGE38
  DL54 PVDDQ_DEF @BASEBOARD_FAB2_LIB.BASEBOARD_FAB2(SCH_1):PVDDQ_DEF    I33 @BASEBOARD_FAB2_LIB.BASEBOARD_FAB2(SCH_1):PAGE38
  DL56 PVDDQ_DEF @BASEBOARD_FAB2_LIB.BASEBOARD_FAB2(SCH_1):PVDDQ_DEF    I33 @BASEBOARD_FAB2_LIB.BASEBOARD_FAB2(SCH_1):PAGE38
  DL58 PVDDQ_DEF @BASEBOARD_FAB2_LIB.BASEBOARD_FAB2(SCH_1):PVDDQ_DEF    I33 @BASEBOARD_FAB2_LIB.BASEBOARD_FAB2(SCH_1):PAGE38
  DL60 PVDDQ_DEF @BASEBOARD_FAB2_LIB.BASEBOARD_FAB2(SCH_1):PVDDQ_DEF    I33 @BASEBOARD_FAB2_LIB.BASEBOARD_FAB2(SCH_1):PAGE38
  DL62 PVDDQ_DEF @BASEBOARD_FAB2_LIB.BASEBOARD_FAB2(SCH_1):PVDDQ_DEF    I33 @BASEBOARD_FAB2_LIB.BASEBOARD_FAB2(SCH_1):PAGE38
  DU46 PVDDQ_DEF @BASEBOARD_FAB2_LIB.BASEBOARD_FAB2(SCH_1):PVDDQ_DEF    I33 @BASEBOARD_FAB2_LIB.BASEBOARD_FAB2(SCH_1):PAGE38
  DU48 PVDDQ_DEF @BASEBOARD_FAB2_LIB.BASEBOARD_FAB2(SCH_1):PVDDQ_DEF    I33 @BASEBOARD_FAB2_LIB.BASEBOARD_FAB2(SCH_1):PAGE38
  DU50 PVDDQ_DEF @BASEBOARD_FAB2_LIB.BASEBOARD_FAB2(SCH_1):PVDDQ_DEF    I33 @BASEBOARD_FAB2_LIB.BASEBOARD_FAB2(SCH_1):PAGE38
  DU52 PVDDQ_DEF @BASEBOARD_FAB2_LIB.BASEBOARD_FAB2(SCH_1):PVDDQ_DEF    I33 @BASEBOARD_FAB2_LIB.BASEBOARD_FAB2(SCH_1):PAGE38
  DU54 PVDDQ_DEF @BASEBOARD_FAB2_LIB.BASEBOARD_FAB2(SCH_1):PVDDQ_DEF    I33 @BASEBOARD_FAB2_LIB.BASEBOARD_FAB2(SCH_1):PAGE38
  DU56 PVDDQ_DEF @BASEBOARD_FAB2_LIB.BASEBOARD_FAB2(SCH_1):PVDDQ_DEF    I33 @BASEBOARD_FAB2_LIB.BASEBOARD_FAB2(SCH_1):PAGE38
  DU58 PVDDQ_DEF @BASEBOARD_FAB2_LIB.BASEBOARD_FAB2(SCH_1):PVDDQ_DEF    I33 @BASEBOARD_FAB2_LIB.BASEBOARD_FAB2(SCH_1):PAGE38
  DU60 PVDDQ_DEF @BASEBOARD_FAB2_LIB.BASEBOARD_FAB2(SCH_1):PVDDQ_DEF    I33 @BASEBOARD_FAB2_LIB.BASEBOARD_FAB2(SCH_1):PAGE38
  DU62 PVDDQ_DEF @BASEBOARD_FAB2_LIB.BASEBOARD_FAB2(SCH_1):PVDDQ_DEF    I33 @BASEBOARD_FAB2_LIB.BASEBOARD_FAB2(SCH_1):PAGE38
  DU64 PVDDQ_DEF @BASEBOARD_FAB2_LIB.BASEBOARD_FAB2(SCH_1):PVDDQ_DEF    I33 @BASEBOARD_FAB2_LIB.BASEBOARD_FAB2(SCH_1):PAGE38
  EC46 PVDDQ_DEF @BASEBOARD_FAB2_LIB.BASEBOARD_FAB2(SCH_1):PVDDQ_DEF    I33 @BASEBOARD_FAB2_LIB.BASEBOARD_FAB2(SCH_1):PAGE38
  EC48 PVDDQ_DEF @BASEBOARD_FAB2_LIB.BASEBOARD_FAB2(SCH_1):PVDDQ_DEF    I33 @BASEBOARD_FAB2_LIB.BASEBOARD_FAB2(SCH_1):PAGE38
  EC50 PVDDQ_DEF @BASEBOARD_FAB2_LIB.BASEBOARD_FAB2(SCH_1):PVDDQ_DEF    I33 @BASEBOARD_FAB2_LIB.BASEBOARD_FAB2(SCH_1):PAGE38
  EC52 PVDDQ_DEF @BASEBOARD_FAB2_LIB.BASEBOARD_FAB2(SCH_1):PVDDQ_DEF    I33 @BASEBOARD_FAB2_LIB.BASEBOARD_FAB2(SCH_1):PAGE38
  EC54 PVDDQ_DEF @BASEBOARD_FAB2_LIB.BASEBOARD_FAB2(SCH_1):PVDDQ_DEF    I33 @BASEBOARD_FAB2_LIB.BASEBOARD_FAB2(SCH_1):PAGE38
  EC56 PVDDQ_DEF @BASEBOARD_FAB2_LIB.BASEBOARD_FAB2(SCH_1):PVDDQ_DEF    I33 @BASEBOARD_FAB2_LIB.BASEBOARD_FAB2(SCH_1):PAGE38
  EC58 PVDDQ_DEF @BASEBOARD_FAB2_LIB.BASEBOARD_FAB2(SCH_1):PVDDQ_DEF    I33 @BASEBOARD_FAB2_LIB.BASEBOARD_FAB2(SCH_1):PAGE38
  EC60 PVDDQ_DEF @BASEBOARD_FAB2_LIB.BASEBOARD_FAB2(SCH_1):PVDDQ_DEF    I33 @BASEBOARD_FAB2_LIB.BASEBOARD_FAB2(SCH_1):PAGE38
  EC62 PVDDQ_DEF @BASEBOARD_FAB2_LIB.BASEBOARD_FAB2(SCH_1):PVDDQ_DEF    I33 @BASEBOARD_FAB2_LIB.BASEBOARD_FAB2(SCH_1):PAGE38
  EF49 PVDDQ_DEF @BASEBOARD_FAB2_LIB.BASEBOARD_FAB2(SCH_1):PVDDQ_DEF    I33 @BASEBOARD_FAB2_LIB.BASEBOARD_FAB2(SCH_1):PAGE38
  EF53 PVDDQ_DEF @BASEBOARD_FAB2_LIB.BASEBOARD_FAB2(SCH_1):PVDDQ_DEF    I33 @BASEBOARD_FAB2_LIB.BASEBOARD_FAB2(SCH_1):PAGE38
  EF59 PVDDQ_DEF @BASEBOARD_FAB2_LIB.BASEBOARD_FAB2(SCH_1):PVDDQ_DEF    I33 @BASEBOARD_FAB2_LIB.BASEBOARD_FAB2(SCH_1):PAGE38
  BY27 P1V8_MCP_CPU0 @BASEBOARD_FAB2_LIB.BASEBOARD_FAB2(SCH_1):P1V8_MCP_CPU0    I34 @BASEBOARD_FAB2_LIB.BASEBOARD_FAB2(SCH_1):PAGE38
  BV27 P1V8_MCP_CPU0 @BASEBOARD_FAB2_LIB.BASEBOARD_FAB2(SCH_1):P1V8_MCP_CPU0    I34 @BASEBOARD_FAB2_LIB.BASEBOARD_FAB2(SCH_1):PAGE38
  BU26 P1V8_MCP_CPU0 @BASEBOARD_FAB2_LIB.BASEBOARD_FAB2(SCH_1):P1V8_MCP_CPU0    I34 @BASEBOARD_FAB2_LIB.BASEBOARD_FAB2(SCH_1):PAGE38
  BT27 P1V8_MCP_CPU0 @BASEBOARD_FAB2_LIB.BASEBOARD_FAB2(SCH_1):P1V8_MCP_CPU0    I34 @BASEBOARD_FAB2_LIB.BASEBOARD_FAB2(SCH_1):PAGE38
  BM11 PVCCIOMCP_CPU0 @BASEBOARD_FAB2_LIB.BASEBOARD_FAB2(SCH_1):PVCCIOMCP_CPU0    I34 @BASEBOARD_FAB2_LIB.BASEBOARD_FAB2(SCH_1):PAGE38
  BN12 PVCCIOMCP_CPU0 @BASEBOARD_FAB2_LIB.BASEBOARD_FAB2(SCH_1):PVCCIOMCP_CPU0    I34 @BASEBOARD_FAB2_LIB.BASEBOARD_FAB2(SCH_1):PAGE38
  BN14 PVCCIOMCP_CPU0 @BASEBOARD_FAB2_LIB.BASEBOARD_FAB2(SCH_1):PVCCIOMCP_CPU0    I34 @BASEBOARD_FAB2_LIB.BASEBOARD_FAB2(SCH_1):PAGE38
  BP11 PVCCIOMCP_CPU0 @BASEBOARD_FAB2_LIB.BASEBOARD_FAB2(SCH_1):PVCCIOMCP_CPU0    I34 @BASEBOARD_FAB2_LIB.BASEBOARD_FAB2(SCH_1):PAGE38
  BP13 PVCCIOMCP_CPU0 @BASEBOARD_FAB2_LIB.BASEBOARD_FAB2(SCH_1):PVCCIOMCP_CPU0    I34 @BASEBOARD_FAB2_LIB.BASEBOARD_FAB2(SCH_1):PAGE38
  BP15 PVCCIOMCP_CPU0 @BASEBOARD_FAB2_LIB.BASEBOARD_FAB2(SCH_1):PVCCIOMCP_CPU0    I34 @BASEBOARD_FAB2_LIB.BASEBOARD_FAB2(SCH_1):PAGE38
  BR12 PVCCIOMCP_CPU0 @BASEBOARD_FAB2_LIB.BASEBOARD_FAB2(SCH_1):PVCCIOMCP_CPU0    I34 @BASEBOARD_FAB2_LIB.BASEBOARD_FAB2(SCH_1):PAGE38
  BR14 PVCCIOMCP_CPU0 @BASEBOARD_FAB2_LIB.BASEBOARD_FAB2(SCH_1):PVCCIOMCP_CPU0    I34 @BASEBOARD_FAB2_LIB.BASEBOARD_FAB2(SCH_1):PAGE38
  BT11 PVCCIOMCP_CPU0 @BASEBOARD_FAB2_LIB.BASEBOARD_FAB2(SCH_1):PVCCIOMCP_CPU0    I34 @BASEBOARD_FAB2_LIB.BASEBOARD_FAB2(SCH_1):PAGE38
  BT13 PVCCIOMCP_CPU0 @BASEBOARD_FAB2_LIB.BASEBOARD_FAB2(SCH_1):PVCCIOMCP_CPU0    I34 @BASEBOARD_FAB2_LIB.BASEBOARD_FAB2(SCH_1):PAGE38
  BT15 PVCCIOMCP_CPU0 @BASEBOARD_FAB2_LIB.BASEBOARD_FAB2(SCH_1):PVCCIOMCP_CPU0    I34 @BASEBOARD_FAB2_LIB.BASEBOARD_FAB2(SCH_1):PAGE38
  BU12 PVCCIOMCP_CPU0 @BASEBOARD_FAB2_LIB.BASEBOARD_FAB2(SCH_1):PVCCIOMCP_CPU0    I34 @BASEBOARD_FAB2_LIB.BASEBOARD_FAB2(SCH_1):PAGE38
  BU14 PVCCIOMCP_CPU0 @BASEBOARD_FAB2_LIB.BASEBOARD_FAB2(SCH_1):PVCCIOMCP_CPU0    I34 @BASEBOARD_FAB2_LIB.BASEBOARD_FAB2(SCH_1):PAGE38
  BV11 PVCCIOMCP_CPU0 @BASEBOARD_FAB2_LIB.BASEBOARD_FAB2(SCH_1):PVCCIOMCP_CPU0    I34 @BASEBOARD_FAB2_LIB.BASEBOARD_FAB2(SCH_1):PAGE38
  BV13 PVCCIOMCP_CPU0 @BASEBOARD_FAB2_LIB.BASEBOARD_FAB2(SCH_1):PVCCIOMCP_CPU0    I34 @BASEBOARD_FAB2_LIB.BASEBOARD_FAB2(SCH_1):PAGE38
  BV15 PVCCIOMCP_CPU0 @BASEBOARD_FAB2_LIB.BASEBOARD_FAB2(SCH_1):PVCCIOMCP_CPU0    I34 @BASEBOARD_FAB2_LIB.BASEBOARD_FAB2(SCH_1):PAGE38
  BD13 PVCCMCP_CPU0 @BASEBOARD_FAB2_LIB.BASEBOARD_FAB2(SCH_1):PVCCMCP_CPU0    I34 @BASEBOARD_FAB2_LIB.BASEBOARD_FAB2(SCH_1):PAGE38
  BE12 PVCCMCP_CPU0 @BASEBOARD_FAB2_LIB.BASEBOARD_FAB2(SCH_1):PVCCMCP_CPU0    I34 @BASEBOARD_FAB2_LIB.BASEBOARD_FAB2(SCH_1):PAGE38
  BE14 PVCCMCP_CPU0 @BASEBOARD_FAB2_LIB.BASEBOARD_FAB2(SCH_1):PVCCMCP_CPU0    I34 @BASEBOARD_FAB2_LIB.BASEBOARD_FAB2(SCH_1):PAGE38
  BF11 PVCCMCP_CPU0 @BASEBOARD_FAB2_LIB.BASEBOARD_FAB2(SCH_1):PVCCMCP_CPU0    I34 @BASEBOARD_FAB2_LIB.BASEBOARD_FAB2(SCH_1):PAGE38
  BF13 PVCCMCP_CPU0 @BASEBOARD_FAB2_LIB.BASEBOARD_FAB2(SCH_1):PVCCMCP_CPU0    I34 @BASEBOARD_FAB2_LIB.BASEBOARD_FAB2(SCH_1):PAGE38
  BG12 PVCCMCP_CPU0 @BASEBOARD_FAB2_LIB.BASEBOARD_FAB2(SCH_1):PVCCMCP_CPU0    I34 @BASEBOARD_FAB2_LIB.BASEBOARD_FAB2(SCH_1):PAGE38
  BG14 PVCCMCP_CPU0 @BASEBOARD_FAB2_LIB.BASEBOARD_FAB2(SCH_1):PVCCMCP_CPU0    I34 @BASEBOARD_FAB2_LIB.BASEBOARD_FAB2(SCH_1):PAGE38
  BH13 PVCCMCP_CPU0 @BASEBOARD_FAB2_LIB.BASEBOARD_FAB2(SCH_1):PVCCMCP_CPU0    I34 @BASEBOARD_FAB2_LIB.BASEBOARD_FAB2(SCH_1):PAGE38
  BJ12 PVCCMCP_CPU0 @BASEBOARD_FAB2_LIB.BASEBOARD_FAB2(SCH_1):PVCCMCP_CPU0    I34 @BASEBOARD_FAB2_LIB.BASEBOARD_FAB2(SCH_1):PAGE38
  BJ14 PVCCMCP_CPU0 @BASEBOARD_FAB2_LIB.BASEBOARD_FAB2(SCH_1):PVCCMCP_CPU0    I34 @BASEBOARD_FAB2_LIB.BASEBOARD_FAB2(SCH_1):PAGE38
  BK13 PVCCMCP_CPU0 @BASEBOARD_FAB2_LIB.BASEBOARD_FAB2(SCH_1):PVCCMCP_CPU0    I34 @BASEBOARD_FAB2_LIB.BASEBOARD_FAB2(SCH_1):PAGE38
  BK15 PVCCMCP_CPU0 @BASEBOARD_FAB2_LIB.BASEBOARD_FAB2(SCH_1):PVCCMCP_CPU0    I34 @BASEBOARD_FAB2_LIB.BASEBOARD_FAB2(SCH_1):PAGE38
  BL14 PVCCMCP_CPU0 @BASEBOARD_FAB2_LIB.BASEBOARD_FAB2(SCH_1):PVCCMCP_CPU0    I34 @BASEBOARD_FAB2_LIB.BASEBOARD_FAB2(SCH_1):PAGE38
    A8 PVPP_ABC @BASEBOARD_FAB2_LIB.BASEBOARD_FAB2(SCH_1):PVPP_ABC    I34 @BASEBOARD_FAB2_LIB.BASEBOARD_FAB2(SCH_1):PAGE38
   A10 PVPP_ABC @BASEBOARD_FAB2_LIB.BASEBOARD_FAB2(SCH_1):PVPP_ABC    I34 @BASEBOARD_FAB2_LIB.BASEBOARD_FAB2(SCH_1):PAGE38
   A12 PVPP_ABC @BASEBOARD_FAB2_LIB.BASEBOARD_FAB2(SCH_1):PVPP_ABC    I34 @BASEBOARD_FAB2_LIB.BASEBOARD_FAB2(SCH_1):PAGE38
   B11 PVPP_ABC @BASEBOARD_FAB2_LIB.BASEBOARD_FAB2(SCH_1):PVPP_ABC    I34 @BASEBOARD_FAB2_LIB.BASEBOARD_FAB2(SCH_1):PAGE38
  CY55 P3V3_STBY @BASEBOARD_FAB2_LIB.BASEBOARD_FAB2(SCH_1):P3V3_STBY    I34 @BASEBOARD_FAB2_LIB.BASEBOARD_FAB2(SCH_1):PAGE38
  AR28 PVCCIO_CPU0 @BASEBOARD_FAB2_LIB.BASEBOARD_FAB2(SCH_1):PVCCIO_CPU0    I34 @BASEBOARD_FAB2_LIB.BASEBOARD_FAB2(SCH_1):PAGE38
  AL28 PVCCIO_CPU0 @BASEBOARD_FAB2_LIB.BASEBOARD_FAB2(SCH_1):PVCCIO_CPU0    I34 @BASEBOARD_FAB2_LIB.BASEBOARD_FAB2(SCH_1):PAGE38
  AM29 PVCCIO_CPU0 @BASEBOARD_FAB2_LIB.BASEBOARD_FAB2(SCH_1):PVCCIO_CPU0    I34 @BASEBOARD_FAB2_LIB.BASEBOARD_FAB2(SCH_1):PAGE38
  AG34 PVCCIO_CPU0 @BASEBOARD_FAB2_LIB.BASEBOARD_FAB2(SCH_1):PVCCIO_CPU0    I34 @BASEBOARD_FAB2_LIB.BASEBOARD_FAB2(SCH_1):PAGE38
  AE34 PVCCIO_CPU0 @BASEBOARD_FAB2_LIB.BASEBOARD_FAB2(SCH_1):PVCCIO_CPU0    I34 @BASEBOARD_FAB2_LIB.BASEBOARD_FAB2(SCH_1):PAGE38
  AD35 PVCCIO_CPU0 @BASEBOARD_FAB2_LIB.BASEBOARD_FAB2(SCH_1):PVCCIO_CPU0    I34 @BASEBOARD_FAB2_LIB.BASEBOARD_FAB2(SCH_1):PAGE38
  AF35 PVCCIO_CPU0 @BASEBOARD_FAB2_LIB.BASEBOARD_FAB2(SCH_1):PVCCIO_CPU0    I34 @BASEBOARD_FAB2_LIB.BASEBOARD_FAB2(SCH_1):PAGE38
  AC36 PVCCIO_CPU0 @BASEBOARD_FAB2_LIB.BASEBOARD_FAB2(SCH_1):PVCCIO_CPU0    I34 @BASEBOARD_FAB2_LIB.BASEBOARD_FAB2(SCH_1):PAGE38
  AD37 PVCCIO_CPU0 @BASEBOARD_FAB2_LIB.BASEBOARD_FAB2(SCH_1):PVCCIO_CPU0    I34 @BASEBOARD_FAB2_LIB.BASEBOARD_FAB2(SCH_1):PAGE38
  AE36 PVCCIO_CPU0 @BASEBOARD_FAB2_LIB.BASEBOARD_FAB2(SCH_1):PVCCIO_CPU0    I34 @BASEBOARD_FAB2_LIB.BASEBOARD_FAB2(SCH_1):PAGE38
  BF27 PVCCIO_CPU0 @BASEBOARD_FAB2_LIB.BASEBOARD_FAB2(SCH_1):PVCCIO_CPU0    I34 @BASEBOARD_FAB2_LIB.BASEBOARD_FAB2(SCH_1):PAGE38
  BG26 PVCCIO_CPU0 @BASEBOARD_FAB2_LIB.BASEBOARD_FAB2(SCH_1):PVCCIO_CPU0    I34 @BASEBOARD_FAB2_LIB.BASEBOARD_FAB2(SCH_1):PAGE38
  BH25 PVCCIO_CPU0 @BASEBOARD_FAB2_LIB.BASEBOARD_FAB2(SCH_1):PVCCIO_CPU0    I34 @BASEBOARD_FAB2_LIB.BASEBOARD_FAB2(SCH_1):PAGE38
  BH27 PVCCIO_CPU0 @BASEBOARD_FAB2_LIB.BASEBOARD_FAB2(SCH_1):PVCCIO_CPU0    I34 @BASEBOARD_FAB2_LIB.BASEBOARD_FAB2(SCH_1):PAGE38
  BJ26 PVCCIO_CPU0 @BASEBOARD_FAB2_LIB.BASEBOARD_FAB2(SCH_1):PVCCIO_CPU0    I34 @BASEBOARD_FAB2_LIB.BASEBOARD_FAB2(SCH_1):PAGE38
  BK25 PVCCIO_CPU0 @BASEBOARD_FAB2_LIB.BASEBOARD_FAB2(SCH_1):PVCCIO_CPU0    I34 @BASEBOARD_FAB2_LIB.BASEBOARD_FAB2(SCH_1):PAGE38
  BK27 PVCCIO_CPU0 @BASEBOARD_FAB2_LIB.BASEBOARD_FAB2(SCH_1):PVCCIO_CPU0    I34 @BASEBOARD_FAB2_LIB.BASEBOARD_FAB2(SCH_1):PAGE38
  BL26 PVCCIO_CPU0 @BASEBOARD_FAB2_LIB.BASEBOARD_FAB2(SCH_1):PVCCIO_CPU0    I34 @BASEBOARD_FAB2_LIB.BASEBOARD_FAB2(SCH_1):PAGE38
  BM27 PVCCIO_CPU0 @BASEBOARD_FAB2_LIB.BASEBOARD_FAB2(SCH_1):PVCCIO_CPU0    I34 @BASEBOARD_FAB2_LIB.BASEBOARD_FAB2(SCH_1):PAGE38
  CH27 PVCCIO_CPU0 @BASEBOARD_FAB2_LIB.BASEBOARD_FAB2(SCH_1):PVCCIO_CPU0    I34 @BASEBOARD_FAB2_LIB.BASEBOARD_FAB2(SCH_1):PAGE38
  CJ28 PVCCIO_CPU0 @BASEBOARD_FAB2_LIB.BASEBOARD_FAB2(SCH_1):PVCCIO_CPU0    I34 @BASEBOARD_FAB2_LIB.BASEBOARD_FAB2(SCH_1):PAGE38
  CC26 PVCCIO_CPU0 @BASEBOARD_FAB2_LIB.BASEBOARD_FAB2(SCH_1):PVCCIO_CPU0    I34 @BASEBOARD_FAB2_LIB.BASEBOARD_FAB2(SCH_1):PAGE38
  CD27 PVCCIO_CPU0 @BASEBOARD_FAB2_LIB.BASEBOARD_FAB2(SCH_1):PVCCIO_CPU0    I34 @BASEBOARD_FAB2_LIB.BASEBOARD_FAB2(SCH_1):PAGE38
  CF27 PVCCIO_CPU0 @BASEBOARD_FAB2_LIB.BASEBOARD_FAB2(SCH_1):PVCCIO_CPU0    I34 @BASEBOARD_FAB2_LIB.BASEBOARD_FAB2(SCH_1):PAGE38
  AV27 PVCCIO_CPU0 @BASEBOARD_FAB2_LIB.BASEBOARD_FAB2(SCH_1):PVCCIO_CPU0    I34 @BASEBOARD_FAB2_LIB.BASEBOARD_FAB2(SCH_1):PAGE38
  AW26 PVCCIO_CPU0 @BASEBOARD_FAB2_LIB.BASEBOARD_FAB2(SCH_1):PVCCIO_CPU0    I34 @BASEBOARD_FAB2_LIB.BASEBOARD_FAB2(SCH_1):PAGE38
  AY27 PVCCIO_CPU0 @BASEBOARD_FAB2_LIB.BASEBOARD_FAB2(SCH_1):PVCCIO_CPU0    I34 @BASEBOARD_FAB2_LIB.BASEBOARD_FAB2(SCH_1):PAGE38
  BA26 PVCCIO_CPU0 @BASEBOARD_FAB2_LIB.BASEBOARD_FAB2(SCH_1):PVCCIO_CPU0    I34 @BASEBOARD_FAB2_LIB.BASEBOARD_FAB2(SCH_1):PAGE38
  BB27 PVCCIO_CPU0 @BASEBOARD_FAB2_LIB.BASEBOARD_FAB2(SCH_1):PVCCIO_CPU0    I34 @BASEBOARD_FAB2_LIB.BASEBOARD_FAB2(SCH_1):PAGE38
  BC26 PVCCIO_CPU0 @BASEBOARD_FAB2_LIB.BASEBOARD_FAB2(SCH_1):PVCCIO_CPU0    I34 @BASEBOARD_FAB2_LIB.BASEBOARD_FAB2(SCH_1):PAGE38
   W10 PVCCIO_CPU0 @BASEBOARD_FAB2_LIB.BASEBOARD_FAB2(SCH_1):PVCCIO_CPU0    I34 @BASEBOARD_FAB2_LIB.BASEBOARD_FAB2(SCH_1):PAGE38
   N18 PVCCIO_CPU0 @BASEBOARD_FAB2_LIB.BASEBOARD_FAB2(SCH_1):PVCCIO_CPU0    I34 @BASEBOARD_FAB2_LIB.BASEBOARD_FAB2(SCH_1):PAGE38
    M9 PVCCIO_CPU0 @BASEBOARD_FAB2_LIB.BASEBOARD_FAB2(SCH_1):PVCCIO_CPU0    I34 @BASEBOARD_FAB2_LIB.BASEBOARD_FAB2(SCH_1):PAGE38
    M7 PVCCIO_CPU0 @BASEBOARD_FAB2_LIB.BASEBOARD_FAB2(SCH_1):PVCCIO_CPU0    I34 @BASEBOARD_FAB2_LIB.BASEBOARD_FAB2(SCH_1):PAGE38
   K15 PVCCIO_CPU0 @BASEBOARD_FAB2_LIB.BASEBOARD_FAB2(SCH_1):PVCCIO_CPU0    I34 @BASEBOARD_FAB2_LIB.BASEBOARD_FAB2(SCH_1):PAGE38
    J2 PVCCIO_CPU0 @BASEBOARD_FAB2_LIB.BASEBOARD_FAB2(SCH_1):PVCCIO_CPU0    I34 @BASEBOARD_FAB2_LIB.BASEBOARD_FAB2(SCH_1):PAGE38
  EB15 PVCCIO_CPU0 @BASEBOARD_FAB2_LIB.BASEBOARD_FAB2(SCH_1):PVCCIO_CPU0    I34 @BASEBOARD_FAB2_LIB.BASEBOARD_FAB2(SCH_1):PAGE38
  EA12 PVCCIO_CPU0 @BASEBOARD_FAB2_LIB.BASEBOARD_FAB2(SCH_1):PVCCIO_CPU0    I34 @BASEBOARD_FAB2_LIB.BASEBOARD_FAB2(SCH_1):PAGE38
  DU20 PVCCIO_CPU0 @BASEBOARD_FAB2_LIB.BASEBOARD_FAB2(SCH_1):PVCCIO_CPU0    I34 @BASEBOARD_FAB2_LIB.BASEBOARD_FAB2(SCH_1):PAGE38
   DR2 PVCCIO_CPU0 @BASEBOARD_FAB2_LIB.BASEBOARD_FAB2(SCH_1):PVCCIO_CPU0    I34 @BASEBOARD_FAB2_LIB.BASEBOARD_FAB2(SCH_1):PAGE38
  DR10 PVCCIO_CPU0 @BASEBOARD_FAB2_LIB.BASEBOARD_FAB2(SCH_1):PVCCIO_CPU0    I34 @BASEBOARD_FAB2_LIB.BASEBOARD_FAB2(SCH_1):PAGE38
  DP19 PVCCIO_CPU0 @BASEBOARD_FAB2_LIB.BASEBOARD_FAB2(SCH_1):PVCCIO_CPU0    I34 @BASEBOARD_FAB2_LIB.BASEBOARD_FAB2(SCH_1):PAGE38
   DN8 PVCCIO_CPU0 @BASEBOARD_FAB2_LIB.BASEBOARD_FAB2(SCH_1):PVCCIO_CPU0    I34 @BASEBOARD_FAB2_LIB.BASEBOARD_FAB2(SCH_1):PAGE38
  DM17 PVCCIO_CPU0 @BASEBOARD_FAB2_LIB.BASEBOARD_FAB2(SCH_1):PVCCIO_CPU0    I34 @BASEBOARD_FAB2_LIB.BASEBOARD_FAB2(SCH_1):PAGE38
  DJ16 PVCCIO_CPU0 @BASEBOARD_FAB2_LIB.BASEBOARD_FAB2(SCH_1):PVCCIO_CPU0    I34 @BASEBOARD_FAB2_LIB.BASEBOARD_FAB2(SCH_1):PAGE38
   H13 PVCCIO_CPU0 @BASEBOARD_FAB2_LIB.BASEBOARD_FAB2(SCH_1):PVCCIO_CPU0    I34 @BASEBOARD_FAB2_LIB.BASEBOARD_FAB2(SCH_1):PAGE38
   J10 PVCCIO_CPU0 @BASEBOARD_FAB2_LIB.BASEBOARD_FAB2(SCH_1):PVCCIO_CPU0    I34 @BASEBOARD_FAB2_LIB.BASEBOARD_FAB2(SCH_1):PAGE38
   L14 PVCCIO_CPU0 @BASEBOARD_FAB2_LIB.BASEBOARD_FAB2(SCH_1):PVCCIO_CPU0    I34 @BASEBOARD_FAB2_LIB.BASEBOARD_FAB2(SCH_1):PAGE38
   L16 PVCCIO_CPU0 @BASEBOARD_FAB2_LIB.BASEBOARD_FAB2(SCH_1):PVCCIO_CPU0    I34 @BASEBOARD_FAB2_LIB.BASEBOARD_FAB2(SCH_1):PAGE38
   DH7 PVCCIO_CPU0 @BASEBOARD_FAB2_LIB.BASEBOARD_FAB2(SCH_1):PVCCIO_CPU0    I34 @BASEBOARD_FAB2_LIB.BASEBOARD_FAB2(SCH_1):PAGE38
   DG8 PVCCIO_CPU0 @BASEBOARD_FAB2_LIB.BASEBOARD_FAB2(SCH_1):PVCCIO_CPU0    I34 @BASEBOARD_FAB2_LIB.BASEBOARD_FAB2(SCH_1):PAGE38
   M11 PVCCIO_CPU0 @BASEBOARD_FAB2_LIB.BASEBOARD_FAB2(SCH_1):PVCCIO_CPU0    I34 @BASEBOARD_FAB2_LIB.BASEBOARD_FAB2(SCH_1):PAGE38
   M21 PVCCIO_CPU0 @BASEBOARD_FAB2_LIB.BASEBOARD_FAB2(SCH_1):PVCCIO_CPU0    I34 @BASEBOARD_FAB2_LIB.BASEBOARD_FAB2(SCH_1):PAGE38
    P5 PVCCIO_CPU0 @BASEBOARD_FAB2_LIB.BASEBOARD_FAB2(SCH_1):PVCCIO_CPU0    I34 @BASEBOARD_FAB2_LIB.BASEBOARD_FAB2(SCH_1):PAGE38
    T3 PVCCIO_CPU0 @BASEBOARD_FAB2_LIB.BASEBOARD_FAB2(SCH_1):PVCCIO_CPU0    I34 @BASEBOARD_FAB2_LIB.BASEBOARD_FAB2(SCH_1):PAGE38
   U14 PVCCIO_CPU0 @BASEBOARD_FAB2_LIB.BASEBOARD_FAB2(SCH_1):PVCCIO_CPU0    I34 @BASEBOARD_FAB2_LIB.BASEBOARD_FAB2(SCH_1):PAGE38
  DF21 PVCCIO_CPU0 @BASEBOARD_FAB2_LIB.BASEBOARD_FAB2(SCH_1):PVCCIO_CPU0    I34 @BASEBOARD_FAB2_LIB.BASEBOARD_FAB2(SCH_1):PAGE38
    W4 PVCCIO_CPU0 @BASEBOARD_FAB2_LIB.BASEBOARD_FAB2(SCH_1):PVCCIO_CPU0    I34 @BASEBOARD_FAB2_LIB.BASEBOARD_FAB2(SCH_1):PAGE38
    W6 PVCCIO_CPU0 @BASEBOARD_FAB2_LIB.BASEBOARD_FAB2(SCH_1):PVCCIO_CPU0    I34 @BASEBOARD_FAB2_LIB.BASEBOARD_FAB2(SCH_1):PAGE38
  AA10 PVCCIO_CPU0 @BASEBOARD_FAB2_LIB.BASEBOARD_FAB2(SCH_1):PVCCIO_CPU0    I34 @BASEBOARD_FAB2_LIB.BASEBOARD_FAB2(SCH_1):PAGE38
  AC20 PVCCIO_CPU0 @BASEBOARD_FAB2_LIB.BASEBOARD_FAB2(SCH_1):PVCCIO_CPU0    I34 @BASEBOARD_FAB2_LIB.BASEBOARD_FAB2(SCH_1):PAGE38
   AC4 PVCCIO_CPU0 @BASEBOARD_FAB2_LIB.BASEBOARD_FAB2(SCH_1):PVCCIO_CPU0    I34 @BASEBOARD_FAB2_LIB.BASEBOARD_FAB2(SCH_1):PAGE38
   AH9 PVCCIO_CPU0 @BASEBOARD_FAB2_LIB.BASEBOARD_FAB2(SCH_1):PVCCIO_CPU0    I34 @BASEBOARD_FAB2_LIB.BASEBOARD_FAB2(SCH_1):PAGE38
  DF13 PVCCIO_CPU0 @BASEBOARD_FAB2_LIB.BASEBOARD_FAB2(SCH_1):PVCCIO_CPU0    I34 @BASEBOARD_FAB2_LIB.BASEBOARD_FAB2(SCH_1):PAGE38
  AN10 PVCCIO_CPU0 @BASEBOARD_FAB2_LIB.BASEBOARD_FAB2(SCH_1):PVCCIO_CPU0    I34 @BASEBOARD_FAB2_LIB.BASEBOARD_FAB2(SCH_1):PAGE38
   DD7 PVCCIO_CPU0 @BASEBOARD_FAB2_LIB.BASEBOARD_FAB2(SCH_1):PVCCIO_CPU0    I34 @BASEBOARD_FAB2_LIB.BASEBOARD_FAB2(SCH_1):PAGE38
  AT11 PVCCIO_CPU0 @BASEBOARD_FAB2_LIB.BASEBOARD_FAB2(SCH_1):PVCCIO_CPU0    I34 @BASEBOARD_FAB2_LIB.BASEBOARD_FAB2(SCH_1):PAGE38
   AW6 PVCCIO_CPU0 @BASEBOARD_FAB2_LIB.BASEBOARD_FAB2(SCH_1):PVCCIO_CPU0    I34 @BASEBOARD_FAB2_LIB.BASEBOARD_FAB2(SCH_1):PAGE38
  AY11 PVCCIO_CPU0 @BASEBOARD_FAB2_LIB.BASEBOARD_FAB2(SCH_1):PVCCIO_CPU0    I34 @BASEBOARD_FAB2_LIB.BASEBOARD_FAB2(SCH_1):PAGE38
  BA24 PVCCIO_CPU0 @BASEBOARD_FAB2_LIB.BASEBOARD_FAB2(SCH_1):PVCCIO_CPU0    I34 @BASEBOARD_FAB2_LIB.BASEBOARD_FAB2(SCH_1):PAGE38
   BB5 PVCCIO_CPU0 @BASEBOARD_FAB2_LIB.BASEBOARD_FAB2(SCH_1):PVCCIO_CPU0    I34 @BASEBOARD_FAB2_LIB.BASEBOARD_FAB2(SCH_1):PAGE38
  DA14 PVCCIO_CPU0 @BASEBOARD_FAB2_LIB.BASEBOARD_FAB2(SCH_1):PVCCIO_CPU0    I34 @BASEBOARD_FAB2_LIB.BASEBOARD_FAB2(SCH_1):PAGE38
  BF23 PVCCIO_CPU0 @BASEBOARD_FAB2_LIB.BASEBOARD_FAB2(SCH_1):PVCCIO_CPU0    I34 @BASEBOARD_FAB2_LIB.BASEBOARD_FAB2(SCH_1):PAGE38
  BJ24 PVCCIO_CPU0 @BASEBOARD_FAB2_LIB.BASEBOARD_FAB2(SCH_1):PVCCIO_CPU0    I34 @BASEBOARD_FAB2_LIB.BASEBOARD_FAB2(SCH_1):PAGE38
  BP25 PVCCIO_CPU0 @BASEBOARD_FAB2_LIB.BASEBOARD_FAB2(SCH_1):PVCCIO_CPU0    I34 @BASEBOARD_FAB2_LIB.BASEBOARD_FAB2(SCH_1):PAGE38
  CB13 PVCCIO_CPU0 @BASEBOARD_FAB2_LIB.BASEBOARD_FAB2(SCH_1):PVCCIO_CPU0    I34 @BASEBOARD_FAB2_LIB.BASEBOARD_FAB2(SCH_1):PAGE38
  CB17 PVCCIO_CPU0 @BASEBOARD_FAB2_LIB.BASEBOARD_FAB2(SCH_1):PVCCIO_CPU0    I34 @BASEBOARD_FAB2_LIB.BASEBOARD_FAB2(SCH_1):PAGE38
   CD9 PVCCIO_CPU0 @BASEBOARD_FAB2_LIB.BASEBOARD_FAB2(SCH_1):PVCCIO_CPU0    I34 @BASEBOARD_FAB2_LIB.BASEBOARD_FAB2(SCH_1):PAGE38
  CE18 PVCCIO_CPU0 @BASEBOARD_FAB2_LIB.BASEBOARD_FAB2(SCH_1):PVCCIO_CPU0    I34 @BASEBOARD_FAB2_LIB.BASEBOARD_FAB2(SCH_1):PAGE38
    D7 PVCCIO_CPU0 @BASEBOARD_FAB2_LIB.BASEBOARD_FAB2(SCH_1):PVCCIO_CPU0    I34 @BASEBOARD_FAB2_LIB.BASEBOARD_FAB2(SCH_1):PAGE38
   CH9 PVCCIO_CPU0 @BASEBOARD_FAB2_LIB.BASEBOARD_FAB2(SCH_1):PVCCIO_CPU0    I34 @BASEBOARD_FAB2_LIB.BASEBOARD_FAB2(SCH_1):PAGE38
   CV7 PVCCIO_CPU0 @BASEBOARD_FAB2_LIB.BASEBOARD_FAB2(SCH_1):PVCCIO_CPU0    I34 @BASEBOARD_FAB2_LIB.BASEBOARD_FAB2(SCH_1):PAGE38
   CK5 PVCCIO_CPU0 @BASEBOARD_FAB2_LIB.BASEBOARD_FAB2(SCH_1):PVCCIO_CPU0    I34 @BASEBOARD_FAB2_LIB.BASEBOARD_FAB2(SCH_1):PAGE38
  CL12 PVCCIO_CPU0 @BASEBOARD_FAB2_LIB.BASEBOARD_FAB2(SCH_1):PVCCIO_CPU0    I34 @BASEBOARD_FAB2_LIB.BASEBOARD_FAB2(SCH_1):PAGE38
  CM15 PVCCIO_CPU0 @BASEBOARD_FAB2_LIB.BASEBOARD_FAB2(SCH_1):PVCCIO_CPU0    I34 @BASEBOARD_FAB2_LIB.BASEBOARD_FAB2(SCH_1):PAGE38
  CB65 PVSA_CPU0 @BASEBOARD_FAB2_LIB.BASEBOARD_FAB2(SCH_1):PVSA_CPU0    I34 @BASEBOARD_FAB2_LIB.BASEBOARD_FAB2(SCH_1):PAGE38
  CB67 PVSA_CPU0 @BASEBOARD_FAB2_LIB.BASEBOARD_FAB2(SCH_1):PVSA_CPU0    I34 @BASEBOARD_FAB2_LIB.BASEBOARD_FAB2(SCH_1):PAGE38
  CB69 PVSA_CPU0 @BASEBOARD_FAB2_LIB.BASEBOARD_FAB2(SCH_1):PVSA_CPU0    I34 @BASEBOARD_FAB2_LIB.BASEBOARD_FAB2(SCH_1):PAGE38
  CC66 PVSA_CPU0 @BASEBOARD_FAB2_LIB.BASEBOARD_FAB2(SCH_1):PVSA_CPU0    I34 @BASEBOARD_FAB2_LIB.BASEBOARD_FAB2(SCH_1):PAGE38
  CC68 PVSA_CPU0 @BASEBOARD_FAB2_LIB.BASEBOARD_FAB2(SCH_1):PVSA_CPU0    I34 @BASEBOARD_FAB2_LIB.BASEBOARD_FAB2(SCH_1):PAGE38
  CC70 PVSA_CPU0 @BASEBOARD_FAB2_LIB.BASEBOARD_FAB2(SCH_1):PVSA_CPU0    I34 @BASEBOARD_FAB2_LIB.BASEBOARD_FAB2(SCH_1):PAGE38
  CD65 PVSA_CPU0 @BASEBOARD_FAB2_LIB.BASEBOARD_FAB2(SCH_1):PVSA_CPU0    I34 @BASEBOARD_FAB2_LIB.BASEBOARD_FAB2(SCH_1):PAGE38
  CD67 PVSA_CPU0 @BASEBOARD_FAB2_LIB.BASEBOARD_FAB2(SCH_1):PVSA_CPU0    I34 @BASEBOARD_FAB2_LIB.BASEBOARD_FAB2(SCH_1):PAGE38
  CD69 PVSA_CPU0 @BASEBOARD_FAB2_LIB.BASEBOARD_FAB2(SCH_1):PVSA_CPU0    I34 @BASEBOARD_FAB2_LIB.BASEBOARD_FAB2(SCH_1):PAGE38
  CD71 PVSA_CPU0 @BASEBOARD_FAB2_LIB.BASEBOARD_FAB2(SCH_1):PVSA_CPU0    I34 @BASEBOARD_FAB2_LIB.BASEBOARD_FAB2(SCH_1):PAGE38
  CE64 PVSA_CPU0 @BASEBOARD_FAB2_LIB.BASEBOARD_FAB2(SCH_1):PVSA_CPU0    I34 @BASEBOARD_FAB2_LIB.BASEBOARD_FAB2(SCH_1):PAGE38
  CE66 PVSA_CPU0 @BASEBOARD_FAB2_LIB.BASEBOARD_FAB2(SCH_1):PVSA_CPU0    I34 @BASEBOARD_FAB2_LIB.BASEBOARD_FAB2(SCH_1):PAGE38
  CE68 PVSA_CPU0 @BASEBOARD_FAB2_LIB.BASEBOARD_FAB2(SCH_1):PVSA_CPU0    I34 @BASEBOARD_FAB2_LIB.BASEBOARD_FAB2(SCH_1):PAGE38
  CE72 PVSA_CPU0 @BASEBOARD_FAB2_LIB.BASEBOARD_FAB2(SCH_1):PVSA_CPU0    I34 @BASEBOARD_FAB2_LIB.BASEBOARD_FAB2(SCH_1):PAGE38
  CE74 PVSA_CPU0 @BASEBOARD_FAB2_LIB.BASEBOARD_FAB2(SCH_1):PVSA_CPU0    I34 @BASEBOARD_FAB2_LIB.BASEBOARD_FAB2(SCH_1):PAGE38
  CF65 PVSA_CPU0 @BASEBOARD_FAB2_LIB.BASEBOARD_FAB2(SCH_1):PVSA_CPU0    I34 @BASEBOARD_FAB2_LIB.BASEBOARD_FAB2(SCH_1):PAGE38
  CF67 PVSA_CPU0 @BASEBOARD_FAB2_LIB.BASEBOARD_FAB2(SCH_1):PVSA_CPU0    I34 @BASEBOARD_FAB2_LIB.BASEBOARD_FAB2(SCH_1):PAGE38
  CF73 PVSA_CPU0 @BASEBOARD_FAB2_LIB.BASEBOARD_FAB2(SCH_1):PVSA_CPU0    I34 @BASEBOARD_FAB2_LIB.BASEBOARD_FAB2(SCH_1):PAGE38
  CF75 PVSA_CPU0 @BASEBOARD_FAB2_LIB.BASEBOARD_FAB2(SCH_1):PVSA_CPU0    I34 @BASEBOARD_FAB2_LIB.BASEBOARD_FAB2(SCH_1):PAGE38
  CG64 PVSA_CPU0 @BASEBOARD_FAB2_LIB.BASEBOARD_FAB2(SCH_1):PVSA_CPU0    I34 @BASEBOARD_FAB2_LIB.BASEBOARD_FAB2(SCH_1):PAGE38
  CG66 PVSA_CPU0 @BASEBOARD_FAB2_LIB.BASEBOARD_FAB2(SCH_1):PVSA_CPU0    I34 @BASEBOARD_FAB2_LIB.BASEBOARD_FAB2(SCH_1):PAGE38
  CG74 PVSA_CPU0 @BASEBOARD_FAB2_LIB.BASEBOARD_FAB2(SCH_1):PVSA_CPU0    I34 @BASEBOARD_FAB2_LIB.BASEBOARD_FAB2(SCH_1):PAGE38
  CH65 PVSA_CPU0 @BASEBOARD_FAB2_LIB.BASEBOARD_FAB2(SCH_1):PVSA_CPU0    I34 @BASEBOARD_FAB2_LIB.BASEBOARD_FAB2(SCH_1):PAGE38
  CH75 PVSA_CPU0 @BASEBOARD_FAB2_LIB.BASEBOARD_FAB2(SCH_1):PVSA_CPU0    I34 @BASEBOARD_FAB2_LIB.BASEBOARD_FAB2(SCH_1):PAGE38
  CJ64 PVSA_CPU0 @BASEBOARD_FAB2_LIB.BASEBOARD_FAB2(SCH_1):PVSA_CPU0    I34 @BASEBOARD_FAB2_LIB.BASEBOARD_FAB2(SCH_1):PAGE38
  CJ66 PVSA_CPU0 @BASEBOARD_FAB2_LIB.BASEBOARD_FAB2(SCH_1):PVSA_CPU0    I34 @BASEBOARD_FAB2_LIB.BASEBOARD_FAB2(SCH_1):PAGE38
  BT17 VSENSE_PVCCIOMCP_CPU0_SKT_VSEN @BASEBOARD_FAB2_LIB.BASEBOARD_FAB2(SCH_1):VSENSE_PVCCIOMCP_CPU0_SKT_VSEN   I127 @BASEBOARD_FAB2_LIB.BASEBOARD_FAB2(SCH_1):PAGE39
  BU16 VSENSE_PVCCIOMCP_CPU0_SKT_VRTN @BASEBOARD_FAB2_LIB.BASEBOARD_FAB2(SCH_1):VSENSE_PVCCIOMCP_CPU0_SKT_VRTN   I127 @BASEBOARD_FAB2_LIB.BASEBOARD_FAB2(SCH_1):PAGE39
  BN16 VSENSE_PVCCMCP_CPU0_SKT_VSEN @BASEBOARD_FAB2_LIB.BASEBOARD_FAB2(SCH_1):VSENSE_PVCCMCP_CPU0_SKT_VSEN   I127 @BASEBOARD_FAB2_LIB.BASEBOARD_FAB2(SCH_1):PAGE39
  BL16 VSENSE_PVCCMCP_CPU0_SKT_VRTN @BASEBOARD_FAB2_LIB.BASEBOARD_FAB2(SCH_1):VSENSE_PVCCMCP_CPU0_SKT_VRTN   I127 @BASEBOARD_FAB2_LIB.BASEBOARD_FAB2(SCH_1):PAGE39
  CL26 PVCCMCP_CPU0 @BASEBOARD_FAB2_LIB.BASEBOARD_FAB2(SCH_1):PVCCMCP_CPU0   I127 @BASEBOARD_FAB2_LIB.BASEBOARD_FAB2(SCH_1):PAGE39
  CM23 PVCCMCP_CPU0 @BASEBOARD_FAB2_LIB.BASEBOARD_FAB2(SCH_1):PVCCMCP_CPU0   I127 @BASEBOARD_FAB2_LIB.BASEBOARD_FAB2(SCH_1):PAGE39
  CM25 PVCCMCP_CPU0 @BASEBOARD_FAB2_LIB.BASEBOARD_FAB2(SCH_1):PVCCMCP_CPU0   I127 @BASEBOARD_FAB2_LIB.BASEBOARD_FAB2(SCH_1):PAGE39
  CN22 TP_CPU0_KTI2_AMONV @BASEBOARD_FAB2_LIB.BASEBOARD_FAB2(SCH_1):TP_CPU0_KTI2_AMONV   I127 @BASEBOARD_FAB2_LIB.BASEBOARD_FAB2(SCH_1):PAGE39
  CN24 PVCCMCP_CPU0 @BASEBOARD_FAB2_LIB.BASEBOARD_FAB2(SCH_1):PVCCMCP_CPU0   I127 @BASEBOARD_FAB2_LIB.BASEBOARD_FAB2(SCH_1):PAGE39
  CN28 PD_CPU0_MCP01_DMON @BASEBOARD_FAB2_LIB.BASEBOARD_FAB2(SCH_1):PD_CPU0_MCP01_DMON   I127 @BASEBOARD_FAB2_LIB.BASEBOARD_FAB2(SCH_1):PAGE39
  CP23 PVCCMCP_CPU0 @BASEBOARD_FAB2_LIB.BASEBOARD_FAB2(SCH_1):PVCCMCP_CPU0   I127 @BASEBOARD_FAB2_LIB.BASEBOARD_FAB2(SCH_1):PAGE39
  CP31 TP_CPU0_RSVD_73 @BASEBOARD_FAB2_LIB.BASEBOARD_FAB2(SCH_1):TP_CPU0_RSVD_73   I127 @BASEBOARD_FAB2_LIB.BASEBOARD_FAB2(SCH_1):PAGE39
  CR60 TP_CPU0_RSVD_72 @BASEBOARD_FAB2_LIB.BASEBOARD_FAB2(SCH_1):TP_CPU0_RSVD_72   I127 @BASEBOARD_FAB2_LIB.BASEBOARD_FAB2(SCH_1):PAGE39
  CT23 PVCCMCP_CPU0 @BASEBOARD_FAB2_LIB.BASEBOARD_FAB2(SCH_1):PVCCMCP_CPU0   I127 @BASEBOARD_FAB2_LIB.BASEBOARD_FAB2(SCH_1):PAGE39
   CT5 TP_CPU0_RSVD_70 @BASEBOARD_FAB2_LIB.BASEBOARD_FAB2(SCH_1):TP_CPU0_RSVD_70   I127 @BASEBOARD_FAB2_LIB.BASEBOARD_FAB2(SCH_1):PAGE39
  CT69 TP_CPU0_RSVD_69 @BASEBOARD_FAB2_LIB.BASEBOARD_FAB2(SCH_1):TP_CPU0_RSVD_69   I127 @BASEBOARD_FAB2_LIB.BASEBOARD_FAB2(SCH_1):PAGE39
  CU24 PVCCMCP_CPU0 @BASEBOARD_FAB2_LIB.BASEBOARD_FAB2(SCH_1):PVCCMCP_CPU0   I127 @BASEBOARD_FAB2_LIB.BASEBOARD_FAB2(SCH_1):PAGE39
   CU6 TP_CPU0_RSVD_67 @BASEBOARD_FAB2_LIB.BASEBOARD_FAB2(SCH_1):TP_CPU0_RSVD_67   I127 @BASEBOARD_FAB2_LIB.BASEBOARD_FAB2(SCH_1):PAGE39
  CU60 TP_CPU0_RSVD_66 @BASEBOARD_FAB2_LIB.BASEBOARD_FAB2(SCH_1):TP_CPU0_RSVD_66   I127 @BASEBOARD_FAB2_LIB.BASEBOARD_FAB2(SCH_1):PAGE39
  CV23 PVCCMCP_CPU0 @BASEBOARD_FAB2_LIB.BASEBOARD_FAB2(SCH_1):PVCCMCP_CPU0   I127 @BASEBOARD_FAB2_LIB.BASEBOARD_FAB2(SCH_1):PAGE39
  CV69 TP_CPU0_RSVD_64 @BASEBOARD_FAB2_LIB.BASEBOARD_FAB2(SCH_1):TP_CPU0_RSVD_64   I127 @BASEBOARD_FAB2_LIB.BASEBOARD_FAB2(SCH_1):PAGE39
  CW22 TP_CPU0_KTI2_DFX_DN @BASEBOARD_FAB2_LIB.BASEBOARD_FAB2(SCH_1):TP_CPU0_KTI2_DFX_DN   I127 @BASEBOARD_FAB2_LIB.BASEBOARD_FAB2(SCH_1):PAGE39
  CW24 PVCCMCP_CPU0 @BASEBOARD_FAB2_LIB.BASEBOARD_FAB2(SCH_1):PVCCMCP_CPU0   I127 @BASEBOARD_FAB2_LIB.BASEBOARD_FAB2(SCH_1):PAGE39
  CW60 TP_CPU0_RSVD_61 @BASEBOARD_FAB2_LIB.BASEBOARD_FAB2(SCH_1):TP_CPU0_RSVD_61   I127 @BASEBOARD_FAB2_LIB.BASEBOARD_FAB2(SCH_1):PAGE39
  CW62 TP_CPU0_RSVD_60 @BASEBOARD_FAB2_LIB.BASEBOARD_FAB2(SCH_1):TP_CPU0_RSVD_60   I127 @BASEBOARD_FAB2_LIB.BASEBOARD_FAB2(SCH_1):PAGE39
  CY23 TP_CPU0_RSVD_59 @BASEBOARD_FAB2_LIB.BASEBOARD_FAB2(SCH_1):TP_CPU0_RSVD_59   I127 @BASEBOARD_FAB2_LIB.BASEBOARD_FAB2(SCH_1):PAGE39
  CY25 PVCCMCP_CPU0 @BASEBOARD_FAB2_LIB.BASEBOARD_FAB2(SCH_1):PVCCMCP_CPU0   I127 @BASEBOARD_FAB2_LIB.BASEBOARD_FAB2(SCH_1):PAGE39
  CY39 TP_CPU0_RSVD_57 @BASEBOARD_FAB2_LIB.BASEBOARD_FAB2(SCH_1):TP_CPU0_RSVD_57   I127 @BASEBOARD_FAB2_LIB.BASEBOARD_FAB2(SCH_1):PAGE39
  CY53 TP_CPU0_RSVD_56 @BASEBOARD_FAB2_LIB.BASEBOARD_FAB2(SCH_1):TP_CPU0_RSVD_56   I127 @BASEBOARD_FAB2_LIB.BASEBOARD_FAB2(SCH_1):PAGE39
  CY57 TP_CPU0_RSVD_55 @BASEBOARD_FAB2_LIB.BASEBOARD_FAB2(SCH_1):TP_CPU0_RSVD_55   I127 @BASEBOARD_FAB2_LIB.BASEBOARD_FAB2(SCH_1):PAGE39
  CY63 TP_CPU0_RSVD_54 @BASEBOARD_FAB2_LIB.BASEBOARD_FAB2(SCH_1):TP_CPU0_RSVD_54   I127 @BASEBOARD_FAB2_LIB.BASEBOARD_FAB2(SCH_1):PAGE39
  CY73 TP_CPU0_RSVD_53 @BASEBOARD_FAB2_LIB.BASEBOARD_FAB2(SCH_1):TP_CPU0_RSVD_53   I127 @BASEBOARD_FAB2_LIB.BASEBOARD_FAB2(SCH_1):PAGE39
  DA24 PVCCMCP_CPU0 @BASEBOARD_FAB2_LIB.BASEBOARD_FAB2(SCH_1):PVCCMCP_CPU0   I127 @BASEBOARD_FAB2_LIB.BASEBOARD_FAB2(SCH_1):PAGE39
  DA40 TP_CPU0_RSVD_51 @BASEBOARD_FAB2_LIB.BASEBOARD_FAB2(SCH_1):TP_CPU0_RSVD_51   I127 @BASEBOARD_FAB2_LIB.BASEBOARD_FAB2(SCH_1):PAGE39
  DA52 TP_CPU0_RSVD_50 @BASEBOARD_FAB2_LIB.BASEBOARD_FAB2(SCH_1):TP_CPU0_RSVD_50   I127 @BASEBOARD_FAB2_LIB.BASEBOARD_FAB2(SCH_1):PAGE39
  DA54 TP_CPU0_RSVD_49 @BASEBOARD_FAB2_LIB.BASEBOARD_FAB2(SCH_1):TP_CPU0_RSVD_49   I127 @BASEBOARD_FAB2_LIB.BASEBOARD_FAB2(SCH_1):PAGE39
  DA56 TP_CPU0_RSVD_48 @BASEBOARD_FAB2_LIB.BASEBOARD_FAB2(SCH_1):TP_CPU0_RSVD_48   I127 @BASEBOARD_FAB2_LIB.BASEBOARD_FAB2(SCH_1):PAGE39
  DC46 TP_CPU0_RSVD_47 @BASEBOARD_FAB2_LIB.BASEBOARD_FAB2(SCH_1):TP_CPU0_RSVD_47   I127 @BASEBOARD_FAB2_LIB.BASEBOARD_FAB2(SCH_1):PAGE39
  DC52 TP_CPU0_RSVD_46 @BASEBOARD_FAB2_LIB.BASEBOARD_FAB2(SCH_1):TP_CPU0_RSVD_46   I127 @BASEBOARD_FAB2_LIB.BASEBOARD_FAB2(SCH_1):PAGE39
  DD51 TP_CPU0_RSVD_45 @BASEBOARD_FAB2_LIB.BASEBOARD_FAB2(SCH_1):TP_CPU0_RSVD_45   I127 @BASEBOARD_FAB2_LIB.BASEBOARD_FAB2(SCH_1):PAGE39
  DG36 TP_CPU0_RSVD_44 @BASEBOARD_FAB2_LIB.BASEBOARD_FAB2(SCH_1):TP_CPU0_RSVD_44   I127 @BASEBOARD_FAB2_LIB.BASEBOARD_FAB2(SCH_1):PAGE39
  DG64 TP_CPU0_RSVD_43 @BASEBOARD_FAB2_LIB.BASEBOARD_FAB2(SCH_1):TP_CPU0_RSVD_43   I127 @BASEBOARD_FAB2_LIB.BASEBOARD_FAB2(SCH_1):PAGE39
  DH65 TP_CPU0_RSVD_42 @BASEBOARD_FAB2_LIB.BASEBOARD_FAB2(SCH_1):TP_CPU0_RSVD_42   I127 @BASEBOARD_FAB2_LIB.BASEBOARD_FAB2(SCH_1):PAGE39
  DJ36 TP_CPU0_RSVD_41 @BASEBOARD_FAB2_LIB.BASEBOARD_FAB2(SCH_1):TP_CPU0_RSVD_41   I127 @BASEBOARD_FAB2_LIB.BASEBOARD_FAB2(SCH_1):PAGE39
  DJ66 TP_CPU0_RSVD_40 @BASEBOARD_FAB2_LIB.BASEBOARD_FAB2(SCH_1):TP_CPU0_RSVD_40   I127 @BASEBOARD_FAB2_LIB.BASEBOARD_FAB2(SCH_1):PAGE39
  DK15 TP_CPU0_RSVD_39 @BASEBOARD_FAB2_LIB.BASEBOARD_FAB2(SCH_1):TP_CPU0_RSVD_39   I127 @BASEBOARD_FAB2_LIB.BASEBOARD_FAB2(SCH_1):PAGE39
  DK37 TP_CPU0_RSVD_38 @BASEBOARD_FAB2_LIB.BASEBOARD_FAB2(SCH_1):TP_CPU0_RSVD_38   I127 @BASEBOARD_FAB2_LIB.BASEBOARD_FAB2(SCH_1):PAGE39
  DK65 TP_CPU0_RSVD_37 @BASEBOARD_FAB2_LIB.BASEBOARD_FAB2(SCH_1):TP_CPU0_RSVD_37   I127 @BASEBOARD_FAB2_LIB.BASEBOARD_FAB2(SCH_1):PAGE39
  DK67 TP_CPU0_RSVD_36 @BASEBOARD_FAB2_LIB.BASEBOARD_FAB2(SCH_1):TP_CPU0_RSVD_36   I127 @BASEBOARD_FAB2_LIB.BASEBOARD_FAB2(SCH_1):PAGE39
  DL38 TP_CPU0_RSVD_35 @BASEBOARD_FAB2_LIB.BASEBOARD_FAB2(SCH_1):TP_CPU0_RSVD_35   I127 @BASEBOARD_FAB2_LIB.BASEBOARD_FAB2(SCH_1):PAGE39
  DL66 TP_CPU0_RSVD_34 @BASEBOARD_FAB2_LIB.BASEBOARD_FAB2(SCH_1):TP_CPU0_RSVD_34   I127 @BASEBOARD_FAB2_LIB.BASEBOARD_FAB2(SCH_1):PAGE39
  DM67 TP_CPU0_RSVD_33 @BASEBOARD_FAB2_LIB.BASEBOARD_FAB2(SCH_1):TP_CPU0_RSVD_33   I127 @BASEBOARD_FAB2_LIB.BASEBOARD_FAB2(SCH_1):PAGE39
  DN62 TP_CPU0_RSVD_32 @BASEBOARD_FAB2_LIB.BASEBOARD_FAB2(SCH_1):TP_CPU0_RSVD_32   I127 @BASEBOARD_FAB2_LIB.BASEBOARD_FAB2(SCH_1):PAGE39
  DN66 TP_CPU0_RSVD_31 @BASEBOARD_FAB2_LIB.BASEBOARD_FAB2(SCH_1):TP_CPU0_RSVD_31   I127 @BASEBOARD_FAB2_LIB.BASEBOARD_FAB2(SCH_1):PAGE39
  DP17 TP_CPU0_RSVD_30 @BASEBOARD_FAB2_LIB.BASEBOARD_FAB2(SCH_1):TP_CPU0_RSVD_30   I127 @BASEBOARD_FAB2_LIB.BASEBOARD_FAB2(SCH_1):PAGE39
  DP65 TP_CPU0_RSVD_29 @BASEBOARD_FAB2_LIB.BASEBOARD_FAB2(SCH_1):TP_CPU0_RSVD_29   I127 @BASEBOARD_FAB2_LIB.BASEBOARD_FAB2(SCH_1):PAGE39
  DR44 TP_CPU0_RSVD_28 @BASEBOARD_FAB2_LIB.BASEBOARD_FAB2(SCH_1):TP_CPU0_RSVD_28   I127 @BASEBOARD_FAB2_LIB.BASEBOARD_FAB2(SCH_1):PAGE39
  DT71 TP_CPU0_RSVD_27 @BASEBOARD_FAB2_LIB.BASEBOARD_FAB2(SCH_1):TP_CPU0_RSVD_27   I127 @BASEBOARD_FAB2_LIB.BASEBOARD_FAB2(SCH_1):PAGE39
  DU44 TP_CPU0_RSVD_26 @BASEBOARD_FAB2_LIB.BASEBOARD_FAB2(SCH_1):TP_CPU0_RSVD_26   I127 @BASEBOARD_FAB2_LIB.BASEBOARD_FAB2(SCH_1):PAGE39
  DV61 TP_CPU0_RSVD_25 @BASEBOARD_FAB2_LIB.BASEBOARD_FAB2(SCH_1):TP_CPU0_RSVD_25   I127 @BASEBOARD_FAB2_LIB.BASEBOARD_FAB2(SCH_1):PAGE39
  DV71 TP_CPU0_RSVD_24 @BASEBOARD_FAB2_LIB.BASEBOARD_FAB2(SCH_1):TP_CPU0_RSVD_24   I127 @BASEBOARD_FAB2_LIB.BASEBOARD_FAB2(SCH_1):PAGE39
  DW44 TP_CPU0_RSVD_23 @BASEBOARD_FAB2_LIB.BASEBOARD_FAB2(SCH_1):TP_CPU0_RSVD_23   I127 @BASEBOARD_FAB2_LIB.BASEBOARD_FAB2(SCH_1):PAGE39
  DW46 TP_CPU0_RSVD_22 @BASEBOARD_FAB2_LIB.BASEBOARD_FAB2(SCH_1):TP_CPU0_RSVD_22   I127 @BASEBOARD_FAB2_LIB.BASEBOARD_FAB2(SCH_1):PAGE39
   DY3 TP_CPU0_RSVD_21 @BASEBOARD_FAB2_LIB.BASEBOARD_FAB2(SCH_1):TP_CPU0_RSVD_21   I127 @BASEBOARD_FAB2_LIB.BASEBOARD_FAB2(SCH_1):PAGE39
   EA4 TP_CPU0_RSVD_20 @BASEBOARD_FAB2_LIB.BASEBOARD_FAB2(SCH_1):TP_CPU0_RSVD_20   I127 @BASEBOARD_FAB2_LIB.BASEBOARD_FAB2(SCH_1):PAGE39
  EA44 TP_CPU0_RSVD_19 @BASEBOARD_FAB2_LIB.BASEBOARD_FAB2(SCH_1):TP_CPU0_RSVD_19   I127 @BASEBOARD_FAB2_LIB.BASEBOARD_FAB2(SCH_1):PAGE39
   EB3 TP_CPU0_RSVD_18 @BASEBOARD_FAB2_LIB.BASEBOARD_FAB2(SCH_1):TP_CPU0_RSVD_18   I127 @BASEBOARD_FAB2_LIB.BASEBOARD_FAB2(SCH_1):PAGE39
   EB5 TP_CPU0_RSVD_17 @BASEBOARD_FAB2_LIB.BASEBOARD_FAB2(SCH_1):TP_CPU0_RSVD_17   I127 @BASEBOARD_FAB2_LIB.BASEBOARD_FAB2(SCH_1):PAGE39
  EB85 TP_CPU0_RSVD_16 @BASEBOARD_FAB2_LIB.BASEBOARD_FAB2(SCH_1):TP_CPU0_RSVD_16   I127 @BASEBOARD_FAB2_LIB.BASEBOARD_FAB2(SCH_1):PAGE39
  EC16 TP_CPU0_RSVD_15 @BASEBOARD_FAB2_LIB.BASEBOARD_FAB2(SCH_1):TP_CPU0_RSVD_15   I127 @BASEBOARD_FAB2_LIB.BASEBOARD_FAB2(SCH_1):PAGE39
   EC4 TP_CPU0_RSVD_14 @BASEBOARD_FAB2_LIB.BASEBOARD_FAB2(SCH_1):TP_CPU0_RSVD_14   I127 @BASEBOARD_FAB2_LIB.BASEBOARD_FAB2(SCH_1):PAGE39
  EC44 TP_CPU0_RSVD_13 @BASEBOARD_FAB2_LIB.BASEBOARD_FAB2(SCH_1):TP_CPU0_RSVD_13   I127 @BASEBOARD_FAB2_LIB.BASEBOARD_FAB2(SCH_1):PAGE39
  EC84 TP_CPU0_RSVD_12 @BASEBOARD_FAB2_LIB.BASEBOARD_FAB2(SCH_1):TP_CPU0_RSVD_12   I127 @BASEBOARD_FAB2_LIB.BASEBOARD_FAB2(SCH_1):PAGE39
  ED45 TP_CPU0_RSVD_11 @BASEBOARD_FAB2_LIB.BASEBOARD_FAB2(SCH_1):TP_CPU0_RSVD_11   I127 @BASEBOARD_FAB2_LIB.BASEBOARD_FAB2(SCH_1):PAGE39
   ED5 TP_CPU0_RSVD_10 @BASEBOARD_FAB2_LIB.BASEBOARD_FAB2(SCH_1):TP_CPU0_RSVD_10   I127 @BASEBOARD_FAB2_LIB.BASEBOARD_FAB2(SCH_1):PAGE39
  ED83 TP_CPU0_RSVD_9 @BASEBOARD_FAB2_LIB.BASEBOARD_FAB2(SCH_1):TP_CPU0_RSVD_9   I127 @BASEBOARD_FAB2_LIB.BASEBOARD_FAB2(SCH_1):PAGE39
  EE16 TP_CPU0_RSVD_8 @BASEBOARD_FAB2_LIB.BASEBOARD_FAB2(SCH_1):TP_CPU0_RSVD_8   I127 @BASEBOARD_FAB2_LIB.BASEBOARD_FAB2(SCH_1):PAGE39
  EE46 TP_CPU0_RSVD_7 @BASEBOARD_FAB2_LIB.BASEBOARD_FAB2(SCH_1):TP_CPU0_RSVD_7   I127 @BASEBOARD_FAB2_LIB.BASEBOARD_FAB2(SCH_1):PAGE39
   EE6 TP_CPU0_RSVD_6 @BASEBOARD_FAB2_LIB.BASEBOARD_FAB2(SCH_1):TP_CPU0_RSVD_6   I127 @BASEBOARD_FAB2_LIB.BASEBOARD_FAB2(SCH_1):PAGE39
  EE82 TP_CPU0_RSVD_5 @BASEBOARD_FAB2_LIB.BASEBOARD_FAB2(SCH_1):TP_CPU0_RSVD_5   I127 @BASEBOARD_FAB2_LIB.BASEBOARD_FAB2(SCH_1):PAGE39
  EE84 TP_CPU0_RSVD_4 @BASEBOARD_FAB2_LIB.BASEBOARD_FAB2(SCH_1):TP_CPU0_RSVD_4   I127 @BASEBOARD_FAB2_LIB.BASEBOARD_FAB2(SCH_1):PAGE39
  EF47 TP_CPU0_RSVD_3 @BASEBOARD_FAB2_LIB.BASEBOARD_FAB2(SCH_1):TP_CPU0_RSVD_3   I127 @BASEBOARD_FAB2_LIB.BASEBOARD_FAB2(SCH_1):PAGE39
  EF77 TP_CPU0_RSVD_2 @BASEBOARD_FAB2_LIB.BASEBOARD_FAB2(SCH_1):TP_CPU0_RSVD_2   I127 @BASEBOARD_FAB2_LIB.BASEBOARD_FAB2(SCH_1):PAGE39
  EF81 TP_CPU0_RSVD_1 @BASEBOARD_FAB2_LIB.BASEBOARD_FAB2(SCH_1):TP_CPU0_RSVD_1   I127 @BASEBOARD_FAB2_LIB.BASEBOARD_FAB2(SCH_1):PAGE39
  EF83 TP_CPU0_RSVD_0 @BASEBOARD_FAB2_LIB.BASEBOARD_FAB2(SCH_1):TP_CPU0_RSVD_0   I127 @BASEBOARD_FAB2_LIB.BASEBOARD_FAB2(SCH_1):PAGE39
   CN6 PVCCIO_CPU0 @BASEBOARD_FAB2_LIB.BASEBOARD_FAB2(SCH_1):PVCCIO_CPU0   I127 @BASEBOARD_FAB2_LIB.BASEBOARD_FAB2(SCH_1):PAGE39
  CU12 PVCCIO_CPU0 @BASEBOARD_FAB2_LIB.BASEBOARD_FAB2(SCH_1):PVCCIO_CPU0   I127 @BASEBOARD_FAB2_LIB.BASEBOARD_FAB2(SCH_1):PAGE39
  CV21 PVCCIO_CPU0 @BASEBOARD_FAB2_LIB.BASEBOARD_FAB2(SCH_1):PVCCIO_CPU0   I127 @BASEBOARD_FAB2_LIB.BASEBOARD_FAB2(SCH_1):PAGE39
  CU18 PVCCIO_CPU0 @BASEBOARD_FAB2_LIB.BASEBOARD_FAB2(SCH_1):PVCCIO_CPU0   I127 @BASEBOARD_FAB2_LIB.BASEBOARD_FAB2(SCH_1):PAGE39
  CY17 PVCCIO_CPU0 @BASEBOARD_FAB2_LIB.BASEBOARD_FAB2(SCH_1):PVCCIO_CPU0   I127 @BASEBOARD_FAB2_LIB.BASEBOARD_FAB2(SCH_1):PAGE39
  DC18 PVCCIO_CPU0 @BASEBOARD_FAB2_LIB.BASEBOARD_FAB2(SCH_1):PVCCIO_CPU0   I127 @BASEBOARD_FAB2_LIB.BASEBOARD_FAB2(SCH_1):PAGE39
  DE14 PVCCIO_CPU0 @BASEBOARD_FAB2_LIB.BASEBOARD_FAB2(SCH_1):PVCCIO_CPU0   I127 @BASEBOARD_FAB2_LIB.BASEBOARD_FAB2(SCH_1):PAGE39
  CP13 PVCCIO_CPU0 @BASEBOARD_FAB2_LIB.BASEBOARD_FAB2(SCH_1):PVCCIO_CPU0   I127 @BASEBOARD_FAB2_LIB.BASEBOARD_FAB2(SCH_1):PAGE39
  CL20 PVCCIO_CPU0 @BASEBOARD_FAB2_LIB.BASEBOARD_FAB2(SCH_1):PVCCIO_CPU0   I127 @BASEBOARD_FAB2_LIB.BASEBOARD_FAB2(SCH_1):PAGE39
  CG14 PVCCIO_CPU0 @BASEBOARD_FAB2_LIB.BASEBOARD_FAB2(SCH_1):PVCCIO_CPU0   I127 @BASEBOARD_FAB2_LIB.BASEBOARD_FAB2(SCH_1):PAGE39
   CF5 PVCCIO_CPU0 @BASEBOARD_FAB2_LIB.BASEBOARD_FAB2(SCH_1):PVCCIO_CPU0   I127 @BASEBOARD_FAB2_LIB.BASEBOARD_FAB2(SCH_1):PAGE39
  DK21 PVCCIO_CPU0 @BASEBOARD_FAB2_LIB.BASEBOARD_FAB2(SCH_1):PVCCIO_CPU0   I127 @BASEBOARD_FAB2_LIB.BASEBOARD_FAB2(SCH_1):PAGE39
  BE24 PVCCIO_CPU0 @BASEBOARD_FAB2_LIB.BASEBOARD_FAB2(SCH_1):PVCCIO_CPU0   I127 @BASEBOARD_FAB2_LIB.BASEBOARD_FAB2(SCH_1):PAGE39
   AT7 PVCCIO_CPU0 @BASEBOARD_FAB2_LIB.BASEBOARD_FAB2(SCH_1):PVCCIO_CPU0   I127 @BASEBOARD_FAB2_LIB.BASEBOARD_FAB2(SCH_1):PAGE39
   AT5 PVCCIO_CPU0 @BASEBOARD_FAB2_LIB.BASEBOARD_FAB2(SCH_1):PVCCIO_CPU0   I127 @BASEBOARD_FAB2_LIB.BASEBOARD_FAB2(SCH_1):PAGE39
   AM5 PVCCIO_CPU0 @BASEBOARD_FAB2_LIB.BASEBOARD_FAB2(SCH_1):PVCCIO_CPU0   I127 @BASEBOARD_FAB2_LIB.BASEBOARD_FAB2(SCH_1):PAGE39
  DV11 PVCCIO_CPU0 @BASEBOARD_FAB2_LIB.BASEBOARD_FAB2(SCH_1):PVCCIO_CPU0   I127 @BASEBOARD_FAB2_LIB.BASEBOARD_FAB2(SCH_1):PAGE39
   AF5 PVCCIO_CPU0 @BASEBOARD_FAB2_LIB.BASEBOARD_FAB2(SCH_1):PVCCIO_CPU0   I127 @BASEBOARD_FAB2_LIB.BASEBOARD_FAB2(SCH_1):PAGE39
  AE10 PVCCIO_CPU0 @BASEBOARD_FAB2_LIB.BASEBOARD_FAB2(SCH_1):PVCCIO_CPU0   I127 @BASEBOARD_FAB2_LIB.BASEBOARD_FAB2(SCH_1):PAGE39
  EE10 PVCCIO_CPU0 @BASEBOARD_FAB2_LIB.BASEBOARD_FAB2(SCH_1):PVCCIO_CPU0   I127 @BASEBOARD_FAB2_LIB.BASEBOARD_FAB2(SCH_1):PAGE39
   BH5 VSENSE_PVCCIO_CPU0_SKT_VSEN @BASEBOARD_FAB2_LIB.BASEBOARD_FAB2(SCH_1):VSENSE_PVCCIO_CPU0_SKT_VSEN   I127 @BASEBOARD_FAB2_LIB.BASEBOARD_FAB2(SCH_1):PAGE39
  CE76 VSENSE_PVSA_CPU0_SKT_VSEN @BASEBOARD_FAB2_LIB.BASEBOARD_FAB2(SCH_1):VSENSE_PVSA_CPU0_SKT_VSEN   I127 @BASEBOARD_FAB2_LIB.BASEBOARD_FAB2(SCH_1):PAGE39
   BF5 VSENSE_PVCCIO_CPU0_SKT_VRTN @BASEBOARD_FAB2_LIB.BASEBOARD_FAB2(SCH_1):VSENSE_PVCCIO_CPU0_SKT_VRTN   I127 @BASEBOARD_FAB2_LIB.BASEBOARD_FAB2(SCH_1):PAGE39
  CG76 VSENSE_PVSA_CPU0_SKT_VRTN @BASEBOARD_FAB2_LIB.BASEBOARD_FAB2(SCH_1):VSENSE_PVSA_CPU0_SKT_VRTN   I127 @BASEBOARD_FAB2_LIB.BASEBOARD_FAB2(SCH_1):PAGE39
    B9    GND @BASEBOARD_FAB2_LIB.BASEBOARD_FAB2(SCH_1):GND    I20 @BASEBOARD_FAB2_LIB.BASEBOARD_FAB2(SCH_1):PAGE40
   A42    GND @BASEBOARD_FAB2_LIB.BASEBOARD_FAB2(SCH_1):GND    I20 @BASEBOARD_FAB2_LIB.BASEBOARD_FAB2(SCH_1):PAGE40
   B43    GND @BASEBOARD_FAB2_LIB.BASEBOARD_FAB2(SCH_1):GND    I20 @BASEBOARD_FAB2_LIB.BASEBOARD_FAB2(SCH_1):PAGE40
    B5    GND @BASEBOARD_FAB2_LIB.BASEBOARD_FAB2(SCH_1):GND    I20 @BASEBOARD_FAB2_LIB.BASEBOARD_FAB2(SCH_1):PAGE40
   B79    GND @BASEBOARD_FAB2_LIB.BASEBOARD_FAB2(SCH_1):GND    I20 @BASEBOARD_FAB2_LIB.BASEBOARD_FAB2(SCH_1):PAGE40
    C4    GND @BASEBOARD_FAB2_LIB.BASEBOARD_FAB2(SCH_1):GND    I20 @BASEBOARD_FAB2_LIB.BASEBOARD_FAB2(SCH_1):PAGE40
   C80    GND @BASEBOARD_FAB2_LIB.BASEBOARD_FAB2(SCH_1):GND    I20 @BASEBOARD_FAB2_LIB.BASEBOARD_FAB2(SCH_1):PAGE40
    D3    GND @BASEBOARD_FAB2_LIB.BASEBOARD_FAB2(SCH_1):GND    I20 @BASEBOARD_FAB2_LIB.BASEBOARD_FAB2(SCH_1):PAGE40
   D81    GND @BASEBOARD_FAB2_LIB.BASEBOARD_FAB2(SCH_1):GND    I20 @BASEBOARD_FAB2_LIB.BASEBOARD_FAB2(SCH_1):PAGE40
   E82    GND @BASEBOARD_FAB2_LIB.BASEBOARD_FAB2(SCH_1):GND    I20 @BASEBOARD_FAB2_LIB.BASEBOARD_FAB2(SCH_1):PAGE40
   J86    GND @BASEBOARD_FAB2_LIB.BASEBOARD_FAB2(SCH_1):GND    I20 @BASEBOARD_FAB2_LIB.BASEBOARD_FAB2(SCH_1):PAGE40
  DY85    GND @BASEBOARD_FAB2_LIB.BASEBOARD_FAB2(SCH_1):GND    I20 @BASEBOARD_FAB2_LIB.BASEBOARD_FAB2(SCH_1):PAGE40
  EA84    GND @BASEBOARD_FAB2_LIB.BASEBOARD_FAB2(SCH_1):GND    I20 @BASEBOARD_FAB2_LIB.BASEBOARD_FAB2(SCH_1):PAGE40
  EB83    GND @BASEBOARD_FAB2_LIB.BASEBOARD_FAB2(SCH_1):GND    I20 @BASEBOARD_FAB2_LIB.BASEBOARD_FAB2(SCH_1):PAGE40
   DW2    GND @BASEBOARD_FAB2_LIB.BASEBOARD_FAB2(SCH_1):GND    I20 @BASEBOARD_FAB2_LIB.BASEBOARD_FAB2(SCH_1):PAGE40
  EC42    GND @BASEBOARD_FAB2_LIB.BASEBOARD_FAB2(SCH_1):GND    I20 @BASEBOARD_FAB2_LIB.BASEBOARD_FAB2(SCH_1):PAGE40
   EC6    GND @BASEBOARD_FAB2_LIB.BASEBOARD_FAB2(SCH_1):GND    I20 @BASEBOARD_FAB2_LIB.BASEBOARD_FAB2(SCH_1):PAGE40
  EC82    GND @BASEBOARD_FAB2_LIB.BASEBOARD_FAB2(SCH_1):GND    I20 @BASEBOARD_FAB2_LIB.BASEBOARD_FAB2(SCH_1):PAGE40
  ED41    GND @BASEBOARD_FAB2_LIB.BASEBOARD_FAB2(SCH_1):GND    I20 @BASEBOARD_FAB2_LIB.BASEBOARD_FAB2(SCH_1):PAGE40
   ED7    GND @BASEBOARD_FAB2_LIB.BASEBOARD_FAB2(SCH_1):GND    I20 @BASEBOARD_FAB2_LIB.BASEBOARD_FAB2(SCH_1):PAGE40
  ED81    GND @BASEBOARD_FAB2_LIB.BASEBOARD_FAB2(SCH_1):GND    I20 @BASEBOARD_FAB2_LIB.BASEBOARD_FAB2(SCH_1):PAGE40
  EE40    GND @BASEBOARD_FAB2_LIB.BASEBOARD_FAB2(SCH_1):GND    I20 @BASEBOARD_FAB2_LIB.BASEBOARD_FAB2(SCH_1):PAGE40
   EE8    GND @BASEBOARD_FAB2_LIB.BASEBOARD_FAB2(SCH_1):GND    I20 @BASEBOARD_FAB2_LIB.BASEBOARD_FAB2(SCH_1):PAGE40
  EE80    GND @BASEBOARD_FAB2_LIB.BASEBOARD_FAB2(SCH_1):GND    I20 @BASEBOARD_FAB2_LIB.BASEBOARD_FAB2(SCH_1):PAGE40
  ED69    GND @BASEBOARD_FAB2_LIB.BASEBOARD_FAB2(SCH_1):GND    I20 @BASEBOARD_FAB2_LIB.BASEBOARD_FAB2(SCH_1):PAGE40
   E66    GND @BASEBOARD_FAB2_LIB.BASEBOARD_FAB2(SCH_1):GND    I20 @BASEBOARD_FAB2_LIB.BASEBOARD_FAB2(SCH_1):PAGE40
   V11    GND @BASEBOARD_FAB2_LIB.BASEBOARD_FAB2(SCH_1):GND    I20 @BASEBOARD_FAB2_LIB.BASEBOARD_FAB2(SCH_1):PAGE40
    L8    GND @BASEBOARD_FAB2_LIB.BASEBOARD_FAB2(SCH_1):GND    I20 @BASEBOARD_FAB2_LIB.BASEBOARD_FAB2(SCH_1):PAGE40
  EA14    GND @BASEBOARD_FAB2_LIB.BASEBOARD_FAB2(SCH_1):GND    I20 @BASEBOARD_FAB2_LIB.BASEBOARD_FAB2(SCH_1):PAGE40
  DY63    GND @BASEBOARD_FAB2_LIB.BASEBOARD_FAB2(SCH_1):GND    I20 @BASEBOARD_FAB2_LIB.BASEBOARD_FAB2(SCH_1):PAGE40
  DY61    GND @BASEBOARD_FAB2_LIB.BASEBOARD_FAB2(SCH_1):GND    I20 @BASEBOARD_FAB2_LIB.BASEBOARD_FAB2(SCH_1):PAGE40
  DY59    GND @BASEBOARD_FAB2_LIB.BASEBOARD_FAB2(SCH_1):GND    I20 @BASEBOARD_FAB2_LIB.BASEBOARD_FAB2(SCH_1):PAGE40
  DY57    GND @BASEBOARD_FAB2_LIB.BASEBOARD_FAB2(SCH_1):GND    I20 @BASEBOARD_FAB2_LIB.BASEBOARD_FAB2(SCH_1):PAGE40
  DY55    GND @BASEBOARD_FAB2_LIB.BASEBOARD_FAB2(SCH_1):GND    I20 @BASEBOARD_FAB2_LIB.BASEBOARD_FAB2(SCH_1):PAGE40
  DY53    GND @BASEBOARD_FAB2_LIB.BASEBOARD_FAB2(SCH_1):GND    I20 @BASEBOARD_FAB2_LIB.BASEBOARD_FAB2(SCH_1):PAGE40
  DY51    GND @BASEBOARD_FAB2_LIB.BASEBOARD_FAB2(SCH_1):GND    I20 @BASEBOARD_FAB2_LIB.BASEBOARD_FAB2(SCH_1):PAGE40
  DY49    GND @BASEBOARD_FAB2_LIB.BASEBOARD_FAB2(SCH_1):GND    I20 @BASEBOARD_FAB2_LIB.BASEBOARD_FAB2(SCH_1):PAGE40
  DY47    GND @BASEBOARD_FAB2_LIB.BASEBOARD_FAB2(SCH_1):GND    I20 @BASEBOARD_FAB2_LIB.BASEBOARD_FAB2(SCH_1):PAGE40
  DY45    GND @BASEBOARD_FAB2_LIB.BASEBOARD_FAB2(SCH_1):GND    I20 @BASEBOARD_FAB2_LIB.BASEBOARD_FAB2(SCH_1):PAGE40
  DV19    GND @BASEBOARD_FAB2_LIB.BASEBOARD_FAB2(SCH_1):GND    I20 @BASEBOARD_FAB2_LIB.BASEBOARD_FAB2(SCH_1):PAGE40
   DP9    GND @BASEBOARD_FAB2_LIB.BASEBOARD_FAB2(SCH_1):GND    I20 @BASEBOARD_FAB2_LIB.BASEBOARD_FAB2(SCH_1):PAGE40
  DP63    GND @BASEBOARD_FAB2_LIB.BASEBOARD_FAB2(SCH_1):GND    I20 @BASEBOARD_FAB2_LIB.BASEBOARD_FAB2(SCH_1):PAGE40
  DP61    GND @BASEBOARD_FAB2_LIB.BASEBOARD_FAB2(SCH_1):GND    I20 @BASEBOARD_FAB2_LIB.BASEBOARD_FAB2(SCH_1):PAGE40
  DP59    GND @BASEBOARD_FAB2_LIB.BASEBOARD_FAB2(SCH_1):GND    I20 @BASEBOARD_FAB2_LIB.BASEBOARD_FAB2(SCH_1):PAGE40
  DP57    GND @BASEBOARD_FAB2_LIB.BASEBOARD_FAB2(SCH_1):GND    I20 @BASEBOARD_FAB2_LIB.BASEBOARD_FAB2(SCH_1):PAGE40
  DP55    GND @BASEBOARD_FAB2_LIB.BASEBOARD_FAB2(SCH_1):GND    I20 @BASEBOARD_FAB2_LIB.BASEBOARD_FAB2(SCH_1):PAGE40
  DP53    GND @BASEBOARD_FAB2_LIB.BASEBOARD_FAB2(SCH_1):GND    I20 @BASEBOARD_FAB2_LIB.BASEBOARD_FAB2(SCH_1):PAGE40
  DP51    GND @BASEBOARD_FAB2_LIB.BASEBOARD_FAB2(SCH_1):GND    I20 @BASEBOARD_FAB2_LIB.BASEBOARD_FAB2(SCH_1):PAGE40
  DP49    GND @BASEBOARD_FAB2_LIB.BASEBOARD_FAB2(SCH_1):GND    I20 @BASEBOARD_FAB2_LIB.BASEBOARD_FAB2(SCH_1):PAGE40
  DP47    GND @BASEBOARD_FAB2_LIB.BASEBOARD_FAB2(SCH_1):GND    I20 @BASEBOARD_FAB2_LIB.BASEBOARD_FAB2(SCH_1):PAGE40
  DP45    GND @BASEBOARD_FAB2_LIB.BASEBOARD_FAB2(SCH_1):GND    I20 @BASEBOARD_FAB2_LIB.BASEBOARD_FAB2(SCH_1):PAGE40
  DN18    GND @BASEBOARD_FAB2_LIB.BASEBOARD_FAB2(SCH_1):GND    I20 @BASEBOARD_FAB2_LIB.BASEBOARD_FAB2(SCH_1):PAGE40
   DL8    GND @BASEBOARD_FAB2_LIB.BASEBOARD_FAB2(SCH_1):GND    I20 @BASEBOARD_FAB2_LIB.BASEBOARD_FAB2(SCH_1):PAGE40
  DE62    GND @BASEBOARD_FAB2_LIB.BASEBOARD_FAB2(SCH_1):GND    I20 @BASEBOARD_FAB2_LIB.BASEBOARD_FAB2(SCH_1):PAGE40
  DE60    GND @BASEBOARD_FAB2_LIB.BASEBOARD_FAB2(SCH_1):GND    I20 @BASEBOARD_FAB2_LIB.BASEBOARD_FAB2(SCH_1):PAGE40
  DE58    GND @BASEBOARD_FAB2_LIB.BASEBOARD_FAB2(SCH_1):GND    I20 @BASEBOARD_FAB2_LIB.BASEBOARD_FAB2(SCH_1):PAGE40
  DE56    GND @BASEBOARD_FAB2_LIB.BASEBOARD_FAB2(SCH_1):GND    I20 @BASEBOARD_FAB2_LIB.BASEBOARD_FAB2(SCH_1):PAGE40
  DE54    GND @BASEBOARD_FAB2_LIB.BASEBOARD_FAB2(SCH_1):GND    I20 @BASEBOARD_FAB2_LIB.BASEBOARD_FAB2(SCH_1):PAGE40
  DE52    GND @BASEBOARD_FAB2_LIB.BASEBOARD_FAB2(SCH_1):GND    I20 @BASEBOARD_FAB2_LIB.BASEBOARD_FAB2(SCH_1):PAGE40
  DE50    GND @BASEBOARD_FAB2_LIB.BASEBOARD_FAB2(SCH_1):GND    I20 @BASEBOARD_FAB2_LIB.BASEBOARD_FAB2(SCH_1):PAGE40
  DE48    GND @BASEBOARD_FAB2_LIB.BASEBOARD_FAB2(SCH_1):GND    I20 @BASEBOARD_FAB2_LIB.BASEBOARD_FAB2(SCH_1):PAGE40
   CW6    GND @BASEBOARD_FAB2_LIB.BASEBOARD_FAB2(SCH_1):GND    I20 @BASEBOARD_FAB2_LIB.BASEBOARD_FAB2(SCH_1):PAGE40
   CG6    GND @BASEBOARD_FAB2_LIB.BASEBOARD_FAB2(SCH_1):GND    I20 @BASEBOARD_FAB2_LIB.BASEBOARD_FAB2(SCH_1):PAGE40
   AR6    GND @BASEBOARD_FAB2_LIB.BASEBOARD_FAB2(SCH_1):GND    I20 @BASEBOARD_FAB2_LIB.BASEBOARD_FAB2(SCH_1):PAGE40
   AJ4    GND @BASEBOARD_FAB2_LIB.BASEBOARD_FAB2(SCH_1):GND    I20 @BASEBOARD_FAB2_LIB.BASEBOARD_FAB2(SCH_1):PAGE40
  AC62    GND @BASEBOARD_FAB2_LIB.BASEBOARD_FAB2(SCH_1):GND    I20 @BASEBOARD_FAB2_LIB.BASEBOARD_FAB2(SCH_1):PAGE40
  AC60    GND @BASEBOARD_FAB2_LIB.BASEBOARD_FAB2(SCH_1):GND    I20 @BASEBOARD_FAB2_LIB.BASEBOARD_FAB2(SCH_1):PAGE40
  AC58    GND @BASEBOARD_FAB2_LIB.BASEBOARD_FAB2(SCH_1):GND    I20 @BASEBOARD_FAB2_LIB.BASEBOARD_FAB2(SCH_1):PAGE40
   A26    GND @BASEBOARD_FAB2_LIB.BASEBOARD_FAB2(SCH_1):GND    I20 @BASEBOARD_FAB2_LIB.BASEBOARD_FAB2(SCH_1):PAGE40
   A30    GND @BASEBOARD_FAB2_LIB.BASEBOARD_FAB2(SCH_1):GND    I20 @BASEBOARD_FAB2_LIB.BASEBOARD_FAB2(SCH_1):PAGE40
   A32    GND @BASEBOARD_FAB2_LIB.BASEBOARD_FAB2(SCH_1):GND    I20 @BASEBOARD_FAB2_LIB.BASEBOARD_FAB2(SCH_1):PAGE40
   A36    GND @BASEBOARD_FAB2_LIB.BASEBOARD_FAB2(SCH_1):GND    I20 @BASEBOARD_FAB2_LIB.BASEBOARD_FAB2(SCH_1):PAGE40
   A38    GND @BASEBOARD_FAB2_LIB.BASEBOARD_FAB2(SCH_1):GND    I20 @BASEBOARD_FAB2_LIB.BASEBOARD_FAB2(SCH_1):PAGE40
   B25    GND @BASEBOARD_FAB2_LIB.BASEBOARD_FAB2(SCH_1):GND    I20 @BASEBOARD_FAB2_LIB.BASEBOARD_FAB2(SCH_1):PAGE40
   B31    GND @BASEBOARD_FAB2_LIB.BASEBOARD_FAB2(SCH_1):GND    I20 @BASEBOARD_FAB2_LIB.BASEBOARD_FAB2(SCH_1):PAGE40
   B37    GND @BASEBOARD_FAB2_LIB.BASEBOARD_FAB2(SCH_1):GND    I20 @BASEBOARD_FAB2_LIB.BASEBOARD_FAB2(SCH_1):PAGE40
   B71    GND @BASEBOARD_FAB2_LIB.BASEBOARD_FAB2(SCH_1):GND    I20 @BASEBOARD_FAB2_LIB.BASEBOARD_FAB2(SCH_1):PAGE40
   B75    GND @BASEBOARD_FAB2_LIB.BASEBOARD_FAB2(SCH_1):GND    I20 @BASEBOARD_FAB2_LIB.BASEBOARD_FAB2(SCH_1):PAGE40
    C8    GND @BASEBOARD_FAB2_LIB.BASEBOARD_FAB2(SCH_1):GND    I20 @BASEBOARD_FAB2_LIB.BASEBOARD_FAB2(SCH_1):PAGE40
   C10    GND @BASEBOARD_FAB2_LIB.BASEBOARD_FAB2(SCH_1):GND    I20 @BASEBOARD_FAB2_LIB.BASEBOARD_FAB2(SCH_1):PAGE40
   C12    GND @BASEBOARD_FAB2_LIB.BASEBOARD_FAB2(SCH_1):GND    I20 @BASEBOARD_FAB2_LIB.BASEBOARD_FAB2(SCH_1):PAGE40
   C14    GND @BASEBOARD_FAB2_LIB.BASEBOARD_FAB2(SCH_1):GND    I20 @BASEBOARD_FAB2_LIB.BASEBOARD_FAB2(SCH_1):PAGE40
   C16    GND @BASEBOARD_FAB2_LIB.BASEBOARD_FAB2(SCH_1):GND    I20 @BASEBOARD_FAB2_LIB.BASEBOARD_FAB2(SCH_1):PAGE40
   C76    GND @BASEBOARD_FAB2_LIB.BASEBOARD_FAB2(SCH_1):GND    I20 @BASEBOARD_FAB2_LIB.BASEBOARD_FAB2(SCH_1):PAGE40
   C78    GND @BASEBOARD_FAB2_LIB.BASEBOARD_FAB2(SCH_1):GND    I20 @BASEBOARD_FAB2_LIB.BASEBOARD_FAB2(SCH_1):PAGE40
  CM27    GND @BASEBOARD_FAB2_LIB.BASEBOARD_FAB2(SCH_1):GND    I20 @BASEBOARD_FAB2_LIB.BASEBOARD_FAB2(SCH_1):PAGE40
   D11    GND @BASEBOARD_FAB2_LIB.BASEBOARD_FAB2(SCH_1):GND    I20 @BASEBOARD_FAB2_LIB.BASEBOARD_FAB2(SCH_1):PAGE40
   D13    GND @BASEBOARD_FAB2_LIB.BASEBOARD_FAB2(SCH_1):GND    I20 @BASEBOARD_FAB2_LIB.BASEBOARD_FAB2(SCH_1):PAGE40
   D25    GND @BASEBOARD_FAB2_LIB.BASEBOARD_FAB2(SCH_1):GND    I20 @BASEBOARD_FAB2_LIB.BASEBOARD_FAB2(SCH_1):PAGE40
   D27    GND @BASEBOARD_FAB2_LIB.BASEBOARD_FAB2(SCH_1):GND    I20 @BASEBOARD_FAB2_LIB.BASEBOARD_FAB2(SCH_1):PAGE40
   D29    GND @BASEBOARD_FAB2_LIB.BASEBOARD_FAB2(SCH_1):GND    I20 @BASEBOARD_FAB2_LIB.BASEBOARD_FAB2(SCH_1):PAGE40
   D31    GND @BASEBOARD_FAB2_LIB.BASEBOARD_FAB2(SCH_1):GND    I20 @BASEBOARD_FAB2_LIB.BASEBOARD_FAB2(SCH_1):PAGE40
   D33    GND @BASEBOARD_FAB2_LIB.BASEBOARD_FAB2(SCH_1):GND    I20 @BASEBOARD_FAB2_LIB.BASEBOARD_FAB2(SCH_1):PAGE40
   D35    GND @BASEBOARD_FAB2_LIB.BASEBOARD_FAB2(SCH_1):GND    I20 @BASEBOARD_FAB2_LIB.BASEBOARD_FAB2(SCH_1):PAGE40
   D37    GND @BASEBOARD_FAB2_LIB.BASEBOARD_FAB2(SCH_1):GND    I20 @BASEBOARD_FAB2_LIB.BASEBOARD_FAB2(SCH_1):PAGE40
   D39    GND @BASEBOARD_FAB2_LIB.BASEBOARD_FAB2(SCH_1):GND    I20 @BASEBOARD_FAB2_LIB.BASEBOARD_FAB2(SCH_1):PAGE40
   D41    GND @BASEBOARD_FAB2_LIB.BASEBOARD_FAB2(SCH_1):GND    I20 @BASEBOARD_FAB2_LIB.BASEBOARD_FAB2(SCH_1):PAGE40
   D43    GND @BASEBOARD_FAB2_LIB.BASEBOARD_FAB2(SCH_1):GND    I20 @BASEBOARD_FAB2_LIB.BASEBOARD_FAB2(SCH_1):PAGE40
   D77    GND @BASEBOARD_FAB2_LIB.BASEBOARD_FAB2(SCH_1):GND    I20 @BASEBOARD_FAB2_LIB.BASEBOARD_FAB2(SCH_1):PAGE40
    E6    GND @BASEBOARD_FAB2_LIB.BASEBOARD_FAB2(SCH_1):GND    I20 @BASEBOARD_FAB2_LIB.BASEBOARD_FAB2(SCH_1):PAGE40
    E8    GND @BASEBOARD_FAB2_LIB.BASEBOARD_FAB2(SCH_1):GND    I20 @BASEBOARD_FAB2_LIB.BASEBOARD_FAB2(SCH_1):PAGE40
   E16    GND @BASEBOARD_FAB2_LIB.BASEBOARD_FAB2(SCH_1):GND    I20 @BASEBOARD_FAB2_LIB.BASEBOARD_FAB2(SCH_1):PAGE40
   E18    GND @BASEBOARD_FAB2_LIB.BASEBOARD_FAB2(SCH_1):GND    I20 @BASEBOARD_FAB2_LIB.BASEBOARD_FAB2(SCH_1):PAGE40
   E20    GND @BASEBOARD_FAB2_LIB.BASEBOARD_FAB2(SCH_1):GND    I20 @BASEBOARD_FAB2_LIB.BASEBOARD_FAB2(SCH_1):PAGE40
   E22    GND @BASEBOARD_FAB2_LIB.BASEBOARD_FAB2(SCH_1):GND    I20 @BASEBOARD_FAB2_LIB.BASEBOARD_FAB2(SCH_1):PAGE40
   E72    GND @BASEBOARD_FAB2_LIB.BASEBOARD_FAB2(SCH_1):GND    I20 @BASEBOARD_FAB2_LIB.BASEBOARD_FAB2(SCH_1):PAGE40
   E74    GND @BASEBOARD_FAB2_LIB.BASEBOARD_FAB2(SCH_1):GND    I20 @BASEBOARD_FAB2_LIB.BASEBOARD_FAB2(SCH_1):PAGE40
   E76    GND @BASEBOARD_FAB2_LIB.BASEBOARD_FAB2(SCH_1):GND    I20 @BASEBOARD_FAB2_LIB.BASEBOARD_FAB2(SCH_1):PAGE40
    F5    GND @BASEBOARD_FAB2_LIB.BASEBOARD_FAB2(SCH_1):GND    I20 @BASEBOARD_FAB2_LIB.BASEBOARD_FAB2(SCH_1):PAGE40
   F17    GND @BASEBOARD_FAB2_LIB.BASEBOARD_FAB2(SCH_1):GND    I20 @BASEBOARD_FAB2_LIB.BASEBOARD_FAB2(SCH_1):PAGE40
   F19    GND @BASEBOARD_FAB2_LIB.BASEBOARD_FAB2(SCH_1):GND    I20 @BASEBOARD_FAB2_LIB.BASEBOARD_FAB2(SCH_1):PAGE40
   F25    GND @BASEBOARD_FAB2_LIB.BASEBOARD_FAB2(SCH_1):GND    I20 @BASEBOARD_FAB2_LIB.BASEBOARD_FAB2(SCH_1):PAGE40
   F31    GND @BASEBOARD_FAB2_LIB.BASEBOARD_FAB2(SCH_1):GND    I20 @BASEBOARD_FAB2_LIB.BASEBOARD_FAB2(SCH_1):PAGE40
   F37    GND @BASEBOARD_FAB2_LIB.BASEBOARD_FAB2(SCH_1):GND    I20 @BASEBOARD_FAB2_LIB.BASEBOARD_FAB2(SCH_1):PAGE40
   F43    GND @BASEBOARD_FAB2_LIB.BASEBOARD_FAB2(SCH_1):GND    I20 @BASEBOARD_FAB2_LIB.BASEBOARD_FAB2(SCH_1):PAGE40
   F67    GND @BASEBOARD_FAB2_LIB.BASEBOARD_FAB2(SCH_1):GND    I20 @BASEBOARD_FAB2_LIB.BASEBOARD_FAB2(SCH_1):PAGE40
   F69    GND @BASEBOARD_FAB2_LIB.BASEBOARD_FAB2(SCH_1):GND    I20 @BASEBOARD_FAB2_LIB.BASEBOARD_FAB2(SCH_1):PAGE40
    G4    GND @BASEBOARD_FAB2_LIB.BASEBOARD_FAB2(SCH_1):GND    I20 @BASEBOARD_FAB2_LIB.BASEBOARD_FAB2(SCH_1):PAGE40
    G8    GND @BASEBOARD_FAB2_LIB.BASEBOARD_FAB2(SCH_1):GND    I20 @BASEBOARD_FAB2_LIB.BASEBOARD_FAB2(SCH_1):PAGE40
   G22    GND @BASEBOARD_FAB2_LIB.BASEBOARD_FAB2(SCH_1):GND    I20 @BASEBOARD_FAB2_LIB.BASEBOARD_FAB2(SCH_1):PAGE40
   G24    GND @BASEBOARD_FAB2_LIB.BASEBOARD_FAB2(SCH_1):GND    I20 @BASEBOARD_FAB2_LIB.BASEBOARD_FAB2(SCH_1):PAGE40
   G26    GND @BASEBOARD_FAB2_LIB.BASEBOARD_FAB2(SCH_1):GND    I20 @BASEBOARD_FAB2_LIB.BASEBOARD_FAB2(SCH_1):PAGE40
   G30    GND @BASEBOARD_FAB2_LIB.BASEBOARD_FAB2(SCH_1):GND    I20 @BASEBOARD_FAB2_LIB.BASEBOARD_FAB2(SCH_1):PAGE40
   G32    GND @BASEBOARD_FAB2_LIB.BASEBOARD_FAB2(SCH_1):GND    I20 @BASEBOARD_FAB2_LIB.BASEBOARD_FAB2(SCH_1):PAGE40
   G36    GND @BASEBOARD_FAB2_LIB.BASEBOARD_FAB2(SCH_1):GND    I20 @BASEBOARD_FAB2_LIB.BASEBOARD_FAB2(SCH_1):PAGE40
   G38    GND @BASEBOARD_FAB2_LIB.BASEBOARD_FAB2(SCH_1):GND    I20 @BASEBOARD_FAB2_LIB.BASEBOARD_FAB2(SCH_1):PAGE40
   G42    GND @BASEBOARD_FAB2_LIB.BASEBOARD_FAB2(SCH_1):GND    I20 @BASEBOARD_FAB2_LIB.BASEBOARD_FAB2(SCH_1):PAGE40
   G66    GND @BASEBOARD_FAB2_LIB.BASEBOARD_FAB2(SCH_1):GND    I20 @BASEBOARD_FAB2_LIB.BASEBOARD_FAB2(SCH_1):PAGE40
   G70    GND @BASEBOARD_FAB2_LIB.BASEBOARD_FAB2(SCH_1):GND    I20 @BASEBOARD_FAB2_LIB.BASEBOARD_FAB2(SCH_1):PAGE40
   G76    GND @BASEBOARD_FAB2_LIB.BASEBOARD_FAB2(SCH_1):GND    I20 @BASEBOARD_FAB2_LIB.BASEBOARD_FAB2(SCH_1):PAGE40
   G78    GND @BASEBOARD_FAB2_LIB.BASEBOARD_FAB2(SCH_1):GND    I20 @BASEBOARD_FAB2_LIB.BASEBOARD_FAB2(SCH_1):PAGE40
   G80    GND @BASEBOARD_FAB2_LIB.BASEBOARD_FAB2(SCH_1):GND    I20 @BASEBOARD_FAB2_LIB.BASEBOARD_FAB2(SCH_1):PAGE40
   G82    GND @BASEBOARD_FAB2_LIB.BASEBOARD_FAB2(SCH_1):GND    I20 @BASEBOARD_FAB2_LIB.BASEBOARD_FAB2(SCH_1):PAGE40
    H3    GND @BASEBOARD_FAB2_LIB.BASEBOARD_FAB2(SCH_1):GND    I20 @BASEBOARD_FAB2_LIB.BASEBOARD_FAB2(SCH_1):PAGE40
   H11    GND @BASEBOARD_FAB2_LIB.BASEBOARD_FAB2(SCH_1):GND    I20 @BASEBOARD_FAB2_LIB.BASEBOARD_FAB2(SCH_1):PAGE40
   H25    GND @BASEBOARD_FAB2_LIB.BASEBOARD_FAB2(SCH_1):GND    I20 @BASEBOARD_FAB2_LIB.BASEBOARD_FAB2(SCH_1):PAGE40
   H27    GND @BASEBOARD_FAB2_LIB.BASEBOARD_FAB2(SCH_1):GND    I20 @BASEBOARD_FAB2_LIB.BASEBOARD_FAB2(SCH_1):PAGE40
   H29    GND @BASEBOARD_FAB2_LIB.BASEBOARD_FAB2(SCH_1):GND    I20 @BASEBOARD_FAB2_LIB.BASEBOARD_FAB2(SCH_1):PAGE40
   H31    GND @BASEBOARD_FAB2_LIB.BASEBOARD_FAB2(SCH_1):GND    I20 @BASEBOARD_FAB2_LIB.BASEBOARD_FAB2(SCH_1):PAGE40
   H33    GND @BASEBOARD_FAB2_LIB.BASEBOARD_FAB2(SCH_1):GND    I20 @BASEBOARD_FAB2_LIB.BASEBOARD_FAB2(SCH_1):PAGE40
   H35    GND @BASEBOARD_FAB2_LIB.BASEBOARD_FAB2(SCH_1):GND    I20 @BASEBOARD_FAB2_LIB.BASEBOARD_FAB2(SCH_1):PAGE40
   H37    GND @BASEBOARD_FAB2_LIB.BASEBOARD_FAB2(SCH_1):GND    I20 @BASEBOARD_FAB2_LIB.BASEBOARD_FAB2(SCH_1):PAGE40
   H39    GND @BASEBOARD_FAB2_LIB.BASEBOARD_FAB2(SCH_1):GND    I20 @BASEBOARD_FAB2_LIB.BASEBOARD_FAB2(SCH_1):PAGE40
   H41    GND @BASEBOARD_FAB2_LIB.BASEBOARD_FAB2(SCH_1):GND    I20 @BASEBOARD_FAB2_LIB.BASEBOARD_FAB2(SCH_1):PAGE40
   H65    GND @BASEBOARD_FAB2_LIB.BASEBOARD_FAB2(SCH_1):GND    I20 @BASEBOARD_FAB2_LIB.BASEBOARD_FAB2(SCH_1):PAGE40
   H71    GND @BASEBOARD_FAB2_LIB.BASEBOARD_FAB2(SCH_1):GND    I20 @BASEBOARD_FAB2_LIB.BASEBOARD_FAB2(SCH_1):PAGE40
   H75    GND @BASEBOARD_FAB2_LIB.BASEBOARD_FAB2(SCH_1):GND    I20 @BASEBOARD_FAB2_LIB.BASEBOARD_FAB2(SCH_1):PAGE40
  DN44    GND @BASEBOARD_FAB2_LIB.BASEBOARD_FAB2(SCH_1):GND    I20 @BASEBOARD_FAB2_LIB.BASEBOARD_FAB2(SCH_1):PAGE40
    J4    GND @BASEBOARD_FAB2_LIB.BASEBOARD_FAB2(SCH_1):GND    I20 @BASEBOARD_FAB2_LIB.BASEBOARD_FAB2(SCH_1):PAGE40
   J12    GND @BASEBOARD_FAB2_LIB.BASEBOARD_FAB2(SCH_1):GND    I20 @BASEBOARD_FAB2_LIB.BASEBOARD_FAB2(SCH_1):PAGE40
   J14    GND @BASEBOARD_FAB2_LIB.BASEBOARD_FAB2(SCH_1):GND    I20 @BASEBOARD_FAB2_LIB.BASEBOARD_FAB2(SCH_1):PAGE40
   J22    GND @BASEBOARD_FAB2_LIB.BASEBOARD_FAB2(SCH_1):GND    I20 @BASEBOARD_FAB2_LIB.BASEBOARD_FAB2(SCH_1):PAGE40
   J26    GND @BASEBOARD_FAB2_LIB.BASEBOARD_FAB2(SCH_1):GND    I20 @BASEBOARD_FAB2_LIB.BASEBOARD_FAB2(SCH_1):PAGE40
   J28    GND @BASEBOARD_FAB2_LIB.BASEBOARD_FAB2(SCH_1):GND    I20 @BASEBOARD_FAB2_LIB.BASEBOARD_FAB2(SCH_1):PAGE40
   J32    GND @BASEBOARD_FAB2_LIB.BASEBOARD_FAB2(SCH_1):GND    I20 @BASEBOARD_FAB2_LIB.BASEBOARD_FAB2(SCH_1):PAGE40
   J34    GND @BASEBOARD_FAB2_LIB.BASEBOARD_FAB2(SCH_1):GND    I20 @BASEBOARD_FAB2_LIB.BASEBOARD_FAB2(SCH_1):PAGE40
   J38    GND @BASEBOARD_FAB2_LIB.BASEBOARD_FAB2(SCH_1):GND    I20 @BASEBOARD_FAB2_LIB.BASEBOARD_FAB2(SCH_1):PAGE40
   J40    GND @BASEBOARD_FAB2_LIB.BASEBOARD_FAB2(SCH_1):GND    I20 @BASEBOARD_FAB2_LIB.BASEBOARD_FAB2(SCH_1):PAGE40
   J72    GND @BASEBOARD_FAB2_LIB.BASEBOARD_FAB2(SCH_1):GND    I20 @BASEBOARD_FAB2_LIB.BASEBOARD_FAB2(SCH_1):PAGE40
   J74    GND @BASEBOARD_FAB2_LIB.BASEBOARD_FAB2(SCH_1):GND    I20 @BASEBOARD_FAB2_LIB.BASEBOARD_FAB2(SCH_1):PAGE40
   J76    GND @BASEBOARD_FAB2_LIB.BASEBOARD_FAB2(SCH_1):GND    I21 @BASEBOARD_FAB2_LIB.BASEBOARD_FAB2(SCH_1):PAGE40
   J82    GND @BASEBOARD_FAB2_LIB.BASEBOARD_FAB2(SCH_1):GND    I21 @BASEBOARD_FAB2_LIB.BASEBOARD_FAB2(SCH_1):PAGE40
   J84    GND @BASEBOARD_FAB2_LIB.BASEBOARD_FAB2(SCH_1):GND    I21 @BASEBOARD_FAB2_LIB.BASEBOARD_FAB2(SCH_1):PAGE40
    K1    GND @BASEBOARD_FAB2_LIB.BASEBOARD_FAB2(SCH_1):GND    I21 @BASEBOARD_FAB2_LIB.BASEBOARD_FAB2(SCH_1):PAGE40
   K11    GND @BASEBOARD_FAB2_LIB.BASEBOARD_FAB2(SCH_1):GND    I21 @BASEBOARD_FAB2_LIB.BASEBOARD_FAB2(SCH_1):PAGE40
   K13    GND @BASEBOARD_FAB2_LIB.BASEBOARD_FAB2(SCH_1):GND    I21 @BASEBOARD_FAB2_LIB.BASEBOARD_FAB2(SCH_1):PAGE40
   K17    GND @BASEBOARD_FAB2_LIB.BASEBOARD_FAB2(SCH_1):GND    I21 @BASEBOARD_FAB2_LIB.BASEBOARD_FAB2(SCH_1):PAGE40
   DB7    GND @BASEBOARD_FAB2_LIB.BASEBOARD_FAB2(SCH_1):GND    I21 @BASEBOARD_FAB2_LIB.BASEBOARD_FAB2(SCH_1):PAGE40
   K27    GND @BASEBOARD_FAB2_LIB.BASEBOARD_FAB2(SCH_1):GND    I21 @BASEBOARD_FAB2_LIB.BASEBOARD_FAB2(SCH_1):PAGE40
   K33    GND @BASEBOARD_FAB2_LIB.BASEBOARD_FAB2(SCH_1):GND    I21 @BASEBOARD_FAB2_LIB.BASEBOARD_FAB2(SCH_1):PAGE40
   K39    GND @BASEBOARD_FAB2_LIB.BASEBOARD_FAB2(SCH_1):GND    I21 @BASEBOARD_FAB2_LIB.BASEBOARD_FAB2(SCH_1):PAGE40
   K65    GND @BASEBOARD_FAB2_LIB.BASEBOARD_FAB2(SCH_1):GND    I21 @BASEBOARD_FAB2_LIB.BASEBOARD_FAB2(SCH_1):PAGE40
   K67    GND @BASEBOARD_FAB2_LIB.BASEBOARD_FAB2(SCH_1):GND    I21 @BASEBOARD_FAB2_LIB.BASEBOARD_FAB2(SCH_1):PAGE40
   K69    GND @BASEBOARD_FAB2_LIB.BASEBOARD_FAB2(SCH_1):GND    I21 @BASEBOARD_FAB2_LIB.BASEBOARD_FAB2(SCH_1):PAGE40
   K71    GND @BASEBOARD_FAB2_LIB.BASEBOARD_FAB2(SCH_1):GND    I21 @BASEBOARD_FAB2_LIB.BASEBOARD_FAB2(SCH_1):PAGE40
   K73    GND @BASEBOARD_FAB2_LIB.BASEBOARD_FAB2(SCH_1):GND    I21 @BASEBOARD_FAB2_LIB.BASEBOARD_FAB2(SCH_1):PAGE40
   K77    GND @BASEBOARD_FAB2_LIB.BASEBOARD_FAB2(SCH_1):GND    I21 @BASEBOARD_FAB2_LIB.BASEBOARD_FAB2(SCH_1):PAGE40
   K81    GND @BASEBOARD_FAB2_LIB.BASEBOARD_FAB2(SCH_1):GND    I21 @BASEBOARD_FAB2_LIB.BASEBOARD_FAB2(SCH_1):PAGE40
   K83    GND @BASEBOARD_FAB2_LIB.BASEBOARD_FAB2(SCH_1):GND    I21 @BASEBOARD_FAB2_LIB.BASEBOARD_FAB2(SCH_1):PAGE40
   K85    GND @BASEBOARD_FAB2_LIB.BASEBOARD_FAB2(SCH_1):GND    I21 @BASEBOARD_FAB2_LIB.BASEBOARD_FAB2(SCH_1):PAGE40
   L10    GND @BASEBOARD_FAB2_LIB.BASEBOARD_FAB2(SCH_1):GND    I21 @BASEBOARD_FAB2_LIB.BASEBOARD_FAB2(SCH_1):PAGE40
    L2    GND @BASEBOARD_FAB2_LIB.BASEBOARD_FAB2(SCH_1):GND    I21 @BASEBOARD_FAB2_LIB.BASEBOARD_FAB2(SCH_1):PAGE40
    L6    GND @BASEBOARD_FAB2_LIB.BASEBOARD_FAB2(SCH_1):GND    I21 @BASEBOARD_FAB2_LIB.BASEBOARD_FAB2(SCH_1):PAGE40
   L20    GND @BASEBOARD_FAB2_LIB.BASEBOARD_FAB2(SCH_1):GND    I21 @BASEBOARD_FAB2_LIB.BASEBOARD_FAB2(SCH_1):PAGE40
   L22    GND @BASEBOARD_FAB2_LIB.BASEBOARD_FAB2(SCH_1):GND    I21 @BASEBOARD_FAB2_LIB.BASEBOARD_FAB2(SCH_1):PAGE40
   L72    GND @BASEBOARD_FAB2_LIB.BASEBOARD_FAB2(SCH_1):GND    I21 @BASEBOARD_FAB2_LIB.BASEBOARD_FAB2(SCH_1):PAGE40
   L78    GND @BASEBOARD_FAB2_LIB.BASEBOARD_FAB2(SCH_1):GND    I21 @BASEBOARD_FAB2_LIB.BASEBOARD_FAB2(SCH_1):PAGE40
   L80    GND @BASEBOARD_FAB2_LIB.BASEBOARD_FAB2(SCH_1):GND    I21 @BASEBOARD_FAB2_LIB.BASEBOARD_FAB2(SCH_1):PAGE40
   L82    GND @BASEBOARD_FAB2_LIB.BASEBOARD_FAB2(SCH_1):GND    I21 @BASEBOARD_FAB2_LIB.BASEBOARD_FAB2(SCH_1):PAGE40
   BT9    GND @BASEBOARD_FAB2_LIB.BASEBOARD_FAB2(SCH_1):GND    I21 @BASEBOARD_FAB2_LIB.BASEBOARD_FAB2(SCH_1):PAGE40
   CT7    GND @BASEBOARD_FAB2_LIB.BASEBOARD_FAB2(SCH_1):GND    I21 @BASEBOARD_FAB2_LIB.BASEBOARD_FAB2(SCH_1):PAGE40
   M15    GND @BASEBOARD_FAB2_LIB.BASEBOARD_FAB2(SCH_1):GND    I21 @BASEBOARD_FAB2_LIB.BASEBOARD_FAB2(SCH_1):PAGE40
   M17    GND @BASEBOARD_FAB2_LIB.BASEBOARD_FAB2(SCH_1):GND    I21 @BASEBOARD_FAB2_LIB.BASEBOARD_FAB2(SCH_1):PAGE40
   M19    GND @BASEBOARD_FAB2_LIB.BASEBOARD_FAB2(SCH_1):GND    I21 @BASEBOARD_FAB2_LIB.BASEBOARD_FAB2(SCH_1):PAGE40
   M23    GND @BASEBOARD_FAB2_LIB.BASEBOARD_FAB2(SCH_1):GND    I21 @BASEBOARD_FAB2_LIB.BASEBOARD_FAB2(SCH_1):PAGE40
   M25    GND @BASEBOARD_FAB2_LIB.BASEBOARD_FAB2(SCH_1):GND    I21 @BASEBOARD_FAB2_LIB.BASEBOARD_FAB2(SCH_1):PAGE40
   M27    GND @BASEBOARD_FAB2_LIB.BASEBOARD_FAB2(SCH_1):GND    I21 @BASEBOARD_FAB2_LIB.BASEBOARD_FAB2(SCH_1):PAGE40
   M29    GND @BASEBOARD_FAB2_LIB.BASEBOARD_FAB2(SCH_1):GND    I21 @BASEBOARD_FAB2_LIB.BASEBOARD_FAB2(SCH_1):PAGE40
   M31    GND @BASEBOARD_FAB2_LIB.BASEBOARD_FAB2(SCH_1):GND    I21 @BASEBOARD_FAB2_LIB.BASEBOARD_FAB2(SCH_1):PAGE40
   M33    GND @BASEBOARD_FAB2_LIB.BASEBOARD_FAB2(SCH_1):GND    I21 @BASEBOARD_FAB2_LIB.BASEBOARD_FAB2(SCH_1):PAGE40
   M35    GND @BASEBOARD_FAB2_LIB.BASEBOARD_FAB2(SCH_1):GND    I21 @BASEBOARD_FAB2_LIB.BASEBOARD_FAB2(SCH_1):PAGE40
   M37    GND @BASEBOARD_FAB2_LIB.BASEBOARD_FAB2(SCH_1):GND    I21 @BASEBOARD_FAB2_LIB.BASEBOARD_FAB2(SCH_1):PAGE40
   M39    GND @BASEBOARD_FAB2_LIB.BASEBOARD_FAB2(SCH_1):GND    I21 @BASEBOARD_FAB2_LIB.BASEBOARD_FAB2(SCH_1):PAGE40
   M41    GND @BASEBOARD_FAB2_LIB.BASEBOARD_FAB2(SCH_1):GND    I21 @BASEBOARD_FAB2_LIB.BASEBOARD_FAB2(SCH_1):PAGE40
   M43    GND @BASEBOARD_FAB2_LIB.BASEBOARD_FAB2(SCH_1):GND    I21 @BASEBOARD_FAB2_LIB.BASEBOARD_FAB2(SCH_1):PAGE40
   M65    GND @BASEBOARD_FAB2_LIB.BASEBOARD_FAB2(SCH_1):GND    I21 @BASEBOARD_FAB2_LIB.BASEBOARD_FAB2(SCH_1):PAGE40
   M71    GND @BASEBOARD_FAB2_LIB.BASEBOARD_FAB2(SCH_1):GND    I21 @BASEBOARD_FAB2_LIB.BASEBOARD_FAB2(SCH_1):PAGE40
   M79    GND @BASEBOARD_FAB2_LIB.BASEBOARD_FAB2(SCH_1):GND    I21 @BASEBOARD_FAB2_LIB.BASEBOARD_FAB2(SCH_1):PAGE40
   M83    GND @BASEBOARD_FAB2_LIB.BASEBOARD_FAB2(SCH_1):GND    I21 @BASEBOARD_FAB2_LIB.BASEBOARD_FAB2(SCH_1):PAGE40
   M85    GND @BASEBOARD_FAB2_LIB.BASEBOARD_FAB2(SCH_1):GND    I21 @BASEBOARD_FAB2_LIB.BASEBOARD_FAB2(SCH_1):PAGE40
  DM19    GND @BASEBOARD_FAB2_LIB.BASEBOARD_FAB2(SCH_1):GND    I21 @BASEBOARD_FAB2_LIB.BASEBOARD_FAB2(SCH_1):PAGE40
   N20    GND @BASEBOARD_FAB2_LIB.BASEBOARD_FAB2(SCH_1):GND    I21 @BASEBOARD_FAB2_LIB.BASEBOARD_FAB2(SCH_1):PAGE40
   N22    GND @BASEBOARD_FAB2_LIB.BASEBOARD_FAB2(SCH_1):GND    I21 @BASEBOARD_FAB2_LIB.BASEBOARD_FAB2(SCH_1):PAGE40
    N6    GND @BASEBOARD_FAB2_LIB.BASEBOARD_FAB2(SCH_1):GND    I21 @BASEBOARD_FAB2_LIB.BASEBOARD_FAB2(SCH_1):PAGE40
   N66    GND @BASEBOARD_FAB2_LIB.BASEBOARD_FAB2(SCH_1):GND    I21 @BASEBOARD_FAB2_LIB.BASEBOARD_FAB2(SCH_1):PAGE40
   N70    GND @BASEBOARD_FAB2_LIB.BASEBOARD_FAB2(SCH_1):GND    I21 @BASEBOARD_FAB2_LIB.BASEBOARD_FAB2(SCH_1):PAGE40
   N72    GND @BASEBOARD_FAB2_LIB.BASEBOARD_FAB2(SCH_1):GND    I21 @BASEBOARD_FAB2_LIB.BASEBOARD_FAB2(SCH_1):PAGE40
   N74    GND @BASEBOARD_FAB2_LIB.BASEBOARD_FAB2(SCH_1):GND    I21 @BASEBOARD_FAB2_LIB.BASEBOARD_FAB2(SCH_1):PAGE40
   N76    GND @BASEBOARD_FAB2_LIB.BASEBOARD_FAB2(SCH_1):GND    I21 @BASEBOARD_FAB2_LIB.BASEBOARD_FAB2(SCH_1):PAGE40
   N78    GND @BASEBOARD_FAB2_LIB.BASEBOARD_FAB2(SCH_1):GND    I21 @BASEBOARD_FAB2_LIB.BASEBOARD_FAB2(SCH_1):PAGE40
    N4    GND @BASEBOARD_FAB2_LIB.BASEBOARD_FAB2(SCH_1):GND    I21 @BASEBOARD_FAB2_LIB.BASEBOARD_FAB2(SCH_1):PAGE40
    N8    GND @BASEBOARD_FAB2_LIB.BASEBOARD_FAB2(SCH_1):GND    I21 @BASEBOARD_FAB2_LIB.BASEBOARD_FAB2(SCH_1):PAGE40
   P11    GND @BASEBOARD_FAB2_LIB.BASEBOARD_FAB2(SCH_1):GND    I21 @BASEBOARD_FAB2_LIB.BASEBOARD_FAB2(SCH_1):PAGE40
   P15    GND @BASEBOARD_FAB2_LIB.BASEBOARD_FAB2(SCH_1):GND    I21 @BASEBOARD_FAB2_LIB.BASEBOARD_FAB2(SCH_1):PAGE40
   P27    GND @BASEBOARD_FAB2_LIB.BASEBOARD_FAB2(SCH_1):GND    I21 @BASEBOARD_FAB2_LIB.BASEBOARD_FAB2(SCH_1):PAGE40
   P33    GND @BASEBOARD_FAB2_LIB.BASEBOARD_FAB2(SCH_1):GND    I21 @BASEBOARD_FAB2_LIB.BASEBOARD_FAB2(SCH_1):PAGE40
   P39    GND @BASEBOARD_FAB2_LIB.BASEBOARD_FAB2(SCH_1):GND    I21 @BASEBOARD_FAB2_LIB.BASEBOARD_FAB2(SCH_1):PAGE40
   P67    GND @BASEBOARD_FAB2_LIB.BASEBOARD_FAB2(SCH_1):GND    I21 @BASEBOARD_FAB2_LIB.BASEBOARD_FAB2(SCH_1):PAGE40
   P69    GND @BASEBOARD_FAB2_LIB.BASEBOARD_FAB2(SCH_1):GND    I21 @BASEBOARD_FAB2_LIB.BASEBOARD_FAB2(SCH_1):PAGE40
   P71    GND @BASEBOARD_FAB2_LIB.BASEBOARD_FAB2(SCH_1):GND    I21 @BASEBOARD_FAB2_LIB.BASEBOARD_FAB2(SCH_1):PAGE40
   P81    GND @BASEBOARD_FAB2_LIB.BASEBOARD_FAB2(SCH_1):GND    I21 @BASEBOARD_FAB2_LIB.BASEBOARD_FAB2(SCH_1):PAGE40
   P83    GND @BASEBOARD_FAB2_LIB.BASEBOARD_FAB2(SCH_1):GND    I21 @BASEBOARD_FAB2_LIB.BASEBOARD_FAB2(SCH_1):PAGE40
   R14    GND @BASEBOARD_FAB2_LIB.BASEBOARD_FAB2(SCH_1):GND    I21 @BASEBOARD_FAB2_LIB.BASEBOARD_FAB2(SCH_1):PAGE40
   R18    GND @BASEBOARD_FAB2_LIB.BASEBOARD_FAB2(SCH_1):GND    I21 @BASEBOARD_FAB2_LIB.BASEBOARD_FAB2(SCH_1):PAGE40
    R2    GND @BASEBOARD_FAB2_LIB.BASEBOARD_FAB2(SCH_1):GND    I21 @BASEBOARD_FAB2_LIB.BASEBOARD_FAB2(SCH_1):PAGE40
    R4    GND @BASEBOARD_FAB2_LIB.BASEBOARD_FAB2(SCH_1):GND    I21 @BASEBOARD_FAB2_LIB.BASEBOARD_FAB2(SCH_1):PAGE40
   R22    GND @BASEBOARD_FAB2_LIB.BASEBOARD_FAB2(SCH_1):GND    I21 @BASEBOARD_FAB2_LIB.BASEBOARD_FAB2(SCH_1):PAGE40
   R26    GND @BASEBOARD_FAB2_LIB.BASEBOARD_FAB2(SCH_1):GND    I21 @BASEBOARD_FAB2_LIB.BASEBOARD_FAB2(SCH_1):PAGE40
   R28    GND @BASEBOARD_FAB2_LIB.BASEBOARD_FAB2(SCH_1):GND    I21 @BASEBOARD_FAB2_LIB.BASEBOARD_FAB2(SCH_1):PAGE40
   R32    GND @BASEBOARD_FAB2_LIB.BASEBOARD_FAB2(SCH_1):GND    I21 @BASEBOARD_FAB2_LIB.BASEBOARD_FAB2(SCH_1):PAGE40
   R34    GND @BASEBOARD_FAB2_LIB.BASEBOARD_FAB2(SCH_1):GND    I21 @BASEBOARD_FAB2_LIB.BASEBOARD_FAB2(SCH_1):PAGE40
   R38    GND @BASEBOARD_FAB2_LIB.BASEBOARD_FAB2(SCH_1):GND    I21 @BASEBOARD_FAB2_LIB.BASEBOARD_FAB2(SCH_1):PAGE40
   R40    GND @BASEBOARD_FAB2_LIB.BASEBOARD_FAB2(SCH_1):GND    I21 @BASEBOARD_FAB2_LIB.BASEBOARD_FAB2(SCH_1):PAGE40
   R68    GND @BASEBOARD_FAB2_LIB.BASEBOARD_FAB2(SCH_1):GND    I21 @BASEBOARD_FAB2_LIB.BASEBOARD_FAB2(SCH_1):PAGE40
   R72    GND @BASEBOARD_FAB2_LIB.BASEBOARD_FAB2(SCH_1):GND    I21 @BASEBOARD_FAB2_LIB.BASEBOARD_FAB2(SCH_1):PAGE40
   R78    GND @BASEBOARD_FAB2_LIB.BASEBOARD_FAB2(SCH_1):GND    I21 @BASEBOARD_FAB2_LIB.BASEBOARD_FAB2(SCH_1):PAGE40
   R86    GND @BASEBOARD_FAB2_LIB.BASEBOARD_FAB2(SCH_1):GND    I21 @BASEBOARD_FAB2_LIB.BASEBOARD_FAB2(SCH_1):PAGE40
   T13    GND @BASEBOARD_FAB2_LIB.BASEBOARD_FAB2(SCH_1):GND    I21 @BASEBOARD_FAB2_LIB.BASEBOARD_FAB2(SCH_1):PAGE40
   T17    GND @BASEBOARD_FAB2_LIB.BASEBOARD_FAB2(SCH_1):GND    I21 @BASEBOARD_FAB2_LIB.BASEBOARD_FAB2(SCH_1):PAGE40
   T25    GND @BASEBOARD_FAB2_LIB.BASEBOARD_FAB2(SCH_1):GND    I21 @BASEBOARD_FAB2_LIB.BASEBOARD_FAB2(SCH_1):PAGE40
   T29    GND @BASEBOARD_FAB2_LIB.BASEBOARD_FAB2(SCH_1):GND    I21 @BASEBOARD_FAB2_LIB.BASEBOARD_FAB2(SCH_1):PAGE40
   T31    GND @BASEBOARD_FAB2_LIB.BASEBOARD_FAB2(SCH_1):GND    I21 @BASEBOARD_FAB2_LIB.BASEBOARD_FAB2(SCH_1):PAGE40
   T35    GND @BASEBOARD_FAB2_LIB.BASEBOARD_FAB2(SCH_1):GND    I21 @BASEBOARD_FAB2_LIB.BASEBOARD_FAB2(SCH_1):PAGE40
   T37    GND @BASEBOARD_FAB2_LIB.BASEBOARD_FAB2(SCH_1):GND    I21 @BASEBOARD_FAB2_LIB.BASEBOARD_FAB2(SCH_1):PAGE40
   T41    GND @BASEBOARD_FAB2_LIB.BASEBOARD_FAB2(SCH_1):GND    I21 @BASEBOARD_FAB2_LIB.BASEBOARD_FAB2(SCH_1):PAGE40
   T65    GND @BASEBOARD_FAB2_LIB.BASEBOARD_FAB2(SCH_1):GND    I21 @BASEBOARD_FAB2_LIB.BASEBOARD_FAB2(SCH_1):PAGE40
   T73    GND @BASEBOARD_FAB2_LIB.BASEBOARD_FAB2(SCH_1):GND    I21 @BASEBOARD_FAB2_LIB.BASEBOARD_FAB2(SCH_1):PAGE40
   T77    GND @BASEBOARD_FAB2_LIB.BASEBOARD_FAB2(SCH_1):GND    I21 @BASEBOARD_FAB2_LIB.BASEBOARD_FAB2(SCH_1):PAGE40
   T83    GND @BASEBOARD_FAB2_LIB.BASEBOARD_FAB2(SCH_1):GND    I21 @BASEBOARD_FAB2_LIB.BASEBOARD_FAB2(SCH_1):PAGE40
   T85    GND @BASEBOARD_FAB2_LIB.BASEBOARD_FAB2(SCH_1):GND    I21 @BASEBOARD_FAB2_LIB.BASEBOARD_FAB2(SCH_1):PAGE40
    U2    GND @BASEBOARD_FAB2_LIB.BASEBOARD_FAB2(SCH_1):GND    I21 @BASEBOARD_FAB2_LIB.BASEBOARD_FAB2(SCH_1):PAGE40
    U4    GND @BASEBOARD_FAB2_LIB.BASEBOARD_FAB2(SCH_1):GND    I21 @BASEBOARD_FAB2_LIB.BASEBOARD_FAB2(SCH_1):PAGE40
    U6    GND @BASEBOARD_FAB2_LIB.BASEBOARD_FAB2(SCH_1):GND    I21 @BASEBOARD_FAB2_LIB.BASEBOARD_FAB2(SCH_1):PAGE40
   U20    GND @BASEBOARD_FAB2_LIB.BASEBOARD_FAB2(SCH_1):GND    I21 @BASEBOARD_FAB2_LIB.BASEBOARD_FAB2(SCH_1):PAGE40
   U22    GND @BASEBOARD_FAB2_LIB.BASEBOARD_FAB2(SCH_1):GND    I21 @BASEBOARD_FAB2_LIB.BASEBOARD_FAB2(SCH_1):PAGE40
   U24    GND @BASEBOARD_FAB2_LIB.BASEBOARD_FAB2(SCH_1):GND    I21 @BASEBOARD_FAB2_LIB.BASEBOARD_FAB2(SCH_1):PAGE40
   U30    GND @BASEBOARD_FAB2_LIB.BASEBOARD_FAB2(SCH_1):GND    I21 @BASEBOARD_FAB2_LIB.BASEBOARD_FAB2(SCH_1):PAGE40
   U36    GND @BASEBOARD_FAB2_LIB.BASEBOARD_FAB2(SCH_1):GND    I21 @BASEBOARD_FAB2_LIB.BASEBOARD_FAB2(SCH_1):PAGE40
   U42    GND @BASEBOARD_FAB2_LIB.BASEBOARD_FAB2(SCH_1):GND    I21 @BASEBOARD_FAB2_LIB.BASEBOARD_FAB2(SCH_1):PAGE40
   U68    GND @BASEBOARD_FAB2_LIB.BASEBOARD_FAB2(SCH_1):GND    I21 @BASEBOARD_FAB2_LIB.BASEBOARD_FAB2(SCH_1):PAGE40
   U70    GND @BASEBOARD_FAB2_LIB.BASEBOARD_FAB2(SCH_1):GND    I21 @BASEBOARD_FAB2_LIB.BASEBOARD_FAB2(SCH_1):PAGE40
   U74    GND @BASEBOARD_FAB2_LIB.BASEBOARD_FAB2(SCH_1):GND    I21 @BASEBOARD_FAB2_LIB.BASEBOARD_FAB2(SCH_1):PAGE40
   U76    GND @BASEBOARD_FAB2_LIB.BASEBOARD_FAB2(SCH_1):GND    I21 @BASEBOARD_FAB2_LIB.BASEBOARD_FAB2(SCH_1):PAGE40
   U78    GND @BASEBOARD_FAB2_LIB.BASEBOARD_FAB2(SCH_1):GND    I21 @BASEBOARD_FAB2_LIB.BASEBOARD_FAB2(SCH_1):PAGE40
   U80    GND @BASEBOARD_FAB2_LIB.BASEBOARD_FAB2(SCH_1):GND    I21 @BASEBOARD_FAB2_LIB.BASEBOARD_FAB2(SCH_1):PAGE40
   U86    GND @BASEBOARD_FAB2_LIB.BASEBOARD_FAB2(SCH_1):GND    I21 @BASEBOARD_FAB2_LIB.BASEBOARD_FAB2(SCH_1):PAGE40
    V1    GND @BASEBOARD_FAB2_LIB.BASEBOARD_FAB2(SCH_1):GND    I21 @BASEBOARD_FAB2_LIB.BASEBOARD_FAB2(SCH_1):PAGE40
    V5    GND @BASEBOARD_FAB2_LIB.BASEBOARD_FAB2(SCH_1):GND    I21 @BASEBOARD_FAB2_LIB.BASEBOARD_FAB2(SCH_1):PAGE40
    V9    GND @BASEBOARD_FAB2_LIB.BASEBOARD_FAB2(SCH_1):GND    I21 @BASEBOARD_FAB2_LIB.BASEBOARD_FAB2(SCH_1):PAGE40
   V13    GND @BASEBOARD_FAB2_LIB.BASEBOARD_FAB2(SCH_1):GND    I21 @BASEBOARD_FAB2_LIB.BASEBOARD_FAB2(SCH_1):PAGE40
   V15    GND @BASEBOARD_FAB2_LIB.BASEBOARD_FAB2(SCH_1):GND    I21 @BASEBOARD_FAB2_LIB.BASEBOARD_FAB2(SCH_1):PAGE40
   V21    GND @BASEBOARD_FAB2_LIB.BASEBOARD_FAB2(SCH_1):GND    I21 @BASEBOARD_FAB2_LIB.BASEBOARD_FAB2(SCH_1):PAGE40
   V23    GND @BASEBOARD_FAB2_LIB.BASEBOARD_FAB2(SCH_1):GND    I21 @BASEBOARD_FAB2_LIB.BASEBOARD_FAB2(SCH_1):PAGE40
   V43    GND @BASEBOARD_FAB2_LIB.BASEBOARD_FAB2(SCH_1):GND    I21 @BASEBOARD_FAB2_LIB.BASEBOARD_FAB2(SCH_1):PAGE40
   V73    GND @BASEBOARD_FAB2_LIB.BASEBOARD_FAB2(SCH_1):GND    I21 @BASEBOARD_FAB2_LIB.BASEBOARD_FAB2(SCH_1):PAGE40
   V75    GND @BASEBOARD_FAB2_LIB.BASEBOARD_FAB2(SCH_1):GND    I21 @BASEBOARD_FAB2_LIB.BASEBOARD_FAB2(SCH_1):PAGE40
   V77    GND @BASEBOARD_FAB2_LIB.BASEBOARD_FAB2(SCH_1):GND    I21 @BASEBOARD_FAB2_LIB.BASEBOARD_FAB2(SCH_1):PAGE40
   V83    GND @BASEBOARD_FAB2_LIB.BASEBOARD_FAB2(SCH_1):GND    I21 @BASEBOARD_FAB2_LIB.BASEBOARD_FAB2(SCH_1):PAGE40
    W8    GND @BASEBOARD_FAB2_LIB.BASEBOARD_FAB2(SCH_1):GND    I21 @BASEBOARD_FAB2_LIB.BASEBOARD_FAB2(SCH_1):PAGE40
  AC56    GND @BASEBOARD_FAB2_LIB.BASEBOARD_FAB2(SCH_1):GND    I21 @BASEBOARD_FAB2_LIB.BASEBOARD_FAB2(SCH_1):PAGE40
   W12    GND @BASEBOARD_FAB2_LIB.BASEBOARD_FAB2(SCH_1):GND    I21 @BASEBOARD_FAB2_LIB.BASEBOARD_FAB2(SCH_1):PAGE40
   W22    GND @BASEBOARD_FAB2_LIB.BASEBOARD_FAB2(SCH_1):GND    I21 @BASEBOARD_FAB2_LIB.BASEBOARD_FAB2(SCH_1):PAGE40
   W24    GND @BASEBOARD_FAB2_LIB.BASEBOARD_FAB2(SCH_1):GND    I21 @BASEBOARD_FAB2_LIB.BASEBOARD_FAB2(SCH_1):PAGE40
   W26    GND @BASEBOARD_FAB2_LIB.BASEBOARD_FAB2(SCH_1):GND    I21 @BASEBOARD_FAB2_LIB.BASEBOARD_FAB2(SCH_1):PAGE40
   W28    GND @BASEBOARD_FAB2_LIB.BASEBOARD_FAB2(SCH_1):GND    I21 @BASEBOARD_FAB2_LIB.BASEBOARD_FAB2(SCH_1):PAGE40
   W30    GND @BASEBOARD_FAB2_LIB.BASEBOARD_FAB2(SCH_1):GND    I21 @BASEBOARD_FAB2_LIB.BASEBOARD_FAB2(SCH_1):PAGE40
   W32    GND @BASEBOARD_FAB2_LIB.BASEBOARD_FAB2(SCH_1):GND    I21 @BASEBOARD_FAB2_LIB.BASEBOARD_FAB2(SCH_1):PAGE40
   W34    GND @BASEBOARD_FAB2_LIB.BASEBOARD_FAB2(SCH_1):GND    I21 @BASEBOARD_FAB2_LIB.BASEBOARD_FAB2(SCH_1):PAGE40
   W36    GND @BASEBOARD_FAB2_LIB.BASEBOARD_FAB2(SCH_1):GND    I21 @BASEBOARD_FAB2_LIB.BASEBOARD_FAB2(SCH_1):PAGE40
   W38    GND @BASEBOARD_FAB2_LIB.BASEBOARD_FAB2(SCH_1):GND    I21 @BASEBOARD_FAB2_LIB.BASEBOARD_FAB2(SCH_1):PAGE40
   W40    GND @BASEBOARD_FAB2_LIB.BASEBOARD_FAB2(SCH_1):GND    I21 @BASEBOARD_FAB2_LIB.BASEBOARD_FAB2(SCH_1):PAGE40
   W42    GND @BASEBOARD_FAB2_LIB.BASEBOARD_FAB2(SCH_1):GND    I21 @BASEBOARD_FAB2_LIB.BASEBOARD_FAB2(SCH_1):PAGE40
   W68    GND @BASEBOARD_FAB2_LIB.BASEBOARD_FAB2(SCH_1):GND    I21 @BASEBOARD_FAB2_LIB.BASEBOARD_FAB2(SCH_1):PAGE40
   W74    GND @BASEBOARD_FAB2_LIB.BASEBOARD_FAB2(SCH_1):GND    I21 @BASEBOARD_FAB2_LIB.BASEBOARD_FAB2(SCH_1):PAGE40
   W78    GND @BASEBOARD_FAB2_LIB.BASEBOARD_FAB2(SCH_1):GND    I21 @BASEBOARD_FAB2_LIB.BASEBOARD_FAB2(SCH_1):PAGE40
   W82    GND @BASEBOARD_FAB2_LIB.BASEBOARD_FAB2(SCH_1):GND    I21 @BASEBOARD_FAB2_LIB.BASEBOARD_FAB2(SCH_1):PAGE40
   Y15    GND @BASEBOARD_FAB2_LIB.BASEBOARD_FAB2(SCH_1):GND    I21 @BASEBOARD_FAB2_LIB.BASEBOARD_FAB2(SCH_1):PAGE40
   Y17    GND @BASEBOARD_FAB2_LIB.BASEBOARD_FAB2(SCH_1):GND    I21 @BASEBOARD_FAB2_LIB.BASEBOARD_FAB2(SCH_1):PAGE40
    Y5    GND @BASEBOARD_FAB2_LIB.BASEBOARD_FAB2(SCH_1):GND    I21 @BASEBOARD_FAB2_LIB.BASEBOARD_FAB2(SCH_1):PAGE40
   Y67    GND @BASEBOARD_FAB2_LIB.BASEBOARD_FAB2(SCH_1):GND    I21 @BASEBOARD_FAB2_LIB.BASEBOARD_FAB2(SCH_1):PAGE40
    Y7    GND @BASEBOARD_FAB2_LIB.BASEBOARD_FAB2(SCH_1):GND    I21 @BASEBOARD_FAB2_LIB.BASEBOARD_FAB2(SCH_1):PAGE40
    Y9    GND @BASEBOARD_FAB2_LIB.BASEBOARD_FAB2(SCH_1):GND    I21 @BASEBOARD_FAB2_LIB.BASEBOARD_FAB2(SCH_1):PAGE40
   Y71    GND @BASEBOARD_FAB2_LIB.BASEBOARD_FAB2(SCH_1):GND    I21 @BASEBOARD_FAB2_LIB.BASEBOARD_FAB2(SCH_1):PAGE40
   Y73    GND @BASEBOARD_FAB2_LIB.BASEBOARD_FAB2(SCH_1):GND    I21 @BASEBOARD_FAB2_LIB.BASEBOARD_FAB2(SCH_1):PAGE40
   Y79    GND @BASEBOARD_FAB2_LIB.BASEBOARD_FAB2(SCH_1):GND    I21 @BASEBOARD_FAB2_LIB.BASEBOARD_FAB2(SCH_1):PAGE40
   Y81    GND @BASEBOARD_FAB2_LIB.BASEBOARD_FAB2(SCH_1):GND    I21 @BASEBOARD_FAB2_LIB.BASEBOARD_FAB2(SCH_1):PAGE40
   Y83    GND @BASEBOARD_FAB2_LIB.BASEBOARD_FAB2(SCH_1):GND    I21 @BASEBOARD_FAB2_LIB.BASEBOARD_FAB2(SCH_1):PAGE40
   Y85    GND @BASEBOARD_FAB2_LIB.BASEBOARD_FAB2(SCH_1):GND    I21 @BASEBOARD_FAB2_LIB.BASEBOARD_FAB2(SCH_1):PAGE40
   AA4    GND @BASEBOARD_FAB2_LIB.BASEBOARD_FAB2(SCH_1):GND    I21 @BASEBOARD_FAB2_LIB.BASEBOARD_FAB2(SCH_1):PAGE40
  AA16    GND @BASEBOARD_FAB2_LIB.BASEBOARD_FAB2(SCH_1):GND    I21 @BASEBOARD_FAB2_LIB.BASEBOARD_FAB2(SCH_1):PAGE40
  AA18    GND @BASEBOARD_FAB2_LIB.BASEBOARD_FAB2(SCH_1):GND    I22 @BASEBOARD_FAB2_LIB.BASEBOARD_FAB2(SCH_1):PAGE40
  AA22    GND @BASEBOARD_FAB2_LIB.BASEBOARD_FAB2(SCH_1):GND    I22 @BASEBOARD_FAB2_LIB.BASEBOARD_FAB2(SCH_1):PAGE40
  AA24    GND @BASEBOARD_FAB2_LIB.BASEBOARD_FAB2(SCH_1):GND    I22 @BASEBOARD_FAB2_LIB.BASEBOARD_FAB2(SCH_1):PAGE40
  AA30    GND @BASEBOARD_FAB2_LIB.BASEBOARD_FAB2(SCH_1):GND    I22 @BASEBOARD_FAB2_LIB.BASEBOARD_FAB2(SCH_1):PAGE40
  AA36    GND @BASEBOARD_FAB2_LIB.BASEBOARD_FAB2(SCH_1):GND    I22 @BASEBOARD_FAB2_LIB.BASEBOARD_FAB2(SCH_1):PAGE40
  AA42    GND @BASEBOARD_FAB2_LIB.BASEBOARD_FAB2(SCH_1):GND    I22 @BASEBOARD_FAB2_LIB.BASEBOARD_FAB2(SCH_1):PAGE40
  AA64    GND @BASEBOARD_FAB2_LIB.BASEBOARD_FAB2(SCH_1):GND    I22 @BASEBOARD_FAB2_LIB.BASEBOARD_FAB2(SCH_1):PAGE40
  AA66    GND @BASEBOARD_FAB2_LIB.BASEBOARD_FAB2(SCH_1):GND    I22 @BASEBOARD_FAB2_LIB.BASEBOARD_FAB2(SCH_1):PAGE40
  AA68    GND @BASEBOARD_FAB2_LIB.BASEBOARD_FAB2(SCH_1):GND    I22 @BASEBOARD_FAB2_LIB.BASEBOARD_FAB2(SCH_1):PAGE40
  AA76    GND @BASEBOARD_FAB2_LIB.BASEBOARD_FAB2(SCH_1):GND    I22 @BASEBOARD_FAB2_LIB.BASEBOARD_FAB2(SCH_1):PAGE40
  AA78    GND @BASEBOARD_FAB2_LIB.BASEBOARD_FAB2(SCH_1):GND    I22 @BASEBOARD_FAB2_LIB.BASEBOARD_FAB2(SCH_1):PAGE40
  AA80    GND @BASEBOARD_FAB2_LIB.BASEBOARD_FAB2(SCH_1):GND    I22 @BASEBOARD_FAB2_LIB.BASEBOARD_FAB2(SCH_1):PAGE40
  AA82    GND @BASEBOARD_FAB2_LIB.BASEBOARD_FAB2(SCH_1):GND    I22 @BASEBOARD_FAB2_LIB.BASEBOARD_FAB2(SCH_1):PAGE40
   AB1    GND @BASEBOARD_FAB2_LIB.BASEBOARD_FAB2(SCH_1):GND    I22 @BASEBOARD_FAB2_LIB.BASEBOARD_FAB2(SCH_1):PAGE40
   AB5    GND @BASEBOARD_FAB2_LIB.BASEBOARD_FAB2(SCH_1):GND    I22 @BASEBOARD_FAB2_LIB.BASEBOARD_FAB2(SCH_1):PAGE40
  AB11    GND @BASEBOARD_FAB2_LIB.BASEBOARD_FAB2(SCH_1):GND    I22 @BASEBOARD_FAB2_LIB.BASEBOARD_FAB2(SCH_1):PAGE40
  AB21    GND @BASEBOARD_FAB2_LIB.BASEBOARD_FAB2(SCH_1):GND    I22 @BASEBOARD_FAB2_LIB.BASEBOARD_FAB2(SCH_1):PAGE40
  AB23    GND @BASEBOARD_FAB2_LIB.BASEBOARD_FAB2(SCH_1):GND    I22 @BASEBOARD_FAB2_LIB.BASEBOARD_FAB2(SCH_1):PAGE40
  AB25    GND @BASEBOARD_FAB2_LIB.BASEBOARD_FAB2(SCH_1):GND    I22 @BASEBOARD_FAB2_LIB.BASEBOARD_FAB2(SCH_1):PAGE40
  AB29    GND @BASEBOARD_FAB2_LIB.BASEBOARD_FAB2(SCH_1):GND    I22 @BASEBOARD_FAB2_LIB.BASEBOARD_FAB2(SCH_1):PAGE40
  AB31    GND @BASEBOARD_FAB2_LIB.BASEBOARD_FAB2(SCH_1):GND    I22 @BASEBOARD_FAB2_LIB.BASEBOARD_FAB2(SCH_1):PAGE40
  AB35    GND @BASEBOARD_FAB2_LIB.BASEBOARD_FAB2(SCH_1):GND    I22 @BASEBOARD_FAB2_LIB.BASEBOARD_FAB2(SCH_1):PAGE40
  AB37    GND @BASEBOARD_FAB2_LIB.BASEBOARD_FAB2(SCH_1):GND    I22 @BASEBOARD_FAB2_LIB.BASEBOARD_FAB2(SCH_1):PAGE40
  AB41    GND @BASEBOARD_FAB2_LIB.BASEBOARD_FAB2(SCH_1):GND    I22 @BASEBOARD_FAB2_LIB.BASEBOARD_FAB2(SCH_1):PAGE40
  AB65    GND @BASEBOARD_FAB2_LIB.BASEBOARD_FAB2(SCH_1):GND    I22 @BASEBOARD_FAB2_LIB.BASEBOARD_FAB2(SCH_1):PAGE40
  AB69    GND @BASEBOARD_FAB2_LIB.BASEBOARD_FAB2(SCH_1):GND    I22 @BASEBOARD_FAB2_LIB.BASEBOARD_FAB2(SCH_1):PAGE40
  AB73    GND @BASEBOARD_FAB2_LIB.BASEBOARD_FAB2(SCH_1):GND    I22 @BASEBOARD_FAB2_LIB.BASEBOARD_FAB2(SCH_1):PAGE40
  AB79    GND @BASEBOARD_FAB2_LIB.BASEBOARD_FAB2(SCH_1):GND    I22 @BASEBOARD_FAB2_LIB.BASEBOARD_FAB2(SCH_1):PAGE40
  AB83    GND @BASEBOARD_FAB2_LIB.BASEBOARD_FAB2(SCH_1):GND    I22 @BASEBOARD_FAB2_LIB.BASEBOARD_FAB2(SCH_1):PAGE40
  AB85    GND @BASEBOARD_FAB2_LIB.BASEBOARD_FAB2(SCH_1):GND    I22 @BASEBOARD_FAB2_LIB.BASEBOARD_FAB2(SCH_1):PAGE40
  AC18    GND @BASEBOARD_FAB2_LIB.BASEBOARD_FAB2(SCH_1):GND    I22 @BASEBOARD_FAB2_LIB.BASEBOARD_FAB2(SCH_1):PAGE40
  AC22    GND @BASEBOARD_FAB2_LIB.BASEBOARD_FAB2(SCH_1):GND    I22 @BASEBOARD_FAB2_LIB.BASEBOARD_FAB2(SCH_1):PAGE40
  AC26    GND @BASEBOARD_FAB2_LIB.BASEBOARD_FAB2(SCH_1):GND    I22 @BASEBOARD_FAB2_LIB.BASEBOARD_FAB2(SCH_1):PAGE40
  AC28    GND @BASEBOARD_FAB2_LIB.BASEBOARD_FAB2(SCH_1):GND    I22 @BASEBOARD_FAB2_LIB.BASEBOARD_FAB2(SCH_1):PAGE40
  AC32    GND @BASEBOARD_FAB2_LIB.BASEBOARD_FAB2(SCH_1):GND    I22 @BASEBOARD_FAB2_LIB.BASEBOARD_FAB2(SCH_1):PAGE40
  AC34    GND @BASEBOARD_FAB2_LIB.BASEBOARD_FAB2(SCH_1):GND    I22 @BASEBOARD_FAB2_LIB.BASEBOARD_FAB2(SCH_1):PAGE40
  AC38    GND @BASEBOARD_FAB2_LIB.BASEBOARD_FAB2(SCH_1):GND    I22 @BASEBOARD_FAB2_LIB.BASEBOARD_FAB2(SCH_1):PAGE40
  AC40    GND @BASEBOARD_FAB2_LIB.BASEBOARD_FAB2(SCH_1):GND    I22 @BASEBOARD_FAB2_LIB.BASEBOARD_FAB2(SCH_1):PAGE40
  AC64    GND @BASEBOARD_FAB2_LIB.BASEBOARD_FAB2(SCH_1):GND    I22 @BASEBOARD_FAB2_LIB.BASEBOARD_FAB2(SCH_1):PAGE40
  AC70    GND @BASEBOARD_FAB2_LIB.BASEBOARD_FAB2(SCH_1):GND    I22 @BASEBOARD_FAB2_LIB.BASEBOARD_FAB2(SCH_1):PAGE40
  AC72    GND @BASEBOARD_FAB2_LIB.BASEBOARD_FAB2(SCH_1):GND    I22 @BASEBOARD_FAB2_LIB.BASEBOARD_FAB2(SCH_1):PAGE40
  AC78    GND @BASEBOARD_FAB2_LIB.BASEBOARD_FAB2(SCH_1):GND    I22 @BASEBOARD_FAB2_LIB.BASEBOARD_FAB2(SCH_1):PAGE40
  AC84    GND @BASEBOARD_FAB2_LIB.BASEBOARD_FAB2(SCH_1):GND    I22 @BASEBOARD_FAB2_LIB.BASEBOARD_FAB2(SCH_1):PAGE40
  AC86    GND @BASEBOARD_FAB2_LIB.BASEBOARD_FAB2(SCH_1):GND    I22 @BASEBOARD_FAB2_LIB.BASEBOARD_FAB2(SCH_1):PAGE40
   AD3    GND @BASEBOARD_FAB2_LIB.BASEBOARD_FAB2(SCH_1):GND    I22 @BASEBOARD_FAB2_LIB.BASEBOARD_FAB2(SCH_1):PAGE40
   AD7    GND @BASEBOARD_FAB2_LIB.BASEBOARD_FAB2(SCH_1):GND    I22 @BASEBOARD_FAB2_LIB.BASEBOARD_FAB2(SCH_1):PAGE40
   AD9    GND @BASEBOARD_FAB2_LIB.BASEBOARD_FAB2(SCH_1):GND    I22 @BASEBOARD_FAB2_LIB.BASEBOARD_FAB2(SCH_1):PAGE40
  AD11    GND @BASEBOARD_FAB2_LIB.BASEBOARD_FAB2(SCH_1):GND    I22 @BASEBOARD_FAB2_LIB.BASEBOARD_FAB2(SCH_1):PAGE40
  AD13    GND @BASEBOARD_FAB2_LIB.BASEBOARD_FAB2(SCH_1):GND    I22 @BASEBOARD_FAB2_LIB.BASEBOARD_FAB2(SCH_1):PAGE40
  AD15    GND @BASEBOARD_FAB2_LIB.BASEBOARD_FAB2(SCH_1):GND    I22 @BASEBOARD_FAB2_LIB.BASEBOARD_FAB2(SCH_1):PAGE40
  AD19    GND @BASEBOARD_FAB2_LIB.BASEBOARD_FAB2(SCH_1):GND    I22 @BASEBOARD_FAB2_LIB.BASEBOARD_FAB2(SCH_1):PAGE40
  AD21    GND @BASEBOARD_FAB2_LIB.BASEBOARD_FAB2(SCH_1):GND    I22 @BASEBOARD_FAB2_LIB.BASEBOARD_FAB2(SCH_1):PAGE40
  AD27    GND @BASEBOARD_FAB2_LIB.BASEBOARD_FAB2(SCH_1):GND    I22 @BASEBOARD_FAB2_LIB.BASEBOARD_FAB2(SCH_1):PAGE40
  AD33    GND @BASEBOARD_FAB2_LIB.BASEBOARD_FAB2(SCH_1):GND    I22 @BASEBOARD_FAB2_LIB.BASEBOARD_FAB2(SCH_1):PAGE40
  AD39    GND @BASEBOARD_FAB2_LIB.BASEBOARD_FAB2(SCH_1):GND    I22 @BASEBOARD_FAB2_LIB.BASEBOARD_FAB2(SCH_1):PAGE40
  AD43    GND @BASEBOARD_FAB2_LIB.BASEBOARD_FAB2(SCH_1):GND    I22 @BASEBOARD_FAB2_LIB.BASEBOARD_FAB2(SCH_1):PAGE40
  AD71    GND @BASEBOARD_FAB2_LIB.BASEBOARD_FAB2(SCH_1):GND    I22 @BASEBOARD_FAB2_LIB.BASEBOARD_FAB2(SCH_1):PAGE40
  AD73    GND @BASEBOARD_FAB2_LIB.BASEBOARD_FAB2(SCH_1):GND    I22 @BASEBOARD_FAB2_LIB.BASEBOARD_FAB2(SCH_1):PAGE40
  AD75    GND @BASEBOARD_FAB2_LIB.BASEBOARD_FAB2(SCH_1):GND    I22 @BASEBOARD_FAB2_LIB.BASEBOARD_FAB2(SCH_1):PAGE40
  AD81    GND @BASEBOARD_FAB2_LIB.BASEBOARD_FAB2(SCH_1):GND    I22 @BASEBOARD_FAB2_LIB.BASEBOARD_FAB2(SCH_1):PAGE40
  AD83    GND @BASEBOARD_FAB2_LIB.BASEBOARD_FAB2(SCH_1):GND    I22 @BASEBOARD_FAB2_LIB.BASEBOARD_FAB2(SCH_1):PAGE40
  AD85    GND @BASEBOARD_FAB2_LIB.BASEBOARD_FAB2(SCH_1):GND    I22 @BASEBOARD_FAB2_LIB.BASEBOARD_FAB2(SCH_1):PAGE40
   AE4    GND @BASEBOARD_FAB2_LIB.BASEBOARD_FAB2(SCH_1):GND    I22 @BASEBOARD_FAB2_LIB.BASEBOARD_FAB2(SCH_1):PAGE40
   AE8    GND @BASEBOARD_FAB2_LIB.BASEBOARD_FAB2(SCH_1):GND    I22 @BASEBOARD_FAB2_LIB.BASEBOARD_FAB2(SCH_1):PAGE40
  AC54    GND @BASEBOARD_FAB2_LIB.BASEBOARD_FAB2(SCH_1):GND    I22 @BASEBOARD_FAB2_LIB.BASEBOARD_FAB2(SCH_1):PAGE40
  AE16    GND @BASEBOARD_FAB2_LIB.BASEBOARD_FAB2(SCH_1):GND    I22 @BASEBOARD_FAB2_LIB.BASEBOARD_FAB2(SCH_1):PAGE40
  AE38    GND @BASEBOARD_FAB2_LIB.BASEBOARD_FAB2(SCH_1):GND    I22 @BASEBOARD_FAB2_LIB.BASEBOARD_FAB2(SCH_1):PAGE40
  AE40    GND @BASEBOARD_FAB2_LIB.BASEBOARD_FAB2(SCH_1):GND    I22 @BASEBOARD_FAB2_LIB.BASEBOARD_FAB2(SCH_1):PAGE40
  AE42    GND @BASEBOARD_FAB2_LIB.BASEBOARD_FAB2(SCH_1):GND    I22 @BASEBOARD_FAB2_LIB.BASEBOARD_FAB2(SCH_1):PAGE40
  AE64    GND @BASEBOARD_FAB2_LIB.BASEBOARD_FAB2(SCH_1):GND    I22 @BASEBOARD_FAB2_LIB.BASEBOARD_FAB2(SCH_1):PAGE40
  AE66    GND @BASEBOARD_FAB2_LIB.BASEBOARD_FAB2(SCH_1):GND    I22 @BASEBOARD_FAB2_LIB.BASEBOARD_FAB2(SCH_1):PAGE40
  AE68    GND @BASEBOARD_FAB2_LIB.BASEBOARD_FAB2(SCH_1):GND    I22 @BASEBOARD_FAB2_LIB.BASEBOARD_FAB2(SCH_1):PAGE40
  AE70    GND @BASEBOARD_FAB2_LIB.BASEBOARD_FAB2(SCH_1):GND    I22 @BASEBOARD_FAB2_LIB.BASEBOARD_FAB2(SCH_1):PAGE40
  AE78    GND @BASEBOARD_FAB2_LIB.BASEBOARD_FAB2(SCH_1):GND    I22 @BASEBOARD_FAB2_LIB.BASEBOARD_FAB2(SCH_1):PAGE40
   AF1    GND @BASEBOARD_FAB2_LIB.BASEBOARD_FAB2(SCH_1):GND    I22 @BASEBOARD_FAB2_LIB.BASEBOARD_FAB2(SCH_1):PAGE40
  AC52    GND @BASEBOARD_FAB2_LIB.BASEBOARD_FAB2(SCH_1):GND    I22 @BASEBOARD_FAB2_LIB.BASEBOARD_FAB2(SCH_1):PAGE40
   AF9    GND @BASEBOARD_FAB2_LIB.BASEBOARD_FAB2(SCH_1):GND    I22 @BASEBOARD_FAB2_LIB.BASEBOARD_FAB2(SCH_1):PAGE40
  AF21    GND @BASEBOARD_FAB2_LIB.BASEBOARD_FAB2(SCH_1):GND    I22 @BASEBOARD_FAB2_LIB.BASEBOARD_FAB2(SCH_1):PAGE40
  AF23    GND @BASEBOARD_FAB2_LIB.BASEBOARD_FAB2(SCH_1):GND    I22 @BASEBOARD_FAB2_LIB.BASEBOARD_FAB2(SCH_1):PAGE40
  AF25    GND @BASEBOARD_FAB2_LIB.BASEBOARD_FAB2(SCH_1):GND    I22 @BASEBOARD_FAB2_LIB.BASEBOARD_FAB2(SCH_1):PAGE40
  AF27    GND @BASEBOARD_FAB2_LIB.BASEBOARD_FAB2(SCH_1):GND    I22 @BASEBOARD_FAB2_LIB.BASEBOARD_FAB2(SCH_1):PAGE40
  AF29    GND @BASEBOARD_FAB2_LIB.BASEBOARD_FAB2(SCH_1):GND    I22 @BASEBOARD_FAB2_LIB.BASEBOARD_FAB2(SCH_1):PAGE40
  AF31    GND @BASEBOARD_FAB2_LIB.BASEBOARD_FAB2(SCH_1):GND    I22 @BASEBOARD_FAB2_LIB.BASEBOARD_FAB2(SCH_1):PAGE40
  AF33    GND @BASEBOARD_FAB2_LIB.BASEBOARD_FAB2(SCH_1):GND    I22 @BASEBOARD_FAB2_LIB.BASEBOARD_FAB2(SCH_1):PAGE40
  AF37    GND @BASEBOARD_FAB2_LIB.BASEBOARD_FAB2(SCH_1):GND    I22 @BASEBOARD_FAB2_LIB.BASEBOARD_FAB2(SCH_1):PAGE40
  AF39    GND @BASEBOARD_FAB2_LIB.BASEBOARD_FAB2(SCH_1):GND    I22 @BASEBOARD_FAB2_LIB.BASEBOARD_FAB2(SCH_1):PAGE40
  AF41    GND @BASEBOARD_FAB2_LIB.BASEBOARD_FAB2(SCH_1):GND    I22 @BASEBOARD_FAB2_LIB.BASEBOARD_FAB2(SCH_1):PAGE40
  AF73    GND @BASEBOARD_FAB2_LIB.BASEBOARD_FAB2(SCH_1):GND    I22 @BASEBOARD_FAB2_LIB.BASEBOARD_FAB2(SCH_1):PAGE40
  AF77    GND @BASEBOARD_FAB2_LIB.BASEBOARD_FAB2(SCH_1):GND    I22 @BASEBOARD_FAB2_LIB.BASEBOARD_FAB2(SCH_1):PAGE40
  AF83    GND @BASEBOARD_FAB2_LIB.BASEBOARD_FAB2(SCH_1):GND    I22 @BASEBOARD_FAB2_LIB.BASEBOARD_FAB2(SCH_1):PAGE40
  AF85    GND @BASEBOARD_FAB2_LIB.BASEBOARD_FAB2(SCH_1):GND    I22 @BASEBOARD_FAB2_LIB.BASEBOARD_FAB2(SCH_1):PAGE40
  AG12    GND @BASEBOARD_FAB2_LIB.BASEBOARD_FAB2(SCH_1):GND    I22 @BASEBOARD_FAB2_LIB.BASEBOARD_FAB2(SCH_1):PAGE40
  AG14    GND @BASEBOARD_FAB2_LIB.BASEBOARD_FAB2(SCH_1):GND    I22 @BASEBOARD_FAB2_LIB.BASEBOARD_FAB2(SCH_1):PAGE40
  AG18    GND @BASEBOARD_FAB2_LIB.BASEBOARD_FAB2(SCH_1):GND    I22 @BASEBOARD_FAB2_LIB.BASEBOARD_FAB2(SCH_1):PAGE40
  AG36    GND @BASEBOARD_FAB2_LIB.BASEBOARD_FAB2(SCH_1):GND    I22 @BASEBOARD_FAB2_LIB.BASEBOARD_FAB2(SCH_1):PAGE40
  AG64    GND @BASEBOARD_FAB2_LIB.BASEBOARD_FAB2(SCH_1):GND    I22 @BASEBOARD_FAB2_LIB.BASEBOARD_FAB2(SCH_1):PAGE40
  AG70    GND @BASEBOARD_FAB2_LIB.BASEBOARD_FAB2(SCH_1):GND    I22 @BASEBOARD_FAB2_LIB.BASEBOARD_FAB2(SCH_1):PAGE40
  AG74    GND @BASEBOARD_FAB2_LIB.BASEBOARD_FAB2(SCH_1):GND    I22 @BASEBOARD_FAB2_LIB.BASEBOARD_FAB2(SCH_1):PAGE40
  AG76    GND @BASEBOARD_FAB2_LIB.BASEBOARD_FAB2(SCH_1):GND    I22 @BASEBOARD_FAB2_LIB.BASEBOARD_FAB2(SCH_1):PAGE40
  AG78    GND @BASEBOARD_FAB2_LIB.BASEBOARD_FAB2(SCH_1):GND    I22 @BASEBOARD_FAB2_LIB.BASEBOARD_FAB2(SCH_1):PAGE40
  AG80    GND @BASEBOARD_FAB2_LIB.BASEBOARD_FAB2(SCH_1):GND    I22 @BASEBOARD_FAB2_LIB.BASEBOARD_FAB2(SCH_1):PAGE40
   AH1    GND @BASEBOARD_FAB2_LIB.BASEBOARD_FAB2(SCH_1):GND    I22 @BASEBOARD_FAB2_LIB.BASEBOARD_FAB2(SCH_1):PAGE40
   AH5    GND @BASEBOARD_FAB2_LIB.BASEBOARD_FAB2(SCH_1):GND    I22 @BASEBOARD_FAB2_LIB.BASEBOARD_FAB2(SCH_1):PAGE40
  AH21    GND @BASEBOARD_FAB2_LIB.BASEBOARD_FAB2(SCH_1):GND    I22 @BASEBOARD_FAB2_LIB.BASEBOARD_FAB2(SCH_1):PAGE40
  AH27    GND @BASEBOARD_FAB2_LIB.BASEBOARD_FAB2(SCH_1):GND    I22 @BASEBOARD_FAB2_LIB.BASEBOARD_FAB2(SCH_1):PAGE40
  AH33    GND @BASEBOARD_FAB2_LIB.BASEBOARD_FAB2(SCH_1):GND    I22 @BASEBOARD_FAB2_LIB.BASEBOARD_FAB2(SCH_1):PAGE40
  AH35    GND @BASEBOARD_FAB2_LIB.BASEBOARD_FAB2(SCH_1):GND    I22 @BASEBOARD_FAB2_LIB.BASEBOARD_FAB2(SCH_1):PAGE40
  AH45    GND @BASEBOARD_FAB2_LIB.BASEBOARD_FAB2(SCH_1):GND    I22 @BASEBOARD_FAB2_LIB.BASEBOARD_FAB2(SCH_1):PAGE40
  AH47    GND @BASEBOARD_FAB2_LIB.BASEBOARD_FAB2(SCH_1):GND    I22 @BASEBOARD_FAB2_LIB.BASEBOARD_FAB2(SCH_1):PAGE40
  AH49    GND @BASEBOARD_FAB2_LIB.BASEBOARD_FAB2(SCH_1):GND    I22 @BASEBOARD_FAB2_LIB.BASEBOARD_FAB2(SCH_1):PAGE40
  AH51    GND @BASEBOARD_FAB2_LIB.BASEBOARD_FAB2(SCH_1):GND    I22 @BASEBOARD_FAB2_LIB.BASEBOARD_FAB2(SCH_1):PAGE40
  AH53    GND @BASEBOARD_FAB2_LIB.BASEBOARD_FAB2(SCH_1):GND    I22 @BASEBOARD_FAB2_LIB.BASEBOARD_FAB2(SCH_1):PAGE40
  AH59    GND @BASEBOARD_FAB2_LIB.BASEBOARD_FAB2(SCH_1):GND    I22 @BASEBOARD_FAB2_LIB.BASEBOARD_FAB2(SCH_1):PAGE40
  AH61    GND @BASEBOARD_FAB2_LIB.BASEBOARD_FAB2(SCH_1):GND    I22 @BASEBOARD_FAB2_LIB.BASEBOARD_FAB2(SCH_1):PAGE40
  AH65    GND @BASEBOARD_FAB2_LIB.BASEBOARD_FAB2(SCH_1):GND    I22 @BASEBOARD_FAB2_LIB.BASEBOARD_FAB2(SCH_1):PAGE40
  AH69    GND @BASEBOARD_FAB2_LIB.BASEBOARD_FAB2(SCH_1):GND    I22 @BASEBOARD_FAB2_LIB.BASEBOARD_FAB2(SCH_1):PAGE40
  AH75    GND @BASEBOARD_FAB2_LIB.BASEBOARD_FAB2(SCH_1):GND    I22 @BASEBOARD_FAB2_LIB.BASEBOARD_FAB2(SCH_1):PAGE40
  AH77    GND @BASEBOARD_FAB2_LIB.BASEBOARD_FAB2(SCH_1):GND    I22 @BASEBOARD_FAB2_LIB.BASEBOARD_FAB2(SCH_1):PAGE40
  AH83    GND @BASEBOARD_FAB2_LIB.BASEBOARD_FAB2(SCH_1):GND    I22 @BASEBOARD_FAB2_LIB.BASEBOARD_FAB2(SCH_1):PAGE40
   AJ8    GND @BASEBOARD_FAB2_LIB.BASEBOARD_FAB2(SCH_1):GND    I22 @BASEBOARD_FAB2_LIB.BASEBOARD_FAB2(SCH_1):PAGE40
  AJ22    GND @BASEBOARD_FAB2_LIB.BASEBOARD_FAB2(SCH_1):GND    I22 @BASEBOARD_FAB2_LIB.BASEBOARD_FAB2(SCH_1):PAGE40
  AJ26    GND @BASEBOARD_FAB2_LIB.BASEBOARD_FAB2(SCH_1):GND    I22 @BASEBOARD_FAB2_LIB.BASEBOARD_FAB2(SCH_1):PAGE40
  AJ28    GND @BASEBOARD_FAB2_LIB.BASEBOARD_FAB2(SCH_1):GND    I22 @BASEBOARD_FAB2_LIB.BASEBOARD_FAB2(SCH_1):PAGE40
  AJ32    GND @BASEBOARD_FAB2_LIB.BASEBOARD_FAB2(SCH_1):GND    I22 @BASEBOARD_FAB2_LIB.BASEBOARD_FAB2(SCH_1):PAGE40
  AJ34    GND @BASEBOARD_FAB2_LIB.BASEBOARD_FAB2(SCH_1):GND    I22 @BASEBOARD_FAB2_LIB.BASEBOARD_FAB2(SCH_1):PAGE40
  AJ46    GND @BASEBOARD_FAB2_LIB.BASEBOARD_FAB2(SCH_1):GND    I22 @BASEBOARD_FAB2_LIB.BASEBOARD_FAB2(SCH_1):PAGE40
  AJ48    GND @BASEBOARD_FAB2_LIB.BASEBOARD_FAB2(SCH_1):GND    I22 @BASEBOARD_FAB2_LIB.BASEBOARD_FAB2(SCH_1):PAGE40
  AJ50    GND @BASEBOARD_FAB2_LIB.BASEBOARD_FAB2(SCH_1):GND    I22 @BASEBOARD_FAB2_LIB.BASEBOARD_FAB2(SCH_1):PAGE40
  AJ52    GND @BASEBOARD_FAB2_LIB.BASEBOARD_FAB2(SCH_1):GND    I22 @BASEBOARD_FAB2_LIB.BASEBOARD_FAB2(SCH_1):PAGE40
  AJ54    GND @BASEBOARD_FAB2_LIB.BASEBOARD_FAB2(SCH_1):GND    I22 @BASEBOARD_FAB2_LIB.BASEBOARD_FAB2(SCH_1):PAGE40
  AJ66    GND @BASEBOARD_FAB2_LIB.BASEBOARD_FAB2(SCH_1):GND    I22 @BASEBOARD_FAB2_LIB.BASEBOARD_FAB2(SCH_1):PAGE40
  AJ68    GND @BASEBOARD_FAB2_LIB.BASEBOARD_FAB2(SCH_1):GND    I22 @BASEBOARD_FAB2_LIB.BASEBOARD_FAB2(SCH_1):PAGE40
  AJ74    GND @BASEBOARD_FAB2_LIB.BASEBOARD_FAB2(SCH_1):GND    I22 @BASEBOARD_FAB2_LIB.BASEBOARD_FAB2(SCH_1):PAGE40
  AJ78    GND @BASEBOARD_FAB2_LIB.BASEBOARD_FAB2(SCH_1):GND    I22 @BASEBOARD_FAB2_LIB.BASEBOARD_FAB2(SCH_1):PAGE40
  AJ82    GND @BASEBOARD_FAB2_LIB.BASEBOARD_FAB2(SCH_1):GND    I22 @BASEBOARD_FAB2_LIB.BASEBOARD_FAB2(SCH_1):PAGE40
  AJ86    GND @BASEBOARD_FAB2_LIB.BASEBOARD_FAB2(SCH_1):GND    I22 @BASEBOARD_FAB2_LIB.BASEBOARD_FAB2(SCH_1):PAGE40
   AK9    GND @BASEBOARD_FAB2_LIB.BASEBOARD_FAB2(SCH_1):GND    I22 @BASEBOARD_FAB2_LIB.BASEBOARD_FAB2(SCH_1):PAGE40
  AK13    GND @BASEBOARD_FAB2_LIB.BASEBOARD_FAB2(SCH_1):GND    I22 @BASEBOARD_FAB2_LIB.BASEBOARD_FAB2(SCH_1):PAGE40
  AK19    GND @BASEBOARD_FAB2_LIB.BASEBOARD_FAB2(SCH_1):GND    I22 @BASEBOARD_FAB2_LIB.BASEBOARD_FAB2(SCH_1):PAGE40
  AK23    GND @BASEBOARD_FAB2_LIB.BASEBOARD_FAB2(SCH_1):GND    I22 @BASEBOARD_FAB2_LIB.BASEBOARD_FAB2(SCH_1):PAGE40
  AK25    GND @BASEBOARD_FAB2_LIB.BASEBOARD_FAB2(SCH_1):GND    I22 @BASEBOARD_FAB2_LIB.BASEBOARD_FAB2(SCH_1):PAGE40
  AK29    GND @BASEBOARD_FAB2_LIB.BASEBOARD_FAB2(SCH_1):GND    I22 @BASEBOARD_FAB2_LIB.BASEBOARD_FAB2(SCH_1):PAGE40
  AK31    GND @BASEBOARD_FAB2_LIB.BASEBOARD_FAB2(SCH_1):GND    I22 @BASEBOARD_FAB2_LIB.BASEBOARD_FAB2(SCH_1):PAGE40
  AK33    GND @BASEBOARD_FAB2_LIB.BASEBOARD_FAB2(SCH_1):GND    I22 @BASEBOARD_FAB2_LIB.BASEBOARD_FAB2(SCH_1):PAGE40
  AK55    GND @BASEBOARD_FAB2_LIB.BASEBOARD_FAB2(SCH_1):GND    I22 @BASEBOARD_FAB2_LIB.BASEBOARD_FAB2(SCH_1):PAGE40
  AK65    GND @BASEBOARD_FAB2_LIB.BASEBOARD_FAB2(SCH_1):GND    I22 @BASEBOARD_FAB2_LIB.BASEBOARD_FAB2(SCH_1):PAGE40
  AK67    GND @BASEBOARD_FAB2_LIB.BASEBOARD_FAB2(SCH_1):GND    I22 @BASEBOARD_FAB2_LIB.BASEBOARD_FAB2(SCH_1):PAGE40
  AK73    GND @BASEBOARD_FAB2_LIB.BASEBOARD_FAB2(SCH_1):GND    I22 @BASEBOARD_FAB2_LIB.BASEBOARD_FAB2(SCH_1):PAGE40
  AK79    GND @BASEBOARD_FAB2_LIB.BASEBOARD_FAB2(SCH_1):GND    I22 @BASEBOARD_FAB2_LIB.BASEBOARD_FAB2(SCH_1):PAGE40
  AK81    GND @BASEBOARD_FAB2_LIB.BASEBOARD_FAB2(SCH_1):GND    I22 @BASEBOARD_FAB2_LIB.BASEBOARD_FAB2(SCH_1):PAGE40
  AK83    GND @BASEBOARD_FAB2_LIB.BASEBOARD_FAB2(SCH_1):GND    I22 @BASEBOARD_FAB2_LIB.BASEBOARD_FAB2(SCH_1):PAGE40
  AK85    GND @BASEBOARD_FAB2_LIB.BASEBOARD_FAB2(SCH_1):GND    I22 @BASEBOARD_FAB2_LIB.BASEBOARD_FAB2(SCH_1):PAGE40
   AL4    GND @BASEBOARD_FAB2_LIB.BASEBOARD_FAB2(SCH_1):GND    I22 @BASEBOARD_FAB2_LIB.BASEBOARD_FAB2(SCH_1):PAGE40
  AL10    GND @BASEBOARD_FAB2_LIB.BASEBOARD_FAB2(SCH_1):GND    I22 @BASEBOARD_FAB2_LIB.BASEBOARD_FAB2(SCH_1):PAGE40
  AL24    GND @BASEBOARD_FAB2_LIB.BASEBOARD_FAB2(SCH_1):GND    I22 @BASEBOARD_FAB2_LIB.BASEBOARD_FAB2(SCH_1):PAGE40
  AL30    GND @BASEBOARD_FAB2_LIB.BASEBOARD_FAB2(SCH_1):GND    I22 @BASEBOARD_FAB2_LIB.BASEBOARD_FAB2(SCH_1):PAGE40
  AL32    GND @BASEBOARD_FAB2_LIB.BASEBOARD_FAB2(SCH_1):GND    I22 @BASEBOARD_FAB2_LIB.BASEBOARD_FAB2(SCH_1):PAGE40
  AL56    GND @BASEBOARD_FAB2_LIB.BASEBOARD_FAB2(SCH_1):GND    I22 @BASEBOARD_FAB2_LIB.BASEBOARD_FAB2(SCH_1):PAGE40
  AL64    GND @BASEBOARD_FAB2_LIB.BASEBOARD_FAB2(SCH_1):GND    I22 @BASEBOARD_FAB2_LIB.BASEBOARD_FAB2(SCH_1):PAGE40
  AL68    GND @BASEBOARD_FAB2_LIB.BASEBOARD_FAB2(SCH_1):GND    I22 @BASEBOARD_FAB2_LIB.BASEBOARD_FAB2(SCH_1):PAGE40
  AL76    GND @BASEBOARD_FAB2_LIB.BASEBOARD_FAB2(SCH_1):GND    I23 @BASEBOARD_FAB2_LIB.BASEBOARD_FAB2(SCH_1):PAGE40
  AL78    GND @BASEBOARD_FAB2_LIB.BASEBOARD_FAB2(SCH_1):GND    I23 @BASEBOARD_FAB2_LIB.BASEBOARD_FAB2(SCH_1):PAGE40
  AL80    GND @BASEBOARD_FAB2_LIB.BASEBOARD_FAB2(SCH_1):GND    I23 @BASEBOARD_FAB2_LIB.BASEBOARD_FAB2(SCH_1):PAGE40
  AL82    GND @BASEBOARD_FAB2_LIB.BASEBOARD_FAB2(SCH_1):GND    I23 @BASEBOARD_FAB2_LIB.BASEBOARD_FAB2(SCH_1):PAGE40
  AL86    GND @BASEBOARD_FAB2_LIB.BASEBOARD_FAB2(SCH_1):GND    I23 @BASEBOARD_FAB2_LIB.BASEBOARD_FAB2(SCH_1):PAGE40
   AM1    GND @BASEBOARD_FAB2_LIB.BASEBOARD_FAB2(SCH_1):GND    I23 @BASEBOARD_FAB2_LIB.BASEBOARD_FAB2(SCH_1):PAGE40
  AC50    GND @BASEBOARD_FAB2_LIB.BASEBOARD_FAB2(SCH_1):GND    I23 @BASEBOARD_FAB2_LIB.BASEBOARD_FAB2(SCH_1):PAGE40
  AM31    GND @BASEBOARD_FAB2_LIB.BASEBOARD_FAB2(SCH_1):GND    I23 @BASEBOARD_FAB2_LIB.BASEBOARD_FAB2(SCH_1):PAGE40
  AM57    GND @BASEBOARD_FAB2_LIB.BASEBOARD_FAB2(SCH_1):GND    I23 @BASEBOARD_FAB2_LIB.BASEBOARD_FAB2(SCH_1):PAGE40
  AM63    GND @BASEBOARD_FAB2_LIB.BASEBOARD_FAB2(SCH_1):GND    I23 @BASEBOARD_FAB2_LIB.BASEBOARD_FAB2(SCH_1):PAGE40
  AM69    GND @BASEBOARD_FAB2_LIB.BASEBOARD_FAB2(SCH_1):GND    I23 @BASEBOARD_FAB2_LIB.BASEBOARD_FAB2(SCH_1):PAGE40
  AM73    GND @BASEBOARD_FAB2_LIB.BASEBOARD_FAB2(SCH_1):GND    I23 @BASEBOARD_FAB2_LIB.BASEBOARD_FAB2(SCH_1):PAGE40
  AM79    GND @BASEBOARD_FAB2_LIB.BASEBOARD_FAB2(SCH_1):GND    I23 @BASEBOARD_FAB2_LIB.BASEBOARD_FAB2(SCH_1):PAGE40
  AM83    GND @BASEBOARD_FAB2_LIB.BASEBOARD_FAB2(SCH_1):GND    I23 @BASEBOARD_FAB2_LIB.BASEBOARD_FAB2(SCH_1):PAGE40
   AN2    GND @BASEBOARD_FAB2_LIB.BASEBOARD_FAB2(SCH_1):GND    I23 @BASEBOARD_FAB2_LIB.BASEBOARD_FAB2(SCH_1):PAGE40
   AN6    GND @BASEBOARD_FAB2_LIB.BASEBOARD_FAB2(SCH_1):GND    I23 @BASEBOARD_FAB2_LIB.BASEBOARD_FAB2(SCH_1):PAGE40
  AN28    GND @BASEBOARD_FAB2_LIB.BASEBOARD_FAB2(SCH_1):GND    I23 @BASEBOARD_FAB2_LIB.BASEBOARD_FAB2(SCH_1):PAGE40
  AN58    GND @BASEBOARD_FAB2_LIB.BASEBOARD_FAB2(SCH_1):GND    I23 @BASEBOARD_FAB2_LIB.BASEBOARD_FAB2(SCH_1):PAGE40
  AN78    GND @BASEBOARD_FAB2_LIB.BASEBOARD_FAB2(SCH_1):GND    I23 @BASEBOARD_FAB2_LIB.BASEBOARD_FAB2(SCH_1):PAGE40
   AP5    GND @BASEBOARD_FAB2_LIB.BASEBOARD_FAB2(SCH_1):GND    I23 @BASEBOARD_FAB2_LIB.BASEBOARD_FAB2(SCH_1):PAGE40
   AP9    GND @BASEBOARD_FAB2_LIB.BASEBOARD_FAB2(SCH_1):GND    I23 @BASEBOARD_FAB2_LIB.BASEBOARD_FAB2(SCH_1):PAGE40
  AP13    GND @BASEBOARD_FAB2_LIB.BASEBOARD_FAB2(SCH_1):GND    I23 @BASEBOARD_FAB2_LIB.BASEBOARD_FAB2(SCH_1):PAGE40
  AP19    GND @BASEBOARD_FAB2_LIB.BASEBOARD_FAB2(SCH_1):GND    I23 @BASEBOARD_FAB2_LIB.BASEBOARD_FAB2(SCH_1):PAGE40
  AP31    GND @BASEBOARD_FAB2_LIB.BASEBOARD_FAB2(SCH_1):GND    I23 @BASEBOARD_FAB2_LIB.BASEBOARD_FAB2(SCH_1):PAGE40
  AP59    GND @BASEBOARD_FAB2_LIB.BASEBOARD_FAB2(SCH_1):GND    I23 @BASEBOARD_FAB2_LIB.BASEBOARD_FAB2(SCH_1):PAGE40
  AP63    GND @BASEBOARD_FAB2_LIB.BASEBOARD_FAB2(SCH_1):GND    I23 @BASEBOARD_FAB2_LIB.BASEBOARD_FAB2(SCH_1):PAGE40
  AP65    GND @BASEBOARD_FAB2_LIB.BASEBOARD_FAB2(SCH_1):GND    I23 @BASEBOARD_FAB2_LIB.BASEBOARD_FAB2(SCH_1):PAGE40
  AP67    GND @BASEBOARD_FAB2_LIB.BASEBOARD_FAB2(SCH_1):GND    I23 @BASEBOARD_FAB2_LIB.BASEBOARD_FAB2(SCH_1):PAGE40
  AP69    GND @BASEBOARD_FAB2_LIB.BASEBOARD_FAB2(SCH_1):GND    I23 @BASEBOARD_FAB2_LIB.BASEBOARD_FAB2(SCH_1):PAGE40
  AP73    GND @BASEBOARD_FAB2_LIB.BASEBOARD_FAB2(SCH_1):GND    I23 @BASEBOARD_FAB2_LIB.BASEBOARD_FAB2(SCH_1):PAGE40
  AP75    GND @BASEBOARD_FAB2_LIB.BASEBOARD_FAB2(SCH_1):GND    I23 @BASEBOARD_FAB2_LIB.BASEBOARD_FAB2(SCH_1):PAGE40
  AP81    GND @BASEBOARD_FAB2_LIB.BASEBOARD_FAB2(SCH_1):GND    I23 @BASEBOARD_FAB2_LIB.BASEBOARD_FAB2(SCH_1):PAGE40
  AP83    GND @BASEBOARD_FAB2_LIB.BASEBOARD_FAB2(SCH_1):GND    I23 @BASEBOARD_FAB2_LIB.BASEBOARD_FAB2(SCH_1):PAGE40
  AP85    GND @BASEBOARD_FAB2_LIB.BASEBOARD_FAB2(SCH_1):GND    I23 @BASEBOARD_FAB2_LIB.BASEBOARD_FAB2(SCH_1):PAGE40
  AR10    GND @BASEBOARD_FAB2_LIB.BASEBOARD_FAB2(SCH_1):GND    I23 @BASEBOARD_FAB2_LIB.BASEBOARD_FAB2(SCH_1):PAGE40
  AR24    GND @BASEBOARD_FAB2_LIB.BASEBOARD_FAB2(SCH_1):GND    I23 @BASEBOARD_FAB2_LIB.BASEBOARD_FAB2(SCH_1):PAGE40
  AR30    GND @BASEBOARD_FAB2_LIB.BASEBOARD_FAB2(SCH_1):GND    I23 @BASEBOARD_FAB2_LIB.BASEBOARD_FAB2(SCH_1):PAGE40
  AR60    GND @BASEBOARD_FAB2_LIB.BASEBOARD_FAB2(SCH_1):GND    I23 @BASEBOARD_FAB2_LIB.BASEBOARD_FAB2(SCH_1):PAGE40
  AR72    GND @BASEBOARD_FAB2_LIB.BASEBOARD_FAB2(SCH_1):GND    I23 @BASEBOARD_FAB2_LIB.BASEBOARD_FAB2(SCH_1):PAGE40
  AR78    GND @BASEBOARD_FAB2_LIB.BASEBOARD_FAB2(SCH_1):GND    I23 @BASEBOARD_FAB2_LIB.BASEBOARD_FAB2(SCH_1):PAGE40
  AC48    GND @BASEBOARD_FAB2_LIB.BASEBOARD_FAB2(SCH_1):GND    I23 @BASEBOARD_FAB2_LIB.BASEBOARD_FAB2(SCH_1):PAGE40
   P63    GND @BASEBOARD_FAB2_LIB.BASEBOARD_FAB2(SCH_1):GND    I23 @BASEBOARD_FAB2_LIB.BASEBOARD_FAB2(SCH_1):PAGE40
  AT15    GND @BASEBOARD_FAB2_LIB.BASEBOARD_FAB2(SCH_1):GND    I23 @BASEBOARD_FAB2_LIB.BASEBOARD_FAB2(SCH_1):PAGE40
  AT17    GND @BASEBOARD_FAB2_LIB.BASEBOARD_FAB2(SCH_1):GND    I23 @BASEBOARD_FAB2_LIB.BASEBOARD_FAB2(SCH_1):PAGE40
  AT21    GND @BASEBOARD_FAB2_LIB.BASEBOARD_FAB2(SCH_1):GND    I23 @BASEBOARD_FAB2_LIB.BASEBOARD_FAB2(SCH_1):PAGE40
  AT27    GND @BASEBOARD_FAB2_LIB.BASEBOARD_FAB2(SCH_1):GND    I23 @BASEBOARD_FAB2_LIB.BASEBOARD_FAB2(SCH_1):PAGE40
  AT61    GND @BASEBOARD_FAB2_LIB.BASEBOARD_FAB2(SCH_1):GND    I23 @BASEBOARD_FAB2_LIB.BASEBOARD_FAB2(SCH_1):PAGE40
  AT63    GND @BASEBOARD_FAB2_LIB.BASEBOARD_FAB2(SCH_1):GND    I23 @BASEBOARD_FAB2_LIB.BASEBOARD_FAB2(SCH_1):PAGE40
  AT69    GND @BASEBOARD_FAB2_LIB.BASEBOARD_FAB2(SCH_1):GND    I23 @BASEBOARD_FAB2_LIB.BASEBOARD_FAB2(SCH_1):PAGE40
  AT73    GND @BASEBOARD_FAB2_LIB.BASEBOARD_FAB2(SCH_1):GND    I23 @BASEBOARD_FAB2_LIB.BASEBOARD_FAB2(SCH_1):PAGE40
  AT77    GND @BASEBOARD_FAB2_LIB.BASEBOARD_FAB2(SCH_1):GND    I23 @BASEBOARD_FAB2_LIB.BASEBOARD_FAB2(SCH_1):PAGE40
  AT83    GND @BASEBOARD_FAB2_LIB.BASEBOARD_FAB2(SCH_1):GND    I23 @BASEBOARD_FAB2_LIB.BASEBOARD_FAB2(SCH_1):PAGE40
  AT85    GND @BASEBOARD_FAB2_LIB.BASEBOARD_FAB2(SCH_1):GND    I23 @BASEBOARD_FAB2_LIB.BASEBOARD_FAB2(SCH_1):PAGE40
   AU2    GND @BASEBOARD_FAB2_LIB.BASEBOARD_FAB2(SCH_1):GND    I23 @BASEBOARD_FAB2_LIB.BASEBOARD_FAB2(SCH_1):PAGE40
   AU6    GND @BASEBOARD_FAB2_LIB.BASEBOARD_FAB2(SCH_1):GND    I23 @BASEBOARD_FAB2_LIB.BASEBOARD_FAB2(SCH_1):PAGE40
  AU26    GND @BASEBOARD_FAB2_LIB.BASEBOARD_FAB2(SCH_1):GND    I23 @BASEBOARD_FAB2_LIB.BASEBOARD_FAB2(SCH_1):PAGE40
  AU28    GND @BASEBOARD_FAB2_LIB.BASEBOARD_FAB2(SCH_1):GND    I23 @BASEBOARD_FAB2_LIB.BASEBOARD_FAB2(SCH_1):PAGE40
  AU62    GND @BASEBOARD_FAB2_LIB.BASEBOARD_FAB2(SCH_1):GND    I23 @BASEBOARD_FAB2_LIB.BASEBOARD_FAB2(SCH_1):PAGE40
  AU64    GND @BASEBOARD_FAB2_LIB.BASEBOARD_FAB2(SCH_1):GND    I23 @BASEBOARD_FAB2_LIB.BASEBOARD_FAB2(SCH_1):PAGE40
  AU68    GND @BASEBOARD_FAB2_LIB.BASEBOARD_FAB2(SCH_1):GND    I23 @BASEBOARD_FAB2_LIB.BASEBOARD_FAB2(SCH_1):PAGE40
  AU74    GND @BASEBOARD_FAB2_LIB.BASEBOARD_FAB2(SCH_1):GND    I23 @BASEBOARD_FAB2_LIB.BASEBOARD_FAB2(SCH_1):PAGE40
  AU76    GND @BASEBOARD_FAB2_LIB.BASEBOARD_FAB2(SCH_1):GND    I23 @BASEBOARD_FAB2_LIB.BASEBOARD_FAB2(SCH_1):PAGE40
  AU78    GND @BASEBOARD_FAB2_LIB.BASEBOARD_FAB2(SCH_1):GND    I23 @BASEBOARD_FAB2_LIB.BASEBOARD_FAB2(SCH_1):PAGE40
  AU80    GND @BASEBOARD_FAB2_LIB.BASEBOARD_FAB2(SCH_1):GND    I23 @BASEBOARD_FAB2_LIB.BASEBOARD_FAB2(SCH_1):PAGE40
  AU84    GND @BASEBOARD_FAB2_LIB.BASEBOARD_FAB2(SCH_1):GND    I23 @BASEBOARD_FAB2_LIB.BASEBOARD_FAB2(SCH_1):PAGE40
  AU86    GND @BASEBOARD_FAB2_LIB.BASEBOARD_FAB2(SCH_1):GND    I23 @BASEBOARD_FAB2_LIB.BASEBOARD_FAB2(SCH_1):PAGE40
   AV1    GND @BASEBOARD_FAB2_LIB.BASEBOARD_FAB2(SCH_1):GND    I23 @BASEBOARD_FAB2_LIB.BASEBOARD_FAB2(SCH_1):PAGE40
   AV3    GND @BASEBOARD_FAB2_LIB.BASEBOARD_FAB2(SCH_1):GND    I23 @BASEBOARD_FAB2_LIB.BASEBOARD_FAB2(SCH_1):PAGE40
   AV7    GND @BASEBOARD_FAB2_LIB.BASEBOARD_FAB2(SCH_1):GND    I23 @BASEBOARD_FAB2_LIB.BASEBOARD_FAB2(SCH_1):PAGE40
  AV11    GND @BASEBOARD_FAB2_LIB.BASEBOARD_FAB2(SCH_1):GND    I23 @BASEBOARD_FAB2_LIB.BASEBOARD_FAB2(SCH_1):PAGE40
  AV13    GND @BASEBOARD_FAB2_LIB.BASEBOARD_FAB2(SCH_1):GND    I23 @BASEBOARD_FAB2_LIB.BASEBOARD_FAB2(SCH_1):PAGE40
  AV19    GND @BASEBOARD_FAB2_LIB.BASEBOARD_FAB2(SCH_1):GND    I23 @BASEBOARD_FAB2_LIB.BASEBOARD_FAB2(SCH_1):PAGE40
  AV23    GND @BASEBOARD_FAB2_LIB.BASEBOARD_FAB2(SCH_1):GND    I23 @BASEBOARD_FAB2_LIB.BASEBOARD_FAB2(SCH_1):PAGE40
  AV25    GND @BASEBOARD_FAB2_LIB.BASEBOARD_FAB2(SCH_1):GND    I23 @BASEBOARD_FAB2_LIB.BASEBOARD_FAB2(SCH_1):PAGE40
  AV63    GND @BASEBOARD_FAB2_LIB.BASEBOARD_FAB2(SCH_1):GND    I23 @BASEBOARD_FAB2_LIB.BASEBOARD_FAB2(SCH_1):PAGE40
  AV65    GND @BASEBOARD_FAB2_LIB.BASEBOARD_FAB2(SCH_1):GND    I23 @BASEBOARD_FAB2_LIB.BASEBOARD_FAB2(SCH_1):PAGE40
  AV67    GND @BASEBOARD_FAB2_LIB.BASEBOARD_FAB2(SCH_1):GND    I23 @BASEBOARD_FAB2_LIB.BASEBOARD_FAB2(SCH_1):PAGE40
  AV75    GND @BASEBOARD_FAB2_LIB.BASEBOARD_FAB2(SCH_1):GND    I23 @BASEBOARD_FAB2_LIB.BASEBOARD_FAB2(SCH_1):PAGE40
  AV83    GND @BASEBOARD_FAB2_LIB.BASEBOARD_FAB2(SCH_1):GND    I23 @BASEBOARD_FAB2_LIB.BASEBOARD_FAB2(SCH_1):PAGE40
   AW2    GND @BASEBOARD_FAB2_LIB.BASEBOARD_FAB2(SCH_1):GND    I23 @BASEBOARD_FAB2_LIB.BASEBOARD_FAB2(SCH_1):PAGE40
  AW10    GND @BASEBOARD_FAB2_LIB.BASEBOARD_FAB2(SCH_1):GND    I23 @BASEBOARD_FAB2_LIB.BASEBOARD_FAB2(SCH_1):PAGE40
  AW62    GND @BASEBOARD_FAB2_LIB.BASEBOARD_FAB2(SCH_1):GND    I23 @BASEBOARD_FAB2_LIB.BASEBOARD_FAB2(SCH_1):PAGE40
  AW66    GND @BASEBOARD_FAB2_LIB.BASEBOARD_FAB2(SCH_1):GND    I23 @BASEBOARD_FAB2_LIB.BASEBOARD_FAB2(SCH_1):PAGE40
  AW68    GND @BASEBOARD_FAB2_LIB.BASEBOARD_FAB2(SCH_1):GND    I23 @BASEBOARD_FAB2_LIB.BASEBOARD_FAB2(SCH_1):PAGE40
  AW70    GND @BASEBOARD_FAB2_LIB.BASEBOARD_FAB2(SCH_1):GND    I23 @BASEBOARD_FAB2_LIB.BASEBOARD_FAB2(SCH_1):PAGE40
  AW72    GND @BASEBOARD_FAB2_LIB.BASEBOARD_FAB2(SCH_1):GND    I23 @BASEBOARD_FAB2_LIB.BASEBOARD_FAB2(SCH_1):PAGE40
  AW74    GND @BASEBOARD_FAB2_LIB.BASEBOARD_FAB2(SCH_1):GND    I23 @BASEBOARD_FAB2_LIB.BASEBOARD_FAB2(SCH_1):PAGE40
  AW78    GND @BASEBOARD_FAB2_LIB.BASEBOARD_FAB2(SCH_1):GND    I23 @BASEBOARD_FAB2_LIB.BASEBOARD_FAB2(SCH_1):PAGE40
  AW82    GND @BASEBOARD_FAB2_LIB.BASEBOARD_FAB2(SCH_1):GND    I23 @BASEBOARD_FAB2_LIB.BASEBOARD_FAB2(SCH_1):PAGE40
  AW84    GND @BASEBOARD_FAB2_LIB.BASEBOARD_FAB2(SCH_1):GND    I23 @BASEBOARD_FAB2_LIB.BASEBOARD_FAB2(SCH_1):PAGE40
   AY5    GND @BASEBOARD_FAB2_LIB.BASEBOARD_FAB2(SCH_1):GND    I23 @BASEBOARD_FAB2_LIB.BASEBOARD_FAB2(SCH_1):PAGE40
  AY15    GND @BASEBOARD_FAB2_LIB.BASEBOARD_FAB2(SCH_1):GND    I23 @BASEBOARD_FAB2_LIB.BASEBOARD_FAB2(SCH_1):PAGE40
  AY17    GND @BASEBOARD_FAB2_LIB.BASEBOARD_FAB2(SCH_1):GND    I23 @BASEBOARD_FAB2_LIB.BASEBOARD_FAB2(SCH_1):PAGE40
  AY21    GND @BASEBOARD_FAB2_LIB.BASEBOARD_FAB2(SCH_1):GND    I23 @BASEBOARD_FAB2_LIB.BASEBOARD_FAB2(SCH_1):PAGE40
  AY23    GND @BASEBOARD_FAB2_LIB.BASEBOARD_FAB2(SCH_1):GND    I23 @BASEBOARD_FAB2_LIB.BASEBOARD_FAB2(SCH_1):PAGE40
  AY25    GND @BASEBOARD_FAB2_LIB.BASEBOARD_FAB2(SCH_1):GND    I23 @BASEBOARD_FAB2_LIB.BASEBOARD_FAB2(SCH_1):PAGE40
  AY63    GND @BASEBOARD_FAB2_LIB.BASEBOARD_FAB2(SCH_1):GND    I23 @BASEBOARD_FAB2_LIB.BASEBOARD_FAB2(SCH_1):PAGE40
  AY79    GND @BASEBOARD_FAB2_LIB.BASEBOARD_FAB2(SCH_1):GND    I23 @BASEBOARD_FAB2_LIB.BASEBOARD_FAB2(SCH_1):PAGE40
  AY81    GND @BASEBOARD_FAB2_LIB.BASEBOARD_FAB2(SCH_1):GND    I23 @BASEBOARD_FAB2_LIB.BASEBOARD_FAB2(SCH_1):PAGE40
   BA2    GND @BASEBOARD_FAB2_LIB.BASEBOARD_FAB2(SCH_1):GND    I23 @BASEBOARD_FAB2_LIB.BASEBOARD_FAB2(SCH_1):PAGE40
   BA6    GND @BASEBOARD_FAB2_LIB.BASEBOARD_FAB2(SCH_1):GND    I23 @BASEBOARD_FAB2_LIB.BASEBOARD_FAB2(SCH_1):PAGE40
  BA12    GND @BASEBOARD_FAB2_LIB.BASEBOARD_FAB2(SCH_1):GND    I23 @BASEBOARD_FAB2_LIB.BASEBOARD_FAB2(SCH_1):PAGE40
  BA62    GND @BASEBOARD_FAB2_LIB.BASEBOARD_FAB2(SCH_1):GND    I23 @BASEBOARD_FAB2_LIB.BASEBOARD_FAB2(SCH_1):PAGE40
  BA68    GND @BASEBOARD_FAB2_LIB.BASEBOARD_FAB2(SCH_1):GND    I23 @BASEBOARD_FAB2_LIB.BASEBOARD_FAB2(SCH_1):PAGE40
  BA74    GND @BASEBOARD_FAB2_LIB.BASEBOARD_FAB2(SCH_1):GND    I23 @BASEBOARD_FAB2_LIB.BASEBOARD_FAB2(SCH_1):PAGE40
  BA80    GND @BASEBOARD_FAB2_LIB.BASEBOARD_FAB2(SCH_1):GND    I23 @BASEBOARD_FAB2_LIB.BASEBOARD_FAB2(SCH_1):PAGE40
  BA84    GND @BASEBOARD_FAB2_LIB.BASEBOARD_FAB2(SCH_1):GND    I23 @BASEBOARD_FAB2_LIB.BASEBOARD_FAB2(SCH_1):PAGE40
  BB19    GND @BASEBOARD_FAB2_LIB.BASEBOARD_FAB2(SCH_1):GND    I23 @BASEBOARD_FAB2_LIB.BASEBOARD_FAB2(SCH_1):PAGE40
  BB23    GND @BASEBOARD_FAB2_LIB.BASEBOARD_FAB2(SCH_1):GND    I23 @BASEBOARD_FAB2_LIB.BASEBOARD_FAB2(SCH_1):PAGE40
  BB63    GND @BASEBOARD_FAB2_LIB.BASEBOARD_FAB2(SCH_1):GND    I23 @BASEBOARD_FAB2_LIB.BASEBOARD_FAB2(SCH_1):PAGE40
  BB69    GND @BASEBOARD_FAB2_LIB.BASEBOARD_FAB2(SCH_1):GND    I23 @BASEBOARD_FAB2_LIB.BASEBOARD_FAB2(SCH_1):PAGE40
  BB73    GND @BASEBOARD_FAB2_LIB.BASEBOARD_FAB2(SCH_1):GND    I23 @BASEBOARD_FAB2_LIB.BASEBOARD_FAB2(SCH_1):PAGE40
  BB75    GND @BASEBOARD_FAB2_LIB.BASEBOARD_FAB2(SCH_1):GND    I23 @BASEBOARD_FAB2_LIB.BASEBOARD_FAB2(SCH_1):PAGE40
  BB77    GND @BASEBOARD_FAB2_LIB.BASEBOARD_FAB2(SCH_1):GND    I23 @BASEBOARD_FAB2_LIB.BASEBOARD_FAB2(SCH_1):PAGE40
  BB79    GND @BASEBOARD_FAB2_LIB.BASEBOARD_FAB2(SCH_1):GND    I23 @BASEBOARD_FAB2_LIB.BASEBOARD_FAB2(SCH_1):PAGE40
  BB81    GND @BASEBOARD_FAB2_LIB.BASEBOARD_FAB2(SCH_1):GND    I23 @BASEBOARD_FAB2_LIB.BASEBOARD_FAB2(SCH_1):PAGE40
  BB83    GND @BASEBOARD_FAB2_LIB.BASEBOARD_FAB2(SCH_1):GND    I23 @BASEBOARD_FAB2_LIB.BASEBOARD_FAB2(SCH_1):PAGE40
   BC4    GND @BASEBOARD_FAB2_LIB.BASEBOARD_FAB2(SCH_1):GND    I23 @BASEBOARD_FAB2_LIB.BASEBOARD_FAB2(SCH_1):PAGE40
   BC8    GND @BASEBOARD_FAB2_LIB.BASEBOARD_FAB2(SCH_1):GND    I23 @BASEBOARD_FAB2_LIB.BASEBOARD_FAB2(SCH_1):PAGE40
  BC12    GND @BASEBOARD_FAB2_LIB.BASEBOARD_FAB2(SCH_1):GND    I23 @BASEBOARD_FAB2_LIB.BASEBOARD_FAB2(SCH_1):PAGE40
  BC16    GND @BASEBOARD_FAB2_LIB.BASEBOARD_FAB2(SCH_1):GND    I23 @BASEBOARD_FAB2_LIB.BASEBOARD_FAB2(SCH_1):PAGE40
  BC70    GND @BASEBOARD_FAB2_LIB.BASEBOARD_FAB2(SCH_1):GND    I23 @BASEBOARD_FAB2_LIB.BASEBOARD_FAB2(SCH_1):PAGE40
  BC72    GND @BASEBOARD_FAB2_LIB.BASEBOARD_FAB2(SCH_1):GND    I23 @BASEBOARD_FAB2_LIB.BASEBOARD_FAB2(SCH_1):PAGE40
  BC74    GND @BASEBOARD_FAB2_LIB.BASEBOARD_FAB2(SCH_1):GND    I23 @BASEBOARD_FAB2_LIB.BASEBOARD_FAB2(SCH_1):PAGE40
  BC76    GND @BASEBOARD_FAB2_LIB.BASEBOARD_FAB2(SCH_1):GND    I23 @BASEBOARD_FAB2_LIB.BASEBOARD_FAB2(SCH_1):PAGE40
  BC78    GND @BASEBOARD_FAB2_LIB.BASEBOARD_FAB2(SCH_1):GND    I23 @BASEBOARD_FAB2_LIB.BASEBOARD_FAB2(SCH_1):PAGE40
  BC80    GND @BASEBOARD_FAB2_LIB.BASEBOARD_FAB2(SCH_1):GND    I23 @BASEBOARD_FAB2_LIB.BASEBOARD_FAB2(SCH_1):PAGE40
  BC82    GND @BASEBOARD_FAB2_LIB.BASEBOARD_FAB2(SCH_1):GND    I23 @BASEBOARD_FAB2_LIB.BASEBOARD_FAB2(SCH_1):PAGE40
   BD5    GND @BASEBOARD_FAB2_LIB.BASEBOARD_FAB2(SCH_1):GND    I23 @BASEBOARD_FAB2_LIB.BASEBOARD_FAB2(SCH_1):PAGE40
  BD11    GND @BASEBOARD_FAB2_LIB.BASEBOARD_FAB2(SCH_1):GND    I23 @BASEBOARD_FAB2_LIB.BASEBOARD_FAB2(SCH_1):PAGE40
  BD15    GND @BASEBOARD_FAB2_LIB.BASEBOARD_FAB2(SCH_1):GND    I23 @BASEBOARD_FAB2_LIB.BASEBOARD_FAB2(SCH_1):PAGE40
  BD21    GND @BASEBOARD_FAB2_LIB.BASEBOARD_FAB2(SCH_1):GND    I23 @BASEBOARD_FAB2_LIB.BASEBOARD_FAB2(SCH_1):PAGE40
  BD27    GND @BASEBOARD_FAB2_LIB.BASEBOARD_FAB2(SCH_1):GND    I23 @BASEBOARD_FAB2_LIB.BASEBOARD_FAB2(SCH_1):PAGE40
  BD63    GND @BASEBOARD_FAB2_LIB.BASEBOARD_FAB2(SCH_1):GND    I23 @BASEBOARD_FAB2_LIB.BASEBOARD_FAB2(SCH_1):PAGE40
  BD71    GND @BASEBOARD_FAB2_LIB.BASEBOARD_FAB2(SCH_1):GND    I23 @BASEBOARD_FAB2_LIB.BASEBOARD_FAB2(SCH_1):PAGE40
   BE4    GND @BASEBOARD_FAB2_LIB.BASEBOARD_FAB2(SCH_1):GND    I23 @BASEBOARD_FAB2_LIB.BASEBOARD_FAB2(SCH_1):PAGE40
   BE6    GND @BASEBOARD_FAB2_LIB.BASEBOARD_FAB2(SCH_1):GND    I23 @BASEBOARD_FAB2_LIB.BASEBOARD_FAB2(SCH_1):PAGE40
   BE8    GND @BASEBOARD_FAB2_LIB.BASEBOARD_FAB2(SCH_1):GND    I23 @BASEBOARD_FAB2_LIB.BASEBOARD_FAB2(SCH_1):PAGE40
  BE10    GND @BASEBOARD_FAB2_LIB.BASEBOARD_FAB2(SCH_1):GND    I23 @BASEBOARD_FAB2_LIB.BASEBOARD_FAB2(SCH_1):PAGE40
  BE26    GND @BASEBOARD_FAB2_LIB.BASEBOARD_FAB2(SCH_1):GND    I23 @BASEBOARD_FAB2_LIB.BASEBOARD_FAB2(SCH_1):PAGE40
  BE64    GND @BASEBOARD_FAB2_LIB.BASEBOARD_FAB2(SCH_1):GND    I23 @BASEBOARD_FAB2_LIB.BASEBOARD_FAB2(SCH_1):PAGE40
  BE66    GND @BASEBOARD_FAB2_LIB.BASEBOARD_FAB2(SCH_1):GND    I23 @BASEBOARD_FAB2_LIB.BASEBOARD_FAB2(SCH_1):PAGE40
  BE68    GND @BASEBOARD_FAB2_LIB.BASEBOARD_FAB2(SCH_1):GND    I23 @BASEBOARD_FAB2_LIB.BASEBOARD_FAB2(SCH_1):PAGE40
  BE70    GND @BASEBOARD_FAB2_LIB.BASEBOARD_FAB2(SCH_1):GND    I23 @BASEBOARD_FAB2_LIB.BASEBOARD_FAB2(SCH_1):PAGE40
   BF9    GND @BASEBOARD_FAB2_LIB.BASEBOARD_FAB2(SCH_1):GND    I23 @BASEBOARD_FAB2_LIB.BASEBOARD_FAB2(SCH_1):PAGE40
  BF15    GND @BASEBOARD_FAB2_LIB.BASEBOARD_FAB2(SCH_1):GND    I23 @BASEBOARD_FAB2_LIB.BASEBOARD_FAB2(SCH_1):PAGE40
  BF17    GND @BASEBOARD_FAB2_LIB.BASEBOARD_FAB2(SCH_1):GND    I23 @BASEBOARD_FAB2_LIB.BASEBOARD_FAB2(SCH_1):PAGE40
  BF19    GND @BASEBOARD_FAB2_LIB.BASEBOARD_FAB2(SCH_1):GND    I23 @BASEBOARD_FAB2_LIB.BASEBOARD_FAB2(SCH_1):PAGE40
  BF25    GND @BASEBOARD_FAB2_LIB.BASEBOARD_FAB2(SCH_1):GND    I23 @BASEBOARD_FAB2_LIB.BASEBOARD_FAB2(SCH_1):PAGE40
  BF63    GND @BASEBOARD_FAB2_LIB.BASEBOARD_FAB2(SCH_1):GND    I23 @BASEBOARD_FAB2_LIB.BASEBOARD_FAB2(SCH_1):PAGE40
  BF65    GND @BASEBOARD_FAB2_LIB.BASEBOARD_FAB2(SCH_1):GND    I23 @BASEBOARD_FAB2_LIB.BASEBOARD_FAB2(SCH_1):PAGE40
  BF67    GND @BASEBOARD_FAB2_LIB.BASEBOARD_FAB2(SCH_1):GND    I23 @BASEBOARD_FAB2_LIB.BASEBOARD_FAB2(SCH_1):PAGE40
  BF69    GND @BASEBOARD_FAB2_LIB.BASEBOARD_FAB2(SCH_1):GND    I23 @BASEBOARD_FAB2_LIB.BASEBOARD_FAB2(SCH_1):PAGE40
  BF71    GND @BASEBOARD_FAB2_LIB.BASEBOARD_FAB2(SCH_1):GND    I23 @BASEBOARD_FAB2_LIB.BASEBOARD_FAB2(SCH_1):PAGE40
   BG6    GND @BASEBOARD_FAB2_LIB.BASEBOARD_FAB2(SCH_1):GND    I23 @BASEBOARD_FAB2_LIB.BASEBOARD_FAB2(SCH_1):PAGE40
   BG8    GND @BASEBOARD_FAB2_LIB.BASEBOARD_FAB2(SCH_1):GND    I23 @BASEBOARD_FAB2_LIB.BASEBOARD_FAB2(SCH_1):PAGE40
  BG10    GND @BASEBOARD_FAB2_LIB.BASEBOARD_FAB2(SCH_1):GND    I23 @BASEBOARD_FAB2_LIB.BASEBOARD_FAB2(SCH_1):PAGE40
  BG22    GND @BASEBOARD_FAB2_LIB.BASEBOARD_FAB2(SCH_1):GND    I23 @BASEBOARD_FAB2_LIB.BASEBOARD_FAB2(SCH_1):PAGE40
  BG24    GND @BASEBOARD_FAB2_LIB.BASEBOARD_FAB2(SCH_1):GND    I23 @BASEBOARD_FAB2_LIB.BASEBOARD_FAB2(SCH_1):PAGE40
  BG72    GND @BASEBOARD_FAB2_LIB.BASEBOARD_FAB2(SCH_1):GND    I23 @BASEBOARD_FAB2_LIB.BASEBOARD_FAB2(SCH_1):PAGE40
  BG74    GND @BASEBOARD_FAB2_LIB.BASEBOARD_FAB2(SCH_1):GND   I283 @BASEBOARD_FAB2_LIB.BASEBOARD_FAB2(SCH_1):PAGE41
  BG76    GND @BASEBOARD_FAB2_LIB.BASEBOARD_FAB2(SCH_1):GND   I283 @BASEBOARD_FAB2_LIB.BASEBOARD_FAB2(SCH_1):PAGE41
  BG78    GND @BASEBOARD_FAB2_LIB.BASEBOARD_FAB2(SCH_1):GND   I283 @BASEBOARD_FAB2_LIB.BASEBOARD_FAB2(SCH_1):PAGE41
  BG80    GND @BASEBOARD_FAB2_LIB.BASEBOARD_FAB2(SCH_1):GND   I283 @BASEBOARD_FAB2_LIB.BASEBOARD_FAB2(SCH_1):PAGE41
  BG82    GND @BASEBOARD_FAB2_LIB.BASEBOARD_FAB2(SCH_1):GND   I283 @BASEBOARD_FAB2_LIB.BASEBOARD_FAB2(SCH_1):PAGE41
   BH7    GND @BASEBOARD_FAB2_LIB.BASEBOARD_FAB2(SCH_1):GND   I283 @BASEBOARD_FAB2_LIB.BASEBOARD_FAB2(SCH_1):PAGE41
   BH9    GND @BASEBOARD_FAB2_LIB.BASEBOARD_FAB2(SCH_1):GND   I283 @BASEBOARD_FAB2_LIB.BASEBOARD_FAB2(SCH_1):PAGE41
  BH11    GND @BASEBOARD_FAB2_LIB.BASEBOARD_FAB2(SCH_1):GND   I283 @BASEBOARD_FAB2_LIB.BASEBOARD_FAB2(SCH_1):PAGE41
  BH15    GND @BASEBOARD_FAB2_LIB.BASEBOARD_FAB2(SCH_1):GND   I283 @BASEBOARD_FAB2_LIB.BASEBOARD_FAB2(SCH_1):PAGE41
  BH21    GND @BASEBOARD_FAB2_LIB.BASEBOARD_FAB2(SCH_1):GND   I283 @BASEBOARD_FAB2_LIB.BASEBOARD_FAB2(SCH_1):PAGE41
   BJ4    GND @BASEBOARD_FAB2_LIB.BASEBOARD_FAB2(SCH_1):GND   I283 @BASEBOARD_FAB2_LIB.BASEBOARD_FAB2(SCH_1):PAGE41
   BJ6    GND @BASEBOARD_FAB2_LIB.BASEBOARD_FAB2(SCH_1):GND   I283 @BASEBOARD_FAB2_LIB.BASEBOARD_FAB2(SCH_1):PAGE41
   BK3    GND @BASEBOARD_FAB2_LIB.BASEBOARD_FAB2(SCH_1):GND   I283 @BASEBOARD_FAB2_LIB.BASEBOARD_FAB2(SCH_1):PAGE41
   BK7    GND @BASEBOARD_FAB2_LIB.BASEBOARD_FAB2(SCH_1):GND   I283 @BASEBOARD_FAB2_LIB.BASEBOARD_FAB2(SCH_1):PAGE41
  BK11    GND @BASEBOARD_FAB2_LIB.BASEBOARD_FAB2(SCH_1):GND   I283 @BASEBOARD_FAB2_LIB.BASEBOARD_FAB2(SCH_1):PAGE41
  BK19    GND @BASEBOARD_FAB2_LIB.BASEBOARD_FAB2(SCH_1):GND   I283 @BASEBOARD_FAB2_LIB.BASEBOARD_FAB2(SCH_1):PAGE41
   BL6    GND @BASEBOARD_FAB2_LIB.BASEBOARD_FAB2(SCH_1):GND   I283 @BASEBOARD_FAB2_LIB.BASEBOARD_FAB2(SCH_1):PAGE41
  BL10    GND @BASEBOARD_FAB2_LIB.BASEBOARD_FAB2(SCH_1):GND   I283 @BASEBOARD_FAB2_LIB.BASEBOARD_FAB2(SCH_1):PAGE41
  BL12    GND @BASEBOARD_FAB2_LIB.BASEBOARD_FAB2(SCH_1):GND   I283 @BASEBOARD_FAB2_LIB.BASEBOARD_FAB2(SCH_1):PAGE41
   P61    GND @BASEBOARD_FAB2_LIB.BASEBOARD_FAB2(SCH_1):GND   I283 @BASEBOARD_FAB2_LIB.BASEBOARD_FAB2(SCH_1):PAGE41
  BL22    GND @BASEBOARD_FAB2_LIB.BASEBOARD_FAB2(SCH_1):GND   I283 @BASEBOARD_FAB2_LIB.BASEBOARD_FAB2(SCH_1):PAGE41
  BL24    GND @BASEBOARD_FAB2_LIB.BASEBOARD_FAB2(SCH_1):GND   I283 @BASEBOARD_FAB2_LIB.BASEBOARD_FAB2(SCH_1):PAGE41
  BL64    GND @BASEBOARD_FAB2_LIB.BASEBOARD_FAB2(SCH_1):GND   I283 @BASEBOARD_FAB2_LIB.BASEBOARD_FAB2(SCH_1):PAGE41
  BL66    GND @BASEBOARD_FAB2_LIB.BASEBOARD_FAB2(SCH_1):GND   I283 @BASEBOARD_FAB2_LIB.BASEBOARD_FAB2(SCH_1):PAGE41
  BL68    GND @BASEBOARD_FAB2_LIB.BASEBOARD_FAB2(SCH_1):GND   I283 @BASEBOARD_FAB2_LIB.BASEBOARD_FAB2(SCH_1):PAGE41
  BL70    GND @BASEBOARD_FAB2_LIB.BASEBOARD_FAB2(SCH_1):GND   I283 @BASEBOARD_FAB2_LIB.BASEBOARD_FAB2(SCH_1):PAGE41
  BL72    GND @BASEBOARD_FAB2_LIB.BASEBOARD_FAB2(SCH_1):GND   I283 @BASEBOARD_FAB2_LIB.BASEBOARD_FAB2(SCH_1):PAGE41
  BL74    GND @BASEBOARD_FAB2_LIB.BASEBOARD_FAB2(SCH_1):GND   I283 @BASEBOARD_FAB2_LIB.BASEBOARD_FAB2(SCH_1):PAGE41
  BL76    GND @BASEBOARD_FAB2_LIB.BASEBOARD_FAB2(SCH_1):GND   I283 @BASEBOARD_FAB2_LIB.BASEBOARD_FAB2(SCH_1):PAGE41
  BL78    GND @BASEBOARD_FAB2_LIB.BASEBOARD_FAB2(SCH_1):GND   I283 @BASEBOARD_FAB2_LIB.BASEBOARD_FAB2(SCH_1):PAGE41
  BL80    GND @BASEBOARD_FAB2_LIB.BASEBOARD_FAB2(SCH_1):GND   I283 @BASEBOARD_FAB2_LIB.BASEBOARD_FAB2(SCH_1):PAGE41
  BL82    GND @BASEBOARD_FAB2_LIB.BASEBOARD_FAB2(SCH_1):GND   I283 @BASEBOARD_FAB2_LIB.BASEBOARD_FAB2(SCH_1):PAGE41
   BM9    GND @BASEBOARD_FAB2_LIB.BASEBOARD_FAB2(SCH_1):GND   I283 @BASEBOARD_FAB2_LIB.BASEBOARD_FAB2(SCH_1):PAGE41
  BM13    GND @BASEBOARD_FAB2_LIB.BASEBOARD_FAB2(SCH_1):GND   I283 @BASEBOARD_FAB2_LIB.BASEBOARD_FAB2(SCH_1):PAGE41
  BM15    GND @BASEBOARD_FAB2_LIB.BASEBOARD_FAB2(SCH_1):GND   I283 @BASEBOARD_FAB2_LIB.BASEBOARD_FAB2(SCH_1):PAGE41
   P59    GND @BASEBOARD_FAB2_LIB.BASEBOARD_FAB2(SCH_1):GND   I283 @BASEBOARD_FAB2_LIB.BASEBOARD_FAB2(SCH_1):PAGE41
  BM25    GND @BASEBOARD_FAB2_LIB.BASEBOARD_FAB2(SCH_1):GND   I283 @BASEBOARD_FAB2_LIB.BASEBOARD_FAB2(SCH_1):PAGE41
   BN6    GND @BASEBOARD_FAB2_LIB.BASEBOARD_FAB2(SCH_1):GND   I283 @BASEBOARD_FAB2_LIB.BASEBOARD_FAB2(SCH_1):PAGE41
  BN10    GND @BASEBOARD_FAB2_LIB.BASEBOARD_FAB2(SCH_1):GND   I283 @BASEBOARD_FAB2_LIB.BASEBOARD_FAB2(SCH_1):PAGE41
  BN20    GND @BASEBOARD_FAB2_LIB.BASEBOARD_FAB2(SCH_1):GND   I283 @BASEBOARD_FAB2_LIB.BASEBOARD_FAB2(SCH_1):PAGE41
  BN26    GND @BASEBOARD_FAB2_LIB.BASEBOARD_FAB2(SCH_1):GND   I283 @BASEBOARD_FAB2_LIB.BASEBOARD_FAB2(SCH_1):PAGE41
   BP3    GND @BASEBOARD_FAB2_LIB.BASEBOARD_FAB2(SCH_1):GND   I283 @BASEBOARD_FAB2_LIB.BASEBOARD_FAB2(SCH_1):PAGE41
  BP27    GND @BASEBOARD_FAB2_LIB.BASEBOARD_FAB2(SCH_1):GND   I283 @BASEBOARD_FAB2_LIB.BASEBOARD_FAB2(SCH_1):PAGE41
   BR6    GND @BASEBOARD_FAB2_LIB.BASEBOARD_FAB2(SCH_1):GND   I283 @BASEBOARD_FAB2_LIB.BASEBOARD_FAB2(SCH_1):PAGE41
  BR10    GND @BASEBOARD_FAB2_LIB.BASEBOARD_FAB2(SCH_1):GND   I283 @BASEBOARD_FAB2_LIB.BASEBOARD_FAB2(SCH_1):PAGE41
  BR16    GND @BASEBOARD_FAB2_LIB.BASEBOARD_FAB2(SCH_1):GND   I283 @BASEBOARD_FAB2_LIB.BASEBOARD_FAB2(SCH_1):PAGE41
   P57    GND @BASEBOARD_FAB2_LIB.BASEBOARD_FAB2(SCH_1):GND   I283 @BASEBOARD_FAB2_LIB.BASEBOARD_FAB2(SCH_1):PAGE41
  BR64    GND @BASEBOARD_FAB2_LIB.BASEBOARD_FAB2(SCH_1):GND   I283 @BASEBOARD_FAB2_LIB.BASEBOARD_FAB2(SCH_1):PAGE41
  BR66    GND @BASEBOARD_FAB2_LIB.BASEBOARD_FAB2(SCH_1):GND   I283 @BASEBOARD_FAB2_LIB.BASEBOARD_FAB2(SCH_1):PAGE41
  BR68    GND @BASEBOARD_FAB2_LIB.BASEBOARD_FAB2(SCH_1):GND   I283 @BASEBOARD_FAB2_LIB.BASEBOARD_FAB2(SCH_1):PAGE41
  BR70    GND @BASEBOARD_FAB2_LIB.BASEBOARD_FAB2(SCH_1):GND   I283 @BASEBOARD_FAB2_LIB.BASEBOARD_FAB2(SCH_1):PAGE41
  BR72    GND @BASEBOARD_FAB2_LIB.BASEBOARD_FAB2(SCH_1):GND   I283 @BASEBOARD_FAB2_LIB.BASEBOARD_FAB2(SCH_1):PAGE41
  BR74    GND @BASEBOARD_FAB2_LIB.BASEBOARD_FAB2(SCH_1):GND   I283 @BASEBOARD_FAB2_LIB.BASEBOARD_FAB2(SCH_1):PAGE41
  BR76    GND @BASEBOARD_FAB2_LIB.BASEBOARD_FAB2(SCH_1):GND   I283 @BASEBOARD_FAB2_LIB.BASEBOARD_FAB2(SCH_1):PAGE41
  BR78    GND @BASEBOARD_FAB2_LIB.BASEBOARD_FAB2(SCH_1):GND   I283 @BASEBOARD_FAB2_LIB.BASEBOARD_FAB2(SCH_1):PAGE41
  BR80    GND @BASEBOARD_FAB2_LIB.BASEBOARD_FAB2(SCH_1):GND   I283 @BASEBOARD_FAB2_LIB.BASEBOARD_FAB2(SCH_1):PAGE41
  BR82    GND @BASEBOARD_FAB2_LIB.BASEBOARD_FAB2(SCH_1):GND   I283 @BASEBOARD_FAB2_LIB.BASEBOARD_FAB2(SCH_1):PAGE41
   BT3    GND @BASEBOARD_FAB2_LIB.BASEBOARD_FAB2(SCH_1):GND   I283 @BASEBOARD_FAB2_LIB.BASEBOARD_FAB2(SCH_1):PAGE41
   BT5    GND @BASEBOARD_FAB2_LIB.BASEBOARD_FAB2(SCH_1):GND   I283 @BASEBOARD_FAB2_LIB.BASEBOARD_FAB2(SCH_1):PAGE41
  BT21    GND @BASEBOARD_FAB2_LIB.BASEBOARD_FAB2(SCH_1):GND   I283 @BASEBOARD_FAB2_LIB.BASEBOARD_FAB2(SCH_1):PAGE41
  BT23    GND @BASEBOARD_FAB2_LIB.BASEBOARD_FAB2(SCH_1):GND   I283 @BASEBOARD_FAB2_LIB.BASEBOARD_FAB2(SCH_1):PAGE41
  BT25    GND @BASEBOARD_FAB2_LIB.BASEBOARD_FAB2(SCH_1):GND   I283 @BASEBOARD_FAB2_LIB.BASEBOARD_FAB2(SCH_1):PAGE41
   BU8    GND @BASEBOARD_FAB2_LIB.BASEBOARD_FAB2(SCH_1):GND   I283 @BASEBOARD_FAB2_LIB.BASEBOARD_FAB2(SCH_1):PAGE41
   BV5    GND @BASEBOARD_FAB2_LIB.BASEBOARD_FAB2(SCH_1):GND   I283 @BASEBOARD_FAB2_LIB.BASEBOARD_FAB2(SCH_1):PAGE41
  BU10    GND @BASEBOARD_FAB2_LIB.BASEBOARD_FAB2(SCH_1):GND   I283 @BASEBOARD_FAB2_LIB.BASEBOARD_FAB2(SCH_1):PAGE41
  BV17    GND @BASEBOARD_FAB2_LIB.BASEBOARD_FAB2(SCH_1):GND   I283 @BASEBOARD_FAB2_LIB.BASEBOARD_FAB2(SCH_1):PAGE41
  BV25    GND @BASEBOARD_FAB2_LIB.BASEBOARD_FAB2(SCH_1):GND   I283 @BASEBOARD_FAB2_LIB.BASEBOARD_FAB2(SCH_1):PAGE41
   BW6    GND @BASEBOARD_FAB2_LIB.BASEBOARD_FAB2(SCH_1):GND   I283 @BASEBOARD_FAB2_LIB.BASEBOARD_FAB2(SCH_1):PAGE41
   P55    GND @BASEBOARD_FAB2_LIB.BASEBOARD_FAB2(SCH_1):GND   I283 @BASEBOARD_FAB2_LIB.BASEBOARD_FAB2(SCH_1):PAGE41
  BW12    GND @BASEBOARD_FAB2_LIB.BASEBOARD_FAB2(SCH_1):GND   I283 @BASEBOARD_FAB2_LIB.BASEBOARD_FAB2(SCH_1):PAGE41
  BW14    GND @BASEBOARD_FAB2_LIB.BASEBOARD_FAB2(SCH_1):GND   I283 @BASEBOARD_FAB2_LIB.BASEBOARD_FAB2(SCH_1):PAGE41
  BW16    GND @BASEBOARD_FAB2_LIB.BASEBOARD_FAB2(SCH_1):GND   I283 @BASEBOARD_FAB2_LIB.BASEBOARD_FAB2(SCH_1):PAGE41
  BW18    GND @BASEBOARD_FAB2_LIB.BASEBOARD_FAB2(SCH_1):GND   I283 @BASEBOARD_FAB2_LIB.BASEBOARD_FAB2(SCH_1):PAGE41
  BW26    GND @BASEBOARD_FAB2_LIB.BASEBOARD_FAB2(SCH_1):GND   I283 @BASEBOARD_FAB2_LIB.BASEBOARD_FAB2(SCH_1):PAGE41
  BW72    GND @BASEBOARD_FAB2_LIB.BASEBOARD_FAB2(SCH_1):GND   I283 @BASEBOARD_FAB2_LIB.BASEBOARD_FAB2(SCH_1):PAGE41
  BW74    GND @BASEBOARD_FAB2_LIB.BASEBOARD_FAB2(SCH_1):GND   I283 @BASEBOARD_FAB2_LIB.BASEBOARD_FAB2(SCH_1):PAGE41
  BW76    GND @BASEBOARD_FAB2_LIB.BASEBOARD_FAB2(SCH_1):GND   I283 @BASEBOARD_FAB2_LIB.BASEBOARD_FAB2(SCH_1):PAGE41
  BW78    GND @BASEBOARD_FAB2_LIB.BASEBOARD_FAB2(SCH_1):GND   I283 @BASEBOARD_FAB2_LIB.BASEBOARD_FAB2(SCH_1):PAGE41
  BW80    GND @BASEBOARD_FAB2_LIB.BASEBOARD_FAB2(SCH_1):GND   I283 @BASEBOARD_FAB2_LIB.BASEBOARD_FAB2(SCH_1):PAGE41
  BW82    GND @BASEBOARD_FAB2_LIB.BASEBOARD_FAB2(SCH_1):GND   I283 @BASEBOARD_FAB2_LIB.BASEBOARD_FAB2(SCH_1):PAGE41
  BY11    GND @BASEBOARD_FAB2_LIB.BASEBOARD_FAB2(SCH_1):GND   I283 @BASEBOARD_FAB2_LIB.BASEBOARD_FAB2(SCH_1):PAGE41
  BY13    GND @BASEBOARD_FAB2_LIB.BASEBOARD_FAB2(SCH_1):GND   I283 @BASEBOARD_FAB2_LIB.BASEBOARD_FAB2(SCH_1):PAGE41
  BY23    GND @BASEBOARD_FAB2_LIB.BASEBOARD_FAB2(SCH_1):GND   I283 @BASEBOARD_FAB2_LIB.BASEBOARD_FAB2(SCH_1):PAGE41
  BY63    GND @BASEBOARD_FAB2_LIB.BASEBOARD_FAB2(SCH_1):GND   I283 @BASEBOARD_FAB2_LIB.BASEBOARD_FAB2(SCH_1):PAGE41
  BY65    GND @BASEBOARD_FAB2_LIB.BASEBOARD_FAB2(SCH_1):GND   I283 @BASEBOARD_FAB2_LIB.BASEBOARD_FAB2(SCH_1):PAGE41
  BY67    GND @BASEBOARD_FAB2_LIB.BASEBOARD_FAB2(SCH_1):GND   I283 @BASEBOARD_FAB2_LIB.BASEBOARD_FAB2(SCH_1):PAGE41
  BY69    GND @BASEBOARD_FAB2_LIB.BASEBOARD_FAB2(SCH_1):GND   I283 @BASEBOARD_FAB2_LIB.BASEBOARD_FAB2(SCH_1):PAGE41
  BY71    GND @BASEBOARD_FAB2_LIB.BASEBOARD_FAB2(SCH_1):GND   I283 @BASEBOARD_FAB2_LIB.BASEBOARD_FAB2(SCH_1):PAGE41
   CA2    GND @BASEBOARD_FAB2_LIB.BASEBOARD_FAB2(SCH_1):GND   I283 @BASEBOARD_FAB2_LIB.BASEBOARD_FAB2(SCH_1):PAGE41
   CA6    GND @BASEBOARD_FAB2_LIB.BASEBOARD_FAB2(SCH_1):GND   I283 @BASEBOARD_FAB2_LIB.BASEBOARD_FAB2(SCH_1):PAGE41
   CA8    GND @BASEBOARD_FAB2_LIB.BASEBOARD_FAB2(SCH_1):GND   I283 @BASEBOARD_FAB2_LIB.BASEBOARD_FAB2(SCH_1):PAGE41
  CA10    GND @BASEBOARD_FAB2_LIB.BASEBOARD_FAB2(SCH_1):GND   I283 @BASEBOARD_FAB2_LIB.BASEBOARD_FAB2(SCH_1):PAGE41
  CA14    GND @BASEBOARD_FAB2_LIB.BASEBOARD_FAB2(SCH_1):GND   I283 @BASEBOARD_FAB2_LIB.BASEBOARD_FAB2(SCH_1):PAGE41
  CA18    GND @BASEBOARD_FAB2_LIB.BASEBOARD_FAB2(SCH_1):GND   I283 @BASEBOARD_FAB2_LIB.BASEBOARD_FAB2(SCH_1):PAGE41
  CA26    GND @BASEBOARD_FAB2_LIB.BASEBOARD_FAB2(SCH_1):GND   I283 @BASEBOARD_FAB2_LIB.BASEBOARD_FAB2(SCH_1):PAGE41
  CA64    GND @BASEBOARD_FAB2_LIB.BASEBOARD_FAB2(SCH_1):GND   I283 @BASEBOARD_FAB2_LIB.BASEBOARD_FAB2(SCH_1):PAGE41
  CA66    GND @BASEBOARD_FAB2_LIB.BASEBOARD_FAB2(SCH_1):GND   I283 @BASEBOARD_FAB2_LIB.BASEBOARD_FAB2(SCH_1):PAGE41
  CA68    GND @BASEBOARD_FAB2_LIB.BASEBOARD_FAB2(SCH_1):GND   I283 @BASEBOARD_FAB2_LIB.BASEBOARD_FAB2(SCH_1):PAGE41
  CA70    GND @BASEBOARD_FAB2_LIB.BASEBOARD_FAB2(SCH_1):GND   I283 @BASEBOARD_FAB2_LIB.BASEBOARD_FAB2(SCH_1):PAGE41
   CB7    GND @BASEBOARD_FAB2_LIB.BASEBOARD_FAB2(SCH_1):GND   I283 @BASEBOARD_FAB2_LIB.BASEBOARD_FAB2(SCH_1):PAGE41
   CB9    GND @BASEBOARD_FAB2_LIB.BASEBOARD_FAB2(SCH_1):GND   I283 @BASEBOARD_FAB2_LIB.BASEBOARD_FAB2(SCH_1):PAGE41
  CB27    GND @BASEBOARD_FAB2_LIB.BASEBOARD_FAB2(SCH_1):GND   I283 @BASEBOARD_FAB2_LIB.BASEBOARD_FAB2(SCH_1):PAGE41
  CB63    GND @BASEBOARD_FAB2_LIB.BASEBOARD_FAB2(SCH_1):GND   I283 @BASEBOARD_FAB2_LIB.BASEBOARD_FAB2(SCH_1):PAGE41
  CB71    GND @BASEBOARD_FAB2_LIB.BASEBOARD_FAB2(SCH_1):GND   I283 @BASEBOARD_FAB2_LIB.BASEBOARD_FAB2(SCH_1):PAGE41
   CC4    GND @BASEBOARD_FAB2_LIB.BASEBOARD_FAB2(SCH_1):GND   I283 @BASEBOARD_FAB2_LIB.BASEBOARD_FAB2(SCH_1):PAGE41
  CC16    GND @BASEBOARD_FAB2_LIB.BASEBOARD_FAB2(SCH_1):GND   I283 @BASEBOARD_FAB2_LIB.BASEBOARD_FAB2(SCH_1):PAGE41
  CC18    GND @BASEBOARD_FAB2_LIB.BASEBOARD_FAB2(SCH_1):GND   I283 @BASEBOARD_FAB2_LIB.BASEBOARD_FAB2(SCH_1):PAGE41
  CC24    GND @BASEBOARD_FAB2_LIB.BASEBOARD_FAB2(SCH_1):GND   I283 @BASEBOARD_FAB2_LIB.BASEBOARD_FAB2(SCH_1):PAGE41
  CC64    GND @BASEBOARD_FAB2_LIB.BASEBOARD_FAB2(SCH_1):GND   I283 @BASEBOARD_FAB2_LIB.BASEBOARD_FAB2(SCH_1):PAGE41
  CC72    GND @BASEBOARD_FAB2_LIB.BASEBOARD_FAB2(SCH_1):GND   I283 @BASEBOARD_FAB2_LIB.BASEBOARD_FAB2(SCH_1):PAGE41
  CC74    GND @BASEBOARD_FAB2_LIB.BASEBOARD_FAB2(SCH_1):GND   I283 @BASEBOARD_FAB2_LIB.BASEBOARD_FAB2(SCH_1):PAGE41
  CC76    GND @BASEBOARD_FAB2_LIB.BASEBOARD_FAB2(SCH_1):GND   I283 @BASEBOARD_FAB2_LIB.BASEBOARD_FAB2(SCH_1):PAGE41
  CC78    GND @BASEBOARD_FAB2_LIB.BASEBOARD_FAB2(SCH_1):GND   I283 @BASEBOARD_FAB2_LIB.BASEBOARD_FAB2(SCH_1):PAGE41
  CC80    GND @BASEBOARD_FAB2_LIB.BASEBOARD_FAB2(SCH_1):GND   I283 @BASEBOARD_FAB2_LIB.BASEBOARD_FAB2(SCH_1):PAGE41
  CC82    GND @BASEBOARD_FAB2_LIB.BASEBOARD_FAB2(SCH_1):GND   I283 @BASEBOARD_FAB2_LIB.BASEBOARD_FAB2(SCH_1):PAGE41
   CD5    GND @BASEBOARD_FAB2_LIB.BASEBOARD_FAB2(SCH_1):GND   I283 @BASEBOARD_FAB2_LIB.BASEBOARD_FAB2(SCH_1):PAGE41
  CD13    GND @BASEBOARD_FAB2_LIB.BASEBOARD_FAB2(SCH_1):GND   I283 @BASEBOARD_FAB2_LIB.BASEBOARD_FAB2(SCH_1):PAGE41
  CD63    GND @BASEBOARD_FAB2_LIB.BASEBOARD_FAB2(SCH_1):GND   I283 @BASEBOARD_FAB2_LIB.BASEBOARD_FAB2(SCH_1):PAGE41
  CD73    GND @BASEBOARD_FAB2_LIB.BASEBOARD_FAB2(SCH_1):GND   I283 @BASEBOARD_FAB2_LIB.BASEBOARD_FAB2(SCH_1):PAGE41
  CD75    GND @BASEBOARD_FAB2_LIB.BASEBOARD_FAB2(SCH_1):GND   I283 @BASEBOARD_FAB2_LIB.BASEBOARD_FAB2(SCH_1):PAGE41
  CD77    GND @BASEBOARD_FAB2_LIB.BASEBOARD_FAB2(SCH_1):GND   I283 @BASEBOARD_FAB2_LIB.BASEBOARD_FAB2(SCH_1):PAGE41
  CD79    GND @BASEBOARD_FAB2_LIB.BASEBOARD_FAB2(SCH_1):GND   I283 @BASEBOARD_FAB2_LIB.BASEBOARD_FAB2(SCH_1):PAGE41
  CD81    GND @BASEBOARD_FAB2_LIB.BASEBOARD_FAB2(SCH_1):GND   I283 @BASEBOARD_FAB2_LIB.BASEBOARD_FAB2(SCH_1):PAGE41
  CE10    GND @BASEBOARD_FAB2_LIB.BASEBOARD_FAB2(SCH_1):GND   I283 @BASEBOARD_FAB2_LIB.BASEBOARD_FAB2(SCH_1):PAGE41
  CE14    GND @BASEBOARD_FAB2_LIB.BASEBOARD_FAB2(SCH_1):GND   I283 @BASEBOARD_FAB2_LIB.BASEBOARD_FAB2(SCH_1):PAGE41
  CE20    GND @BASEBOARD_FAB2_LIB.BASEBOARD_FAB2(SCH_1):GND   I283 @BASEBOARD_FAB2_LIB.BASEBOARD_FAB2(SCH_1):PAGE41
  CE26    GND @BASEBOARD_FAB2_LIB.BASEBOARD_FAB2(SCH_1):GND   I283 @BASEBOARD_FAB2_LIB.BASEBOARD_FAB2(SCH_1):PAGE41
  CE62    GND @BASEBOARD_FAB2_LIB.BASEBOARD_FAB2(SCH_1):GND   I283 @BASEBOARD_FAB2_LIB.BASEBOARD_FAB2(SCH_1):PAGE41
  CE70    GND @BASEBOARD_FAB2_LIB.BASEBOARD_FAB2(SCH_1):GND   I283 @BASEBOARD_FAB2_LIB.BASEBOARD_FAB2(SCH_1):PAGE41
  CE82    GND @BASEBOARD_FAB2_LIB.BASEBOARD_FAB2(SCH_1):GND   I283 @BASEBOARD_FAB2_LIB.BASEBOARD_FAB2(SCH_1):PAGE41
   P53    GND @BASEBOARD_FAB2_LIB.BASEBOARD_FAB2(SCH_1):GND   I283 @BASEBOARD_FAB2_LIB.BASEBOARD_FAB2(SCH_1):PAGE41
   CF9    GND @BASEBOARD_FAB2_LIB.BASEBOARD_FAB2(SCH_1):GND   I283 @BASEBOARD_FAB2_LIB.BASEBOARD_FAB2(SCH_1):PAGE41
  CF63    GND @BASEBOARD_FAB2_LIB.BASEBOARD_FAB2(SCH_1):GND   I283 @BASEBOARD_FAB2_LIB.BASEBOARD_FAB2(SCH_1):PAGE41
  CF69    GND @BASEBOARD_FAB2_LIB.BASEBOARD_FAB2(SCH_1):GND   I283 @BASEBOARD_FAB2_LIB.BASEBOARD_FAB2(SCH_1):PAGE41
  CF71    GND @BASEBOARD_FAB2_LIB.BASEBOARD_FAB2(SCH_1):GND   I283 @BASEBOARD_FAB2_LIB.BASEBOARD_FAB2(SCH_1):PAGE41
  CF77    GND @BASEBOARD_FAB2_LIB.BASEBOARD_FAB2(SCH_1):GND   I283 @BASEBOARD_FAB2_LIB.BASEBOARD_FAB2(SCH_1):PAGE41
  CF83    GND @BASEBOARD_FAB2_LIB.BASEBOARD_FAB2(SCH_1):GND   I283 @BASEBOARD_FAB2_LIB.BASEBOARD_FAB2(SCH_1):PAGE41
   P51    GND @BASEBOARD_FAB2_LIB.BASEBOARD_FAB2(SCH_1):GND   I283 @BASEBOARD_FAB2_LIB.BASEBOARD_FAB2(SCH_1):PAGE41
  CG18    GND @BASEBOARD_FAB2_LIB.BASEBOARD_FAB2(SCH_1):GND   I283 @BASEBOARD_FAB2_LIB.BASEBOARD_FAB2(SCH_1):PAGE41
  CG22    GND @BASEBOARD_FAB2_LIB.BASEBOARD_FAB2(SCH_1):GND   I283 @BASEBOARD_FAB2_LIB.BASEBOARD_FAB2(SCH_1):PAGE41
  CG62    GND @BASEBOARD_FAB2_LIB.BASEBOARD_FAB2(SCH_1):GND   I283 @BASEBOARD_FAB2_LIB.BASEBOARD_FAB2(SCH_1):PAGE41
  CG68    GND @BASEBOARD_FAB2_LIB.BASEBOARD_FAB2(SCH_1):GND   I283 @BASEBOARD_FAB2_LIB.BASEBOARD_FAB2(SCH_1):PAGE41
  CG72    GND @BASEBOARD_FAB2_LIB.BASEBOARD_FAB2(SCH_1):GND   I283 @BASEBOARD_FAB2_LIB.BASEBOARD_FAB2(SCH_1):PAGE41
  CG80    GND @BASEBOARD_FAB2_LIB.BASEBOARD_FAB2(SCH_1):GND   I283 @BASEBOARD_FAB2_LIB.BASEBOARD_FAB2(SCH_1):PAGE41
   CH1    GND @BASEBOARD_FAB2_LIB.BASEBOARD_FAB2(SCH_1):GND   I283 @BASEBOARD_FAB2_LIB.BASEBOARD_FAB2(SCH_1):PAGE41
   CH3    GND @BASEBOARD_FAB2_LIB.BASEBOARD_FAB2(SCH_1):GND   I283 @BASEBOARD_FAB2_LIB.BASEBOARD_FAB2(SCH_1):PAGE41
  CH15    GND @BASEBOARD_FAB2_LIB.BASEBOARD_FAB2(SCH_1):GND   I283 @BASEBOARD_FAB2_LIB.BASEBOARD_FAB2(SCH_1):PAGE41
  CH19    GND @BASEBOARD_FAB2_LIB.BASEBOARD_FAB2(SCH_1):GND   I283 @BASEBOARD_FAB2_LIB.BASEBOARD_FAB2(SCH_1):PAGE41
  CH63    GND @BASEBOARD_FAB2_LIB.BASEBOARD_FAB2(SCH_1):GND   I283 @BASEBOARD_FAB2_LIB.BASEBOARD_FAB2(SCH_1):PAGE41
  CH67    GND @BASEBOARD_FAB2_LIB.BASEBOARD_FAB2(SCH_1):GND   I283 @BASEBOARD_FAB2_LIB.BASEBOARD_FAB2(SCH_1):PAGE41
  CH73    GND @BASEBOARD_FAB2_LIB.BASEBOARD_FAB2(SCH_1):GND   I283 @BASEBOARD_FAB2_LIB.BASEBOARD_FAB2(SCH_1):PAGE41
  CH79    GND @BASEBOARD_FAB2_LIB.BASEBOARD_FAB2(SCH_1):GND   I283 @BASEBOARD_FAB2_LIB.BASEBOARD_FAB2(SCH_1):PAGE41
  CH81    GND @BASEBOARD_FAB2_LIB.BASEBOARD_FAB2(SCH_1):GND   I283 @BASEBOARD_FAB2_LIB.BASEBOARD_FAB2(SCH_1):PAGE41
  CH83    GND @BASEBOARD_FAB2_LIB.BASEBOARD_FAB2(SCH_1):GND   I283 @BASEBOARD_FAB2_LIB.BASEBOARD_FAB2(SCH_1):PAGE41
   CJ2    GND @BASEBOARD_FAB2_LIB.BASEBOARD_FAB2(SCH_1):GND   I283 @BASEBOARD_FAB2_LIB.BASEBOARD_FAB2(SCH_1):PAGE41
   CJ6    GND @BASEBOARD_FAB2_LIB.BASEBOARD_FAB2(SCH_1):GND   I283 @BASEBOARD_FAB2_LIB.BASEBOARD_FAB2(SCH_1):PAGE41
   CJ8    GND @BASEBOARD_FAB2_LIB.BASEBOARD_FAB2(SCH_1):GND   I283 @BASEBOARD_FAB2_LIB.BASEBOARD_FAB2(SCH_1):PAGE41
  CJ10    GND @BASEBOARD_FAB2_LIB.BASEBOARD_FAB2(SCH_1):GND   I283 @BASEBOARD_FAB2_LIB.BASEBOARD_FAB2(SCH_1):PAGE41
  CJ12    GND @BASEBOARD_FAB2_LIB.BASEBOARD_FAB2(SCH_1):GND   I283 @BASEBOARD_FAB2_LIB.BASEBOARD_FAB2(SCH_1):PAGE41
   P49    GND @BASEBOARD_FAB2_LIB.BASEBOARD_FAB2(SCH_1):GND   I283 @BASEBOARD_FAB2_LIB.BASEBOARD_FAB2(SCH_1):PAGE41
   P47    GND @BASEBOARD_FAB2_LIB.BASEBOARD_FAB2(SCH_1):GND   I284 @BASEBOARD_FAB2_LIB.BASEBOARD_FAB2(SCH_1):PAGE41
  CJ62    GND @BASEBOARD_FAB2_LIB.BASEBOARD_FAB2(SCH_1):GND   I284 @BASEBOARD_FAB2_LIB.BASEBOARD_FAB2(SCH_1):PAGE41
  CJ74    GND @BASEBOARD_FAB2_LIB.BASEBOARD_FAB2(SCH_1):GND   I284 @BASEBOARD_FAB2_LIB.BASEBOARD_FAB2(SCH_1):PAGE41
  CJ76    GND @BASEBOARD_FAB2_LIB.BASEBOARD_FAB2(SCH_1):GND   I284 @BASEBOARD_FAB2_LIB.BASEBOARD_FAB2(SCH_1):PAGE41
  CJ78    GND @BASEBOARD_FAB2_LIB.BASEBOARD_FAB2(SCH_1):GND   I284 @BASEBOARD_FAB2_LIB.BASEBOARD_FAB2(SCH_1):PAGE41
  CJ82    GND @BASEBOARD_FAB2_LIB.BASEBOARD_FAB2(SCH_1):GND   I284 @BASEBOARD_FAB2_LIB.BASEBOARD_FAB2(SCH_1):PAGE41
  CJ84    GND @BASEBOARD_FAB2_LIB.BASEBOARD_FAB2(SCH_1):GND   I284 @BASEBOARD_FAB2_LIB.BASEBOARD_FAB2(SCH_1):PAGE41
  CJ86    GND @BASEBOARD_FAB2_LIB.BASEBOARD_FAB2(SCH_1):GND   I284 @BASEBOARD_FAB2_LIB.BASEBOARD_FAB2(SCH_1):PAGE41
  CK11    GND @BASEBOARD_FAB2_LIB.BASEBOARD_FAB2(SCH_1):GND   I284 @BASEBOARD_FAB2_LIB.BASEBOARD_FAB2(SCH_1):PAGE41
  CK15    GND @BASEBOARD_FAB2_LIB.BASEBOARD_FAB2(SCH_1):GND   I284 @BASEBOARD_FAB2_LIB.BASEBOARD_FAB2(SCH_1):PAGE41
  CK21    GND @BASEBOARD_FAB2_LIB.BASEBOARD_FAB2(SCH_1):GND   I284 @BASEBOARD_FAB2_LIB.BASEBOARD_FAB2(SCH_1):PAGE41
  CK27    GND @BASEBOARD_FAB2_LIB.BASEBOARD_FAB2(SCH_1):GND   I284 @BASEBOARD_FAB2_LIB.BASEBOARD_FAB2(SCH_1):PAGE41
  CK63    GND @BASEBOARD_FAB2_LIB.BASEBOARD_FAB2(SCH_1):GND   I284 @BASEBOARD_FAB2_LIB.BASEBOARD_FAB2(SCH_1):PAGE41
  CK65    GND @BASEBOARD_FAB2_LIB.BASEBOARD_FAB2(SCH_1):GND   I284 @BASEBOARD_FAB2_LIB.BASEBOARD_FAB2(SCH_1):PAGE41
  CK67    GND @BASEBOARD_FAB2_LIB.BASEBOARD_FAB2(SCH_1):GND   I284 @BASEBOARD_FAB2_LIB.BASEBOARD_FAB2(SCH_1):PAGE41
  CK69    GND @BASEBOARD_FAB2_LIB.BASEBOARD_FAB2(SCH_1):GND   I284 @BASEBOARD_FAB2_LIB.BASEBOARD_FAB2(SCH_1):PAGE41
  CK71    GND @BASEBOARD_FAB2_LIB.BASEBOARD_FAB2(SCH_1):GND   I284 @BASEBOARD_FAB2_LIB.BASEBOARD_FAB2(SCH_1):PAGE41
  CK73    GND @BASEBOARD_FAB2_LIB.BASEBOARD_FAB2(SCH_1):GND   I284 @BASEBOARD_FAB2_LIB.BASEBOARD_FAB2(SCH_1):PAGE41
  CK75    GND @BASEBOARD_FAB2_LIB.BASEBOARD_FAB2(SCH_1):GND   I284 @BASEBOARD_FAB2_LIB.BASEBOARD_FAB2(SCH_1):PAGE41
  CK83    GND @BASEBOARD_FAB2_LIB.BASEBOARD_FAB2(SCH_1):GND   I284 @BASEBOARD_FAB2_LIB.BASEBOARD_FAB2(SCH_1):PAGE41
  CK85    GND @BASEBOARD_FAB2_LIB.BASEBOARD_FAB2(SCH_1):GND   I284 @BASEBOARD_FAB2_LIB.BASEBOARD_FAB2(SCH_1):PAGE41
   CL8    GND @BASEBOARD_FAB2_LIB.BASEBOARD_FAB2(SCH_1):GND   I284 @BASEBOARD_FAB2_LIB.BASEBOARD_FAB2(SCH_1):PAGE41
  CL14    GND @BASEBOARD_FAB2_LIB.BASEBOARD_FAB2(SCH_1):GND   I284 @BASEBOARD_FAB2_LIB.BASEBOARD_FAB2(SCH_1):PAGE41
  CL18    GND @BASEBOARD_FAB2_LIB.BASEBOARD_FAB2(SCH_1):GND   I284 @BASEBOARD_FAB2_LIB.BASEBOARD_FAB2(SCH_1):PAGE41
   P45    GND @BASEBOARD_FAB2_LIB.BASEBOARD_FAB2(SCH_1):GND   I284 @BASEBOARD_FAB2_LIB.BASEBOARD_FAB2(SCH_1):PAGE41
   H63    GND @BASEBOARD_FAB2_LIB.BASEBOARD_FAB2(SCH_1):GND   I284 @BASEBOARD_FAB2_LIB.BASEBOARD_FAB2(SCH_1):PAGE41
  CL62    GND @BASEBOARD_FAB2_LIB.BASEBOARD_FAB2(SCH_1):GND   I284 @BASEBOARD_FAB2_LIB.BASEBOARD_FAB2(SCH_1):PAGE41
  CL64    GND @BASEBOARD_FAB2_LIB.BASEBOARD_FAB2(SCH_1):GND   I284 @BASEBOARD_FAB2_LIB.BASEBOARD_FAB2(SCH_1):PAGE41
  CL66    GND @BASEBOARD_FAB2_LIB.BASEBOARD_FAB2(SCH_1):GND   I284 @BASEBOARD_FAB2_LIB.BASEBOARD_FAB2(SCH_1):PAGE41
  CL74    GND @BASEBOARD_FAB2_LIB.BASEBOARD_FAB2(SCH_1):GND   I284 @BASEBOARD_FAB2_LIB.BASEBOARD_FAB2(SCH_1):PAGE41
  CL76    GND @BASEBOARD_FAB2_LIB.BASEBOARD_FAB2(SCH_1):GND   I284 @BASEBOARD_FAB2_LIB.BASEBOARD_FAB2(SCH_1):PAGE41
  CL78    GND @BASEBOARD_FAB2_LIB.BASEBOARD_FAB2(SCH_1):GND   I284 @BASEBOARD_FAB2_LIB.BASEBOARD_FAB2(SCH_1):PAGE41
  CL80    GND @BASEBOARD_FAB2_LIB.BASEBOARD_FAB2(SCH_1):GND   I284 @BASEBOARD_FAB2_LIB.BASEBOARD_FAB2(SCH_1):PAGE41
  CM19    GND @BASEBOARD_FAB2_LIB.BASEBOARD_FAB2(SCH_1):GND   I284 @BASEBOARD_FAB2_LIB.BASEBOARD_FAB2(SCH_1):PAGE41
  CM29    GND @BASEBOARD_FAB2_LIB.BASEBOARD_FAB2(SCH_1):GND   I284 @BASEBOARD_FAB2_LIB.BASEBOARD_FAB2(SCH_1):PAGE41
   CM5    GND @BASEBOARD_FAB2_LIB.BASEBOARD_FAB2(SCH_1):GND   I284 @BASEBOARD_FAB2_LIB.BASEBOARD_FAB2(SCH_1):PAGE41
  CM31    GND @BASEBOARD_FAB2_LIB.BASEBOARD_FAB2(SCH_1):GND   I284 @BASEBOARD_FAB2_LIB.BASEBOARD_FAB2(SCH_1):PAGE41
  CM61    GND @BASEBOARD_FAB2_LIB.BASEBOARD_FAB2(SCH_1):GND   I284 @BASEBOARD_FAB2_LIB.BASEBOARD_FAB2(SCH_1):PAGE41
  CM63    GND @BASEBOARD_FAB2_LIB.BASEBOARD_FAB2(SCH_1):GND   I284 @BASEBOARD_FAB2_LIB.BASEBOARD_FAB2(SCH_1):PAGE41
  CM67    GND @BASEBOARD_FAB2_LIB.BASEBOARD_FAB2(SCH_1):GND   I284 @BASEBOARD_FAB2_LIB.BASEBOARD_FAB2(SCH_1):PAGE41
  CM73    GND @BASEBOARD_FAB2_LIB.BASEBOARD_FAB2(SCH_1):GND   I284 @BASEBOARD_FAB2_LIB.BASEBOARD_FAB2(SCH_1):PAGE41
  CM77    GND @BASEBOARD_FAB2_LIB.BASEBOARD_FAB2(SCH_1):GND   I284 @BASEBOARD_FAB2_LIB.BASEBOARD_FAB2(SCH_1):PAGE41
  CM83    GND @BASEBOARD_FAB2_LIB.BASEBOARD_FAB2(SCH_1):GND   I284 @BASEBOARD_FAB2_LIB.BASEBOARD_FAB2(SCH_1):PAGE41
  CM85    GND @BASEBOARD_FAB2_LIB.BASEBOARD_FAB2(SCH_1):GND   I284 @BASEBOARD_FAB2_LIB.BASEBOARD_FAB2(SCH_1):PAGE41
   CN2    GND @BASEBOARD_FAB2_LIB.BASEBOARD_FAB2(SCH_1):GND   I284 @BASEBOARD_FAB2_LIB.BASEBOARD_FAB2(SCH_1):PAGE41
  CN12    GND @BASEBOARD_FAB2_LIB.BASEBOARD_FAB2(SCH_1):GND   I284 @BASEBOARD_FAB2_LIB.BASEBOARD_FAB2(SCH_1):PAGE41
   H61    GND @BASEBOARD_FAB2_LIB.BASEBOARD_FAB2(SCH_1):GND   I284 @BASEBOARD_FAB2_LIB.BASEBOARD_FAB2(SCH_1):PAGE41
  CN26    GND @BASEBOARD_FAB2_LIB.BASEBOARD_FAB2(SCH_1):GND   I284 @BASEBOARD_FAB2_LIB.BASEBOARD_FAB2(SCH_1):PAGE41
  CN32    GND @BASEBOARD_FAB2_LIB.BASEBOARD_FAB2(SCH_1):GND   I284 @BASEBOARD_FAB2_LIB.BASEBOARD_FAB2(SCH_1):PAGE41
  CN60    GND @BASEBOARD_FAB2_LIB.BASEBOARD_FAB2(SCH_1):GND   I284 @BASEBOARD_FAB2_LIB.BASEBOARD_FAB2(SCH_1):PAGE41
  CN62    GND @BASEBOARD_FAB2_LIB.BASEBOARD_FAB2(SCH_1):GND   I284 @BASEBOARD_FAB2_LIB.BASEBOARD_FAB2(SCH_1):PAGE41
  CN68    GND @BASEBOARD_FAB2_LIB.BASEBOARD_FAB2(SCH_1):GND   I284 @BASEBOARD_FAB2_LIB.BASEBOARD_FAB2(SCH_1):PAGE41
  CN78    GND @BASEBOARD_FAB2_LIB.BASEBOARD_FAB2(SCH_1):GND   I284 @BASEBOARD_FAB2_LIB.BASEBOARD_FAB2(SCH_1):PAGE41
   CP1    GND @BASEBOARD_FAB2_LIB.BASEBOARD_FAB2(SCH_1):GND   I284 @BASEBOARD_FAB2_LIB.BASEBOARD_FAB2(SCH_1):PAGE41
   H59    GND @BASEBOARD_FAB2_LIB.BASEBOARD_FAB2(SCH_1):GND   I284 @BASEBOARD_FAB2_LIB.BASEBOARD_FAB2(SCH_1):PAGE41
  CP25    GND @BASEBOARD_FAB2_LIB.BASEBOARD_FAB2(SCH_1):GND   I284 @BASEBOARD_FAB2_LIB.BASEBOARD_FAB2(SCH_1):PAGE41
  CP59    GND @BASEBOARD_FAB2_LIB.BASEBOARD_FAB2(SCH_1):GND   I284 @BASEBOARD_FAB2_LIB.BASEBOARD_FAB2(SCH_1):PAGE41
  CP69    GND @BASEBOARD_FAB2_LIB.BASEBOARD_FAB2(SCH_1):GND   I284 @BASEBOARD_FAB2_LIB.BASEBOARD_FAB2(SCH_1):PAGE41
  CP73    GND @BASEBOARD_FAB2_LIB.BASEBOARD_FAB2(SCH_1):GND   I284 @BASEBOARD_FAB2_LIB.BASEBOARD_FAB2(SCH_1):PAGE41
  CP75    GND @BASEBOARD_FAB2_LIB.BASEBOARD_FAB2(SCH_1):GND   I284 @BASEBOARD_FAB2_LIB.BASEBOARD_FAB2(SCH_1):PAGE41
  CP81    GND @BASEBOARD_FAB2_LIB.BASEBOARD_FAB2(SCH_1):GND   I284 @BASEBOARD_FAB2_LIB.BASEBOARD_FAB2(SCH_1):PAGE41
  CP83    GND @BASEBOARD_FAB2_LIB.BASEBOARD_FAB2(SCH_1):GND   I284 @BASEBOARD_FAB2_LIB.BASEBOARD_FAB2(SCH_1):PAGE41
   CR6    GND @BASEBOARD_FAB2_LIB.BASEBOARD_FAB2(SCH_1):GND   I284 @BASEBOARD_FAB2_LIB.BASEBOARD_FAB2(SCH_1):PAGE41
  CR10    GND @BASEBOARD_FAB2_LIB.BASEBOARD_FAB2(SCH_1):GND   I284 @BASEBOARD_FAB2_LIB.BASEBOARD_FAB2(SCH_1):PAGE41
  CR22    GND @BASEBOARD_FAB2_LIB.BASEBOARD_FAB2(SCH_1):GND   I284 @BASEBOARD_FAB2_LIB.BASEBOARD_FAB2(SCH_1):PAGE41
  CR24    GND @BASEBOARD_FAB2_LIB.BASEBOARD_FAB2(SCH_1):GND   I284 @BASEBOARD_FAB2_LIB.BASEBOARD_FAB2(SCH_1):PAGE41
  CR32    GND @BASEBOARD_FAB2_LIB.BASEBOARD_FAB2(SCH_1):GND   I284 @BASEBOARD_FAB2_LIB.BASEBOARD_FAB2(SCH_1):PAGE41
  CR58    GND @BASEBOARD_FAB2_LIB.BASEBOARD_FAB2(SCH_1):GND   I284 @BASEBOARD_FAB2_LIB.BASEBOARD_FAB2(SCH_1):PAGE41
  CR62    GND @BASEBOARD_FAB2_LIB.BASEBOARD_FAB2(SCH_1):GND   I284 @BASEBOARD_FAB2_LIB.BASEBOARD_FAB2(SCH_1):PAGE41
  CR64    GND @BASEBOARD_FAB2_LIB.BASEBOARD_FAB2(SCH_1):GND   I284 @BASEBOARD_FAB2_LIB.BASEBOARD_FAB2(SCH_1):PAGE41
  CR66    GND @BASEBOARD_FAB2_LIB.BASEBOARD_FAB2(SCH_1):GND   I284 @BASEBOARD_FAB2_LIB.BASEBOARD_FAB2(SCH_1):PAGE41
  CR68    GND @BASEBOARD_FAB2_LIB.BASEBOARD_FAB2(SCH_1):GND   I284 @BASEBOARD_FAB2_LIB.BASEBOARD_FAB2(SCH_1):PAGE41
  CR78    GND @BASEBOARD_FAB2_LIB.BASEBOARD_FAB2(SCH_1):GND   I284 @BASEBOARD_FAB2_LIB.BASEBOARD_FAB2(SCH_1):PAGE41
  CR86    GND @BASEBOARD_FAB2_LIB.BASEBOARD_FAB2(SCH_1):GND   I284 @BASEBOARD_FAB2_LIB.BASEBOARD_FAB2(SCH_1):PAGE41
   H57    GND @BASEBOARD_FAB2_LIB.BASEBOARD_FAB2(SCH_1):GND   I284 @BASEBOARD_FAB2_LIB.BASEBOARD_FAB2(SCH_1):PAGE41
  CT13    GND @BASEBOARD_FAB2_LIB.BASEBOARD_FAB2(SCH_1):GND   I284 @BASEBOARD_FAB2_LIB.BASEBOARD_FAB2(SCH_1):PAGE41
  CT19    GND @BASEBOARD_FAB2_LIB.BASEBOARD_FAB2(SCH_1):GND   I284 @BASEBOARD_FAB2_LIB.BASEBOARD_FAB2(SCH_1):PAGE41
  CT27    GND @BASEBOARD_FAB2_LIB.BASEBOARD_FAB2(SCH_1):GND   I284 @BASEBOARD_FAB2_LIB.BASEBOARD_FAB2(SCH_1):PAGE41
  CT29    GND @BASEBOARD_FAB2_LIB.BASEBOARD_FAB2(SCH_1):GND   I284 @BASEBOARD_FAB2_LIB.BASEBOARD_FAB2(SCH_1):PAGE41
  CT33    GND @BASEBOARD_FAB2_LIB.BASEBOARD_FAB2(SCH_1):GND   I284 @BASEBOARD_FAB2_LIB.BASEBOARD_FAB2(SCH_1):PAGE41
  CT35    GND @BASEBOARD_FAB2_LIB.BASEBOARD_FAB2(SCH_1):GND   I284 @BASEBOARD_FAB2_LIB.BASEBOARD_FAB2(SCH_1):PAGE41
  CT57    GND @BASEBOARD_FAB2_LIB.BASEBOARD_FAB2(SCH_1):GND   I284 @BASEBOARD_FAB2_LIB.BASEBOARD_FAB2(SCH_1):PAGE41
  CT73    GND @BASEBOARD_FAB2_LIB.BASEBOARD_FAB2(SCH_1):GND   I284 @BASEBOARD_FAB2_LIB.BASEBOARD_FAB2(SCH_1):PAGE41
  CT79    GND @BASEBOARD_FAB2_LIB.BASEBOARD_FAB2(SCH_1):GND   I284 @BASEBOARD_FAB2_LIB.BASEBOARD_FAB2(SCH_1):PAGE41
  CT83    GND @BASEBOARD_FAB2_LIB.BASEBOARD_FAB2(SCH_1):GND   I284 @BASEBOARD_FAB2_LIB.BASEBOARD_FAB2(SCH_1):PAGE41
  CT85    GND @BASEBOARD_FAB2_LIB.BASEBOARD_FAB2(SCH_1):GND   I284 @BASEBOARD_FAB2_LIB.BASEBOARD_FAB2(SCH_1):PAGE41
   CU4    GND @BASEBOARD_FAB2_LIB.BASEBOARD_FAB2(SCH_1):GND   I284 @BASEBOARD_FAB2_LIB.BASEBOARD_FAB2(SCH_1):PAGE41
  CU22    GND @BASEBOARD_FAB2_LIB.BASEBOARD_FAB2(SCH_1):GND   I284 @BASEBOARD_FAB2_LIB.BASEBOARD_FAB2(SCH_1):PAGE41
  CU28    GND @BASEBOARD_FAB2_LIB.BASEBOARD_FAB2(SCH_1):GND   I284 @BASEBOARD_FAB2_LIB.BASEBOARD_FAB2(SCH_1):PAGE41
  CU30    GND @BASEBOARD_FAB2_LIB.BASEBOARD_FAB2(SCH_1):GND   I284 @BASEBOARD_FAB2_LIB.BASEBOARD_FAB2(SCH_1):PAGE41
  CU34    GND @BASEBOARD_FAB2_LIB.BASEBOARD_FAB2(SCH_1):GND   I284 @BASEBOARD_FAB2_LIB.BASEBOARD_FAB2(SCH_1):PAGE41
  CU36    GND @BASEBOARD_FAB2_LIB.BASEBOARD_FAB2(SCH_1):GND   I284 @BASEBOARD_FAB2_LIB.BASEBOARD_FAB2(SCH_1):PAGE41
  CU56    GND @BASEBOARD_FAB2_LIB.BASEBOARD_FAB2(SCH_1):GND   I284 @BASEBOARD_FAB2_LIB.BASEBOARD_FAB2(SCH_1):PAGE41
  CU62    GND @BASEBOARD_FAB2_LIB.BASEBOARD_FAB2(SCH_1):GND   I284 @BASEBOARD_FAB2_LIB.BASEBOARD_FAB2(SCH_1):PAGE41
  CU68    GND @BASEBOARD_FAB2_LIB.BASEBOARD_FAB2(SCH_1):GND   I284 @BASEBOARD_FAB2_LIB.BASEBOARD_FAB2(SCH_1):PAGE41
  CU76    GND @BASEBOARD_FAB2_LIB.BASEBOARD_FAB2(SCH_1):GND   I284 @BASEBOARD_FAB2_LIB.BASEBOARD_FAB2(SCH_1):PAGE41
  CU78    GND @BASEBOARD_FAB2_LIB.BASEBOARD_FAB2(SCH_1):GND   I284 @BASEBOARD_FAB2_LIB.BASEBOARD_FAB2(SCH_1):PAGE41
  CU80    GND @BASEBOARD_FAB2_LIB.BASEBOARD_FAB2(SCH_1):GND   I284 @BASEBOARD_FAB2_LIB.BASEBOARD_FAB2(SCH_1):PAGE41
  CU82    GND @BASEBOARD_FAB2_LIB.BASEBOARD_FAB2(SCH_1):GND   I284 @BASEBOARD_FAB2_LIB.BASEBOARD_FAB2(SCH_1):PAGE41
  CU86    GND @BASEBOARD_FAB2_LIB.BASEBOARD_FAB2(SCH_1):GND   I284 @BASEBOARD_FAB2_LIB.BASEBOARD_FAB2(SCH_1):PAGE41
   CV1    GND @BASEBOARD_FAB2_LIB.BASEBOARD_FAB2(SCH_1):GND   I284 @BASEBOARD_FAB2_LIB.BASEBOARD_FAB2(SCH_1):PAGE41
   H55    GND @BASEBOARD_FAB2_LIB.BASEBOARD_FAB2(SCH_1):GND   I284 @BASEBOARD_FAB2_LIB.BASEBOARD_FAB2(SCH_1):PAGE41
  CV17    GND @BASEBOARD_FAB2_LIB.BASEBOARD_FAB2(SCH_1):GND   I284 @BASEBOARD_FAB2_LIB.BASEBOARD_FAB2(SCH_1):PAGE41
  CV25    GND @BASEBOARD_FAB2_LIB.BASEBOARD_FAB2(SCH_1):GND   I284 @BASEBOARD_FAB2_LIB.BASEBOARD_FAB2(SCH_1):PAGE41
  CV27    GND @BASEBOARD_FAB2_LIB.BASEBOARD_FAB2(SCH_1):GND   I284 @BASEBOARD_FAB2_LIB.BASEBOARD_FAB2(SCH_1):PAGE41
  CV31    GND @BASEBOARD_FAB2_LIB.BASEBOARD_FAB2(SCH_1):GND   I284 @BASEBOARD_FAB2_LIB.BASEBOARD_FAB2(SCH_1):PAGE41
  CV33    GND @BASEBOARD_FAB2_LIB.BASEBOARD_FAB2(SCH_1):GND   I284 @BASEBOARD_FAB2_LIB.BASEBOARD_FAB2(SCH_1):PAGE41
  CV37    GND @BASEBOARD_FAB2_LIB.BASEBOARD_FAB2(SCH_1):GND   I284 @BASEBOARD_FAB2_LIB.BASEBOARD_FAB2(SCH_1):PAGE41
  CV39    GND @BASEBOARD_FAB2_LIB.BASEBOARD_FAB2(SCH_1):GND   I284 @BASEBOARD_FAB2_LIB.BASEBOARD_FAB2(SCH_1):PAGE41
  CV41    GND @BASEBOARD_FAB2_LIB.BASEBOARD_FAB2(SCH_1):GND   I284 @BASEBOARD_FAB2_LIB.BASEBOARD_FAB2(SCH_1):PAGE41
  CV53    GND @BASEBOARD_FAB2_LIB.BASEBOARD_FAB2(SCH_1):GND   I284 @BASEBOARD_FAB2_LIB.BASEBOARD_FAB2(SCH_1):PAGE41
  CV55    GND @BASEBOARD_FAB2_LIB.BASEBOARD_FAB2(SCH_1):GND   I284 @BASEBOARD_FAB2_LIB.BASEBOARD_FAB2(SCH_1):PAGE41
  CV63    GND @BASEBOARD_FAB2_LIB.BASEBOARD_FAB2(SCH_1):GND   I284 @BASEBOARD_FAB2_LIB.BASEBOARD_FAB2(SCH_1):PAGE41
  CV67    GND @BASEBOARD_FAB2_LIB.BASEBOARD_FAB2(SCH_1):GND   I284 @BASEBOARD_FAB2_LIB.BASEBOARD_FAB2(SCH_1):PAGE41
  CV73    GND @BASEBOARD_FAB2_LIB.BASEBOARD_FAB2(SCH_1):GND   I284 @BASEBOARD_FAB2_LIB.BASEBOARD_FAB2(SCH_1):PAGE41
  CV79    GND @BASEBOARD_FAB2_LIB.BASEBOARD_FAB2(SCH_1):GND   I284 @BASEBOARD_FAB2_LIB.BASEBOARD_FAB2(SCH_1):PAGE41
  CV81    GND @BASEBOARD_FAB2_LIB.BASEBOARD_FAB2(SCH_1):GND   I284 @BASEBOARD_FAB2_LIB.BASEBOARD_FAB2(SCH_1):PAGE41
  CV83    GND @BASEBOARD_FAB2_LIB.BASEBOARD_FAB2(SCH_1):GND   I284 @BASEBOARD_FAB2_LIB.BASEBOARD_FAB2(SCH_1):PAGE41
  CW12    GND @BASEBOARD_FAB2_LIB.BASEBOARD_FAB2(SCH_1):GND   I284 @BASEBOARD_FAB2_LIB.BASEBOARD_FAB2(SCH_1):PAGE41
  CW26    GND @BASEBOARD_FAB2_LIB.BASEBOARD_FAB2(SCH_1):GND   I284 @BASEBOARD_FAB2_LIB.BASEBOARD_FAB2(SCH_1):PAGE41
  CW32    GND @BASEBOARD_FAB2_LIB.BASEBOARD_FAB2(SCH_1):GND   I284 @BASEBOARD_FAB2_LIB.BASEBOARD_FAB2(SCH_1):PAGE41
  CW38    GND @BASEBOARD_FAB2_LIB.BASEBOARD_FAB2(SCH_1):GND   I284 @BASEBOARD_FAB2_LIB.BASEBOARD_FAB2(SCH_1):PAGE41
  CW40    GND @BASEBOARD_FAB2_LIB.BASEBOARD_FAB2(SCH_1):GND   I284 @BASEBOARD_FAB2_LIB.BASEBOARD_FAB2(SCH_1):PAGE41
  CW42    GND @BASEBOARD_FAB2_LIB.BASEBOARD_FAB2(SCH_1):GND   I284 @BASEBOARD_FAB2_LIB.BASEBOARD_FAB2(SCH_1):PAGE41
  CW52    GND @BASEBOARD_FAB2_LIB.BASEBOARD_FAB2(SCH_1):GND   I284 @BASEBOARD_FAB2_LIB.BASEBOARD_FAB2(SCH_1):PAGE41
  CW54    GND @BASEBOARD_FAB2_LIB.BASEBOARD_FAB2(SCH_1):GND   I284 @BASEBOARD_FAB2_LIB.BASEBOARD_FAB2(SCH_1):PAGE41
  CW64    GND @BASEBOARD_FAB2_LIB.BASEBOARD_FAB2(SCH_1):GND   I284 @BASEBOARD_FAB2_LIB.BASEBOARD_FAB2(SCH_1):PAGE41
  CW66    GND @BASEBOARD_FAB2_LIB.BASEBOARD_FAB2(SCH_1):GND   I284 @BASEBOARD_FAB2_LIB.BASEBOARD_FAB2(SCH_1):PAGE41
  CW68    GND @BASEBOARD_FAB2_LIB.BASEBOARD_FAB2(SCH_1):GND   I284 @BASEBOARD_FAB2_LIB.BASEBOARD_FAB2(SCH_1):PAGE41
  CW74    GND @BASEBOARD_FAB2_LIB.BASEBOARD_FAB2(SCH_1):GND   I284 @BASEBOARD_FAB2_LIB.BASEBOARD_FAB2(SCH_1):PAGE41
  CW78    GND @BASEBOARD_FAB2_LIB.BASEBOARD_FAB2(SCH_1):GND   I284 @BASEBOARD_FAB2_LIB.BASEBOARD_FAB2(SCH_1):PAGE41
  CW82    GND @BASEBOARD_FAB2_LIB.BASEBOARD_FAB2(SCH_1):GND   I284 @BASEBOARD_FAB2_LIB.BASEBOARD_FAB2(SCH_1):PAGE41
   CY1    GND @BASEBOARD_FAB2_LIB.BASEBOARD_FAB2(SCH_1):GND   I284 @BASEBOARD_FAB2_LIB.BASEBOARD_FAB2(SCH_1):PAGE41
   CY9    GND @BASEBOARD_FAB2_LIB.BASEBOARD_FAB2(SCH_1):GND   I284 @BASEBOARD_FAB2_LIB.BASEBOARD_FAB2(SCH_1):PAGE41
  CY13    GND @BASEBOARD_FAB2_LIB.BASEBOARD_FAB2(SCH_1):GND   I284 @BASEBOARD_FAB2_LIB.BASEBOARD_FAB2(SCH_1):PAGE41
  CY15    GND @BASEBOARD_FAB2_LIB.BASEBOARD_FAB2(SCH_1):GND   I284 @BASEBOARD_FAB2_LIB.BASEBOARD_FAB2(SCH_1):PAGE41
  CY21    GND @BASEBOARD_FAB2_LIB.BASEBOARD_FAB2(SCH_1):GND   I284 @BASEBOARD_FAB2_LIB.BASEBOARD_FAB2(SCH_1):PAGE41
  CY41    GND @BASEBOARD_FAB2_LIB.BASEBOARD_FAB2(SCH_1):GND   I284 @BASEBOARD_FAB2_LIB.BASEBOARD_FAB2(SCH_1):PAGE41
  CY45    GND @BASEBOARD_FAB2_LIB.BASEBOARD_FAB2(SCH_1):GND   I284 @BASEBOARD_FAB2_LIB.BASEBOARD_FAB2(SCH_1):PAGE41
  CY51    GND @BASEBOARD_FAB2_LIB.BASEBOARD_FAB2(SCH_1):GND   I284 @BASEBOARD_FAB2_LIB.BASEBOARD_FAB2(SCH_1):PAGE41
  CY59    GND @BASEBOARD_FAB2_LIB.BASEBOARD_FAB2(SCH_1):GND   I284 @BASEBOARD_FAB2_LIB.BASEBOARD_FAB2(SCH_1):PAGE41
  CY61    GND @BASEBOARD_FAB2_LIB.BASEBOARD_FAB2(SCH_1):GND   I284 @BASEBOARD_FAB2_LIB.BASEBOARD_FAB2(SCH_1):PAGE41
  CY65    GND @BASEBOARD_FAB2_LIB.BASEBOARD_FAB2(SCH_1):GND   I284 @BASEBOARD_FAB2_LIB.BASEBOARD_FAB2(SCH_1):PAGE41
  CY69    GND @BASEBOARD_FAB2_LIB.BASEBOARD_FAB2(SCH_1):GND   I284 @BASEBOARD_FAB2_LIB.BASEBOARD_FAB2(SCH_1):PAGE41
  CY75    GND @BASEBOARD_FAB2_LIB.BASEBOARD_FAB2(SCH_1):GND   I284 @BASEBOARD_FAB2_LIB.BASEBOARD_FAB2(SCH_1):PAGE41
  CY77    GND @BASEBOARD_FAB2_LIB.BASEBOARD_FAB2(SCH_1):GND   I284 @BASEBOARD_FAB2_LIB.BASEBOARD_FAB2(SCH_1):PAGE41
  CY83    GND @BASEBOARD_FAB2_LIB.BASEBOARD_FAB2(SCH_1):GND   I284 @BASEBOARD_FAB2_LIB.BASEBOARD_FAB2(SCH_1):PAGE41
  CY85    GND @BASEBOARD_FAB2_LIB.BASEBOARD_FAB2(SCH_1):GND   I284 @BASEBOARD_FAB2_LIB.BASEBOARD_FAB2(SCH_1):PAGE41
   DA6    GND @BASEBOARD_FAB2_LIB.BASEBOARD_FAB2(SCH_1):GND   I284 @BASEBOARD_FAB2_LIB.BASEBOARD_FAB2(SCH_1):PAGE41
   H53    GND @BASEBOARD_FAB2_LIB.BASEBOARD_FAB2(SCH_1):GND   I284 @BASEBOARD_FAB2_LIB.BASEBOARD_FAB2(SCH_1):PAGE41
  DA18    GND @BASEBOARD_FAB2_LIB.BASEBOARD_FAB2(SCH_1):GND   I284 @BASEBOARD_FAB2_LIB.BASEBOARD_FAB2(SCH_1):PAGE41
  DA26    GND @BASEBOARD_FAB2_LIB.BASEBOARD_FAB2(SCH_1):GND   I284 @BASEBOARD_FAB2_LIB.BASEBOARD_FAB2(SCH_1):PAGE41
  DA28    GND @BASEBOARD_FAB2_LIB.BASEBOARD_FAB2(SCH_1):GND   I284 @BASEBOARD_FAB2_LIB.BASEBOARD_FAB2(SCH_1):PAGE41
  DA30    GND @BASEBOARD_FAB2_LIB.BASEBOARD_FAB2(SCH_1):GND   I284 @BASEBOARD_FAB2_LIB.BASEBOARD_FAB2(SCH_1):PAGE41
  DA32    GND @BASEBOARD_FAB2_LIB.BASEBOARD_FAB2(SCH_1):GND   I284 @BASEBOARD_FAB2_LIB.BASEBOARD_FAB2(SCH_1):PAGE41
  DA34    GND @BASEBOARD_FAB2_LIB.BASEBOARD_FAB2(SCH_1):GND   I284 @BASEBOARD_FAB2_LIB.BASEBOARD_FAB2(SCH_1):PAGE41
  DA36    GND @BASEBOARD_FAB2_LIB.BASEBOARD_FAB2(SCH_1):GND   I284 @BASEBOARD_FAB2_LIB.BASEBOARD_FAB2(SCH_1):PAGE41
  DA38    GND @BASEBOARD_FAB2_LIB.BASEBOARD_FAB2(SCH_1):GND   I284 @BASEBOARD_FAB2_LIB.BASEBOARD_FAB2(SCH_1):PAGE41
  DA44    GND @BASEBOARD_FAB2_LIB.BASEBOARD_FAB2(SCH_1):GND   I284 @BASEBOARD_FAB2_LIB.BASEBOARD_FAB2(SCH_1):PAGE41
  DA46    GND @BASEBOARD_FAB2_LIB.BASEBOARD_FAB2(SCH_1):GND   I284 @BASEBOARD_FAB2_LIB.BASEBOARD_FAB2(SCH_1):PAGE41
  DA48    GND @BASEBOARD_FAB2_LIB.BASEBOARD_FAB2(SCH_1):GND   I285 @BASEBOARD_FAB2_LIB.BASEBOARD_FAB2(SCH_1):PAGE41
  DA50    GND @BASEBOARD_FAB2_LIB.BASEBOARD_FAB2(SCH_1):GND   I285 @BASEBOARD_FAB2_LIB.BASEBOARD_FAB2(SCH_1):PAGE41
  DA64    GND @BASEBOARD_FAB2_LIB.BASEBOARD_FAB2(SCH_1):GND   I285 @BASEBOARD_FAB2_LIB.BASEBOARD_FAB2(SCH_1):PAGE41
  DA70    GND @BASEBOARD_FAB2_LIB.BASEBOARD_FAB2(SCH_1):GND   I285 @BASEBOARD_FAB2_LIB.BASEBOARD_FAB2(SCH_1):PAGE41
  DA74    GND @BASEBOARD_FAB2_LIB.BASEBOARD_FAB2(SCH_1):GND   I285 @BASEBOARD_FAB2_LIB.BASEBOARD_FAB2(SCH_1):PAGE41
  DA76    GND @BASEBOARD_FAB2_LIB.BASEBOARD_FAB2(SCH_1):GND   I285 @BASEBOARD_FAB2_LIB.BASEBOARD_FAB2(SCH_1):PAGE41
  DA78    GND @BASEBOARD_FAB2_LIB.BASEBOARD_FAB2(SCH_1):GND   I285 @BASEBOARD_FAB2_LIB.BASEBOARD_FAB2(SCH_1):PAGE41
  DA80    GND @BASEBOARD_FAB2_LIB.BASEBOARD_FAB2(SCH_1):GND   I285 @BASEBOARD_FAB2_LIB.BASEBOARD_FAB2(SCH_1):PAGE41
   DB3    GND @BASEBOARD_FAB2_LIB.BASEBOARD_FAB2(SCH_1):GND   I285 @BASEBOARD_FAB2_LIB.BASEBOARD_FAB2(SCH_1):PAGE41
  DB13    GND @BASEBOARD_FAB2_LIB.BASEBOARD_FAB2(SCH_1):GND   I285 @BASEBOARD_FAB2_LIB.BASEBOARD_FAB2(SCH_1):PAGE41
  DB17    GND @BASEBOARD_FAB2_LIB.BASEBOARD_FAB2(SCH_1):GND   I285 @BASEBOARD_FAB2_LIB.BASEBOARD_FAB2(SCH_1):PAGE41
  DB23    GND @BASEBOARD_FAB2_LIB.BASEBOARD_FAB2(SCH_1):GND   I285 @BASEBOARD_FAB2_LIB.BASEBOARD_FAB2(SCH_1):PAGE41
  DB25    GND @BASEBOARD_FAB2_LIB.BASEBOARD_FAB2(SCH_1):GND   I285 @BASEBOARD_FAB2_LIB.BASEBOARD_FAB2(SCH_1):PAGE41
  DB39    GND @BASEBOARD_FAB2_LIB.BASEBOARD_FAB2(SCH_1):GND   I285 @BASEBOARD_FAB2_LIB.BASEBOARD_FAB2(SCH_1):PAGE41
  DB41    GND @BASEBOARD_FAB2_LIB.BASEBOARD_FAB2(SCH_1):GND   I285 @BASEBOARD_FAB2_LIB.BASEBOARD_FAB2(SCH_1):PAGE41
  DB47    GND @BASEBOARD_FAB2_LIB.BASEBOARD_FAB2(SCH_1):GND   I285 @BASEBOARD_FAB2_LIB.BASEBOARD_FAB2(SCH_1):PAGE41
  DB49    GND @BASEBOARD_FAB2_LIB.BASEBOARD_FAB2(SCH_1):GND   I285 @BASEBOARD_FAB2_LIB.BASEBOARD_FAB2(SCH_1):PAGE41
  DB73    GND @BASEBOARD_FAB2_LIB.BASEBOARD_FAB2(SCH_1):GND   I285 @BASEBOARD_FAB2_LIB.BASEBOARD_FAB2(SCH_1):PAGE41
  DB77    GND @BASEBOARD_FAB2_LIB.BASEBOARD_FAB2(SCH_1):GND   I285 @BASEBOARD_FAB2_LIB.BASEBOARD_FAB2(SCH_1):PAGE41
  DB83    GND @BASEBOARD_FAB2_LIB.BASEBOARD_FAB2(SCH_1):GND   I285 @BASEBOARD_FAB2_LIB.BASEBOARD_FAB2(SCH_1):PAGE41
  DB85    GND @BASEBOARD_FAB2_LIB.BASEBOARD_FAB2(SCH_1):GND   I285 @BASEBOARD_FAB2_LIB.BASEBOARD_FAB2(SCH_1):PAGE41
  DC14    GND @BASEBOARD_FAB2_LIB.BASEBOARD_FAB2(SCH_1):GND   I285 @BASEBOARD_FAB2_LIB.BASEBOARD_FAB2(SCH_1):PAGE41
  DC24    GND @BASEBOARD_FAB2_LIB.BASEBOARD_FAB2(SCH_1):GND   I285 @BASEBOARD_FAB2_LIB.BASEBOARD_FAB2(SCH_1):PAGE41
  DC26    GND @BASEBOARD_FAB2_LIB.BASEBOARD_FAB2(SCH_1):GND   I285 @BASEBOARD_FAB2_LIB.BASEBOARD_FAB2(SCH_1):PAGE41
  DC32    GND @BASEBOARD_FAB2_LIB.BASEBOARD_FAB2(SCH_1):GND   I285 @BASEBOARD_FAB2_LIB.BASEBOARD_FAB2(SCH_1):PAGE41
  DC38    GND @BASEBOARD_FAB2_LIB.BASEBOARD_FAB2(SCH_1):GND   I285 @BASEBOARD_FAB2_LIB.BASEBOARD_FAB2(SCH_1):PAGE41
  DC42    GND @BASEBOARD_FAB2_LIB.BASEBOARD_FAB2(SCH_1):GND   I285 @BASEBOARD_FAB2_LIB.BASEBOARD_FAB2(SCH_1):PAGE41
  DC64    GND @BASEBOARD_FAB2_LIB.BASEBOARD_FAB2(SCH_1):GND   I285 @BASEBOARD_FAB2_LIB.BASEBOARD_FAB2(SCH_1):PAGE41
  DC66    GND @BASEBOARD_FAB2_LIB.BASEBOARD_FAB2(SCH_1):GND   I285 @BASEBOARD_FAB2_LIB.BASEBOARD_FAB2(SCH_1):PAGE41
  DC68    GND @BASEBOARD_FAB2_LIB.BASEBOARD_FAB2(SCH_1):GND   I285 @BASEBOARD_FAB2_LIB.BASEBOARD_FAB2(SCH_1):PAGE41
  DC70    GND @BASEBOARD_FAB2_LIB.BASEBOARD_FAB2(SCH_1):GND   I285 @BASEBOARD_FAB2_LIB.BASEBOARD_FAB2(SCH_1):PAGE41
  DC78    GND @BASEBOARD_FAB2_LIB.BASEBOARD_FAB2(SCH_1):GND   I285 @BASEBOARD_FAB2_LIB.BASEBOARD_FAB2(SCH_1):PAGE41
  DC84    GND @BASEBOARD_FAB2_LIB.BASEBOARD_FAB2(SCH_1):GND   I285 @BASEBOARD_FAB2_LIB.BASEBOARD_FAB2(SCH_1):PAGE41
  DC86    GND @BASEBOARD_FAB2_LIB.BASEBOARD_FAB2(SCH_1):GND   I285 @BASEBOARD_FAB2_LIB.BASEBOARD_FAB2(SCH_1):PAGE41
  DD11    GND @BASEBOARD_FAB2_LIB.BASEBOARD_FAB2(SCH_1):GND   I285 @BASEBOARD_FAB2_LIB.BASEBOARD_FAB2(SCH_1):PAGE41
  DD23    GND @BASEBOARD_FAB2_LIB.BASEBOARD_FAB2(SCH_1):GND   I285 @BASEBOARD_FAB2_LIB.BASEBOARD_FAB2(SCH_1):PAGE41
  DD27    GND @BASEBOARD_FAB2_LIB.BASEBOARD_FAB2(SCH_1):GND   I285 @BASEBOARD_FAB2_LIB.BASEBOARD_FAB2(SCH_1):PAGE41
  DD31    GND @BASEBOARD_FAB2_LIB.BASEBOARD_FAB2(SCH_1):GND   I285 @BASEBOARD_FAB2_LIB.BASEBOARD_FAB2(SCH_1):PAGE41
  DD33    GND @BASEBOARD_FAB2_LIB.BASEBOARD_FAB2(SCH_1):GND   I285 @BASEBOARD_FAB2_LIB.BASEBOARD_FAB2(SCH_1):PAGE41
  DD37    GND @BASEBOARD_FAB2_LIB.BASEBOARD_FAB2(SCH_1):GND   I285 @BASEBOARD_FAB2_LIB.BASEBOARD_FAB2(SCH_1):PAGE41
  DD71    GND @BASEBOARD_FAB2_LIB.BASEBOARD_FAB2(SCH_1):GND   I285 @BASEBOARD_FAB2_LIB.BASEBOARD_FAB2(SCH_1):PAGE41
  DD73    GND @BASEBOARD_FAB2_LIB.BASEBOARD_FAB2(SCH_1):GND   I285 @BASEBOARD_FAB2_LIB.BASEBOARD_FAB2(SCH_1):PAGE41
  DD75    GND @BASEBOARD_FAB2_LIB.BASEBOARD_FAB2(SCH_1):GND   I285 @BASEBOARD_FAB2_LIB.BASEBOARD_FAB2(SCH_1):PAGE41
  DD81    GND @BASEBOARD_FAB2_LIB.BASEBOARD_FAB2(SCH_1):GND   I285 @BASEBOARD_FAB2_LIB.BASEBOARD_FAB2(SCH_1):PAGE41
  DD83    GND @BASEBOARD_FAB2_LIB.BASEBOARD_FAB2(SCH_1):GND   I285 @BASEBOARD_FAB2_LIB.BASEBOARD_FAB2(SCH_1):PAGE41
   DE6    GND @BASEBOARD_FAB2_LIB.BASEBOARD_FAB2(SCH_1):GND   I285 @BASEBOARD_FAB2_LIB.BASEBOARD_FAB2(SCH_1):PAGE41
   DE8    GND @BASEBOARD_FAB2_LIB.BASEBOARD_FAB2(SCH_1):GND   I285 @BASEBOARD_FAB2_LIB.BASEBOARD_FAB2(SCH_1):PAGE41
  DE18    GND @BASEBOARD_FAB2_LIB.BASEBOARD_FAB2(SCH_1):GND   I285 @BASEBOARD_FAB2_LIB.BASEBOARD_FAB2(SCH_1):PAGE41
  DE20    GND @BASEBOARD_FAB2_LIB.BASEBOARD_FAB2(SCH_1):GND   I285 @BASEBOARD_FAB2_LIB.BASEBOARD_FAB2(SCH_1):PAGE41
  DE24    GND @BASEBOARD_FAB2_LIB.BASEBOARD_FAB2(SCH_1):GND   I285 @BASEBOARD_FAB2_LIB.BASEBOARD_FAB2(SCH_1):PAGE41
  DE28    GND @BASEBOARD_FAB2_LIB.BASEBOARD_FAB2(SCH_1):GND   I285 @BASEBOARD_FAB2_LIB.BASEBOARD_FAB2(SCH_1):PAGE41
  DE30    GND @BASEBOARD_FAB2_LIB.BASEBOARD_FAB2(SCH_1):GND   I285 @BASEBOARD_FAB2_LIB.BASEBOARD_FAB2(SCH_1):PAGE41
  DE34    GND @BASEBOARD_FAB2_LIB.BASEBOARD_FAB2(SCH_1):GND   I285 @BASEBOARD_FAB2_LIB.BASEBOARD_FAB2(SCH_1):PAGE41
  DE36    GND @BASEBOARD_FAB2_LIB.BASEBOARD_FAB2(SCH_1):GND   I285 @BASEBOARD_FAB2_LIB.BASEBOARD_FAB2(SCH_1):PAGE41
  DE64    GND @BASEBOARD_FAB2_LIB.BASEBOARD_FAB2(SCH_1):GND   I285 @BASEBOARD_FAB2_LIB.BASEBOARD_FAB2(SCH_1):PAGE41
  DE70    GND @BASEBOARD_FAB2_LIB.BASEBOARD_FAB2(SCH_1):GND   I285 @BASEBOARD_FAB2_LIB.BASEBOARD_FAB2(SCH_1):PAGE41
  DE72    GND @BASEBOARD_FAB2_LIB.BASEBOARD_FAB2(SCH_1):GND   I285 @BASEBOARD_FAB2_LIB.BASEBOARD_FAB2(SCH_1):PAGE41
  DE78    GND @BASEBOARD_FAB2_LIB.BASEBOARD_FAB2(SCH_1):GND   I285 @BASEBOARD_FAB2_LIB.BASEBOARD_FAB2(SCH_1):PAGE41
   DF5    GND @BASEBOARD_FAB2_LIB.BASEBOARD_FAB2(SCH_1):GND   I285 @BASEBOARD_FAB2_LIB.BASEBOARD_FAB2(SCH_1):PAGE41
   DF7    GND @BASEBOARD_FAB2_LIB.BASEBOARD_FAB2(SCH_1):GND   I285 @BASEBOARD_FAB2_LIB.BASEBOARD_FAB2(SCH_1):PAGE41
   H51    GND @BASEBOARD_FAB2_LIB.BASEBOARD_FAB2(SCH_1):GND   I285 @BASEBOARD_FAB2_LIB.BASEBOARD_FAB2(SCH_1):PAGE41
  DF19    GND @BASEBOARD_FAB2_LIB.BASEBOARD_FAB2(SCH_1):GND   I285 @BASEBOARD_FAB2_LIB.BASEBOARD_FAB2(SCH_1):PAGE41
  DF29    GND @BASEBOARD_FAB2_LIB.BASEBOARD_FAB2(SCH_1):GND   I285 @BASEBOARD_FAB2_LIB.BASEBOARD_FAB2(SCH_1):PAGE41
  DF35    GND @BASEBOARD_FAB2_LIB.BASEBOARD_FAB2(SCH_1):GND   I285 @BASEBOARD_FAB2_LIB.BASEBOARD_FAB2(SCH_1):PAGE41
  DF37    GND @BASEBOARD_FAB2_LIB.BASEBOARD_FAB2(SCH_1):GND   I285 @BASEBOARD_FAB2_LIB.BASEBOARD_FAB2(SCH_1):PAGE41
  DF39    GND @BASEBOARD_FAB2_LIB.BASEBOARD_FAB2(SCH_1):GND   I285 @BASEBOARD_FAB2_LIB.BASEBOARD_FAB2(SCH_1):PAGE41
  DF41    GND @BASEBOARD_FAB2_LIB.BASEBOARD_FAB2(SCH_1):GND   I285 @BASEBOARD_FAB2_LIB.BASEBOARD_FAB2(SCH_1):PAGE41
  DF65    GND @BASEBOARD_FAB2_LIB.BASEBOARD_FAB2(SCH_1):GND   I285 @BASEBOARD_FAB2_LIB.BASEBOARD_FAB2(SCH_1):PAGE41
  DF69    GND @BASEBOARD_FAB2_LIB.BASEBOARD_FAB2(SCH_1):GND   I285 @BASEBOARD_FAB2_LIB.BASEBOARD_FAB2(SCH_1):PAGE41
  DF73    GND @BASEBOARD_FAB2_LIB.BASEBOARD_FAB2(SCH_1):GND   I285 @BASEBOARD_FAB2_LIB.BASEBOARD_FAB2(SCH_1):PAGE41
  DF79    GND @BASEBOARD_FAB2_LIB.BASEBOARD_FAB2(SCH_1):GND   I285 @BASEBOARD_FAB2_LIB.BASEBOARD_FAB2(SCH_1):PAGE41
  DF83    GND @BASEBOARD_FAB2_LIB.BASEBOARD_FAB2(SCH_1):GND   I285 @BASEBOARD_FAB2_LIB.BASEBOARD_FAB2(SCH_1):PAGE41
  DF85    GND @BASEBOARD_FAB2_LIB.BASEBOARD_FAB2(SCH_1):GND   I285 @BASEBOARD_FAB2_LIB.BASEBOARD_FAB2(SCH_1):PAGE41
   DG2    GND @BASEBOARD_FAB2_LIB.BASEBOARD_FAB2(SCH_1):GND   I285 @BASEBOARD_FAB2_LIB.BASEBOARD_FAB2(SCH_1):PAGE41
   H49    GND @BASEBOARD_FAB2_LIB.BASEBOARD_FAB2(SCH_1):GND   I285 @BASEBOARD_FAB2_LIB.BASEBOARD_FAB2(SCH_1):PAGE41
  DG14    GND @BASEBOARD_FAB2_LIB.BASEBOARD_FAB2(SCH_1):GND   I285 @BASEBOARD_FAB2_LIB.BASEBOARD_FAB2(SCH_1):PAGE41
  DG16    GND @BASEBOARD_FAB2_LIB.BASEBOARD_FAB2(SCH_1):GND   I285 @BASEBOARD_FAB2_LIB.BASEBOARD_FAB2(SCH_1):PAGE41
  DG24    GND @BASEBOARD_FAB2_LIB.BASEBOARD_FAB2(SCH_1):GND   I285 @BASEBOARD_FAB2_LIB.BASEBOARD_FAB2(SCH_1):PAGE41
  DG66    GND @BASEBOARD_FAB2_LIB.BASEBOARD_FAB2(SCH_1):GND   I285 @BASEBOARD_FAB2_LIB.BASEBOARD_FAB2(SCH_1):PAGE41
  DG68    GND @BASEBOARD_FAB2_LIB.BASEBOARD_FAB2(SCH_1):GND   I285 @BASEBOARD_FAB2_LIB.BASEBOARD_FAB2(SCH_1):PAGE41
  DG76    GND @BASEBOARD_FAB2_LIB.BASEBOARD_FAB2(SCH_1):GND   I285 @BASEBOARD_FAB2_LIB.BASEBOARD_FAB2(SCH_1):PAGE41
  DG78    GND @BASEBOARD_FAB2_LIB.BASEBOARD_FAB2(SCH_1):GND   I285 @BASEBOARD_FAB2_LIB.BASEBOARD_FAB2(SCH_1):PAGE41
  DG80    GND @BASEBOARD_FAB2_LIB.BASEBOARD_FAB2(SCH_1):GND   I285 @BASEBOARD_FAB2_LIB.BASEBOARD_FAB2(SCH_1):PAGE41
  DG82    GND @BASEBOARD_FAB2_LIB.BASEBOARD_FAB2(SCH_1):GND   I285 @BASEBOARD_FAB2_LIB.BASEBOARD_FAB2(SCH_1):PAGE41
  DH13    GND @BASEBOARD_FAB2_LIB.BASEBOARD_FAB2(SCH_1):GND   I285 @BASEBOARD_FAB2_LIB.BASEBOARD_FAB2(SCH_1):PAGE41
  DH15    GND @BASEBOARD_FAB2_LIB.BASEBOARD_FAB2(SCH_1):GND   I285 @BASEBOARD_FAB2_LIB.BASEBOARD_FAB2(SCH_1):PAGE41
  DH23    GND @BASEBOARD_FAB2_LIB.BASEBOARD_FAB2(SCH_1):GND   I285 @BASEBOARD_FAB2_LIB.BASEBOARD_FAB2(SCH_1):PAGE41
  DH25    GND @BASEBOARD_FAB2_LIB.BASEBOARD_FAB2(SCH_1):GND   I285 @BASEBOARD_FAB2_LIB.BASEBOARD_FAB2(SCH_1):PAGE41
  DH27    GND @BASEBOARD_FAB2_LIB.BASEBOARD_FAB2(SCH_1):GND   I285 @BASEBOARD_FAB2_LIB.BASEBOARD_FAB2(SCH_1):PAGE41
  DH29    GND @BASEBOARD_FAB2_LIB.BASEBOARD_FAB2(SCH_1):GND   I285 @BASEBOARD_FAB2_LIB.BASEBOARD_FAB2(SCH_1):PAGE41
  DH31    GND @BASEBOARD_FAB2_LIB.BASEBOARD_FAB2(SCH_1):GND   I285 @BASEBOARD_FAB2_LIB.BASEBOARD_FAB2(SCH_1):PAGE41
  DH33    GND @BASEBOARD_FAB2_LIB.BASEBOARD_FAB2(SCH_1):GND   I285 @BASEBOARD_FAB2_LIB.BASEBOARD_FAB2(SCH_1):PAGE41
  DH35    GND @BASEBOARD_FAB2_LIB.BASEBOARD_FAB2(SCH_1):GND   I285 @BASEBOARD_FAB2_LIB.BASEBOARD_FAB2(SCH_1):PAGE41
  DH37    GND @BASEBOARD_FAB2_LIB.BASEBOARD_FAB2(SCH_1):GND   I285 @BASEBOARD_FAB2_LIB.BASEBOARD_FAB2(SCH_1):PAGE41
  DH41    GND @BASEBOARD_FAB2_LIB.BASEBOARD_FAB2(SCH_1):GND   I285 @BASEBOARD_FAB2_LIB.BASEBOARD_FAB2(SCH_1):PAGE41
  DH67    GND @BASEBOARD_FAB2_LIB.BASEBOARD_FAB2(SCH_1):GND   I285 @BASEBOARD_FAB2_LIB.BASEBOARD_FAB2(SCH_1):PAGE41
  DH71    GND @BASEBOARD_FAB2_LIB.BASEBOARD_FAB2(SCH_1):GND   I285 @BASEBOARD_FAB2_LIB.BASEBOARD_FAB2(SCH_1):PAGE41
  DH73    GND @BASEBOARD_FAB2_LIB.BASEBOARD_FAB2(SCH_1):GND   I285 @BASEBOARD_FAB2_LIB.BASEBOARD_FAB2(SCH_1):PAGE41
  DH79    GND @BASEBOARD_FAB2_LIB.BASEBOARD_FAB2(SCH_1):GND   I285 @BASEBOARD_FAB2_LIB.BASEBOARD_FAB2(SCH_1):PAGE41
  DH81    GND @BASEBOARD_FAB2_LIB.BASEBOARD_FAB2(SCH_1):GND   I285 @BASEBOARD_FAB2_LIB.BASEBOARD_FAB2(SCH_1):PAGE41
  DH83    GND @BASEBOARD_FAB2_LIB.BASEBOARD_FAB2(SCH_1):GND   I285 @BASEBOARD_FAB2_LIB.BASEBOARD_FAB2(SCH_1):PAGE41
   DJ2    GND @BASEBOARD_FAB2_LIB.BASEBOARD_FAB2(SCH_1):GND   I285 @BASEBOARD_FAB2_LIB.BASEBOARD_FAB2(SCH_1):PAGE41
  DJ10    GND @BASEBOARD_FAB2_LIB.BASEBOARD_FAB2(SCH_1):GND   I285 @BASEBOARD_FAB2_LIB.BASEBOARD_FAB2(SCH_1):PAGE41
   H47    GND @BASEBOARD_FAB2_LIB.BASEBOARD_FAB2(SCH_1):GND   I285 @BASEBOARD_FAB2_LIB.BASEBOARD_FAB2(SCH_1):PAGE41
  DJ22    GND @BASEBOARD_FAB2_LIB.BASEBOARD_FAB2(SCH_1):GND   I285 @BASEBOARD_FAB2_LIB.BASEBOARD_FAB2(SCH_1):PAGE41
  DJ38    GND @BASEBOARD_FAB2_LIB.BASEBOARD_FAB2(SCH_1):GND   I285 @BASEBOARD_FAB2_LIB.BASEBOARD_FAB2(SCH_1):PAGE41
  DJ42    GND @BASEBOARD_FAB2_LIB.BASEBOARD_FAB2(SCH_1):GND   I285 @BASEBOARD_FAB2_LIB.BASEBOARD_FAB2(SCH_1):PAGE41
  DJ68    GND @BASEBOARD_FAB2_LIB.BASEBOARD_FAB2(SCH_1):GND   I285 @BASEBOARD_FAB2_LIB.BASEBOARD_FAB2(SCH_1):PAGE41
  DJ74    GND @BASEBOARD_FAB2_LIB.BASEBOARD_FAB2(SCH_1):GND   I285 @BASEBOARD_FAB2_LIB.BASEBOARD_FAB2(SCH_1):PAGE41
  DJ78    GND @BASEBOARD_FAB2_LIB.BASEBOARD_FAB2(SCH_1):GND   I285 @BASEBOARD_FAB2_LIB.BASEBOARD_FAB2(SCH_1):PAGE41
  DJ82    GND @BASEBOARD_FAB2_LIB.BASEBOARD_FAB2(SCH_1):GND   I285 @BASEBOARD_FAB2_LIB.BASEBOARD_FAB2(SCH_1):PAGE41
  DJ84    GND @BASEBOARD_FAB2_LIB.BASEBOARD_FAB2(SCH_1):GND   I285 @BASEBOARD_FAB2_LIB.BASEBOARD_FAB2(SCH_1):PAGE41
   DK7    GND @BASEBOARD_FAB2_LIB.BASEBOARD_FAB2(SCH_1):GND   I285 @BASEBOARD_FAB2_LIB.BASEBOARD_FAB2(SCH_1):PAGE41
  DK23    GND @BASEBOARD_FAB2_LIB.BASEBOARD_FAB2(SCH_1):GND   I285 @BASEBOARD_FAB2_LIB.BASEBOARD_FAB2(SCH_1):PAGE41
  DK29    GND @BASEBOARD_FAB2_LIB.BASEBOARD_FAB2(SCH_1):GND   I285 @BASEBOARD_FAB2_LIB.BASEBOARD_FAB2(SCH_1):PAGE41
  DK35    GND @BASEBOARD_FAB2_LIB.BASEBOARD_FAB2(SCH_1):GND   I285 @BASEBOARD_FAB2_LIB.BASEBOARD_FAB2(SCH_1):PAGE41
  DK39    GND @BASEBOARD_FAB2_LIB.BASEBOARD_FAB2(SCH_1):GND   I285 @BASEBOARD_FAB2_LIB.BASEBOARD_FAB2(SCH_1):PAGE41
  DK41    GND @BASEBOARD_FAB2_LIB.BASEBOARD_FAB2(SCH_1):GND   I285 @BASEBOARD_FAB2_LIB.BASEBOARD_FAB2(SCH_1):PAGE41
  DK73    GND @BASEBOARD_FAB2_LIB.BASEBOARD_FAB2(SCH_1):GND   I285 @BASEBOARD_FAB2_LIB.BASEBOARD_FAB2(SCH_1):PAGE41
  DK75    GND @BASEBOARD_FAB2_LIB.BASEBOARD_FAB2(SCH_1):GND   I285 @BASEBOARD_FAB2_LIB.BASEBOARD_FAB2(SCH_1):PAGE41
  DK77    GND @BASEBOARD_FAB2_LIB.BASEBOARD_FAB2(SCH_1):GND   I285 @BASEBOARD_FAB2_LIB.BASEBOARD_FAB2(SCH_1):PAGE41
  DK83    GND @BASEBOARD_FAB2_LIB.BASEBOARD_FAB2(SCH_1):GND   I285 @BASEBOARD_FAB2_LIB.BASEBOARD_FAB2(SCH_1):PAGE41
  DK85    GND @BASEBOARD_FAB2_LIB.BASEBOARD_FAB2(SCH_1):GND   I285 @BASEBOARD_FAB2_LIB.BASEBOARD_FAB2(SCH_1):PAGE41
  DL16    GND @BASEBOARD_FAB2_LIB.BASEBOARD_FAB2(SCH_1):GND   I285 @BASEBOARD_FAB2_LIB.BASEBOARD_FAB2(SCH_1):PAGE41
  DL18    GND @BASEBOARD_FAB2_LIB.BASEBOARD_FAB2(SCH_1):GND   I285 @BASEBOARD_FAB2_LIB.BASEBOARD_FAB2(SCH_1):PAGE41
   DL4    GND @BASEBOARD_FAB2_LIB.BASEBOARD_FAB2(SCH_1):GND   I285 @BASEBOARD_FAB2_LIB.BASEBOARD_FAB2(SCH_1):PAGE41
  DL22    GND @BASEBOARD_FAB2_LIB.BASEBOARD_FAB2(SCH_1):GND   I285 @BASEBOARD_FAB2_LIB.BASEBOARD_FAB2(SCH_1):PAGE41
  DL24    GND @BASEBOARD_FAB2_LIB.BASEBOARD_FAB2(SCH_1):GND   I285 @BASEBOARD_FAB2_LIB.BASEBOARD_FAB2(SCH_1):PAGE41
  DL28    GND @BASEBOARD_FAB2_LIB.BASEBOARD_FAB2(SCH_1):GND   I285 @BASEBOARD_FAB2_LIB.BASEBOARD_FAB2(SCH_1):PAGE41
  DL30    GND @BASEBOARD_FAB2_LIB.BASEBOARD_FAB2(SCH_1):GND   I285 @BASEBOARD_FAB2_LIB.BASEBOARD_FAB2(SCH_1):PAGE41
  DL34    GND @BASEBOARD_FAB2_LIB.BASEBOARD_FAB2(SCH_1):GND   I285 @BASEBOARD_FAB2_LIB.BASEBOARD_FAB2(SCH_1):PAGE41
  DL36    GND @BASEBOARD_FAB2_LIB.BASEBOARD_FAB2(SCH_1):GND   I285 @BASEBOARD_FAB2_LIB.BASEBOARD_FAB2(SCH_1):PAGE41
  DL40    GND @BASEBOARD_FAB2_LIB.BASEBOARD_FAB2(SCH_1):GND   I285 @BASEBOARD_FAB2_LIB.BASEBOARD_FAB2(SCH_1):PAGE41
  DL68    GND @BASEBOARD_FAB2_LIB.BASEBOARD_FAB2(SCH_1):GND   I285 @BASEBOARD_FAB2_LIB.BASEBOARD_FAB2(SCH_1):PAGE41
  DL70    GND @BASEBOARD_FAB2_LIB.BASEBOARD_FAB2(SCH_1):GND   I285 @BASEBOARD_FAB2_LIB.BASEBOARD_FAB2(SCH_1):PAGE41
  DL74    GND @BASEBOARD_FAB2_LIB.BASEBOARD_FAB2(SCH_1):GND   I285 @BASEBOARD_FAB2_LIB.BASEBOARD_FAB2(SCH_1):PAGE41
  DL76    GND @BASEBOARD_FAB2_LIB.BASEBOARD_FAB2(SCH_1):GND   I285 @BASEBOARD_FAB2_LIB.BASEBOARD_FAB2(SCH_1):PAGE41
  DL78    GND @BASEBOARD_FAB2_LIB.BASEBOARD_FAB2(SCH_1):GND   I285 @BASEBOARD_FAB2_LIB.BASEBOARD_FAB2(SCH_1):PAGE41
  DL80    GND @BASEBOARD_FAB2_LIB.BASEBOARD_FAB2(SCH_1):GND   I285 @BASEBOARD_FAB2_LIB.BASEBOARD_FAB2(SCH_1):PAGE41
  DM15    GND @BASEBOARD_FAB2_LIB.BASEBOARD_FAB2(SCH_1):GND   I285 @BASEBOARD_FAB2_LIB.BASEBOARD_FAB2(SCH_1):PAGE41
   H45    GND @BASEBOARD_FAB2_LIB.BASEBOARD_FAB2(SCH_1):GND   I285 @BASEBOARD_FAB2_LIB.BASEBOARD_FAB2(SCH_1):PAGE41
  DM25    GND @BASEBOARD_FAB2_LIB.BASEBOARD_FAB2(SCH_1):GND   I285 @BASEBOARD_FAB2_LIB.BASEBOARD_FAB2(SCH_1):PAGE41
  DM27    GND @BASEBOARD_FAB2_LIB.BASEBOARD_FAB2(SCH_1):GND   I285 @BASEBOARD_FAB2_LIB.BASEBOARD_FAB2(SCH_1):PAGE41
  DM31    GND @BASEBOARD_FAB2_LIB.BASEBOARD_FAB2(SCH_1):GND   I285 @BASEBOARD_FAB2_LIB.BASEBOARD_FAB2(SCH_1):PAGE41
  DM33    GND @BASEBOARD_FAB2_LIB.BASEBOARD_FAB2(SCH_1):GND   I285 @BASEBOARD_FAB2_LIB.BASEBOARD_FAB2(SCH_1):PAGE41
  DM37    GND @BASEBOARD_FAB2_LIB.BASEBOARD_FAB2(SCH_1):GND   I285 @BASEBOARD_FAB2_LIB.BASEBOARD_FAB2(SCH_1):PAGE41
  DM39    GND @BASEBOARD_FAB2_LIB.BASEBOARD_FAB2(SCH_1):GND   I285 @BASEBOARD_FAB2_LIB.BASEBOARD_FAB2(SCH_1):PAGE41
  DM65    GND @BASEBOARD_FAB2_LIB.BASEBOARD_FAB2(SCH_1):GND   I285 @BASEBOARD_FAB2_LIB.BASEBOARD_FAB2(SCH_1):PAGE41
  DM73    GND @BASEBOARD_FAB2_LIB.BASEBOARD_FAB2(SCH_1):GND   I285 @BASEBOARD_FAB2_LIB.BASEBOARD_FAB2(SCH_1):PAGE41
  DM77    GND @BASEBOARD_FAB2_LIB.BASEBOARD_FAB2(SCH_1):GND   I285 @BASEBOARD_FAB2_LIB.BASEBOARD_FAB2(SCH_1):PAGE41
  DM83    GND @BASEBOARD_FAB2_LIB.BASEBOARD_FAB2(SCH_1):GND   I285 @BASEBOARD_FAB2_LIB.BASEBOARD_FAB2(SCH_1):PAGE41
   DN2    GND @BASEBOARD_FAB2_LIB.BASEBOARD_FAB2(SCH_1):GND   I285 @BASEBOARD_FAB2_LIB.BASEBOARD_FAB2(SCH_1):PAGE41
  BH17    GND @BASEBOARD_FAB2_LIB.BASEBOARD_FAB2(SCH_1):GND   I285 @BASEBOARD_FAB2_LIB.BASEBOARD_FAB2(SCH_1):PAGE41
  DN12    GND @BASEBOARD_FAB2_LIB.BASEBOARD_FAB2(SCH_1):GND   I285 @BASEBOARD_FAB2_LIB.BASEBOARD_FAB2(SCH_1):PAGE41
  DN22    GND @BASEBOARD_FAB2_LIB.BASEBOARD_FAB2(SCH_1):GND   I285 @BASEBOARD_FAB2_LIB.BASEBOARD_FAB2(SCH_1):PAGE41
  DN26    GND @BASEBOARD_FAB2_LIB.BASEBOARD_FAB2(SCH_1):GND   I285 @BASEBOARD_FAB2_LIB.BASEBOARD_FAB2(SCH_1):PAGE41
  DN32    GND @BASEBOARD_FAB2_LIB.BASEBOARD_FAB2(SCH_1):GND   I285 @BASEBOARD_FAB2_LIB.BASEBOARD_FAB2(SCH_1):PAGE41
  DN38    GND @BASEBOARD_FAB2_LIB.BASEBOARD_FAB2(SCH_1):GND   I285 @BASEBOARD_FAB2_LIB.BASEBOARD_FAB2(SCH_1):PAGE41
  DN68    GND @BASEBOARD_FAB2_LIB.BASEBOARD_FAB2(SCH_1):GND   I285 @BASEBOARD_FAB2_LIB.BASEBOARD_FAB2(SCH_1):PAGE41
  DN72    GND @BASEBOARD_FAB2_LIB.BASEBOARD_FAB2(SCH_1):GND   I285 @BASEBOARD_FAB2_LIB.BASEBOARD_FAB2(SCH_1):PAGE41
  DN78    GND @BASEBOARD_FAB2_LIB.BASEBOARD_FAB2(SCH_1):GND   I286 @BASEBOARD_FAB2_LIB.BASEBOARD_FAB2(SCH_1):PAGE41
  DP67    GND @BASEBOARD_FAB2_LIB.BASEBOARD_FAB2(SCH_1):GND   I286 @BASEBOARD_FAB2_LIB.BASEBOARD_FAB2(SCH_1):PAGE41
  DP69    GND @BASEBOARD_FAB2_LIB.BASEBOARD_FAB2(SCH_1):GND   I286 @BASEBOARD_FAB2_LIB.BASEBOARD_FAB2(SCH_1):PAGE41
  DP71    GND @BASEBOARD_FAB2_LIB.BASEBOARD_FAB2(SCH_1):GND   I286 @BASEBOARD_FAB2_LIB.BASEBOARD_FAB2(SCH_1):PAGE41
  DP81    GND @BASEBOARD_FAB2_LIB.BASEBOARD_FAB2(SCH_1):GND   I286 @BASEBOARD_FAB2_LIB.BASEBOARD_FAB2(SCH_1):PAGE41
  DP83    GND @BASEBOARD_FAB2_LIB.BASEBOARD_FAB2(SCH_1):GND   I286 @BASEBOARD_FAB2_LIB.BASEBOARD_FAB2(SCH_1):PAGE41
  BR26    GND @BASEBOARD_FAB2_LIB.BASEBOARD_FAB2(SCH_1):GND   I286 @BASEBOARD_FAB2_LIB.BASEBOARD_FAB2(SCH_1):PAGE41
   DR6    GND @BASEBOARD_FAB2_LIB.BASEBOARD_FAB2(SCH_1):GND   I286 @BASEBOARD_FAB2_LIB.BASEBOARD_FAB2(SCH_1):PAGE41
  CA20    GND @BASEBOARD_FAB2_LIB.BASEBOARD_FAB2(SCH_1):GND   I286 @BASEBOARD_FAB2_LIB.BASEBOARD_FAB2(SCH_1):PAGE41
  CL22    GND @BASEBOARD_FAB2_LIB.BASEBOARD_FAB2(SCH_1):GND   I286 @BASEBOARD_FAB2_LIB.BASEBOARD_FAB2(SCH_1):PAGE41
  DR20    GND @BASEBOARD_FAB2_LIB.BASEBOARD_FAB2(SCH_1):GND   I286 @BASEBOARD_FAB2_LIB.BASEBOARD_FAB2(SCH_1):PAGE41
  DR22    GND @BASEBOARD_FAB2_LIB.BASEBOARD_FAB2(SCH_1):GND   I286 @BASEBOARD_FAB2_LIB.BASEBOARD_FAB2(SCH_1):PAGE41
  DR24    GND @BASEBOARD_FAB2_LIB.BASEBOARD_FAB2(SCH_1):GND   I286 @BASEBOARD_FAB2_LIB.BASEBOARD_FAB2(SCH_1):PAGE41
  DR26    GND @BASEBOARD_FAB2_LIB.BASEBOARD_FAB2(SCH_1):GND   I286 @BASEBOARD_FAB2_LIB.BASEBOARD_FAB2(SCH_1):PAGE41
  DR28    GND @BASEBOARD_FAB2_LIB.BASEBOARD_FAB2(SCH_1):GND   I286 @BASEBOARD_FAB2_LIB.BASEBOARD_FAB2(SCH_1):PAGE41
  DR30    GND @BASEBOARD_FAB2_LIB.BASEBOARD_FAB2(SCH_1):GND   I286 @BASEBOARD_FAB2_LIB.BASEBOARD_FAB2(SCH_1):PAGE41
  DR32    GND @BASEBOARD_FAB2_LIB.BASEBOARD_FAB2(SCH_1):GND   I286 @BASEBOARD_FAB2_LIB.BASEBOARD_FAB2(SCH_1):PAGE41
  DR34    GND @BASEBOARD_FAB2_LIB.BASEBOARD_FAB2(SCH_1):GND   I286 @BASEBOARD_FAB2_LIB.BASEBOARD_FAB2(SCH_1):PAGE41
  DR36    GND @BASEBOARD_FAB2_LIB.BASEBOARD_FAB2(SCH_1):GND   I286 @BASEBOARD_FAB2_LIB.BASEBOARD_FAB2(SCH_1):PAGE41
  DR38    GND @BASEBOARD_FAB2_LIB.BASEBOARD_FAB2(SCH_1):GND   I286 @BASEBOARD_FAB2_LIB.BASEBOARD_FAB2(SCH_1):PAGE41
  DR40    GND @BASEBOARD_FAB2_LIB.BASEBOARD_FAB2(SCH_1):GND   I286 @BASEBOARD_FAB2_LIB.BASEBOARD_FAB2(SCH_1):PAGE41
  DR42    GND @BASEBOARD_FAB2_LIB.BASEBOARD_FAB2(SCH_1):GND   I286 @BASEBOARD_FAB2_LIB.BASEBOARD_FAB2(SCH_1):PAGE41
  DR66    GND @BASEBOARD_FAB2_LIB.BASEBOARD_FAB2(SCH_1):GND   I286 @BASEBOARD_FAB2_LIB.BASEBOARD_FAB2(SCH_1):PAGE41
  DR68    GND @BASEBOARD_FAB2_LIB.BASEBOARD_FAB2(SCH_1):GND   I286 @BASEBOARD_FAB2_LIB.BASEBOARD_FAB2(SCH_1):PAGE41
  DR70    GND @BASEBOARD_FAB2_LIB.BASEBOARD_FAB2(SCH_1):GND   I286 @BASEBOARD_FAB2_LIB.BASEBOARD_FAB2(SCH_1):PAGE41
  DR72    GND @BASEBOARD_FAB2_LIB.BASEBOARD_FAB2(SCH_1):GND   I286 @BASEBOARD_FAB2_LIB.BASEBOARD_FAB2(SCH_1):PAGE41
  DR74    GND @BASEBOARD_FAB2_LIB.BASEBOARD_FAB2(SCH_1):GND   I286 @BASEBOARD_FAB2_LIB.BASEBOARD_FAB2(SCH_1):PAGE41
  DR76    GND @BASEBOARD_FAB2_LIB.BASEBOARD_FAB2(SCH_1):GND   I286 @BASEBOARD_FAB2_LIB.BASEBOARD_FAB2(SCH_1):PAGE41
  DR78    GND @BASEBOARD_FAB2_LIB.BASEBOARD_FAB2(SCH_1):GND   I286 @BASEBOARD_FAB2_LIB.BASEBOARD_FAB2(SCH_1):PAGE41
   DT3    GND @BASEBOARD_FAB2_LIB.BASEBOARD_FAB2(SCH_1):GND   I286 @BASEBOARD_FAB2_LIB.BASEBOARD_FAB2(SCH_1):PAGE41
  DT17    GND @BASEBOARD_FAB2_LIB.BASEBOARD_FAB2(SCH_1):GND   I286 @BASEBOARD_FAB2_LIB.BASEBOARD_FAB2(SCH_1):PAGE41
  DH21    GND @BASEBOARD_FAB2_LIB.BASEBOARD_FAB2(SCH_1):GND   I286 @BASEBOARD_FAB2_LIB.BASEBOARD_FAB2(SCH_1):PAGE41
  DT65    GND @BASEBOARD_FAB2_LIB.BASEBOARD_FAB2(SCH_1):GND   I286 @BASEBOARD_FAB2_LIB.BASEBOARD_FAB2(SCH_1):PAGE41
  DT69    GND @BASEBOARD_FAB2_LIB.BASEBOARD_FAB2(SCH_1):GND   I286 @BASEBOARD_FAB2_LIB.BASEBOARD_FAB2(SCH_1):PAGE41
  DT79    GND @BASEBOARD_FAB2_LIB.BASEBOARD_FAB2(SCH_1):GND   I286 @BASEBOARD_FAB2_LIB.BASEBOARD_FAB2(SCH_1):PAGE41
  DT83    GND @BASEBOARD_FAB2_LIB.BASEBOARD_FAB2(SCH_1):GND   I286 @BASEBOARD_FAB2_LIB.BASEBOARD_FAB2(SCH_1):PAGE41
  DT85    GND @BASEBOARD_FAB2_LIB.BASEBOARD_FAB2(SCH_1):GND   I286 @BASEBOARD_FAB2_LIB.BASEBOARD_FAB2(SCH_1):PAGE41
  DU10    GND @BASEBOARD_FAB2_LIB.BASEBOARD_FAB2(SCH_1):GND   I286 @BASEBOARD_FAB2_LIB.BASEBOARD_FAB2(SCH_1):PAGE41
  DU14    GND @BASEBOARD_FAB2_LIB.BASEBOARD_FAB2(SCH_1):GND   I286 @BASEBOARD_FAB2_LIB.BASEBOARD_FAB2(SCH_1):PAGE41
  CN14    GND @BASEBOARD_FAB2_LIB.BASEBOARD_FAB2(SCH_1):GND   I286 @BASEBOARD_FAB2_LIB.BASEBOARD_FAB2(SCH_1):PAGE41
  DU22    GND @BASEBOARD_FAB2_LIB.BASEBOARD_FAB2(SCH_1):GND   I286 @BASEBOARD_FAB2_LIB.BASEBOARD_FAB2(SCH_1):PAGE41
  DU26    GND @BASEBOARD_FAB2_LIB.BASEBOARD_FAB2(SCH_1):GND   I286 @BASEBOARD_FAB2_LIB.BASEBOARD_FAB2(SCH_1):PAGE41
  DU32    GND @BASEBOARD_FAB2_LIB.BASEBOARD_FAB2(SCH_1):GND   I286 @BASEBOARD_FAB2_LIB.BASEBOARD_FAB2(SCH_1):PAGE41
  DU38    GND @BASEBOARD_FAB2_LIB.BASEBOARD_FAB2(SCH_1):GND   I286 @BASEBOARD_FAB2_LIB.BASEBOARD_FAB2(SCH_1):PAGE41
  DU70    GND @BASEBOARD_FAB2_LIB.BASEBOARD_FAB2(SCH_1):GND   I286 @BASEBOARD_FAB2_LIB.BASEBOARD_FAB2(SCH_1):PAGE41
  DU72    GND @BASEBOARD_FAB2_LIB.BASEBOARD_FAB2(SCH_1):GND   I286 @BASEBOARD_FAB2_LIB.BASEBOARD_FAB2(SCH_1):PAGE41
  DU78    GND @BASEBOARD_FAB2_LIB.BASEBOARD_FAB2(SCH_1):GND   I286 @BASEBOARD_FAB2_LIB.BASEBOARD_FAB2(SCH_1):PAGE41
  DU80    GND @BASEBOARD_FAB2_LIB.BASEBOARD_FAB2(SCH_1):GND   I286 @BASEBOARD_FAB2_LIB.BASEBOARD_FAB2(SCH_1):PAGE41
  DU82    GND @BASEBOARD_FAB2_LIB.BASEBOARD_FAB2(SCH_1):GND   I286 @BASEBOARD_FAB2_LIB.BASEBOARD_FAB2(SCH_1):PAGE41
  DU84    GND @BASEBOARD_FAB2_LIB.BASEBOARD_FAB2(SCH_1):GND   I286 @BASEBOARD_FAB2_LIB.BASEBOARD_FAB2(SCH_1):PAGE41
  DV21    GND @BASEBOARD_FAB2_LIB.BASEBOARD_FAB2(SCH_1):GND   I286 @BASEBOARD_FAB2_LIB.BASEBOARD_FAB2(SCH_1):PAGE41
  DV25    GND @BASEBOARD_FAB2_LIB.BASEBOARD_FAB2(SCH_1):GND   I286 @BASEBOARD_FAB2_LIB.BASEBOARD_FAB2(SCH_1):PAGE41
  DV27    GND @BASEBOARD_FAB2_LIB.BASEBOARD_FAB2(SCH_1):GND   I286 @BASEBOARD_FAB2_LIB.BASEBOARD_FAB2(SCH_1):PAGE41
  DV31    GND @BASEBOARD_FAB2_LIB.BASEBOARD_FAB2(SCH_1):GND   I286 @BASEBOARD_FAB2_LIB.BASEBOARD_FAB2(SCH_1):PAGE41
  DV33    GND @BASEBOARD_FAB2_LIB.BASEBOARD_FAB2(SCH_1):GND   I286 @BASEBOARD_FAB2_LIB.BASEBOARD_FAB2(SCH_1):PAGE41
  DV37    GND @BASEBOARD_FAB2_LIB.BASEBOARD_FAB2(SCH_1):GND   I286 @BASEBOARD_FAB2_LIB.BASEBOARD_FAB2(SCH_1):PAGE41
  DV39    GND @BASEBOARD_FAB2_LIB.BASEBOARD_FAB2(SCH_1):GND   I286 @BASEBOARD_FAB2_LIB.BASEBOARD_FAB2(SCH_1):PAGE41
  DV73    GND @BASEBOARD_FAB2_LIB.BASEBOARD_FAB2(SCH_1):GND   I286 @BASEBOARD_FAB2_LIB.BASEBOARD_FAB2(SCH_1):PAGE41
  DV77    GND @BASEBOARD_FAB2_LIB.BASEBOARD_FAB2(SCH_1):GND   I286 @BASEBOARD_FAB2_LIB.BASEBOARD_FAB2(SCH_1):PAGE41
  DV81    GND @BASEBOARD_FAB2_LIB.BASEBOARD_FAB2(SCH_1):GND   I286 @BASEBOARD_FAB2_LIB.BASEBOARD_FAB2(SCH_1):PAGE41
  DW12    GND @BASEBOARD_FAB2_LIB.BASEBOARD_FAB2(SCH_1):GND   I286 @BASEBOARD_FAB2_LIB.BASEBOARD_FAB2(SCH_1):PAGE41
  DW20    GND @BASEBOARD_FAB2_LIB.BASEBOARD_FAB2(SCH_1):GND   I286 @BASEBOARD_FAB2_LIB.BASEBOARD_FAB2(SCH_1):PAGE41
  DW24    GND @BASEBOARD_FAB2_LIB.BASEBOARD_FAB2(SCH_1):GND   I286 @BASEBOARD_FAB2_LIB.BASEBOARD_FAB2(SCH_1):PAGE41
  DW28    GND @BASEBOARD_FAB2_LIB.BASEBOARD_FAB2(SCH_1):GND   I286 @BASEBOARD_FAB2_LIB.BASEBOARD_FAB2(SCH_1):PAGE41
  DW30    GND @BASEBOARD_FAB2_LIB.BASEBOARD_FAB2(SCH_1):GND   I286 @BASEBOARD_FAB2_LIB.BASEBOARD_FAB2(SCH_1):PAGE41
  DW34    GND @BASEBOARD_FAB2_LIB.BASEBOARD_FAB2(SCH_1):GND   I286 @BASEBOARD_FAB2_LIB.BASEBOARD_FAB2(SCH_1):PAGE41
  DW36    GND @BASEBOARD_FAB2_LIB.BASEBOARD_FAB2(SCH_1):GND   I286 @BASEBOARD_FAB2_LIB.BASEBOARD_FAB2(SCH_1):PAGE41
  DW40    GND @BASEBOARD_FAB2_LIB.BASEBOARD_FAB2(SCH_1):GND   I286 @BASEBOARD_FAB2_LIB.BASEBOARD_FAB2(SCH_1):PAGE41
  DW64    GND @BASEBOARD_FAB2_LIB.BASEBOARD_FAB2(SCH_1):GND   I286 @BASEBOARD_FAB2_LIB.BASEBOARD_FAB2(SCH_1):PAGE41
  DW66    GND @BASEBOARD_FAB2_LIB.BASEBOARD_FAB2(SCH_1):GND   I286 @BASEBOARD_FAB2_LIB.BASEBOARD_FAB2(SCH_1):PAGE41
  DW68    GND @BASEBOARD_FAB2_LIB.BASEBOARD_FAB2(SCH_1):GND   I286 @BASEBOARD_FAB2_LIB.BASEBOARD_FAB2(SCH_1):PAGE41
  DW70    GND @BASEBOARD_FAB2_LIB.BASEBOARD_FAB2(SCH_1):GND   I286 @BASEBOARD_FAB2_LIB.BASEBOARD_FAB2(SCH_1):PAGE41
  DW72    GND @BASEBOARD_FAB2_LIB.BASEBOARD_FAB2(SCH_1):GND   I286 @BASEBOARD_FAB2_LIB.BASEBOARD_FAB2(SCH_1):PAGE41
  DW74    GND @BASEBOARD_FAB2_LIB.BASEBOARD_FAB2(SCH_1):GND   I286 @BASEBOARD_FAB2_LIB.BASEBOARD_FAB2(SCH_1):PAGE41
  DW76    GND @BASEBOARD_FAB2_LIB.BASEBOARD_FAB2(SCH_1):GND   I286 @BASEBOARD_FAB2_LIB.BASEBOARD_FAB2(SCH_1):PAGE41
   DW8    GND @BASEBOARD_FAB2_LIB.BASEBOARD_FAB2(SCH_1):GND   I286 @BASEBOARD_FAB2_LIB.BASEBOARD_FAB2(SCH_1):PAGE41
  DW82    GND @BASEBOARD_FAB2_LIB.BASEBOARD_FAB2(SCH_1):GND   I286 @BASEBOARD_FAB2_LIB.BASEBOARD_FAB2(SCH_1):PAGE41
  DW84    GND @BASEBOARD_FAB2_LIB.BASEBOARD_FAB2(SCH_1):GND   I286 @BASEBOARD_FAB2_LIB.BASEBOARD_FAB2(SCH_1):PAGE41
   DY5    GND @BASEBOARD_FAB2_LIB.BASEBOARD_FAB2(SCH_1):GND   I286 @BASEBOARD_FAB2_LIB.BASEBOARD_FAB2(SCH_1):PAGE41
  DY19    GND @BASEBOARD_FAB2_LIB.BASEBOARD_FAB2(SCH_1):GND   I286 @BASEBOARD_FAB2_LIB.BASEBOARD_FAB2(SCH_1):PAGE41
  DY23    GND @BASEBOARD_FAB2_LIB.BASEBOARD_FAB2(SCH_1):GND   I286 @BASEBOARD_FAB2_LIB.BASEBOARD_FAB2(SCH_1):PAGE41
  DY29    GND @BASEBOARD_FAB2_LIB.BASEBOARD_FAB2(SCH_1):GND   I286 @BASEBOARD_FAB2_LIB.BASEBOARD_FAB2(SCH_1):PAGE41
  DY35    GND @BASEBOARD_FAB2_LIB.BASEBOARD_FAB2(SCH_1):GND   I286 @BASEBOARD_FAB2_LIB.BASEBOARD_FAB2(SCH_1):PAGE41
  DY41    GND @BASEBOARD_FAB2_LIB.BASEBOARD_FAB2(SCH_1):GND   I286 @BASEBOARD_FAB2_LIB.BASEBOARD_FAB2(SCH_1):PAGE41
  DY71    GND @BASEBOARD_FAB2_LIB.BASEBOARD_FAB2(SCH_1):GND   I286 @BASEBOARD_FAB2_LIB.BASEBOARD_FAB2(SCH_1):PAGE41
  DY75    GND @BASEBOARD_FAB2_LIB.BASEBOARD_FAB2(SCH_1):GND   I286 @BASEBOARD_FAB2_LIB.BASEBOARD_FAB2(SCH_1):PAGE41
   EA6    GND @BASEBOARD_FAB2_LIB.BASEBOARD_FAB2(SCH_1):GND   I286 @BASEBOARD_FAB2_LIB.BASEBOARD_FAB2(SCH_1):PAGE41
   J16    GND @BASEBOARD_FAB2_LIB.BASEBOARD_FAB2(SCH_1):GND   I286 @BASEBOARD_FAB2_LIB.BASEBOARD_FAB2(SCH_1):PAGE41
  EA16    GND @BASEBOARD_FAB2_LIB.BASEBOARD_FAB2(SCH_1):GND   I286 @BASEBOARD_FAB2_LIB.BASEBOARD_FAB2(SCH_1):PAGE41
  EA20    GND @BASEBOARD_FAB2_LIB.BASEBOARD_FAB2(SCH_1):GND   I286 @BASEBOARD_FAB2_LIB.BASEBOARD_FAB2(SCH_1):PAGE41
  EA22    GND @BASEBOARD_FAB2_LIB.BASEBOARD_FAB2(SCH_1):GND   I286 @BASEBOARD_FAB2_LIB.BASEBOARD_FAB2(SCH_1):PAGE41
  EA42    GND @BASEBOARD_FAB2_LIB.BASEBOARD_FAB2(SCH_1):GND   I286 @BASEBOARD_FAB2_LIB.BASEBOARD_FAB2(SCH_1):PAGE41
  EA64    GND @BASEBOARD_FAB2_LIB.BASEBOARD_FAB2(SCH_1):GND   I286 @BASEBOARD_FAB2_LIB.BASEBOARD_FAB2(SCH_1):PAGE41
  EA70    GND @BASEBOARD_FAB2_LIB.BASEBOARD_FAB2(SCH_1):GND   I286 @BASEBOARD_FAB2_LIB.BASEBOARD_FAB2(SCH_1):PAGE41
  EA76    GND @BASEBOARD_FAB2_LIB.BASEBOARD_FAB2(SCH_1):GND   I286 @BASEBOARD_FAB2_LIB.BASEBOARD_FAB2(SCH_1):PAGE41
  EA78    GND @BASEBOARD_FAB2_LIB.BASEBOARD_FAB2(SCH_1):GND   I286 @BASEBOARD_FAB2_LIB.BASEBOARD_FAB2(SCH_1):PAGE41
  EA80    GND @BASEBOARD_FAB2_LIB.BASEBOARD_FAB2(SCH_1):GND   I286 @BASEBOARD_FAB2_LIB.BASEBOARD_FAB2(SCH_1):PAGE41
  EA82    GND @BASEBOARD_FAB2_LIB.BASEBOARD_FAB2(SCH_1):GND   I286 @BASEBOARD_FAB2_LIB.BASEBOARD_FAB2(SCH_1):PAGE41
  EB13    GND @BASEBOARD_FAB2_LIB.BASEBOARD_FAB2(SCH_1):GND   I286 @BASEBOARD_FAB2_LIB.BASEBOARD_FAB2(SCH_1):PAGE41
  BR18    GND @BASEBOARD_FAB2_LIB.BASEBOARD_FAB2(SCH_1):GND   I286 @BASEBOARD_FAB2_LIB.BASEBOARD_FAB2(SCH_1):PAGE41
  EB23    GND @BASEBOARD_FAB2_LIB.BASEBOARD_FAB2(SCH_1):GND   I286 @BASEBOARD_FAB2_LIB.BASEBOARD_FAB2(SCH_1):PAGE41
  EB25    GND @BASEBOARD_FAB2_LIB.BASEBOARD_FAB2(SCH_1):GND   I286 @BASEBOARD_FAB2_LIB.BASEBOARD_FAB2(SCH_1):PAGE41
  EB27    GND @BASEBOARD_FAB2_LIB.BASEBOARD_FAB2(SCH_1):GND   I286 @BASEBOARD_FAB2_LIB.BASEBOARD_FAB2(SCH_1):PAGE41
  EB29    GND @BASEBOARD_FAB2_LIB.BASEBOARD_FAB2(SCH_1):GND   I286 @BASEBOARD_FAB2_LIB.BASEBOARD_FAB2(SCH_1):PAGE41
  EB31    GND @BASEBOARD_FAB2_LIB.BASEBOARD_FAB2(SCH_1):GND   I286 @BASEBOARD_FAB2_LIB.BASEBOARD_FAB2(SCH_1):PAGE41
  EB33    GND @BASEBOARD_FAB2_LIB.BASEBOARD_FAB2(SCH_1):GND   I286 @BASEBOARD_FAB2_LIB.BASEBOARD_FAB2(SCH_1):PAGE41
  EB35    GND @BASEBOARD_FAB2_LIB.BASEBOARD_FAB2(SCH_1):GND   I286 @BASEBOARD_FAB2_LIB.BASEBOARD_FAB2(SCH_1):PAGE41
  EB37    GND @BASEBOARD_FAB2_LIB.BASEBOARD_FAB2(SCH_1):GND   I286 @BASEBOARD_FAB2_LIB.BASEBOARD_FAB2(SCH_1):PAGE41
  EB39    GND @BASEBOARD_FAB2_LIB.BASEBOARD_FAB2(SCH_1):GND   I286 @BASEBOARD_FAB2_LIB.BASEBOARD_FAB2(SCH_1):PAGE41
  EB41    GND @BASEBOARD_FAB2_LIB.BASEBOARD_FAB2(SCH_1):GND   I286 @BASEBOARD_FAB2_LIB.BASEBOARD_FAB2(SCH_1):PAGE41
  EB65    GND @BASEBOARD_FAB2_LIB.BASEBOARD_FAB2(SCH_1):GND   I286 @BASEBOARD_FAB2_LIB.BASEBOARD_FAB2(SCH_1):PAGE41
  EB69    GND @BASEBOARD_FAB2_LIB.BASEBOARD_FAB2(SCH_1):GND   I286 @BASEBOARD_FAB2_LIB.BASEBOARD_FAB2(SCH_1):PAGE41
  EC10    GND @BASEBOARD_FAB2_LIB.BASEBOARD_FAB2(SCH_1):GND   I286 @BASEBOARD_FAB2_LIB.BASEBOARD_FAB2(SCH_1):PAGE41
  EC70    GND @BASEBOARD_FAB2_LIB.BASEBOARD_FAB2(SCH_1):GND   I286 @BASEBOARD_FAB2_LIB.BASEBOARD_FAB2(SCH_1):PAGE41
  EC72    GND @BASEBOARD_FAB2_LIB.BASEBOARD_FAB2(SCH_1):GND   I286 @BASEBOARD_FAB2_LIB.BASEBOARD_FAB2(SCH_1):PAGE41
  EC74    GND @BASEBOARD_FAB2_LIB.BASEBOARD_FAB2(SCH_1):GND   I286 @BASEBOARD_FAB2_LIB.BASEBOARD_FAB2(SCH_1):PAGE41
  EC76    GND @BASEBOARD_FAB2_LIB.BASEBOARD_FAB2(SCH_1):GND   I286 @BASEBOARD_FAB2_LIB.BASEBOARD_FAB2(SCH_1):PAGE41
  ED11    GND @BASEBOARD_FAB2_LIB.BASEBOARD_FAB2(SCH_1):GND   I286 @BASEBOARD_FAB2_LIB.BASEBOARD_FAB2(SCH_1):PAGE41
  ED15    GND @BASEBOARD_FAB2_LIB.BASEBOARD_FAB2(SCH_1):GND   I286 @BASEBOARD_FAB2_LIB.BASEBOARD_FAB2(SCH_1):PAGE41
  ED23    GND @BASEBOARD_FAB2_LIB.BASEBOARD_FAB2(SCH_1):GND   I286 @BASEBOARD_FAB2_LIB.BASEBOARD_FAB2(SCH_1):PAGE41
  ED29    GND @BASEBOARD_FAB2_LIB.BASEBOARD_FAB2(SCH_1):GND   I286 @BASEBOARD_FAB2_LIB.BASEBOARD_FAB2(SCH_1):PAGE41
  ED35    GND @BASEBOARD_FAB2_LIB.BASEBOARD_FAB2(SCH_1):GND   I286 @BASEBOARD_FAB2_LIB.BASEBOARD_FAB2(SCH_1):PAGE41
  ED77    GND @BASEBOARD_FAB2_LIB.BASEBOARD_FAB2(SCH_1):GND   I286 @BASEBOARD_FAB2_LIB.BASEBOARD_FAB2(SCH_1):PAGE41
  EE24    GND @BASEBOARD_FAB2_LIB.BASEBOARD_FAB2(SCH_1):GND   I286 @BASEBOARD_FAB2_LIB.BASEBOARD_FAB2(SCH_1):PAGE41
  EE28    GND @BASEBOARD_FAB2_LIB.BASEBOARD_FAB2(SCH_1):GND   I286 @BASEBOARD_FAB2_LIB.BASEBOARD_FAB2(SCH_1):PAGE41
  EE30    GND @BASEBOARD_FAB2_LIB.BASEBOARD_FAB2(SCH_1):GND   I286 @BASEBOARD_FAB2_LIB.BASEBOARD_FAB2(SCH_1):PAGE41
  EE34    GND @BASEBOARD_FAB2_LIB.BASEBOARD_FAB2(SCH_1):GND   I286 @BASEBOARD_FAB2_LIB.BASEBOARD_FAB2(SCH_1):PAGE41
  EE36    GND @BASEBOARD_FAB2_LIB.BASEBOARD_FAB2(SCH_1):GND   I286 @BASEBOARD_FAB2_LIB.BASEBOARD_FAB2(SCH_1):PAGE41
  EE70    GND @BASEBOARD_FAB2_LIB.BASEBOARD_FAB2(SCH_1):GND   I286 @BASEBOARD_FAB2_LIB.BASEBOARD_FAB2(SCH_1):PAGE41
  EE76    GND @BASEBOARD_FAB2_LIB.BASEBOARD_FAB2(SCH_1):GND   I286 @BASEBOARD_FAB2_LIB.BASEBOARD_FAB2(SCH_1):PAGE41
  EE78    GND @BASEBOARD_FAB2_LIB.BASEBOARD_FAB2(SCH_1):GND   I286 @BASEBOARD_FAB2_LIB.BASEBOARD_FAB2(SCH_1):PAGE41
  EF71    GND @BASEBOARD_FAB2_LIB.BASEBOARD_FAB2(SCH_1):GND   I286 @BASEBOARD_FAB2_LIB.BASEBOARD_FAB2(SCH_1):PAGE41
  EF75    GND @BASEBOARD_FAB2_LIB.BASEBOARD_FAB2(SCH_1):GND   I286 @BASEBOARD_FAB2_LIB.BASEBOARD_FAB2(SCH_1):PAGE41
  EF79    GND @BASEBOARD_FAB2_LIB.BASEBOARD_FAB2(SCH_1):GND   I286 @BASEBOARD_FAB2_LIB.BASEBOARD_FAB2(SCH_1):PAGE41

U6F1 PCA9617_SSOP-IC,G81764-001-GNDA
     5 TP_SMB_DDR_ABC_EN @BASEBOARD_FAB2_LIB.BASEBOARD_FAB2(SCH_1):TP_SMB_DDR_ABC_EN    I15 @BASEBOARD_FAB2_LIB.BASEBOARD_FAB2(SCH_1):PAGE99
     2 SMB_DDR_ABC_SCL_G @BASEBOARD_FAB2_LIB.BASEBOARD_FAB2(SCH_1):SMB_DDR_ABC_SCL_G    I15 @BASEBOARD_FAB2_LIB.BASEBOARD_FAB2(SCH_1):PAGE99
     7 SMB_DDR_ABC_VPP_SCL_R @BASEBOARD_FAB2_LIB.BASEBOARD_FAB2(SCH_1):SMB_DDR_ABC_VPP_SCL_R    I15 @BASEBOARD_FAB2_LIB.BASEBOARD_FAB2(SCH_1):PAGE99
     3 SMB_DDR_ABC_SDA_G @BASEBOARD_FAB2_LIB.BASEBOARD_FAB2(SCH_1):SMB_DDR_ABC_SDA_G    I15 @BASEBOARD_FAB2_LIB.BASEBOARD_FAB2(SCH_1):PAGE99
     6 SMB_DDR_ABC_VPP_SDA_R @BASEBOARD_FAB2_LIB.BASEBOARD_FAB2(SCH_1):SMB_DDR_ABC_VPP_SDA_R    I15 @BASEBOARD_FAB2_LIB.BASEBOARD_FAB2(SCH_1):PAGE99
     1 PVCCIO_CPU0 @BASEBOARD_FAB2_LIB.BASEBOARD_FAB2(SCH_1):PVCCIO_CPU0    I15 @BASEBOARD_FAB2_LIB.BASEBOARD_FAB2(SCH_1):PAGE99
     8 PVPP_ABC @BASEBOARD_FAB2_LIB.BASEBOARD_FAB2(SCH_1):PVPP_ABC    I15 @BASEBOARD_FAB2_LIB.BASEBOARD_FAB2(SCH_1):PAGE99

U6M1 74CBTLV1G125_SMLF-IC,C88177-00A
     4 JTAG_MCP_CPU1_TDI_R @BASEBOARD_FAB2_LIB.BASEBOARD_FAB2(SCH_1):JTAG_MCP_CPU1_TDI_R   I190 @BASEBOARD_FAB2_LIB.BASEBOARD_FAB2(SCH_1):PAGE113
     1 FM_CPU1_PKGID1 @BASEBOARD_FAB2_LIB.BASEBOARD_FAB2(SCH_1):FM_CPU1_PKGID1   I190 @BASEBOARD_FAB2_LIB.BASEBOARD_FAB2(SCH_1):PAGE113
     2 P1V8_MCP_CPU1 @BASEBOARD_FAB2_LIB.BASEBOARD_FAB2(SCH_1):P1V8_MCP_CPU1   I190 @BASEBOARD_FAB2_LIB.BASEBOARD_FAB2(SCH_1):PAGE113

U6W1 TCA9555PWR-GP_DISCRET-GC1-TCA9A
     1 PCA9555_INT_N @BASEBOARD_FAB2_LIB.BASEBOARD_FAB2(SCH_1):PCA9555_INT_N   I120 @BASEBOARD_FAB2_LIB.BASEBOARD_FAB2(SCH_1):PAGE247
     2 PCA9555_A1 @BASEBOARD_FAB2_LIB.BASEBOARD_FAB2(SCH_1):PCA9555_A1   I120 @BASEBOARD_FAB2_LIB.BASEBOARD_FAB2(SCH_1):PAGE247
     3 PCA9555_A2 @BASEBOARD_FAB2_LIB.BASEBOARD_FAB2(SCH_1):PCA9555_A2   I120 @BASEBOARD_FAB2_LIB.BASEBOARD_FAB2(SCH_1):PAGE247
     4 LED_POSTCODE_0_R @BASEBOARD_FAB2_LIB.BASEBOARD_FAB2(SCH_1):LED_POSTCODE_0_R   I120 @BASEBOARD_FAB2_LIB.BASEBOARD_FAB2(SCH_1):PAGE247
     5 LED_POSTCODE_1_R @BASEBOARD_FAB2_LIB.BASEBOARD_FAB2(SCH_1):LED_POSTCODE_1_R   I120 @BASEBOARD_FAB2_LIB.BASEBOARD_FAB2(SCH_1):PAGE247
     6 LED_POSTCODE_2_R @BASEBOARD_FAB2_LIB.BASEBOARD_FAB2(SCH_1):LED_POSTCODE_2_R   I120 @BASEBOARD_FAB2_LIB.BASEBOARD_FAB2(SCH_1):PAGE247
     7 LED_POSTCODE_3_R @BASEBOARD_FAB2_LIB.BASEBOARD_FAB2(SCH_1):LED_POSTCODE_3_R   I120 @BASEBOARD_FAB2_LIB.BASEBOARD_FAB2(SCH_1):PAGE247
     8 LED_POSTCODE_4_R @BASEBOARD_FAB2_LIB.BASEBOARD_FAB2(SCH_1):LED_POSTCODE_4_R   I120 @BASEBOARD_FAB2_LIB.BASEBOARD_FAB2(SCH_1):PAGE247
     9 LED_POSTCODE_5_R @BASEBOARD_FAB2_LIB.BASEBOARD_FAB2(SCH_1):LED_POSTCODE_5_R   I120 @BASEBOARD_FAB2_LIB.BASEBOARD_FAB2(SCH_1):PAGE247
    10 LED_POSTCODE_6_R @BASEBOARD_FAB2_LIB.BASEBOARD_FAB2(SCH_1):LED_POSTCODE_6_R   I120 @BASEBOARD_FAB2_LIB.BASEBOARD_FAB2(SCH_1):PAGE247
    11 LED_POSTCODE_7_R @BASEBOARD_FAB2_LIB.BASEBOARD_FAB2(SCH_1):LED_POSTCODE_7_R   I120 @BASEBOARD_FAB2_LIB.BASEBOARD_FAB2(SCH_1):PAGE247
    12    GND @BASEBOARD_FAB2_LIB.BASEBOARD_FAB2(SCH_1):GND   I120 @BASEBOARD_FAB2_LIB.BASEBOARD_FAB2(SCH_1):PAGE247
    24 P3V3_STBY @BASEBOARD_FAB2_LIB.BASEBOARD_FAB2(SCH_1):P3V3_STBY   I120 @BASEBOARD_FAB2_LIB.BASEBOARD_FAB2(SCH_1):PAGE247
    23 SMB_DEBUG_STBY_LVC3_SDA @BASEBOARD_FAB2_LIB.BASEBOARD_FAB2(SCH_1):SMB_DEBUG_STBY_LVC3_SDA   I120 @BASEBOARD_FAB2_LIB.BASEBOARD_FAB2(SCH_1):PAGE247
    22 SMB_DEBUG_STBY_LVC3_SCL @BASEBOARD_FAB2_LIB.BASEBOARD_FAB2(SCH_1):SMB_DEBUG_STBY_LVC3_SCL   I120 @BASEBOARD_FAB2_LIB.BASEBOARD_FAB2(SCH_1):PAGE247
    21 PCA9555_A0 @BASEBOARD_FAB2_LIB.BASEBOARD_FAB2(SCH_1):PCA9555_A0   I120 @BASEBOARD_FAB2_LIB.BASEBOARD_FAB2(SCH_1):PAGE247
    13 FM_DEBUG_RST_BTN_N @BASEBOARD_FAB2_LIB.BASEBOARD_FAB2(SCH_1):FM_DEBUG_RST_BTN_N   I120 @BASEBOARD_FAB2_LIB.BASEBOARD_FAB2(SCH_1):PAGE247
    14 FP_PWR_BTN_R_N @BASEBOARD_FAB2_LIB.BASEBOARD_FAB2(SCH_1):FP_PWR_BTN_R_N   I120 @BASEBOARD_FAB2_LIB.BASEBOARD_FAB2(SCH_1):PAGE247
    15 PWRGD_SYS_PWROK @BASEBOARD_FAB2_LIB.BASEBOARD_FAB2(SCH_1):PWRGD_SYS_PWROK   I120 @BASEBOARD_FAB2_LIB.BASEBOARD_FAB2(SCH_1):PAGE247
    16 RST_PLTRST_N @BASEBOARD_FAB2_LIB.BASEBOARD_FAB2(SCH_1):RST_PLTRST_N   I120 @BASEBOARD_FAB2_LIB.BASEBOARD_FAB2(SCH_1):PAGE247
    17 PWRGD_DSW_PWROK @BASEBOARD_FAB2_LIB.BASEBOARD_FAB2(SCH_1):PWRGD_DSW_PWROK   I120 @BASEBOARD_FAB2_LIB.BASEBOARD_FAB2(SCH_1):PAGE247
    18 FM_CPU_CATERR_MSMI_LVT3_N @BASEBOARD_FAB2_LIB.BASEBOARD_FAB2(SCH_1):FM_CPU_CATERR_MSMI_LVT3_N   I120 @BASEBOARD_FAB2_LIB.BASEBOARD_FAB2(SCH_1):PAGE247
    19 FM_SLPS3_N @BASEBOARD_FAB2_LIB.BASEBOARD_FAB2(SCH_1):FM_SLPS3_N   I120 @BASEBOARD_FAB2_LIB.BASEBOARD_FAB2(SCH_1):PAGE247
    20 FM_UART_SWITCH_N @BASEBOARD_FAB2_LIB.BASEBOARD_FAB2(SCH_1):FM_UART_SWITCH_N   I120 @BASEBOARD_FAB2_LIB.BASEBOARD_FAB2(SCH_1):PAGE247

U6W2 TCA9517DGKR-GP_DISCRET-G8-TCA9A
     1 P3V3_STBY @BASEBOARD_FAB2_LIB.BASEBOARD_FAB2(SCH_1):P3V3_STBY   I118 @BASEBOARD_FAB2_LIB.BASEBOARD_FAB2(SCH_1):PAGE247
     2 SMB_PMBUS_BMC_STBY_LVC3_SCL_R1 @BASEBOARD_FAB2_LIB.BASEBOARD_FAB2(SCH_1):SMB_PMBUS_BMC_STBY_LVC3_SCL_R1   I118 @BASEBOARD_FAB2_LIB.BASEBOARD_FAB2(SCH_1):PAGE247
     3 SMB_PMBUS_BMC_STBY_LVC3_SDA_R1 @BASEBOARD_FAB2_LIB.BASEBOARD_FAB2(SCH_1):SMB_PMBUS_BMC_STBY_LVC3_SDA_R1   I118 @BASEBOARD_FAB2_LIB.BASEBOARD_FAB2(SCH_1):PAGE247
     4    GND @BASEBOARD_FAB2_LIB.BASEBOARD_FAB2(SCH_1):GND   I118 @BASEBOARD_FAB2_LIB.BASEBOARD_FAB2(SCH_1):PAGE247
     8 P3V3_STBY @BASEBOARD_FAB2_LIB.BASEBOARD_FAB2(SCH_1):P3V3_STBY   I118 @BASEBOARD_FAB2_LIB.BASEBOARD_FAB2(SCH_1):PAGE247
     7 SMB_BMC_PMBUS_STBY_LVC3_SCL @BASEBOARD_FAB2_LIB.BASEBOARD_FAB2(SCH_1):SMB_BMC_PMBUS_STBY_LVC3_SCL   I118 @BASEBOARD_FAB2_LIB.BASEBOARD_FAB2(SCH_1):PAGE247
     6 SMB_BMC_PMBUS_STBY_LVC3_SDA @BASEBOARD_FAB2_LIB.BASEBOARD_FAB2(SCH_1):SMB_BMC_PMBUS_STBY_LVC3_SDA   I118 @BASEBOARD_FAB2_LIB.BASEBOARD_FAB2(SCH_1):PAGE247
     5 HSC_SMBUS_SWITCH_EN @BASEBOARD_FAB2_LIB.BASEBOARD_FAB2(SCH_1):HSC_SMBUS_SWITCH_EN   I118 @BASEBOARD_FAB2_LIB.BASEBOARD_FAB2(SCH_1):PAGE247

U6W3 AT24C64_SOICLF-IC,C47049-001-GA
     1 PU_ID_EEPROM_A0 @BASEBOARD_FAB2_LIB.BASEBOARD_FAB2(SCH_1):PU_ID_EEPROM_A0    I89 @BASEBOARD_FAB2_LIB.BASEBOARD_FAB2(SCH_1):PAGE247
     2    GND @BASEBOARD_FAB2_LIB.BASEBOARD_FAB2(SCH_1):GND    I89 @BASEBOARD_FAB2_LIB.BASEBOARD_FAB2(SCH_1):PAGE247
     3    GND @BASEBOARD_FAB2_LIB.BASEBOARD_FAB2(SCH_1):GND    I89 @BASEBOARD_FAB2_LIB.BASEBOARD_FAB2(SCH_1):PAGE247
     6 SMB_HOST_STBY_LVC3_SCL_R3 @BASEBOARD_FAB2_LIB.BASEBOARD_FAB2(SCH_1):SMB_HOST_STBY_LVC3_SCL_R3    I89 @BASEBOARD_FAB2_LIB.BASEBOARD_FAB2(SCH_1):PAGE247
     7 PD_ID_EEPROM_WP @BASEBOARD_FAB2_LIB.BASEBOARD_FAB2(SCH_1):PD_ID_EEPROM_WP    I89 @BASEBOARD_FAB2_LIB.BASEBOARD_FAB2(SCH_1):PAGE247
     5 SMB_HOST_STBY_LVC3_SDA_R3 @BASEBOARD_FAB2_LIB.BASEBOARD_FAB2(SCH_1):SMB_HOST_STBY_LVC3_SDA_R3    I89 @BASEBOARD_FAB2_LIB.BASEBOARD_FAB2(SCH_1):PAGE247

U6W4 TTL1G126_A_SOT-74HC1G126,IC,A7B
     1 DEBUG_CARD2_PRSNT @BASEBOARD_FAB2_LIB.BASEBOARD_FAB2(SCH_1):DEBUG_CARD2_PRSNT   I146 @BASEBOARD_FAB2_LIB.BASEBOARD_FAB2(SCH_1):PAGE176
     2 SPA_MID_DBG2_RX @BASEBOARD_FAB2_LIB.BASEBOARD_FAB2(SCH_1):SPA_MID_DBG2_RX   I146 @BASEBOARD_FAB2_LIB.BASEBOARD_FAB2(SCH_1):PAGE176
     4 SPA_MID_DBG2_RX_BUF @BASEBOARD_FAB2_LIB.BASEBOARD_FAB2(SCH_1):SPA_MID_DBG2_RX_BUF   I146 @BASEBOARD_FAB2_LIB.BASEBOARD_FAB2(SCH_1):PAGE176

U6W5 TTL1G126_A_SOT-74HC1G126,IC,A7B
     1 DEBUG_CARD2_PRSNT @BASEBOARD_FAB2_LIB.BASEBOARD_FAB2(SCH_1):DEBUG_CARD2_PRSNT   I148 @BASEBOARD_FAB2_LIB.BASEBOARD_FAB2(SCH_1):PAGE176
     2 SPA_MID_DBG_TX @BASEBOARD_FAB2_LIB.BASEBOARD_FAB2(SCH_1):SPA_MID_DBG_TX   I148 @BASEBOARD_FAB2_LIB.BASEBOARD_FAB2(SCH_1):PAGE176
     4 SPA_MID_DBG2_TX_R @BASEBOARD_FAB2_LIB.BASEBOARD_FAB2(SCH_1):SPA_MID_DBG2_TX_R   I148 @BASEBOARD_FAB2_LIB.BASEBOARD_FAB2(SCH_1):PAGE176

U6W6 TTL1G126_A_SOT-74HC1G126,IC,A7B
     1 SPA_MID_DBG1_TX_EN @BASEBOARD_FAB2_LIB.BASEBOARD_FAB2(SCH_1):SPA_MID_DBG1_TX_EN   I157 @BASEBOARD_FAB2_LIB.BASEBOARD_FAB2(SCH_1):PAGE176
     2 SPA_MID_DBG_TX @BASEBOARD_FAB2_LIB.BASEBOARD_FAB2(SCH_1):SPA_MID_DBG_TX   I157 @BASEBOARD_FAB2_LIB.BASEBOARD_FAB2(SCH_1):PAGE176
     4 SPA_MID_DBG1_TX_R @BASEBOARD_FAB2_LIB.BASEBOARD_FAB2(SCH_1):SPA_MID_DBG1_TX_R   I157 @BASEBOARD_FAB2_LIB.BASEBOARD_FAB2(SCH_1):PAGE176

U6W11 PCA9554PWR-GP_DISCRET-G1-PCA95A
     1 PCA9554_A0 @BASEBOARD_FAB2_LIB.BASEBOARD_FAB2(SCH_1):PCA9554_A0    I97 @BASEBOARD_FAB2_LIB.BASEBOARD_FAB2(SCH_1):PAGE164
     2 PCA9554_A1 @BASEBOARD_FAB2_LIB.BASEBOARD_FAB2(SCH_1):PCA9554_A1    I97 @BASEBOARD_FAB2_LIB.BASEBOARD_FAB2(SCH_1):PAGE164
     3 PCA9554_A2 @BASEBOARD_FAB2_LIB.BASEBOARD_FAB2(SCH_1):PCA9554_A2    I97 @BASEBOARD_FAB2_LIB.BASEBOARD_FAB2(SCH_1):PAGE164
     4 FM_MB_SLOT_ID0 @BASEBOARD_FAB2_LIB.BASEBOARD_FAB2(SCH_1):FM_MB_SLOT_ID0    I97 @BASEBOARD_FAB2_LIB.BASEBOARD_FAB2(SCH_1):PAGE164
     5 FM_MB_SLOT_ID1 @BASEBOARD_FAB2_LIB.BASEBOARD_FAB2(SCH_1):FM_MB_SLOT_ID1    I97 @BASEBOARD_FAB2_LIB.BASEBOARD_FAB2(SCH_1):PAGE164
     6 FM_MB_SLOT_ID2 @BASEBOARD_FAB2_LIB.BASEBOARD_FAB2(SCH_1):FM_MB_SLOT_ID2    I97 @BASEBOARD_FAB2_LIB.BASEBOARD_FAB2(SCH_1):PAGE164
     7 FM_CPU_BMC_INIT @BASEBOARD_FAB2_LIB.BASEBOARD_FAB2(SCH_1):FM_CPU_BMC_INIT    I97 @BASEBOARD_FAB2_LIB.BASEBOARD_FAB2(SCH_1):PAGE164
     8    GND @BASEBOARD_FAB2_LIB.BASEBOARD_FAB2(SCH_1):GND    I97 @BASEBOARD_FAB2_LIB.BASEBOARD_FAB2(SCH_1):PAGE164
     9     NC     NC    I97 @BASEBOARD_FAB2_LIB.BASEBOARD_FAB2(SCH_1):PAGE164
    10     NC     NC    I97 @BASEBOARD_FAB2_LIB.BASEBOARD_FAB2(SCH_1):PAGE164
    11     NC     NC    I97 @BASEBOARD_FAB2_LIB.BASEBOARD_FAB2(SCH_1):PAGE164
    12     NC     NC    I97 @BASEBOARD_FAB2_LIB.BASEBOARD_FAB2(SCH_1):PAGE164
    13 PCA9554_INT_N @BASEBOARD_FAB2_LIB.BASEBOARD_FAB2(SCH_1):PCA9554_INT_N    I97 @BASEBOARD_FAB2_LIB.BASEBOARD_FAB2(SCH_1):PAGE164
    14 SMB_SENSOR_STBY_LVC3_SCL @BASEBOARD_FAB2_LIB.BASEBOARD_FAB2(SCH_1):SMB_SENSOR_STBY_LVC3_SCL    I97 @BASEBOARD_FAB2_LIB.BASEBOARD_FAB2(SCH_1):PAGE164
    15 SMB_SENSOR_STBY_LVC3_SDA @BASEBOARD_FAB2_LIB.BASEBOARD_FAB2(SCH_1):SMB_SENSOR_STBY_LVC3_SDA    I97 @BASEBOARD_FAB2_LIB.BASEBOARD_FAB2(SCH_1):PAGE164
    16 P3V3_STBY @BASEBOARD_FAB2_LIB.BASEBOARD_FAB2(SCH_1):P3V3_STBY    I97 @BASEBOARD_FAB2_LIB.BASEBOARD_FAB2(SCH_1):PAGE164

U6W12 NC7SB3157_SMLF-IC,C99406-001
     6 DEBUG_CARD2_PRSNT @BASEBOARD_FAB2_LIB.BASEBOARD_FAB2(SCH_1):DEBUG_CARD2_PRSNT   I182 @BASEBOARD_FAB2_LIB.BASEBOARD_FAB2(SCH_1):PAGE176
     3 SPA_MID_DBG1_RX @BASEBOARD_FAB2_LIB.BASEBOARD_FAB2(SCH_1):SPA_MID_DBG1_RX   I182 @BASEBOARD_FAB2_LIB.BASEBOARD_FAB2(SCH_1):PAGE176
     1 SPA_MID_DBG2_RX_BUF @BASEBOARD_FAB2_LIB.BASEBOARD_FAB2(SCH_1):SPA_MID_DBG2_RX_BUF   I182 @BASEBOARD_FAB2_LIB.BASEBOARD_FAB2(SCH_1):PAGE176
     4 SPA_MID_DBG_RX @BASEBOARD_FAB2_LIB.BASEBOARD_FAB2(SCH_1):SPA_MID_DBG_RX   I182 @BASEBOARD_FAB2_LIB.BASEBOARD_FAB2(SCH_1):PAGE176
     5 P3V3_STBY @BASEBOARD_FAB2_LIB.BASEBOARD_FAB2(SCH_1):P3V3_STBY   I182 @BASEBOARD_FAB2_LIB.BASEBOARD_FAB2(SCH_1):PAGE176
     2    GND @BASEBOARD_FAB2_LIB.BASEBOARD_FAB2(SCH_1):GND   I182 @BASEBOARD_FAB2_LIB.BASEBOARD_FAB2(SCH_1):PAGE176

U7C1 LBG_CORE_QAT_EXT_D_BGA1-IC,H91A
   A39 CLK_100M_PCH_XDP_DN @BASEBOARD_FAB2_LIB.BASEBOARD_FAB2(SCH_1):CLK_100M_PCH_XDP_DN    I40 @BASEBOARD_FAB2_LIB.BASEBOARD_FAB2(SCH_1):PAGE114
   C39 CLK_100M_PCH_XDP_DP @BASEBOARD_FAB2_LIB.BASEBOARD_FAB2(SCH_1):CLK_100M_PCH_XDP_DP    I40 @BASEBOARD_FAB2_LIB.BASEBOARD_FAB2(SCH_1):PAGE114
   A32 TP_CLK_100M_NSSCC0_DN @BASEBOARD_FAB2_LIB.BASEBOARD_FAB2(SCH_1):TP_CLK_100M_NSSCC0_DN    I40 @BASEBOARD_FAB2_LIB.BASEBOARD_FAB2(SCH_1):PAGE114
   C32 TP_CLK_100M_NSSCC0_DP @BASEBOARD_FAB2_LIB.BASEBOARD_FAB2(SCH_1):TP_CLK_100M_NSSCC0_DP    I40 @BASEBOARD_FAB2_LIB.BASEBOARD_FAB2(SCH_1):PAGE114
   B38 TP_CLK_100M_NSSCC1_DN @BASEBOARD_FAB2_LIB.BASEBOARD_FAB2(SCH_1):TP_CLK_100M_NSSCC1_DN    I40 @BASEBOARD_FAB2_LIB.BASEBOARD_FAB2(SCH_1):PAGE114
   D38 TP_CLK_100M_NSSCC1_DP @BASEBOARD_FAB2_LIB.BASEBOARD_FAB2(SCH_1):TP_CLK_100M_NSSCC1_DP    I40 @BASEBOARD_FAB2_LIB.BASEBOARD_FAB2(SCH_1):PAGE114
   B29 CLK_100M_BMC_PE_DN @BASEBOARD_FAB2_LIB.BASEBOARD_FAB2(SCH_1):CLK_100M_BMC_PE_DN    I40 @BASEBOARD_FAB2_LIB.BASEBOARD_FAB2(SCH_1):PAGE114
   D29 CLK_100M_BMC_PE_DP @BASEBOARD_FAB2_LIB.BASEBOARD_FAB2(SCH_1):CLK_100M_BMC_PE_DP    I40 @BASEBOARD_FAB2_LIB.BASEBOARD_FAB2(SCH_1):PAGE114
   B40 TP_CLK_100M_PLAT1_DN @BASEBOARD_FAB2_LIB.BASEBOARD_FAB2(SCH_1):TP_CLK_100M_PLAT1_DN    I40 @BASEBOARD_FAB2_LIB.BASEBOARD_FAB2(SCH_1):PAGE114
   D40 TP_CLK_100M_PLAT1_DP @BASEBOARD_FAB2_LIB.BASEBOARD_FAB2(SCH_1):TP_CLK_100M_PLAT1_DP    I40 @BASEBOARD_FAB2_LIB.BASEBOARD_FAB2(SCH_1):PAGE114
   K27 CLK_100M_M2_DN @BASEBOARD_FAB2_LIB.BASEBOARD_FAB2(SCH_1):CLK_100M_M2_DN    I40 @BASEBOARD_FAB2_LIB.BASEBOARD_FAB2(SCH_1):PAGE114
   C20 CLK_100M_SPRV_DN @BASEBOARD_FAB2_LIB.BASEBOARD_FAB2(SCH_1):CLK_100M_SPRV_DN    I40 @BASEBOARD_FAB2_LIB.BASEBOARD_FAB2(SCH_1):PAGE114
   C24     NC     NC    I40 @BASEBOARD_FAB2_LIB.BASEBOARD_FAB2(SCH_1):PAGE114
   K24     NC     NC    I40 @BASEBOARD_FAB2_LIB.BASEBOARD_FAB2(SCH_1):PAGE114
   B21 CLK_100M_MEZZ4_DN @BASEBOARD_FAB2_LIB.BASEBOARD_FAB2(SCH_1):CLK_100M_MEZZ4_DN    I40 @BASEBOARD_FAB2_LIB.BASEBOARD_FAB2(SCH_1):PAGE114
   B23 CLK_100M_MEZZ3_DN @BASEBOARD_FAB2_LIB.BASEBOARD_FAB2(SCH_1):CLK_100M_MEZZ3_DN    I40 @BASEBOARD_FAB2_LIB.BASEBOARD_FAB2(SCH_1):PAGE114
   J26 CLK_100M_MEZZ2_DN @BASEBOARD_FAB2_LIB.BASEBOARD_FAB2(SCH_1):CLK_100M_MEZZ2_DN    I40 @BASEBOARD_FAB2_LIB.BASEBOARD_FAB2(SCH_1):PAGE114
   D31 CLK_100M_MEZZ1_DN @BASEBOARD_FAB2_LIB.BASEBOARD_FAB2(SCH_1):CLK_100M_MEZZ1_DN    I40 @BASEBOARD_FAB2_LIB.BASEBOARD_FAB2(SCH_1):PAGE114
   H31 CLK_100M_PCH_SLOTX24_S5_DN @BASEBOARD_FAB2_LIB.BASEBOARD_FAB2(SCH_1):CLK_100M_PCH_SLOTX24_S5_DN    I40 @BASEBOARD_FAB2_LIB.BASEBOARD_FAB2(SCH_1):PAGE114
   D33 CLK_100M_PCH_SLOTX24_S4_DN @BASEBOARD_FAB2_LIB.BASEBOARD_FAB2(SCH_1):CLK_100M_PCH_SLOTX24_S4_DN    I40 @BASEBOARD_FAB2_LIB.BASEBOARD_FAB2(SCH_1):PAGE114
   J40 CLK_100M_PCH_SLOTX24_S3_DN @BASEBOARD_FAB2_LIB.BASEBOARD_FAB2(SCH_1):CLK_100M_PCH_SLOTX24_S3_DN    I40 @BASEBOARD_FAB2_LIB.BASEBOARD_FAB2(SCH_1):PAGE114
   A28 CLK_100M_PCH_SLOTX24_S2_DN @BASEBOARD_FAB2_LIB.BASEBOARD_FAB2(SCH_1):CLK_100M_PCH_SLOTX24_S2_DN    I40 @BASEBOARD_FAB2_LIB.BASEBOARD_FAB2(SCH_1):PAGE114
   K42 CLK_100M_PCH_SLOTX24_S1_DN @BASEBOARD_FAB2_LIB.BASEBOARD_FAB2(SCH_1):CLK_100M_PCH_SLOTX24_S1_DN    I40 @BASEBOARD_FAB2_LIB.BASEBOARD_FAB2(SCH_1):PAGE114
   J33 CLK_100M_PCH_SLOTX24_S0_DN @BASEBOARD_FAB2_LIB.BASEBOARD_FAB2(SCH_1):CLK_100M_PCH_SLOTX24_S0_DN    I40 @BASEBOARD_FAB2_LIB.BASEBOARD_FAB2(SCH_1):PAGE114
   K35 CLK_100M_DB1200_DN @BASEBOARD_FAB2_LIB.BASEBOARD_FAB2(SCH_1):CLK_100M_DB1200_DN    I40 @BASEBOARD_FAB2_LIB.BASEBOARD_FAB2(SCH_1):PAGE114
   K38 CLK_100M_AIRMAX8_PE1_DN @BASEBOARD_FAB2_LIB.BASEBOARD_FAB2(SCH_1):CLK_100M_AIRMAX8_PE1_DN    I40 @BASEBOARD_FAB2_LIB.BASEBOARD_FAB2(SCH_1):PAGE114
   H27 CLK_100M_M2_DP @BASEBOARD_FAB2_LIB.BASEBOARD_FAB2(SCH_1):CLK_100M_M2_DP    I40 @BASEBOARD_FAB2_LIB.BASEBOARD_FAB2(SCH_1):PAGE114
   A20 CLK_100M_SPRV_DP @BASEBOARD_FAB2_LIB.BASEBOARD_FAB2(SCH_1):CLK_100M_SPRV_DP    I40 @BASEBOARD_FAB2_LIB.BASEBOARD_FAB2(SCH_1):PAGE114
   A24     NC     NC    I40 @BASEBOARD_FAB2_LIB.BASEBOARD_FAB2(SCH_1):PAGE114
   H24     NC     NC    I40 @BASEBOARD_FAB2_LIB.BASEBOARD_FAB2(SCH_1):PAGE114
   D21 CLK_100M_MEZZ4_DP @BASEBOARD_FAB2_LIB.BASEBOARD_FAB2(SCH_1):CLK_100M_MEZZ4_DP    I40 @BASEBOARD_FAB2_LIB.BASEBOARD_FAB2(SCH_1):PAGE114
   D23 CLK_100M_MEZZ3_DP @BASEBOARD_FAB2_LIB.BASEBOARD_FAB2(SCH_1):CLK_100M_MEZZ3_DP    I40 @BASEBOARD_FAB2_LIB.BASEBOARD_FAB2(SCH_1):PAGE114
   G26 CLK_100M_MEZZ2_DP @BASEBOARD_FAB2_LIB.BASEBOARD_FAB2(SCH_1):CLK_100M_MEZZ2_DP    I40 @BASEBOARD_FAB2_LIB.BASEBOARD_FAB2(SCH_1):PAGE114
   B31 CLK_100M_MEZZ1_DP @BASEBOARD_FAB2_LIB.BASEBOARD_FAB2(SCH_1):CLK_100M_MEZZ1_DP    I40 @BASEBOARD_FAB2_LIB.BASEBOARD_FAB2(SCH_1):PAGE114
   K31 CLK_100M_PCH_SLOTX24_S5_DP @BASEBOARD_FAB2_LIB.BASEBOARD_FAB2(SCH_1):CLK_100M_PCH_SLOTX24_S5_DP    I40 @BASEBOARD_FAB2_LIB.BASEBOARD_FAB2(SCH_1):PAGE114
   B33 CLK_100M_PCH_SLOTX24_S4_DP @BASEBOARD_FAB2_LIB.BASEBOARD_FAB2(SCH_1):CLK_100M_PCH_SLOTX24_S4_DP    I40 @BASEBOARD_FAB2_LIB.BASEBOARD_FAB2(SCH_1):PAGE114
   G40 CLK_100M_PCH_SLOTX24_S3_DP @BASEBOARD_FAB2_LIB.BASEBOARD_FAB2(SCH_1):CLK_100M_PCH_SLOTX24_S3_DP    I40 @BASEBOARD_FAB2_LIB.BASEBOARD_FAB2(SCH_1):PAGE114
   C28 CLK_100M_PCH_SLOTX24_S2_DP @BASEBOARD_FAB2_LIB.BASEBOARD_FAB2(SCH_1):CLK_100M_PCH_SLOTX24_S2_DP    I40 @BASEBOARD_FAB2_LIB.BASEBOARD_FAB2(SCH_1):PAGE114
   H42 CLK_100M_PCH_SLOTX24_S1_DP @BASEBOARD_FAB2_LIB.BASEBOARD_FAB2(SCH_1):CLK_100M_PCH_SLOTX24_S1_DP    I40 @BASEBOARD_FAB2_LIB.BASEBOARD_FAB2(SCH_1):PAGE114
   G33 CLK_100M_PCH_SLOTX24_S0_DP @BASEBOARD_FAB2_LIB.BASEBOARD_FAB2(SCH_1):CLK_100M_PCH_SLOTX24_S0_DP    I40 @BASEBOARD_FAB2_LIB.BASEBOARD_FAB2(SCH_1):PAGE114
   H35 CLK_100M_DB1200_DP @BASEBOARD_FAB2_LIB.BASEBOARD_FAB2(SCH_1):CLK_100M_DB1200_DP    I40 @BASEBOARD_FAB2_LIB.BASEBOARD_FAB2(SCH_1):PAGE114
   H38 CLK_100M_AIRMAX8_PE1_DP @BASEBOARD_FAB2_LIB.BASEBOARD_FAB2(SCH_1):CLK_100M_AIRMAX8_PE1_DP    I40 @BASEBOARD_FAB2_LIB.BASEBOARD_FAB2(SCH_1):PAGE114
  BW50 CLK_48M_USB_BMC @BASEBOARD_FAB2_LIB.BASEBOARD_FAB2(SCH_1):CLK_48M_USB_BMC    I40 @BASEBOARD_FAB2_LIB.BASEBOARD_FAB2(SCH_1):PAGE114
  BY51 H_PMSYNC_CLK_24M_R @BASEBOARD_FAB2_LIB.BASEBOARD_FAB2(SCH_1):H_PMSYNC_CLK_24M_R    I40 @BASEBOARD_FAB2_LIB.BASEBOARD_FAB2(SCH_1):PAGE114
  BV51 TP_CLK_24M_PMSYNC2 @BASEBOARD_FAB2_LIB.BASEBOARD_FAB2(SCH_1):TP_CLK_24M_PMSYNC2    I40 @BASEBOARD_FAB2_LIB.BASEBOARD_FAB2(SCH_1):PAGE114
   A26 TP_PCH_RSVD65 @BASEBOARD_FAB2_LIB.BASEBOARD_FAB2(SCH_1):TP_PCH_RSVD65    I40 @BASEBOARD_FAB2_LIB.BASEBOARD_FAB2(SCH_1):PAGE114
   C26 TP_PCH_RSVD64 @BASEBOARD_FAB2_LIB.BASEBOARD_FAB2(SCH_1):TP_PCH_RSVD64    I40 @BASEBOARD_FAB2_LIB.BASEBOARD_FAB2(SCH_1):PAGE114
   K17 XTAL_33K_RTC1 @BASEBOARD_FAB2_LIB.BASEBOARD_FAB2(SCH_1):XTAL_33K_RTC1    I40 @BASEBOARD_FAB2_LIB.BASEBOARD_FAB2(SCH_1):PAGE114
   H17 XTAL_33K_RTC2 @BASEBOARD_FAB2_LIB.BASEBOARD_FAB2(SCH_1):XTAL_33K_RTC2    I40 @BASEBOARD_FAB2_LIB.BASEBOARD_FAB2(SCH_1):PAGE114
   G44 A_PCH_XCLK_BIASREF @BASEBOARD_FAB2_LIB.BASEBOARD_FAB2(SCH_1):A_PCH_XCLK_BIASREF    I40 @BASEBOARD_FAB2_LIB.BASEBOARD_FAB2(SCH_1):PAGE114
   B35 XTAL_PCH_48M_IN @BASEBOARD_FAB2_LIB.BASEBOARD_FAB2(SCH_1):XTAL_PCH_48M_IN    I40 @BASEBOARD_FAB2_LIB.BASEBOARD_FAB2(SCH_1):PAGE114
   D35 XTAL_PCH_48M_OUT @BASEBOARD_FAB2_LIB.BASEBOARD_FAB2(SCH_1):XTAL_PCH_48M_OUT    I40 @BASEBOARD_FAB2_LIB.BASEBOARD_FAB2(SCH_1):PAGE114
  BN68 TP_PCH_RSVD55 @BASEBOARD_FAB2_LIB.BASEBOARD_FAB2(SCH_1):TP_PCH_RSVD55    I74 @BASEBOARD_FAB2_LIB.BASEBOARD_FAB2(SCH_1):PAGE115
  BY60 USB2_P01_DN @BASEBOARD_FAB2_LIB.BASEBOARD_FAB2(SCH_1):USB2_P01_DN    I74 @BASEBOARD_FAB2_LIB.BASEBOARD_FAB2(SCH_1):PAGE115
  BW65 TP_USB2_P10_DN @BASEBOARD_FAB2_LIB.BASEBOARD_FAB2(SCH_1):TP_USB2_P10_DN    I74 @BASEBOARD_FAB2_LIB.BASEBOARD_FAB2(SCH_1):PAGE115
  CA54 TP_USB2_P11_DN @BASEBOARD_FAB2_LIB.BASEBOARD_FAB2(SCH_1):TP_USB2_P11_DN    I74 @BASEBOARD_FAB2_LIB.BASEBOARD_FAB2(SCH_1):PAGE115
  BW67 TP_USB2_P12_DN @BASEBOARD_FAB2_LIB.BASEBOARD_FAB2(SCH_1):TP_USB2_P12_DN    I74 @BASEBOARD_FAB2_LIB.BASEBOARD_FAB2(SCH_1):PAGE115
  BY53 TP_USB2_P13_DN @BASEBOARD_FAB2_LIB.BASEBOARD_FAB2(SCH_1):TP_USB2_P13_DN    I74 @BASEBOARD_FAB2_LIB.BASEBOARD_FAB2(SCH_1):PAGE115
  BW68 TP_USB2_P14_DN @BASEBOARD_FAB2_LIB.BASEBOARD_FAB2(SCH_1):TP_USB2_P14_DN    I74 @BASEBOARD_FAB2_LIB.BASEBOARD_FAB2(SCH_1):PAGE115
  CA61 USB2_P02_DN_R @BASEBOARD_FAB2_LIB.BASEBOARD_FAB2(SCH_1):USB2_P02_DN_R    I74 @BASEBOARD_FAB2_LIB.BASEBOARD_FAB2(SCH_1):PAGE115
  CA59 TP_USB2_P03_DN @BASEBOARD_FAB2_LIB.BASEBOARD_FAB2(SCH_1):TP_USB2_P03_DN    I74 @BASEBOARD_FAB2_LIB.BASEBOARD_FAB2(SCH_1):PAGE115
  BY62 USB_PCH_BMC_P4_DN_R @BASEBOARD_FAB2_LIB.BASEBOARD_FAB2(SCH_1):USB_PCH_BMC_P4_DN_R    I74 @BASEBOARD_FAB2_LIB.BASEBOARD_FAB2(SCH_1):PAGE115
  BY58 USB2_PCH_BMC_P5_DN_R @BASEBOARD_FAB2_LIB.BASEBOARD_FAB2(SCH_1):USB2_PCH_BMC_P5_DN_R    I74 @BASEBOARD_FAB2_LIB.BASEBOARD_FAB2(SCH_1):PAGE115
  CA63 TP_USB2_P06_DN @BASEBOARD_FAB2_LIB.BASEBOARD_FAB2(SCH_1):TP_USB2_P06_DN    I74 @BASEBOARD_FAB2_LIB.BASEBOARD_FAB2(SCH_1):PAGE115
  CA57 TP_USB2_P07_DN @BASEBOARD_FAB2_LIB.BASEBOARD_FAB2(SCH_1):TP_USB2_P07_DN    I74 @BASEBOARD_FAB2_LIB.BASEBOARD_FAB2(SCH_1):PAGE115
  BY64 TP_USB2_P8_DN @BASEBOARD_FAB2_LIB.BASEBOARD_FAB2(SCH_1):TP_USB2_P8_DN    I74 @BASEBOARD_FAB2_LIB.BASEBOARD_FAB2(SCH_1):PAGE115
  BY55 TP_USB2_P9_DN @BASEBOARD_FAB2_LIB.BASEBOARD_FAB2(SCH_1):TP_USB2_P9_DN    I74 @BASEBOARD_FAB2_LIB.BASEBOARD_FAB2(SCH_1):PAGE115
  BV60 USB2_P01_DP @BASEBOARD_FAB2_LIB.BASEBOARD_FAB2(SCH_1):USB2_P01_DP    I74 @BASEBOARD_FAB2_LIB.BASEBOARD_FAB2(SCH_1):PAGE115
  BU65 TP_USB2_P10_DP @BASEBOARD_FAB2_LIB.BASEBOARD_FAB2(SCH_1):TP_USB2_P10_DP    I74 @BASEBOARD_FAB2_LIB.BASEBOARD_FAB2(SCH_1):PAGE115
  BW54 TP_USB2_P11_DP @BASEBOARD_FAB2_LIB.BASEBOARD_FAB2(SCH_1):TP_USB2_P11_DP    I74 @BASEBOARD_FAB2_LIB.BASEBOARD_FAB2(SCH_1):PAGE115
  BV66 TP_USB2_P12_DP @BASEBOARD_FAB2_LIB.BASEBOARD_FAB2(SCH_1):TP_USB2_P12_DP    I74 @BASEBOARD_FAB2_LIB.BASEBOARD_FAB2(SCH_1):PAGE115
  BV53 TP_USB2_P13_DP @BASEBOARD_FAB2_LIB.BASEBOARD_FAB2(SCH_1):TP_USB2_P13_DP    I74 @BASEBOARD_FAB2_LIB.BASEBOARD_FAB2(SCH_1):PAGE115
  BU67 TP_USB2_P14_DP @BASEBOARD_FAB2_LIB.BASEBOARD_FAB2(SCH_1):TP_USB2_P14_DP    I74 @BASEBOARD_FAB2_LIB.BASEBOARD_FAB2(SCH_1):PAGE115
  BW61 USB2_P02_DP_R @BASEBOARD_FAB2_LIB.BASEBOARD_FAB2(SCH_1):USB2_P02_DP_R    I74 @BASEBOARD_FAB2_LIB.BASEBOARD_FAB2(SCH_1):PAGE115
  BW59 TP_USB2_P03_DP @BASEBOARD_FAB2_LIB.BASEBOARD_FAB2(SCH_1):TP_USB2_P03_DP    I74 @BASEBOARD_FAB2_LIB.BASEBOARD_FAB2(SCH_1):PAGE115
  BV62 USB_PCH_BMC_P4_DP_R @BASEBOARD_FAB2_LIB.BASEBOARD_FAB2(SCH_1):USB_PCH_BMC_P4_DP_R    I74 @BASEBOARD_FAB2_LIB.BASEBOARD_FAB2(SCH_1):PAGE115
  BV58 USB2_PCH_BMC_P5_DP_R @BASEBOARD_FAB2_LIB.BASEBOARD_FAB2(SCH_1):USB2_PCH_BMC_P5_DP_R    I74 @BASEBOARD_FAB2_LIB.BASEBOARD_FAB2(SCH_1):PAGE115
  BW63 TP_USB2_P06_DP @BASEBOARD_FAB2_LIB.BASEBOARD_FAB2(SCH_1):TP_USB2_P06_DP    I74 @BASEBOARD_FAB2_LIB.BASEBOARD_FAB2(SCH_1):PAGE115
  BW57 TP_USB2_P07_DP @BASEBOARD_FAB2_LIB.BASEBOARD_FAB2(SCH_1):TP_USB2_P07_DP    I74 @BASEBOARD_FAB2_LIB.BASEBOARD_FAB2(SCH_1):PAGE115
  BV64 TP_USB2_P8_DP @BASEBOARD_FAB2_LIB.BASEBOARD_FAB2(SCH_1):TP_USB2_P8_DP    I74 @BASEBOARD_FAB2_LIB.BASEBOARD_FAB2(SCH_1):PAGE115
  BV55 TP_USB2_P9_DP @BASEBOARD_FAB2_LIB.BASEBOARD_FAB2(SCH_1):TP_USB2_P9_DP    I74 @BASEBOARD_FAB2_LIB.BASEBOARD_FAB2(SCH_1):PAGE115
  BN70 A_USB2_COMP @BASEBOARD_FAB2_LIB.BASEBOARD_FAB2(SCH_1):A_USB2_COMP    I74 @BASEBOARD_FAB2_LIB.BASEBOARD_FAB2(SCH_1):PAGE115
  BR67 A_USB2_VBUS @BASEBOARD_FAB2_LIB.BASEBOARD_FAB2(SCH_1):A_USB2_VBUS    I74 @BASEBOARD_FAB2_LIB.BASEBOARD_FAB2(SCH_1):PAGE115
  BK71 USB3_P01_RXN @BASEBOARD_FAB2_LIB.BASEBOARD_FAB2(SCH_1):USB3_P01_RXN    I74 @BASEBOARD_FAB2_LIB.BASEBOARD_FAB2(SCH_1):PAGE115
  BK69 USB3_P01_RXP @BASEBOARD_FAB2_LIB.BASEBOARD_FAB2(SCH_1):USB3_P01_RXP    I74 @BASEBOARD_FAB2_LIB.BASEBOARD_FAB2(SCH_1):PAGE115
  BL52 USB3_P01_TXN @BASEBOARD_FAB2_LIB.BASEBOARD_FAB2(SCH_1):USB3_P01_TXN    I74 @BASEBOARD_FAB2_LIB.BASEBOARD_FAB2(SCH_1):PAGE115
  BK54 USB3_P01_TXP @BASEBOARD_FAB2_LIB.BASEBOARD_FAB2(SCH_1):USB3_P01_TXP    I74 @BASEBOARD_FAB2_LIB.BASEBOARD_FAB2(SCH_1):PAGE115
  BJ72 TP_USB3_P02_RXN @BASEBOARD_FAB2_LIB.BASEBOARD_FAB2(SCH_1):TP_USB3_P02_RXN    I74 @BASEBOARD_FAB2_LIB.BASEBOARD_FAB2(SCH_1):PAGE115
  BJ70 TP_USB3_P02_RXP @BASEBOARD_FAB2_LIB.BASEBOARD_FAB2(SCH_1):TP_USB3_P02_RXP    I74 @BASEBOARD_FAB2_LIB.BASEBOARD_FAB2(SCH_1):PAGE115
  BL56 TP_USB3_P02_TXN @BASEBOARD_FAB2_LIB.BASEBOARD_FAB2(SCH_1):TP_USB3_P02_TXN    I74 @BASEBOARD_FAB2_LIB.BASEBOARD_FAB2(SCH_1):PAGE115
  BJ56 TP_USB3_P02_TXP @BASEBOARD_FAB2_LIB.BASEBOARD_FAB2(SCH_1):TP_USB3_P02_TXP    I74 @BASEBOARD_FAB2_LIB.BASEBOARD_FAB2(SCH_1):PAGE115
  BH71 TP_USB3_P03_RXN @BASEBOARD_FAB2_LIB.BASEBOARD_FAB2(SCH_1):TP_USB3_P03_RXN    I74 @BASEBOARD_FAB2_LIB.BASEBOARD_FAB2(SCH_1):PAGE115
  BH69 TP_USB3_P03_RXP @BASEBOARD_FAB2_LIB.BASEBOARD_FAB2(SCH_1):TP_USB3_P03_RXP    I74 @BASEBOARD_FAB2_LIB.BASEBOARD_FAB2(SCH_1):PAGE115
  BM54 TP_USB3_P03_TXN @BASEBOARD_FAB2_LIB.BASEBOARD_FAB2(SCH_1):TP_USB3_P03_TXN    I74 @BASEBOARD_FAB2_LIB.BASEBOARD_FAB2(SCH_1):PAGE115
  BN56 TP_USB3_P03_TXP @BASEBOARD_FAB2_LIB.BASEBOARD_FAB2(SCH_1):TP_USB3_P03_TXP    I74 @BASEBOARD_FAB2_LIB.BASEBOARD_FAB2(SCH_1):PAGE115
  BF72 TP_USB3_P04_RXN @BASEBOARD_FAB2_LIB.BASEBOARD_FAB2(SCH_1):TP_USB3_P04_RXN    I74 @BASEBOARD_FAB2_LIB.BASEBOARD_FAB2(SCH_1):PAGE115
  BF70 TP_USB3_P04_RXP @BASEBOARD_FAB2_LIB.BASEBOARD_FAB2(SCH_1):TP_USB3_P04_RXP    I74 @BASEBOARD_FAB2_LIB.BASEBOARD_FAB2(SCH_1):PAGE115
  BH58 TP_USB3_P04_TXN @BASEBOARD_FAB2_LIB.BASEBOARD_FAB2(SCH_1):TP_USB3_P04_TXN    I74 @BASEBOARD_FAB2_LIB.BASEBOARD_FAB2(SCH_1):PAGE115
  BG56 TP_USB3_P04_TXP @BASEBOARD_FAB2_LIB.BASEBOARD_FAB2(SCH_1):TP_USB3_P04_TXP    I74 @BASEBOARD_FAB2_LIB.BASEBOARD_FAB2(SCH_1):PAGE115
  BE71 TP_USB3_P05_RXN @BASEBOARD_FAB2_LIB.BASEBOARD_FAB2(SCH_1):TP_USB3_P05_RXN    I74 @BASEBOARD_FAB2_LIB.BASEBOARD_FAB2(SCH_1):PAGE115
  BE69 TP_USB3_P05_RXP @BASEBOARD_FAB2_LIB.BASEBOARD_FAB2(SCH_1):TP_USB3_P05_RXP    I74 @BASEBOARD_FAB2_LIB.BASEBOARD_FAB2(SCH_1):PAGE115
  BK58 TP_USB3_P05_TXN @BASEBOARD_FAB2_LIB.BASEBOARD_FAB2(SCH_1):TP_USB3_P05_TXN    I74 @BASEBOARD_FAB2_LIB.BASEBOARD_FAB2(SCH_1):PAGE115
  BJ59 TP_USB3_P05_TXP @BASEBOARD_FAB2_LIB.BASEBOARD_FAB2(SCH_1):TP_USB3_P05_TXP    I74 @BASEBOARD_FAB2_LIB.BASEBOARD_FAB2(SCH_1):PAGE115
  BD72 TP_USB3_P06_RXN @BASEBOARD_FAB2_LIB.BASEBOARD_FAB2(SCH_1):TP_USB3_P06_RXN    I74 @BASEBOARD_FAB2_LIB.BASEBOARD_FAB2(SCH_1):PAGE115
  BD70 TP_USB3_P06_RXP @BASEBOARD_FAB2_LIB.BASEBOARD_FAB2(SCH_1):TP_USB3_P06_RXP    I74 @BASEBOARD_FAB2_LIB.BASEBOARD_FAB2(SCH_1):PAGE115
  BL59 TP_USB3_P06_TXN @BASEBOARD_FAB2_LIB.BASEBOARD_FAB2(SCH_1):TP_USB3_P06_TXN    I74 @BASEBOARD_FAB2_LIB.BASEBOARD_FAB2(SCH_1):PAGE115
  BM61 TP_USB3_P06_TXP @BASEBOARD_FAB2_LIB.BASEBOARD_FAB2(SCH_1):TP_USB3_P06_TXP    I74 @BASEBOARD_FAB2_LIB.BASEBOARD_FAB2(SCH_1):PAGE115
   D66 A_EXTCLKN @BASEBOARD_FAB2_LIB.BASEBOARD_FAB2(SCH_1):A_EXTCLKN   I220 @BASEBOARD_FAB2_LIB.BASEBOARD_FAB2(SCH_1):PAGE116
   E67 A_EXTCLKP @BASEBOARD_FAB2_LIB.BASEBOARD_FAB2(SCH_1):A_EXTCLKP   I220 @BASEBOARD_FAB2_LIB.BASEBOARD_FAB2(SCH_1):PAGE116
  AV63     NC     NC   I220 @BASEBOARD_FAB2_LIB.BASEBOARD_FAB2(SCH_1):PAGE116
  AU65     NC     NC   I220 @BASEBOARD_FAB2_LIB.BASEBOARD_FAB2(SCH_1):PAGE116
  AD70     NC     NC   I220 @BASEBOARD_FAB2_LIB.BASEBOARD_FAB2(SCH_1):PAGE116
  AD72     NC     NC   I220 @BASEBOARD_FAB2_LIB.BASEBOARD_FAB2(SCH_1):PAGE116
  AT66     NC     NC   I220 @BASEBOARD_FAB2_LIB.BASEBOARD_FAB2(SCH_1):PAGE116
  AV66     NC     NC   I220 @BASEBOARD_FAB2_LIB.BASEBOARD_FAB2(SCH_1):PAGE116
  AC69     NC     NC   I220 @BASEBOARD_FAB2_LIB.BASEBOARD_FAB2(SCH_1):PAGE116
  AC71     NC     NC   I220 @BASEBOARD_FAB2_LIB.BASEBOARD_FAB2(SCH_1):PAGE116
  AR61 SATA6G_PCH_PCIE_UP_SATA_RXN<0> @BASEBOARD_FAB2_LIB.BASEBOARD_FAB2(SCH_1):SATA6G_PCH_PCIE_UP_SATA_RXN(0)   I220 @BASEBOARD_FAB2_LIB.BASEBOARD_FAB2(SCH_1):PAGE116
  AT63 SATA6G_PCH_PCIE_UP_SATA_RXP<0> @BASEBOARD_FAB2_LIB.BASEBOARD_FAB2(SCH_1):SATA6G_PCH_PCIE_UP_SATA_RXP(0)   I220 @BASEBOARD_FAB2_LIB.BASEBOARD_FAB2(SCH_1):PAGE116
   W69 SATA6G_PCH_PCIE_UP_SATA_TXN<0> @BASEBOARD_FAB2_LIB.BASEBOARD_FAB2(SCH_1):SATA6G_PCH_PCIE_UP_SATA_TXN(0)   I220 @BASEBOARD_FAB2_LIB.BASEBOARD_FAB2(SCH_1):PAGE116
   W71 SATA6G_PCH_PCIE_UP_SATA_TXP<0> @BASEBOARD_FAB2_LIB.BASEBOARD_FAB2(SCH_1):SATA6G_PCH_PCIE_UP_SATA_TXP(0)   I220 @BASEBOARD_FAB2_LIB.BASEBOARD_FAB2(SCH_1):PAGE116
  AL66 SATA6G_PCH_PCIE_UP_SATA_RXN<1> @BASEBOARD_FAB2_LIB.BASEBOARD_FAB2(SCH_1):SATA6G_PCH_PCIE_UP_SATA_RXN(1)   I220 @BASEBOARD_FAB2_LIB.BASEBOARD_FAB2(SCH_1):PAGE116
  AN65 SATA6G_PCH_PCIE_UP_SATA_RXP<1> @BASEBOARD_FAB2_LIB.BASEBOARD_FAB2(SCH_1):SATA6G_PCH_PCIE_UP_SATA_RXP(1)   I220 @BASEBOARD_FAB2_LIB.BASEBOARD_FAB2(SCH_1):PAGE116
   V70 SATA6G_PCH_PCIE_UP_SATA_TXN<1> @BASEBOARD_FAB2_LIB.BASEBOARD_FAB2(SCH_1):SATA6G_PCH_PCIE_UP_SATA_TXN(1)   I220 @BASEBOARD_FAB2_LIB.BASEBOARD_FAB2(SCH_1):PAGE116
   V72 SATA6G_PCH_PCIE_UP_SATA_TXP<1> @BASEBOARD_FAB2_LIB.BASEBOARD_FAB2(SCH_1):SATA6G_PCH_PCIE_UP_SATA_TXP(1)   I220 @BASEBOARD_FAB2_LIB.BASEBOARD_FAB2(SCH_1):PAGE116
  AK65 SATA6G_PCH_PCIE_UP_SATA_RXN<2> @BASEBOARD_FAB2_LIB.BASEBOARD_FAB2(SCH_1):SATA6G_PCH_PCIE_UP_SATA_RXN(2)   I220 @BASEBOARD_FAB2_LIB.BASEBOARD_FAB2(SCH_1):PAGE116
  AJ63 SATA6G_PCH_PCIE_UP_SATA_RXP<2> @BASEBOARD_FAB2_LIB.BASEBOARD_FAB2(SCH_1):SATA6G_PCH_PCIE_UP_SATA_RXP(2)   I220 @BASEBOARD_FAB2_LIB.BASEBOARD_FAB2(SCH_1):PAGE116
   T69 SATA6G_PCH_PCIE_UP_SATA_TXN<2> @BASEBOARD_FAB2_LIB.BASEBOARD_FAB2(SCH_1):SATA6G_PCH_PCIE_UP_SATA_TXN(2)   I220 @BASEBOARD_FAB2_LIB.BASEBOARD_FAB2(SCH_1):PAGE116
   T71 SATA6G_PCH_PCIE_UP_SATA_TXP<2> @BASEBOARD_FAB2_LIB.BASEBOARD_FAB2(SCH_1):SATA6G_PCH_PCIE_UP_SATA_TXP(2)   I220 @BASEBOARD_FAB2_LIB.BASEBOARD_FAB2(SCH_1):PAGE116
  AP63 SATA6G_PCH_PCIE_UP_SATA_RXN<3> @BASEBOARD_FAB2_LIB.BASEBOARD_FAB2(SCH_1):SATA6G_PCH_PCIE_UP_SATA_RXN(3)   I220 @BASEBOARD_FAB2_LIB.BASEBOARD_FAB2(SCH_1):PAGE116
  AL63 SATA6G_PCH_PCIE_UP_SATA_RXP<3> @BASEBOARD_FAB2_LIB.BASEBOARD_FAB2(SCH_1):SATA6G_PCH_PCIE_UP_SATA_RXP(3)   I220 @BASEBOARD_FAB2_LIB.BASEBOARD_FAB2(SCH_1):PAGE116
   R70 SATA6G_PCH_PCIE_UP_SATA_TXN<3> @BASEBOARD_FAB2_LIB.BASEBOARD_FAB2(SCH_1):SATA6G_PCH_PCIE_UP_SATA_TXN(3)   I220 @BASEBOARD_FAB2_LIB.BASEBOARD_FAB2(SCH_1):PAGE116
   R72 SATA6G_PCH_PCIE_UP_SATA_TXP<3> @BASEBOARD_FAB2_LIB.BASEBOARD_FAB2(SCH_1):SATA6G_PCH_PCIE_UP_SATA_TXP(3)   I220 @BASEBOARD_FAB2_LIB.BASEBOARD_FAB2(SCH_1):PAGE116
  AF65 SATA6G_PCH_PCIE_UP_SATA_RXN<4> @BASEBOARD_FAB2_LIB.BASEBOARD_FAB2(SCH_1):SATA6G_PCH_PCIE_UP_SATA_RXN(4)   I220 @BASEBOARD_FAB2_LIB.BASEBOARD_FAB2(SCH_1):PAGE116
  AH65 SATA6G_PCH_PCIE_UP_SATA_RXP<4> @BASEBOARD_FAB2_LIB.BASEBOARD_FAB2(SCH_1):SATA6G_PCH_PCIE_UP_SATA_RXP(4)   I220 @BASEBOARD_FAB2_LIB.BASEBOARD_FAB2(SCH_1):PAGE116
   P69 SATA6G_PCH_PCIE_UP_SATA_TXN<4> @BASEBOARD_FAB2_LIB.BASEBOARD_FAB2(SCH_1):SATA6G_PCH_PCIE_UP_SATA_TXN(4)   I220 @BASEBOARD_FAB2_LIB.BASEBOARD_FAB2(SCH_1):PAGE116
   P71 SATA6G_PCH_PCIE_UP_SATA_TXP<4> @BASEBOARD_FAB2_LIB.BASEBOARD_FAB2(SCH_1):SATA6G_PCH_PCIE_UP_SATA_TXP(4)   I220 @BASEBOARD_FAB2_LIB.BASEBOARD_FAB2(SCH_1):PAGE116
  AH61 SATA6G_PCH_PCIE_UP_SATA_RXN<5> @BASEBOARD_FAB2_LIB.BASEBOARD_FAB2(SCH_1):SATA6G_PCH_PCIE_UP_SATA_RXN(5)   I220 @BASEBOARD_FAB2_LIB.BASEBOARD_FAB2(SCH_1):PAGE116
  AG63 SATA6G_PCH_PCIE_UP_SATA_RXP<5> @BASEBOARD_FAB2_LIB.BASEBOARD_FAB2(SCH_1):SATA6G_PCH_PCIE_UP_SATA_RXP(5)   I220 @BASEBOARD_FAB2_LIB.BASEBOARD_FAB2(SCH_1):PAGE116
   N70 SATA6G_PCH_PCIE_UP_SATA_TXN<5> @BASEBOARD_FAB2_LIB.BASEBOARD_FAB2(SCH_1):SATA6G_PCH_PCIE_UP_SATA_TXN(5)   I220 @BASEBOARD_FAB2_LIB.BASEBOARD_FAB2(SCH_1):PAGE116
   N72 SATA6G_PCH_PCIE_UP_SATA_TXP<5> @BASEBOARD_FAB2_LIB.BASEBOARD_FAB2(SCH_1):SATA6G_PCH_PCIE_UP_SATA_TXP(5)   I220 @BASEBOARD_FAB2_LIB.BASEBOARD_FAB2(SCH_1):PAGE116
  AP59 SATA6G_PCH_PCIE_UP_SATA_RXN<6> @BASEBOARD_FAB2_LIB.BASEBOARD_FAB2(SCH_1):SATA6G_PCH_PCIE_UP_SATA_RXN(6)   I220 @BASEBOARD_FAB2_LIB.BASEBOARD_FAB2(SCH_1):PAGE116
  AN61 SATA6G_PCH_PCIE_UP_SATA_RXP<6> @BASEBOARD_FAB2_LIB.BASEBOARD_FAB2(SCH_1):SATA6G_PCH_PCIE_UP_SATA_RXP(6)   I220 @BASEBOARD_FAB2_LIB.BASEBOARD_FAB2(SCH_1):PAGE116
   M69 SATA6G_PCH_PCIE_UP_SATA_TXN<6> @BASEBOARD_FAB2_LIB.BASEBOARD_FAB2(SCH_1):SATA6G_PCH_PCIE_UP_SATA_TXN(6)   I220 @BASEBOARD_FAB2_LIB.BASEBOARD_FAB2(SCH_1):PAGE116
   M71 SATA6G_PCH_PCIE_UP_SATA_TXP<6> @BASEBOARD_FAB2_LIB.BASEBOARD_FAB2(SCH_1):SATA6G_PCH_PCIE_UP_SATA_TXP(6)   I220 @BASEBOARD_FAB2_LIB.BASEBOARD_FAB2(SCH_1):PAGE116
  AA61 SATA6G_PCH_PCIE_UP_SATA_RXN<7> @BASEBOARD_FAB2_LIB.BASEBOARD_FAB2(SCH_1):SATA6G_PCH_PCIE_UP_SATA_RXN(7)   I220 @BASEBOARD_FAB2_LIB.BASEBOARD_FAB2(SCH_1):PAGE116
  AD61 SATA6G_PCH_PCIE_UP_SATA_RXP<7> @BASEBOARD_FAB2_LIB.BASEBOARD_FAB2(SCH_1):SATA6G_PCH_PCIE_UP_SATA_RXP(7)   I220 @BASEBOARD_FAB2_LIB.BASEBOARD_FAB2(SCH_1):PAGE116
   L70 SATA6G_PCH_PCIE_UP_SATA_TXN<7> @BASEBOARD_FAB2_LIB.BASEBOARD_FAB2(SCH_1):SATA6G_PCH_PCIE_UP_SATA_TXN(7)   I220 @BASEBOARD_FAB2_LIB.BASEBOARD_FAB2(SCH_1):PAGE116
   L72 SATA6G_PCH_PCIE_UP_SATA_TXP<7> @BASEBOARD_FAB2_LIB.BASEBOARD_FAB2(SCH_1):SATA6G_PCH_PCIE_UP_SATA_TXP(7)   I220 @BASEBOARD_FAB2_LIB.BASEBOARD_FAB2(SCH_1):PAGE116
  AN70 P2E_SSB_BMC_RX_C_DN @BASEBOARD_FAB2_LIB.BASEBOARD_FAB2(SCH_1):P2E_SSB_BMC_RX_C_DN   I220 @BASEBOARD_FAB2_LIB.BASEBOARD_FAB2(SCH_1):PAGE116
  AN72 P2E_SSB_BMC_RX_C_DP @BASEBOARD_FAB2_LIB.BASEBOARD_FAB2(SCH_1):P2E_SSB_BMC_RX_C_DP   I220 @BASEBOARD_FAB2_LIB.BASEBOARD_FAB2(SCH_1):PAGE116
  BG66 P2E_SSB_BMC_TX_DN @BASEBOARD_FAB2_LIB.BASEBOARD_FAB2(SCH_1):P2E_SSB_BMC_TX_DN   I220 @BASEBOARD_FAB2_LIB.BASEBOARD_FAB2(SCH_1):PAGE116
  BJ66 P2E_SSB_BMC_TX_DP @BASEBOARD_FAB2_LIB.BASEBOARD_FAB2(SCH_1):P2E_SSB_BMC_TX_DP   I220 @BASEBOARD_FAB2_LIB.BASEBOARD_FAB2(SCH_1):PAGE116
  AM69 PE_PCH_SPRV_RX_C_DN @BASEBOARD_FAB2_LIB.BASEBOARD_FAB2(SCH_1):PE_PCH_SPRV_RX_C_DN   I220 @BASEBOARD_FAB2_LIB.BASEBOARD_FAB2(SCH_1):PAGE116
  AM71 PE_PCH_SPRV_RX_C_DP @BASEBOARD_FAB2_LIB.BASEBOARD_FAB2(SCH_1):PE_PCH_SPRV_RX_C_DP   I220 @BASEBOARD_FAB2_LIB.BASEBOARD_FAB2(SCH_1):PAGE116
  BH65 PE_PCH_SPRV_TX_DN @BASEBOARD_FAB2_LIB.BASEBOARD_FAB2(SCH_1):PE_PCH_SPRV_TX_DN   I220 @BASEBOARD_FAB2_LIB.BASEBOARD_FAB2(SCH_1):PAGE116
  BJ63 PE_PCH_SPRV_TX_DP @BASEBOARD_FAB2_LIB.BASEBOARD_FAB2(SCH_1):PE_PCH_SPRV_TX_DP   I220 @BASEBOARD_FAB2_LIB.BASEBOARD_FAB2(SCH_1):PAGE116
  BB63 SATA6G_S0_RX_DN @BASEBOARD_FAB2_LIB.BASEBOARD_FAB2(SCH_1):SATA6G_S0_RX_DN   I220 @BASEBOARD_FAB2_LIB.BASEBOARD_FAB2(SCH_1):PAGE116
  BD61 SATA6G_S0_RX_DP @BASEBOARD_FAB2_LIB.BASEBOARD_FAB2(SCH_1):SATA6G_S0_RX_DP   I220 @BASEBOARD_FAB2_LIB.BASEBOARD_FAB2(SCH_1):PAGE116
  AJ70 SATA6G_S0_TX_DN @BASEBOARD_FAB2_LIB.BASEBOARD_FAB2(SCH_1):SATA6G_S0_TX_DN   I220 @BASEBOARD_FAB2_LIB.BASEBOARD_FAB2(SCH_1):PAGE116
  AJ72 SATA6G_S0_TX_DP @BASEBOARD_FAB2_LIB.BASEBOARD_FAB2(SCH_1):SATA6G_S0_TX_DP   I220 @BASEBOARD_FAB2_LIB.BASEBOARD_FAB2(SCH_1):PAGE116
  AY59 SATA6G_S1_RX_DN @BASEBOARD_FAB2_LIB.BASEBOARD_FAB2(SCH_1):SATA6G_S1_RX_DN   I220 @BASEBOARD_FAB2_LIB.BASEBOARD_FAB2(SCH_1):PAGE116
  BA61 SATA6G_S1_RX_DP @BASEBOARD_FAB2_LIB.BASEBOARD_FAB2(SCH_1):SATA6G_S1_RX_DP   I220 @BASEBOARD_FAB2_LIB.BASEBOARD_FAB2(SCH_1):PAGE116
  AH69 SATA6G_S1_TX_DN @BASEBOARD_FAB2_LIB.BASEBOARD_FAB2(SCH_1):SATA6G_S1_TX_DN   I220 @BASEBOARD_FAB2_LIB.BASEBOARD_FAB2(SCH_1):PAGE116
  AH71 SATA6G_S1_TX_DP @BASEBOARD_FAB2_LIB.BASEBOARD_FAB2(SCH_1):SATA6G_S1_TX_DP   I220 @BASEBOARD_FAB2_LIB.BASEBOARD_FAB2(SCH_1):PAGE116
  BA65     NC     NC   I220 @BASEBOARD_FAB2_LIB.BASEBOARD_FAB2(SCH_1):PAGE116
  BD65     NC     NC   I220 @BASEBOARD_FAB2_LIB.BASEBOARD_FAB2(SCH_1):PAGE116
  AF70     NC     NC   I220 @BASEBOARD_FAB2_LIB.BASEBOARD_FAB2(SCH_1):PAGE116
  AF72     NC     NC   I220 @BASEBOARD_FAB2_LIB.BASEBOARD_FAB2(SCH_1):PAGE116
  AW65     NC     NC   I220 @BASEBOARD_FAB2_LIB.BASEBOARD_FAB2(SCH_1):PAGE116
  AY66     NC     NC   I220 @BASEBOARD_FAB2_LIB.BASEBOARD_FAB2(SCH_1):PAGE116
  AE69     NC     NC   I220 @BASEBOARD_FAB2_LIB.BASEBOARD_FAB2(SCH_1):PAGE116
  AE71     NC     NC   I220 @BASEBOARD_FAB2_LIB.BASEBOARD_FAB2(SCH_1):PAGE116
  AF58 A_PCIEUP_RCOMP_N @BASEBOARD_FAB2_LIB.BASEBOARD_FAB2(SCH_1):A_PCIEUP_RCOMP_N   I220 @BASEBOARD_FAB2_LIB.BASEBOARD_FAB2(SCH_1):PAGE116
  AH58 A_PCIEUP_RCOMP_P @BASEBOARD_FAB2_LIB.BASEBOARD_FAB2(SCH_1):A_PCIEUP_RCOMP_P   I220 @BASEBOARD_FAB2_LIB.BASEBOARD_FAB2(SCH_1):PAGE116
  BD58 A_PCIE_RCOMP_N @BASEBOARD_FAB2_LIB.BASEBOARD_FAB2(SCH_1):A_PCIE_RCOMP_N   I220 @BASEBOARD_FAB2_LIB.BASEBOARD_FAB2(SCH_1):PAGE116
  BB56 A_PCIE_RCOMP_P @BASEBOARD_FAB2_LIB.BASEBOARD_FAB2(SCH_1):A_PCIE_RCOMP_P   I220 @BASEBOARD_FAB2_LIB.BASEBOARD_FAB2(SCH_1):PAGE116
  AA71 TP_PCH_RSVD52 @BASEBOARD_FAB2_LIB.BASEBOARD_FAB2(SCH_1):TP_PCH_RSVD52   I220 @BASEBOARD_FAB2_LIB.BASEBOARD_FAB2(SCH_1):PAGE116
  AA69 TP_PCH_RSVD51 @BASEBOARD_FAB2_LIB.BASEBOARD_FAB2(SCH_1):TP_PCH_RSVD51   I220 @BASEBOARD_FAB2_LIB.BASEBOARD_FAB2(SCH_1):PAGE116
   H69 TP_PCH_RSVD50 @BASEBOARD_FAB2_LIB.BASEBOARD_FAB2(SCH_1):TP_PCH_RSVD50   I220 @BASEBOARD_FAB2_LIB.BASEBOARD_FAB2(SCH_1):PAGE116
   G67 TP_PCH_RSVD49 @BASEBOARD_FAB2_LIB.BASEBOARD_FAB2(SCH_1):TP_PCH_RSVD49   I220 @BASEBOARD_FAB2_LIB.BASEBOARD_FAB2(SCH_1):PAGE116
  AP71 TP_PCH_RSVD48 @BASEBOARD_FAB2_LIB.BASEBOARD_FAB2(SCH_1):TP_PCH_RSVD48   I220 @BASEBOARD_FAB2_LIB.BASEBOARD_FAB2(SCH_1):PAGE116
  AP69 TP_PCH_RSVD47 @BASEBOARD_FAB2_LIB.BASEBOARD_FAB2(SCH_1):TP_PCH_RSVD47   I220 @BASEBOARD_FAB2_LIB.BASEBOARD_FAB2(SCH_1):PAGE116
  AV72 P3E_PCH_M2_RX_DN<3> @BASEBOARD_FAB2_LIB.BASEBOARD_FAB2(SCH_1):P3E_PCH_M2_RX_DN(3)   I220 @BASEBOARD_FAB2_LIB.BASEBOARD_FAB2(SCH_1):PAGE116
  AV70 P3E_PCH_M2_RX_DP<3> @BASEBOARD_FAB2_LIB.BASEBOARD_FAB2(SCH_1):P3E_PCH_M2_RX_DP(3)   I220 @BASEBOARD_FAB2_LIB.BASEBOARD_FAB2(SCH_1):PAGE116
  BH61 P3E_PCH_M2_TX_DN<3> @BASEBOARD_FAB2_LIB.BASEBOARD_FAB2(SCH_1):P3E_PCH_M2_TX_DN(3)   I220 @BASEBOARD_FAB2_LIB.BASEBOARD_FAB2(SCH_1):PAGE116
  BK61 P3E_PCH_M2_TX_DP<3> @BASEBOARD_FAB2_LIB.BASEBOARD_FAB2(SCH_1):P3E_PCH_M2_TX_DP(3)   I220 @BASEBOARD_FAB2_LIB.BASEBOARD_FAB2(SCH_1):PAGE116
  BA71 P3E_PCH_RX_0_DN @BASEBOARD_FAB2_LIB.BASEBOARD_FAB2(SCH_1):P3E_PCH_RX_0_DN   I220 @BASEBOARD_FAB2_LIB.BASEBOARD_FAB2(SCH_1):PAGE116
  BA69 P3E_PCH_RX_0_DP @BASEBOARD_FAB2_LIB.BASEBOARD_FAB2(SCH_1):P3E_PCH_RX_0_DP   I220 @BASEBOARD_FAB2_LIB.BASEBOARD_FAB2(SCH_1):PAGE116
  BR61 P3E_PCH_TX_0_DN @BASEBOARD_FAB2_LIB.BASEBOARD_FAB2(SCH_1):P3E_PCH_TX_0_DN   I220 @BASEBOARD_FAB2_LIB.BASEBOARD_FAB2(SCH_1):PAGE116
  BN63 P3E_PCH_TX_0_DP @BASEBOARD_FAB2_LIB.BASEBOARD_FAB2(SCH_1):P3E_PCH_TX_0_DP   I220 @BASEBOARD_FAB2_LIB.BASEBOARD_FAB2(SCH_1):PAGE116
  AY72 P3E_PCH_M2_RX_DN<1> @BASEBOARD_FAB2_LIB.BASEBOARD_FAB2(SCH_1):P3E_PCH_M2_RX_DN(1)   I220 @BASEBOARD_FAB2_LIB.BASEBOARD_FAB2(SCH_1):PAGE116
  AY70 P3E_PCH_M2_RX_DP<1> @BASEBOARD_FAB2_LIB.BASEBOARD_FAB2(SCH_1):P3E_PCH_M2_RX_DP(1)   I220 @BASEBOARD_FAB2_LIB.BASEBOARD_FAB2(SCH_1):PAGE116
  BM65 P3E_PCH_M2_TX_DN<1> @BASEBOARD_FAB2_LIB.BASEBOARD_FAB2(SCH_1):P3E_PCH_M2_TX_DN(1)   I220 @BASEBOARD_FAB2_LIB.BASEBOARD_FAB2(SCH_1):PAGE116
  BR65 P3E_PCH_M2_TX_DP<1> @BASEBOARD_FAB2_LIB.BASEBOARD_FAB2(SCH_1):P3E_PCH_M2_TX_DP(1)   I220 @BASEBOARD_FAB2_LIB.BASEBOARD_FAB2(SCH_1):PAGE116
  AW71 P3E_PCH_M2_RX_DN<2> @BASEBOARD_FAB2_LIB.BASEBOARD_FAB2(SCH_1):P3E_PCH_M2_RX_DN(2)   I220 @BASEBOARD_FAB2_LIB.BASEBOARD_FAB2(SCH_1):PAGE116
  AW69 P3E_PCH_M2_RX_DP<2> @BASEBOARD_FAB2_LIB.BASEBOARD_FAB2(SCH_1):P3E_PCH_M2_RX_DP(2)   I220 @BASEBOARD_FAB2_LIB.BASEBOARD_FAB2(SCH_1):PAGE116
  BK65 P3E_PCH_M2_TX_DN<2> @BASEBOARD_FAB2_LIB.BASEBOARD_FAB2(SCH_1):P3E_PCH_M2_TX_DN(2)   I220 @BASEBOARD_FAB2_LIB.BASEBOARD_FAB2(SCH_1):PAGE116
  BL66 P3E_PCH_M2_TX_DP<2> @BASEBOARD_FAB2_LIB.BASEBOARD_FAB2(SCH_1):P3E_PCH_M2_TX_DP(2)   I220 @BASEBOARD_FAB2_LIB.BASEBOARD_FAB2(SCH_1):PAGE116
   C45 DMI_CPU0_PCH_TX_C_DN<3> @BASEBOARD_FAB2_LIB.BASEBOARD_FAB2(SCH_1):DMI_CPU0_PCH_TX_C_DN(3)     I9 @BASEBOARD_FAB2_LIB.BASEBOARD_FAB2(SCH_1):PAGE117
   D44 DMI_CPU0_PCH_TX_C_DN<2> @BASEBOARD_FAB2_LIB.BASEBOARD_FAB2(SCH_1):DMI_CPU0_PCH_TX_C_DN(2)     I9 @BASEBOARD_FAB2_LIB.BASEBOARD_FAB2(SCH_1):PAGE117
   C43 DMI_CPU0_PCH_TX_C_DN<1> @BASEBOARD_FAB2_LIB.BASEBOARD_FAB2(SCH_1):DMI_CPU0_PCH_TX_C_DN(1)     I9 @BASEBOARD_FAB2_LIB.BASEBOARD_FAB2(SCH_1):PAGE117
   D42 DMI_CPU0_PCH_TX_C_DN<0> @BASEBOARD_FAB2_LIB.BASEBOARD_FAB2(SCH_1):DMI_CPU0_PCH_TX_C_DN(0)     I9 @BASEBOARD_FAB2_LIB.BASEBOARD_FAB2(SCH_1):PAGE117
   A45 DMI_CPU0_PCH_TX_C_DP<3> @BASEBOARD_FAB2_LIB.BASEBOARD_FAB2(SCH_1):DMI_CPU0_PCH_TX_C_DP(3)     I9 @BASEBOARD_FAB2_LIB.BASEBOARD_FAB2(SCH_1):PAGE117
   B44 DMI_CPU0_PCH_TX_C_DP<2> @BASEBOARD_FAB2_LIB.BASEBOARD_FAB2(SCH_1):DMI_CPU0_PCH_TX_C_DP(2)     I9 @BASEBOARD_FAB2_LIB.BASEBOARD_FAB2(SCH_1):PAGE117
   A43 DMI_CPU0_PCH_TX_C_DP<1> @BASEBOARD_FAB2_LIB.BASEBOARD_FAB2(SCH_1):DMI_CPU0_PCH_TX_C_DP(1)     I9 @BASEBOARD_FAB2_LIB.BASEBOARD_FAB2(SCH_1):PAGE117
   B42 DMI_CPU0_PCH_TX_C_DP<0> @BASEBOARD_FAB2_LIB.BASEBOARD_FAB2(SCH_1):DMI_CPU0_PCH_TX_C_DP(0)     I9 @BASEBOARD_FAB2_LIB.BASEBOARD_FAB2(SCH_1):PAGE117
   P52 DMI_CPU0_PCH_RX_DN<3> @BASEBOARD_FAB2_LIB.BASEBOARD_FAB2(SCH_1):DMI_CPU0_PCH_RX_DN(3)     I9 @BASEBOARD_FAB2_LIB.BASEBOARD_FAB2(SCH_1):PAGE117
   K50 DMI_CPU0_PCH_RX_DN<2> @BASEBOARD_FAB2_LIB.BASEBOARD_FAB2(SCH_1):DMI_CPU0_PCH_RX_DN(2)     I9 @BASEBOARD_FAB2_LIB.BASEBOARD_FAB2(SCH_1):PAGE117
   J48 DMI_CPU0_PCH_RX_DN<1> @BASEBOARD_FAB2_LIB.BASEBOARD_FAB2(SCH_1):DMI_CPU0_PCH_RX_DN(1)     I9 @BASEBOARD_FAB2_LIB.BASEBOARD_FAB2(SCH_1):PAGE117
   H46 DMI_CPU0_PCH_RX_DN<0> @BASEBOARD_FAB2_LIB.BASEBOARD_FAB2(SCH_1):DMI_CPU0_PCH_RX_DN(0)     I9 @BASEBOARD_FAB2_LIB.BASEBOARD_FAB2(SCH_1):PAGE117
   N54 DMI_CPU0_PCH_RX_DP<3> @BASEBOARD_FAB2_LIB.BASEBOARD_FAB2(SCH_1):DMI_CPU0_PCH_RX_DP(3)     I9 @BASEBOARD_FAB2_LIB.BASEBOARD_FAB2(SCH_1):PAGE117
   M52 DMI_CPU0_PCH_RX_DP<2> @BASEBOARD_FAB2_LIB.BASEBOARD_FAB2(SCH_1):DMI_CPU0_PCH_RX_DP(2)     I9 @BASEBOARD_FAB2_LIB.BASEBOARD_FAB2(SCH_1):PAGE117
   H50 DMI_CPU0_PCH_RX_DP<1> @BASEBOARD_FAB2_LIB.BASEBOARD_FAB2(SCH_1):DMI_CPU0_PCH_RX_DP(1)     I9 @BASEBOARD_FAB2_LIB.BASEBOARD_FAB2(SCH_1):PAGE117
   K46 DMI_CPU0_PCH_RX_DP<0> @BASEBOARD_FAB2_LIB.BASEBOARD_FAB2(SCH_1):DMI_CPU0_PCH_RX_DP(0)     I9 @BASEBOARD_FAB2_LIB.BASEBOARD_FAB2(SCH_1):PAGE117
   C48 P3E_CPU0_PE1_PCH_TXN<0> @BASEBOARD_FAB2_LIB.BASEBOARD_FAB2(SCH_1):P3E_CPU0_PE1_PCH_TXN(0)     I9 @BASEBOARD_FAB2_LIB.BASEBOARD_FAB2(SCH_1):PAGE117
   A48 P3E_CPU0_PE1_PCH_TXP<0> @BASEBOARD_FAB2_LIB.BASEBOARD_FAB2(SCH_1):P3E_CPU0_PE1_PCH_TXP(0)     I9 @BASEBOARD_FAB2_LIB.BASEBOARD_FAB2(SCH_1):PAGE117
   J52 P3E_CPU0_PE1_PCH_RXN<0> @BASEBOARD_FAB2_LIB.BASEBOARD_FAB2(SCH_1):P3E_CPU0_PE1_PCH_RXN(0)     I9 @BASEBOARD_FAB2_LIB.BASEBOARD_FAB2(SCH_1):PAGE117
   G52 P3E_CPU0_PE1_PCH_RXP<0> @BASEBOARD_FAB2_LIB.BASEBOARD_FAB2(SCH_1):P3E_CPU0_PE1_PCH_RXP(0)     I9 @BASEBOARD_FAB2_LIB.BASEBOARD_FAB2(SCH_1):PAGE117
   C59 P3E_CPU0_PE1_PCH_C_TXP<10> @BASEBOARD_FAB2_LIB.BASEBOARD_FAB2(SCH_1):P3E_CPU0_PE1_PCH_C_TXP(10)     I9 @BASEBOARD_FAB2_LIB.BASEBOARD_FAB2(SCH_1):PAGE117
   A59 P3E_CPU0_PE1_PCH_C_TXN<10> @BASEBOARD_FAB2_LIB.BASEBOARD_FAB2(SCH_1):P3E_CPU0_PE1_PCH_C_TXN(10)     I9 @BASEBOARD_FAB2_LIB.BASEBOARD_FAB2(SCH_1):PAGE117
   N65 P3E_CPU0_PE1_PCH_R_RXN<10> @BASEBOARD_FAB2_LIB.BASEBOARD_FAB2(SCH_1):P3E_CPU0_PE1_PCH_R_RXN(10)     I9 @BASEBOARD_FAB2_LIB.BASEBOARD_FAB2(SCH_1):PAGE117
   P66 P3E_CPU0_PE1_PCH_R_RXP<10> @BASEBOARD_FAB2_LIB.BASEBOARD_FAB2(SCH_1):P3E_CPU0_PE1_PCH_R_RXP(10)     I9 @BASEBOARD_FAB2_LIB.BASEBOARD_FAB2(SCH_1):PAGE117
   D60 P3E_CPU0_PE1_PCH_C_TXN<11> @BASEBOARD_FAB2_LIB.BASEBOARD_FAB2(SCH_1):P3E_CPU0_PE1_PCH_C_TXN(11)     I9 @BASEBOARD_FAB2_LIB.BASEBOARD_FAB2(SCH_1):PAGE117
   B60 P3E_CPU0_PE1_PCH_C_TXP<11> @BASEBOARD_FAB2_LIB.BASEBOARD_FAB2(SCH_1):P3E_CPU0_PE1_PCH_C_TXP(11)     I9 @BASEBOARD_FAB2_LIB.BASEBOARD_FAB2(SCH_1):PAGE117
   T59 P3E_CPU0_PE1_PCH_R_RXN<11> @BASEBOARD_FAB2_LIB.BASEBOARD_FAB2(SCH_1):P3E_CPU0_PE1_PCH_R_RXN(11)     I9 @BASEBOARD_FAB2_LIB.BASEBOARD_FAB2(SCH_1):PAGE117
   V59 P3E_CPU0_PE1_PCH_R_RXP<11> @BASEBOARD_FAB2_LIB.BASEBOARD_FAB2(SCH_1):P3E_CPU0_PE1_PCH_R_RXP(11)     I9 @BASEBOARD_FAB2_LIB.BASEBOARD_FAB2(SCH_1):PAGE117
   C61 P3E_CPU0_PE1_PCH_C_TXP<12> @BASEBOARD_FAB2_LIB.BASEBOARD_FAB2(SCH_1):P3E_CPU0_PE1_PCH_C_TXP(12)     I9 @BASEBOARD_FAB2_LIB.BASEBOARD_FAB2(SCH_1):PAGE117
   A61 P3E_CPU0_PE1_PCH_C_TXN<12> @BASEBOARD_FAB2_LIB.BASEBOARD_FAB2(SCH_1):P3E_CPU0_PE1_PCH_C_TXN(12)     I9 @BASEBOARD_FAB2_LIB.BASEBOARD_FAB2(SCH_1):PAGE117
   R65 P3E_CPU0_PE1_PCH_R_RXN<12> @BASEBOARD_FAB2_LIB.BASEBOARD_FAB2(SCH_1):P3E_CPU0_PE1_PCH_R_RXN(12)     I9 @BASEBOARD_FAB2_LIB.BASEBOARD_FAB2(SCH_1):PAGE117
   U65 P3E_CPU0_PE1_PCH_R_RXP<12> @BASEBOARD_FAB2_LIB.BASEBOARD_FAB2(SCH_1):P3E_CPU0_PE1_PCH_R_RXP(12)     I9 @BASEBOARD_FAB2_LIB.BASEBOARD_FAB2(SCH_1):PAGE117
   D62 P3E_CPU0_PE1_PCH_C_TXP<13> @BASEBOARD_FAB2_LIB.BASEBOARD_FAB2(SCH_1):P3E_CPU0_PE1_PCH_C_TXP(13)     I9 @BASEBOARD_FAB2_LIB.BASEBOARD_FAB2(SCH_1):PAGE117
   B62 P3E_CPU0_PE1_PCH_C_TXN<13> @BASEBOARD_FAB2_LIB.BASEBOARD_FAB2(SCH_1):P3E_CPU0_PE1_PCH_C_TXN(13)     I9 @BASEBOARD_FAB2_LIB.BASEBOARD_FAB2(SCH_1):PAGE117
   T63 P3E_CPU0_PE1_PCH_R_RXN<13> @BASEBOARD_FAB2_LIB.BASEBOARD_FAB2(SCH_1):P3E_CPU0_PE1_PCH_R_RXN(13)     I9 @BASEBOARD_FAB2_LIB.BASEBOARD_FAB2(SCH_1):PAGE117
   U61 P3E_CPU0_PE1_PCH_R_RXP<13> @BASEBOARD_FAB2_LIB.BASEBOARD_FAB2(SCH_1):P3E_CPU0_PE1_PCH_R_RXP(13)     I9 @BASEBOARD_FAB2_LIB.BASEBOARD_FAB2(SCH_1):PAGE117
   C63 P3E_CPU0_PE1_PCH_C_TXP<14> @BASEBOARD_FAB2_LIB.BASEBOARD_FAB2(SCH_1):P3E_CPU0_PE1_PCH_C_TXP(14)     I9 @BASEBOARD_FAB2_LIB.BASEBOARD_FAB2(SCH_1):PAGE117
   A63 P3E_CPU0_PE1_PCH_C_TXN<14> @BASEBOARD_FAB2_LIB.BASEBOARD_FAB2(SCH_1):P3E_CPU0_PE1_PCH_C_TXN(14)     I9 @BASEBOARD_FAB2_LIB.BASEBOARD_FAB2(SCH_1):PAGE117
   W65 P3E_CPU0_PE1_PCH_R_RXN<14> @BASEBOARD_FAB2_LIB.BASEBOARD_FAB2(SCH_1):P3E_CPU0_PE1_PCH_R_RXN(14)     I9 @BASEBOARD_FAB2_LIB.BASEBOARD_FAB2(SCH_1):PAGE117
   V63 P3E_CPU0_PE1_PCH_R_RXP<14> @BASEBOARD_FAB2_LIB.BASEBOARD_FAB2(SCH_1):P3E_CPU0_PE1_PCH_R_RXP(14)     I9 @BASEBOARD_FAB2_LIB.BASEBOARD_FAB2(SCH_1):PAGE117
   D64 P3E_CPU0_PE1_PCH_C_TXP<15> @BASEBOARD_FAB2_LIB.BASEBOARD_FAB2(SCH_1):P3E_CPU0_PE1_PCH_C_TXP(15)     I9 @BASEBOARD_FAB2_LIB.BASEBOARD_FAB2(SCH_1):PAGE117
   B64 P3E_CPU0_PE1_PCH_C_TXN<15> @BASEBOARD_FAB2_LIB.BASEBOARD_FAB2(SCH_1):P3E_CPU0_PE1_PCH_C_TXN(15)     I9 @BASEBOARD_FAB2_LIB.BASEBOARD_FAB2(SCH_1):PAGE117
   Y66 P3E_CPU0_PE1_PCH_R_RXN<15> @BASEBOARD_FAB2_LIB.BASEBOARD_FAB2(SCH_1):P3E_CPU0_PE1_PCH_R_RXN(15)     I9 @BASEBOARD_FAB2_LIB.BASEBOARD_FAB2(SCH_1):PAGE117
  AA65 P3E_CPU0_PE1_PCH_R_RXP<15> @BASEBOARD_FAB2_LIB.BASEBOARD_FAB2(SCH_1):P3E_CPU0_PE1_PCH_R_RXP(15)     I9 @BASEBOARD_FAB2_LIB.BASEBOARD_FAB2(SCH_1):PAGE117
   D49 P3E_CPU0_PE1_PCH_TXN<1> @BASEBOARD_FAB2_LIB.BASEBOARD_FAB2(SCH_1):P3E_CPU0_PE1_PCH_TXN(1)     I9 @BASEBOARD_FAB2_LIB.BASEBOARD_FAB2(SCH_1):PAGE117
   B49 P3E_CPU0_PE1_PCH_TXP<1> @BASEBOARD_FAB2_LIB.BASEBOARD_FAB2(SCH_1):P3E_CPU0_PE1_PCH_TXP(1)     I9 @BASEBOARD_FAB2_LIB.BASEBOARD_FAB2(SCH_1):PAGE117
   P56 P3E_CPU0_PE1_PCH_RXN<1> @BASEBOARD_FAB2_LIB.BASEBOARD_FAB2(SCH_1):P3E_CPU0_PE1_PCH_RXN(1)     I9 @BASEBOARD_FAB2_LIB.BASEBOARD_FAB2(SCH_1):PAGE117
   M56 P3E_CPU0_PE1_PCH_RXP<1> @BASEBOARD_FAB2_LIB.BASEBOARD_FAB2(SCH_1):P3E_CPU0_PE1_PCH_RXP(1)     I9 @BASEBOARD_FAB2_LIB.BASEBOARD_FAB2(SCH_1):PAGE117
   C50 P3E_CPU0_PE1_PCH_TXN<2> @BASEBOARD_FAB2_LIB.BASEBOARD_FAB2(SCH_1):P3E_CPU0_PE1_PCH_TXN(2)     I9 @BASEBOARD_FAB2_LIB.BASEBOARD_FAB2(SCH_1):PAGE117
   A50 P3E_CPU0_PE1_PCH_TXP<2> @BASEBOARD_FAB2_LIB.BASEBOARD_FAB2(SCH_1):P3E_CPU0_PE1_PCH_TXP(2)     I9 @BASEBOARD_FAB2_LIB.BASEBOARD_FAB2(SCH_1):PAGE117
   H54 P3E_CPU0_PE1_PCH_RXN<2> @BASEBOARD_FAB2_LIB.BASEBOARD_FAB2(SCH_1):P3E_CPU0_PE1_PCH_RXN(2)     I9 @BASEBOARD_FAB2_LIB.BASEBOARD_FAB2(SCH_1):PAGE117
   G56 P3E_CPU0_PE1_PCH_RXP<2> @BASEBOARD_FAB2_LIB.BASEBOARD_FAB2(SCH_1):P3E_CPU0_PE1_PCH_RXP(2)     I9 @BASEBOARD_FAB2_LIB.BASEBOARD_FAB2(SCH_1):PAGE117
   D51 P3E_CPU0_PE1_PCH_TXN<3> @BASEBOARD_FAB2_LIB.BASEBOARD_FAB2(SCH_1):P3E_CPU0_PE1_PCH_TXN(3)     I9 @BASEBOARD_FAB2_LIB.BASEBOARD_FAB2(SCH_1):PAGE117
   B51 P3E_CPU0_PE1_PCH_TXP<3> @BASEBOARD_FAB2_LIB.BASEBOARD_FAB2(SCH_1):P3E_CPU0_PE1_PCH_TXP(3)     I9 @BASEBOARD_FAB2_LIB.BASEBOARD_FAB2(SCH_1):PAGE117
   J56 P3E_CPU0_PE1_PCH_RXN<3> @BASEBOARD_FAB2_LIB.BASEBOARD_FAB2(SCH_1):P3E_CPU0_PE1_PCH_RXN(3)     I9 @BASEBOARD_FAB2_LIB.BASEBOARD_FAB2(SCH_1):PAGE117
   K58 P3E_CPU0_PE1_PCH_RXP<3> @BASEBOARD_FAB2_LIB.BASEBOARD_FAB2(SCH_1):P3E_CPU0_PE1_PCH_RXP(3)     I9 @BASEBOARD_FAB2_LIB.BASEBOARD_FAB2(SCH_1):PAGE117
   C52 P3E_CPU0_PE1_PCH_TXN<4> @BASEBOARD_FAB2_LIB.BASEBOARD_FAB2(SCH_1):P3E_CPU0_PE1_PCH_TXN(4)     I9 @BASEBOARD_FAB2_LIB.BASEBOARD_FAB2(SCH_1):PAGE117
   A52 P3E_CPU0_PE1_PCH_TXP<4> @BASEBOARD_FAB2_LIB.BASEBOARD_FAB2(SCH_1):P3E_CPU0_PE1_PCH_TXP(4)     I9 @BASEBOARD_FAB2_LIB.BASEBOARD_FAB2(SCH_1):PAGE117
   N58 P3E_CPU0_PE1_PCH_RXN<4> @BASEBOARD_FAB2_LIB.BASEBOARD_FAB2(SCH_1):P3E_CPU0_PE1_PCH_RXN(4)     I9 @BASEBOARD_FAB2_LIB.BASEBOARD_FAB2(SCH_1):PAGE117
   M59 P3E_CPU0_PE1_PCH_RXP<4> @BASEBOARD_FAB2_LIB.BASEBOARD_FAB2(SCH_1):P3E_CPU0_PE1_PCH_RXP(4)     I9 @BASEBOARD_FAB2_LIB.BASEBOARD_FAB2(SCH_1):PAGE117
   D53 P3E_CPU0_PE1_PCH_TXN<5> @BASEBOARD_FAB2_LIB.BASEBOARD_FAB2(SCH_1):P3E_CPU0_PE1_PCH_TXN(5)     I9 @BASEBOARD_FAB2_LIB.BASEBOARD_FAB2(SCH_1):PAGE117
   B53 P3E_CPU0_PE1_PCH_TXP<5> @BASEBOARD_FAB2_LIB.BASEBOARD_FAB2(SCH_1):P3E_CPU0_PE1_PCH_TXP(5)     I9 @BASEBOARD_FAB2_LIB.BASEBOARD_FAB2(SCH_1):PAGE117
   N61 P3E_CPU0_PE1_PCH_RXN<5> @BASEBOARD_FAB2_LIB.BASEBOARD_FAB2(SCH_1):P3E_CPU0_PE1_PCH_RXN(5)     I9 @BASEBOARD_FAB2_LIB.BASEBOARD_FAB2(SCH_1):PAGE117
   K61 P3E_CPU0_PE1_PCH_RXP<5> @BASEBOARD_FAB2_LIB.BASEBOARD_FAB2(SCH_1):P3E_CPU0_PE1_PCH_RXP(5)     I9 @BASEBOARD_FAB2_LIB.BASEBOARD_FAB2(SCH_1):PAGE117
   C54 P3E_CPU0_PE1_PCH_TXN<6> @BASEBOARD_FAB2_LIB.BASEBOARD_FAB2(SCH_1):P3E_CPU0_PE1_PCH_TXN(6)     I9 @BASEBOARD_FAB2_LIB.BASEBOARD_FAB2(SCH_1):PAGE117
   A54 P3E_CPU0_PE1_PCH_TXP<6> @BASEBOARD_FAB2_LIB.BASEBOARD_FAB2(SCH_1):P3E_CPU0_PE1_PCH_TXP(6)     I9 @BASEBOARD_FAB2_LIB.BASEBOARD_FAB2(SCH_1):PAGE117
   H61 P3E_CPU0_PE1_PCH_RXN<6> @BASEBOARD_FAB2_LIB.BASEBOARD_FAB2(SCH_1):P3E_CPU0_PE1_PCH_RXN(6)     I9 @BASEBOARD_FAB2_LIB.BASEBOARD_FAB2(SCH_1):PAGE117
   J63 P3E_CPU0_PE1_PCH_RXP<6> @BASEBOARD_FAB2_LIB.BASEBOARD_FAB2(SCH_1):P3E_CPU0_PE1_PCH_RXP(6)     I9 @BASEBOARD_FAB2_LIB.BASEBOARD_FAB2(SCH_1):PAGE117
   D55 P3E_CPU0_PE1_PCH_TXN<7> @BASEBOARD_FAB2_LIB.BASEBOARD_FAB2(SCH_1):P3E_CPU0_PE1_PCH_TXN(7)     I9 @BASEBOARD_FAB2_LIB.BASEBOARD_FAB2(SCH_1):PAGE117
   B55 P3E_CPU0_PE1_PCH_TXP<7> @BASEBOARD_FAB2_LIB.BASEBOARD_FAB2(SCH_1):P3E_CPU0_PE1_PCH_TXP(7)     I9 @BASEBOARD_FAB2_LIB.BASEBOARD_FAB2(SCH_1):PAGE117
   P59 P3E_CPU0_PE1_PCH_RXN<7> @BASEBOARD_FAB2_LIB.BASEBOARD_FAB2(SCH_1):P3E_CPU0_PE1_PCH_RXN(7)     I9 @BASEBOARD_FAB2_LIB.BASEBOARD_FAB2(SCH_1):PAGE117
   R61 P3E_CPU0_PE1_PCH_RXP<7> @BASEBOARD_FAB2_LIB.BASEBOARD_FAB2(SCH_1):P3E_CPU0_PE1_PCH_RXP(7)     I9 @BASEBOARD_FAB2_LIB.BASEBOARD_FAB2(SCH_1):PAGE117
   C57 P3E_CPU0_PE1_PCH_C_TXP<8> @BASEBOARD_FAB2_LIB.BASEBOARD_FAB2(SCH_1):P3E_CPU0_PE1_PCH_C_TXP(8)     I9 @BASEBOARD_FAB2_LIB.BASEBOARD_FAB2(SCH_1):PAGE117
   A57 P3E_CPU0_PE1_PCH_C_TXN<8> @BASEBOARD_FAB2_LIB.BASEBOARD_FAB2(SCH_1):P3E_CPU0_PE1_PCH_C_TXN(8)     I9 @BASEBOARD_FAB2_LIB.BASEBOARD_FAB2(SCH_1):PAGE117
   K65 P3E_CPU0_PE1_PCH_R_RXN<8> @BASEBOARD_FAB2_LIB.BASEBOARD_FAB2(SCH_1):P3E_CPU0_PE1_PCH_R_RXN(8)     I9 @BASEBOARD_FAB2_LIB.BASEBOARD_FAB2(SCH_1):PAGE117
   M63 P3E_CPU0_PE1_PCH_R_RXP<8> @BASEBOARD_FAB2_LIB.BASEBOARD_FAB2(SCH_1):P3E_CPU0_PE1_PCH_R_RXP(8)     I9 @BASEBOARD_FAB2_LIB.BASEBOARD_FAB2(SCH_1):PAGE117
   D58 P3E_CPU0_PE1_PCH_C_TXP<9> @BASEBOARD_FAB2_LIB.BASEBOARD_FAB2(SCH_1):P3E_CPU0_PE1_PCH_C_TXP(9)     I9 @BASEBOARD_FAB2_LIB.BASEBOARD_FAB2(SCH_1):PAGE117
   B58 P3E_CPU0_PE1_PCH_C_TXN<9> @BASEBOARD_FAB2_LIB.BASEBOARD_FAB2(SCH_1):P3E_CPU0_PE1_PCH_C_TXN(9)     I9 @BASEBOARD_FAB2_LIB.BASEBOARD_FAB2(SCH_1):PAGE117
   J66 P3E_CPU0_PE1_PCH_R_RXN<9> @BASEBOARD_FAB2_LIB.BASEBOARD_FAB2(SCH_1):P3E_CPU0_PE1_PCH_R_RXN(9)     I9 @BASEBOARD_FAB2_LIB.BASEBOARD_FAB2(SCH_1):PAGE117
   M66 P3E_CPU0_PE1_PCH_R_RXP<9> @BASEBOARD_FAB2_LIB.BASEBOARD_FAB2(SCH_1):P3E_CPU0_PE1_PCH_R_RXP(9)     I9 @BASEBOARD_FAB2_LIB.BASEBOARD_FAB2(SCH_1):PAGE117
  AT56 XDP_TRST_N @BASEBOARD_FAB2_LIB.BASEBOARD_FAB2(SCH_1):XDP_TRST_N    I73 @BASEBOARD_FAB2_LIB.BASEBOARD_FAB2(SCH_1):PAGE118
   K13 PWRGD_DSW_PWROK @BASEBOARD_FAB2_LIB.BASEBOARD_FAB2(SCH_1):PWRGD_DSW_PWROK    I73 @BASEBOARD_FAB2_LIB.BASEBOARD_FAB2(SCH_1):PAGE118
   G15 XDP_PCH_PWR_DEBUG_N @BASEBOARD_FAB2_LIB.BASEBOARD_FAB2(SCH_1):XDP_PCH_PWR_DEBUG_N    I73 @BASEBOARD_FAB2_LIB.BASEBOARD_FAB2(SCH_1):PAGE118
   B14 FM_CPU0_RC_ERROR_R_N @BASEBOARD_FAB2_LIB.BASEBOARD_FAB2(SCH_1):FM_CPU0_RC_ERROR_R_N    I73 @BASEBOARD_FAB2_LIB.BASEBOARD_FAB2(SCH_1):PAGE118
   A13 FM_GBE_LOM_DISABLE_N @BASEBOARD_FAB2_LIB.BASEBOARD_FAB2(SCH_1):FM_GBE_LOM_DISABLE_N    I73 @BASEBOARD_FAB2_LIB.BASEBOARD_FAB2(SCH_1):PAGE118
   H13 FM_CPU1_SKTOCC_LVT3_N @BASEBOARD_FAB2_LIB.BASEBOARD_FAB2(SCH_1):FM_CPU1_SKTOCC_LVT3_N    I73 @BASEBOARD_FAB2_LIB.BASEBOARD_FAB2(SCH_1):PAGE118
   M11 RST_BMC_SRST_R_N @BASEBOARD_FAB2_LIB.BASEBOARD_FAB2(SCH_1):RST_BMC_SRST_R_N    I73 @BASEBOARD_FAB2_LIB.BASEBOARD_FAB2(SCH_1):PAGE118
   C15 FM_PCH_PWRBTN_N @BASEBOARD_FAB2_LIB.BASEBOARD_FAB2(SCH_1):FM_PCH_PWRBTN_N    I73 @BASEBOARD_FAB2_LIB.BASEBOARD_FAB2(SCH_1):PAGE118
   D14 FM_SLPS3_R_N @BASEBOARD_FAB2_LIB.BASEBOARD_FAB2(SCH_1):FM_SLPS3_R_N    I73 @BASEBOARD_FAB2_LIB.BASEBOARD_FAB2(SCH_1):PAGE118
   B16 FM_SLPS4_N @BASEBOARD_FAB2_LIB.BASEBOARD_FAB2(SCH_1):FM_SLPS4_N    I73 @BASEBOARD_FAB2_LIB.BASEBOARD_FAB2(SCH_1):PAGE118
   G11 FM_CPU0_SKTOCC_LVT3_N @BASEBOARD_FAB2_LIB.BASEBOARD_FAB2(SCH_1):FM_CPU0_SKTOCC_LVT3_N    I73 @BASEBOARD_FAB2_LIB.BASEBOARD_FAB2(SCH_1):PAGE118
    H9 FM_BATTERY_SENSE_EN_R_N @BASEBOARD_FAB2_LIB.BASEBOARD_FAB2(SCH_1):FM_BATTERY_SENSE_EN_R_N    I73 @BASEBOARD_FAB2_LIB.BASEBOARD_FAB2(SCH_1):PAGE118
   C13 TP_PCH_GDP8_SUSCLK @BASEBOARD_FAB2_LIB.BASEBOARD_FAB2(SCH_1):TP_PCH_GDP8_SUSCLK    I73 @BASEBOARD_FAB2_LIB.BASEBOARD_FAB2(SCH_1):PAGE118
   A15 FM_BMC_CPLD_MP_RST_N @BASEBOARD_FAB2_LIB.BASEBOARD_FAB2(SCH_1):FM_BMC_CPLD_MP_RST_N    I73 @BASEBOARD_FAB2_LIB.BASEBOARD_FAB2(SCH_1):PAGE118
  AR54 XDP_ITP_PMODE @BASEBOARD_FAB2_LIB.BASEBOARD_FAB2(SCH_1):XDP_ITP_PMODE    I73 @BASEBOARD_FAB2_LIB.BASEBOARD_FAB2(SCH_1):PAGE118
  AF54 XDP_PCH_CPU_TCK0 @BASEBOARD_FAB2_LIB.BASEBOARD_FAB2(SCH_1):XDP_PCH_CPU_TCK0    I73 @BASEBOARD_FAB2_LIB.BASEBOARD_FAB2(SCH_1):PAGE118
  AL56 XDP_PCH_TCK1 @BASEBOARD_FAB2_LIB.BASEBOARD_FAB2(SCH_1):XDP_PCH_TCK1    I73 @BASEBOARD_FAB2_LIB.BASEBOARD_FAB2(SCH_1):PAGE118
  AN54 XDP_TDI @BASEBOARD_FAB2_LIB.BASEBOARD_FAB2(SCH_1):XDP_TDI    I73 @BASEBOARD_FAB2_LIB.BASEBOARD_FAB2(SCH_1):PAGE118
  AP56 XDP_TDO @BASEBOARD_FAB2_LIB.BASEBOARD_FAB2(SCH_1):XDP_TDO    I73 @BASEBOARD_FAB2_LIB.BASEBOARD_FAB2(SCH_1):PAGE118
  AH54 XDP_TMS @BASEBOARD_FAB2_LIB.BASEBOARD_FAB2(SCH_1):XDP_TMS    I73 @BASEBOARD_FAB2_LIB.BASEBOARD_FAB2(SCH_1):PAGE118
  BB29 A_KR0_RBIAS @BASEBOARD_FAB2_LIB.BASEBOARD_FAB2(SCH_1):A_KR0_RBIAS    I73 @BASEBOARD_FAB2_LIB.BASEBOARD_FAB2(SCH_1):PAGE118
  BD42 A_KR1_RBIAS @BASEBOARD_FAB2_LIB.BASEBOARD_FAB2(SCH_1):A_KR1_RBIAS    I73 @BASEBOARD_FAB2_LIB.BASEBOARD_FAB2(SCH_1):PAGE118
  BH31 KR_P0_OCP_RX_C_DN @BASEBOARD_FAB2_LIB.BASEBOARD_FAB2(SCH_1):KR_P0_OCP_RX_C_DN    I73 @BASEBOARD_FAB2_LIB.BASEBOARD_FAB2(SCH_1):PAGE118
  BF31 KR_P0_OCP_RX_C_DP @BASEBOARD_FAB2_LIB.BASEBOARD_FAB2(SCH_1):KR_P0_OCP_RX_C_DP    I73 @BASEBOARD_FAB2_LIB.BASEBOARD_FAB2(SCH_1):PAGE118
  BG29 KR_P1_OCP_RX_C_DN @BASEBOARD_FAB2_LIB.BASEBOARD_FAB2(SCH_1):KR_P1_OCP_RX_C_DN    I73 @BASEBOARD_FAB2_LIB.BASEBOARD_FAB2(SCH_1):PAGE118
  BJ29 KR_P1_OCP_RX_C_DP @BASEBOARD_FAB2_LIB.BASEBOARD_FAB2(SCH_1):KR_P1_OCP_RX_C_DP    I73 @BASEBOARD_FAB2_LIB.BASEBOARD_FAB2(SCH_1):PAGE118
  BJ37     NC     NC    I73 @BASEBOARD_FAB2_LIB.BASEBOARD_FAB2(SCH_1):PAGE118
  BG37     NC     NC    I73 @BASEBOARD_FAB2_LIB.BASEBOARD_FAB2(SCH_1):PAGE118
  BF35     NC     NC    I73 @BASEBOARD_FAB2_LIB.BASEBOARD_FAB2(SCH_1):PAGE118
  BH35     NC     NC    I73 @BASEBOARD_FAB2_LIB.BASEBOARD_FAB2(SCH_1):PAGE118
  BM27 KR_P0_OCP_TX_DN @BASEBOARD_FAB2_LIB.BASEBOARD_FAB2(SCH_1):KR_P0_OCP_TX_DN    I73 @BASEBOARD_FAB2_LIB.BASEBOARD_FAB2(SCH_1):PAGE118
  BR27 KR_P0_OCP_TX_DP @BASEBOARD_FAB2_LIB.BASEBOARD_FAB2(SCH_1):KR_P0_OCP_TX_DP    I73 @BASEBOARD_FAB2_LIB.BASEBOARD_FAB2(SCH_1):PAGE118
  BM24 KR_P1_OCP_TX_DN @BASEBOARD_FAB2_LIB.BASEBOARD_FAB2(SCH_1):KR_P1_OCP_TX_DN    I73 @BASEBOARD_FAB2_LIB.BASEBOARD_FAB2(SCH_1):PAGE118
  BR24 KR_P1_OCP_TX_DP @BASEBOARD_FAB2_LIB.BASEBOARD_FAB2(SCH_1):KR_P1_OCP_TX_DP    I73 @BASEBOARD_FAB2_LIB.BASEBOARD_FAB2(SCH_1):PAGE118
  BM35     NC     NC    I73 @BASEBOARD_FAB2_LIB.BASEBOARD_FAB2(SCH_1):PAGE118
  BR35     NC     NC    I73 @BASEBOARD_FAB2_LIB.BASEBOARD_FAB2(SCH_1):PAGE118
  BR31     NC     NC    I73 @BASEBOARD_FAB2_LIB.BASEBOARD_FAB2(SCH_1):PAGE118
  BM31     NC     NC    I73 @BASEBOARD_FAB2_LIB.BASEBOARD_FAB2(SCH_1):PAGE118
  BV16 XTAL_KR_25M_IN @BASEBOARD_FAB2_LIB.BASEBOARD_FAB2(SCH_1):XTAL_KR_25M_IN    I73 @BASEBOARD_FAB2_LIB.BASEBOARD_FAB2(SCH_1):PAGE118
  BY16 XTAL_KR_25M_OUT @BASEBOARD_FAB2_LIB.BASEBOARD_FAB2(SCH_1):XTAL_KR_25M_OUT    I73 @BASEBOARD_FAB2_LIB.BASEBOARD_FAB2(SCH_1):PAGE118
   R17 PWRGD_PCH_PWROK @BASEBOARD_FAB2_LIB.BASEBOARD_FAB2(SCH_1):PWRGD_PCH_PWROK    I73 @BASEBOARD_FAB2_LIB.BASEBOARD_FAB2(SCH_1):PAGE118
    U9 PECI_PCH @BASEBOARD_FAB2_LIB.BASEBOARD_FAB2(SCH_1):PECI_PCH    I73 @BASEBOARD_FAB2_LIB.BASEBOARD_FAB2(SCH_1):PAGE118
   U17 TP_PLTRST_CPU_N @BASEBOARD_FAB2_LIB.BASEBOARD_FAB2(SCH_1):TP_PLTRST_CPU_N    I73 @BASEBOARD_FAB2_LIB.BASEBOARD_FAB2(SCH_1):PAGE118
   U13 H_PM_SYNC1_GTL_R @BASEBOARD_FAB2_LIB.BASEBOARD_FAB2(SCH_1):H_PM_SYNC1_GTL_R    I73 @BASEBOARD_FAB2_LIB.BASEBOARD_FAB2(SCH_1):PAGE118
    V7 TP_PM_SYNC_GTL @BASEBOARD_FAB2_LIB.BASEBOARD_FAB2(SCH_1):TP_PM_SYNC_GTL    I73 @BASEBOARD_FAB2_LIB.BASEBOARD_FAB2(SCH_1):PAGE118
  AD54 XDP_PRDY_N @BASEBOARD_FAB2_LIB.BASEBOARD_FAB2(SCH_1):XDP_PRDY_N    I73 @BASEBOARD_FAB2_LIB.BASEBOARD_FAB2(SCH_1):PAGE118
   U54 XDP_PREQ_N @BASEBOARD_FAB2_LIB.BASEBOARD_FAB2(SCH_1):XDP_PREQ_N    I73 @BASEBOARD_FAB2_LIB.BASEBOARD_FAB2(SCH_1):PAGE118
    R9 PWRGD_CPUPWRGD_GTL @BASEBOARD_FAB2_LIB.BASEBOARD_FAB2(SCH_1):PWRGD_CPUPWRGD_GTL    I73 @BASEBOARD_FAB2_LIB.BASEBOARD_FAB2(SCH_1):PAGE118
   P15 RST_RSMRST_N @BASEBOARD_FAB2_LIB.BASEBOARD_FAB2(SCH_1):RST_RSMRST_N    I73 @BASEBOARD_FAB2_LIB.BASEBOARD_FAB2(SCH_1):PAGE118
   R24 TP_PCH_RSVD54 @BASEBOARD_FAB2_LIB.BASEBOARD_FAB2(SCH_1):TP_PCH_RSVD54    I73 @BASEBOARD_FAB2_LIB.BASEBOARD_FAB2(SCH_1):PAGE118
   P26 TP_PCH_RSVD53 @BASEBOARD_FAB2_LIB.BASEBOARD_FAB2(SCH_1):TP_PCH_RSVD53    I73 @BASEBOARD_FAB2_LIB.BASEBOARD_FAB2(SCH_1):PAGE118
   P22 TP_PCH_RSVD45 @BASEBOARD_FAB2_LIB.BASEBOARD_FAB2(SCH_1):TP_PCH_RSVD45    I73 @BASEBOARD_FAB2_LIB.BASEBOARD_FAB2(SCH_1):PAGE118
  BN33 TP_10GBE_KR1_MON_DP @BASEBOARD_FAB2_LIB.BASEBOARD_FAB2(SCH_1):TP_10GBE_KR1_MON_DP    I73 @BASEBOARD_FAB2_LIB.BASEBOARD_FAB2(SCH_1):PAGE118
  BL33 TP_10GBE_KR1_MON_DN @BASEBOARD_FAB2_LIB.BASEBOARD_FAB2(SCH_1):TP_10GBE_KR1_MON_DN    I73 @BASEBOARD_FAB2_LIB.BASEBOARD_FAB2(SCH_1):PAGE118
  BG40 TP_PCH_RSVD42 @BASEBOARD_FAB2_LIB.BASEBOARD_FAB2(SCH_1):TP_PCH_RSVD42    I73 @BASEBOARD_FAB2_LIB.BASEBOARD_FAB2(SCH_1):PAGE118
  BJ40 TP_PCH_RSVD41 @BASEBOARD_FAB2_LIB.BASEBOARD_FAB2(SCH_1):TP_PCH_RSVD41    I73 @BASEBOARD_FAB2_LIB.BASEBOARD_FAB2(SCH_1):PAGE118
  BN26 TP_10GBE_KR0_MON_DP @BASEBOARD_FAB2_LIB.BASEBOARD_FAB2(SCH_1):TP_10GBE_KR0_MON_DP    I73 @BASEBOARD_FAB2_LIB.BASEBOARD_FAB2(SCH_1):PAGE118
  BL26 TP_10GBE_KR0_MON_DN @BASEBOARD_FAB2_LIB.BASEBOARD_FAB2(SCH_1):TP_10GBE_KR0_MON_DN    I73 @BASEBOARD_FAB2_LIB.BASEBOARD_FAB2(SCH_1):PAGE118
  BL29 TP_PCH_RSVD38 @BASEBOARD_FAB2_LIB.BASEBOARD_FAB2(SCH_1):TP_PCH_RSVD38    I73 @BASEBOARD_FAB2_LIB.BASEBOARD_FAB2(SCH_1):PAGE118
  BN29 TP_PCH_RSVD37 @BASEBOARD_FAB2_LIB.BASEBOARD_FAB2(SCH_1):TP_PCH_RSVD37    I73 @BASEBOARD_FAB2_LIB.BASEBOARD_FAB2(SCH_1):PAGE118
  AK54 TP_PCH_RSVD36 @BASEBOARD_FAB2_LIB.BASEBOARD_FAB2(SCH_1):TP_PCH_RSVD36    I73 @BASEBOARD_FAB2_LIB.BASEBOARD_FAB2(SCH_1):PAGE118
   W54 TP_PCH_RSVD35 @BASEBOARD_FAB2_LIB.BASEBOARD_FAB2(SCH_1):TP_PCH_RSVD35    I73 @BASEBOARD_FAB2_LIB.BASEBOARD_FAB2(SCH_1):PAGE118
   Y56 TP_PCH_RSVD34 @BASEBOARD_FAB2_LIB.BASEBOARD_FAB2(SCH_1):TP_PCH_RSVD34    I73 @BASEBOARD_FAB2_LIB.BASEBOARD_FAB2(SCH_1):PAGE118
   V56 TP_PCH_RSVD33 @BASEBOARD_FAB2_LIB.BASEBOARD_FAB2(SCH_1):TP_PCH_RSVD33    I73 @BASEBOARD_FAB2_LIB.BASEBOARD_FAB2(SCH_1):PAGE118
  AA54 TP_PCH_RSVD32 @BASEBOARD_FAB2_LIB.BASEBOARD_FAB2(SCH_1):TP_PCH_RSVD32    I73 @BASEBOARD_FAB2_LIB.BASEBOARD_FAB2(SCH_1):PAGE118
   M15 TP_SLP_LAN_N @BASEBOARD_FAB2_LIB.BASEBOARD_FAB2(SCH_1):TP_SLP_LAN_N    I73 @BASEBOARD_FAB2_LIB.BASEBOARD_FAB2(SCH_1):PAGE118
    P7 FM_SLP_SUS_N @BASEBOARD_FAB2_LIB.BASEBOARD_FAB2(SCH_1):FM_SLP_SUS_N    I73 @BASEBOARD_FAB2_LIB.BASEBOARD_FAB2(SCH_1):PAGE118
  BY19 PWRGD_SYS_PWROK @BASEBOARD_FAB2_LIB.BASEBOARD_FAB2(SCH_1):PWRGD_SYS_PWROK    I73 @BASEBOARD_FAB2_LIB.BASEBOARD_FAB2(SCH_1):PAGE118
  BV19 RST_BMC_SYSRST_BTN_OUT_B_N @BASEBOARD_FAB2_LIB.BASEBOARD_FAB2(SCH_1):RST_BMC_SYSRST_BTN_OUT_B_N    I73 @BASEBOARD_FAB2_LIB.BASEBOARD_FAB2(SCH_1):PAGE118
   V15 FM_PCH_LVC1_THERMTRIP_N @BASEBOARD_FAB2_LIB.BASEBOARD_FAB2(SCH_1):FM_PCH_LVC1_THERMTRIP_N    I73 @BASEBOARD_FAB2_LIB.BASEBOARD_FAB2(SCH_1):PAGE118
    M7 TP_CPU_PCH_TRIGGER_IN @BASEBOARD_FAB2_LIB.BASEBOARD_FAB2(SCH_1):TP_CPU_PCH_TRIGGER_IN    I73 @BASEBOARD_FAB2_LIB.BASEBOARD_FAB2(SCH_1):PAGE118
   R13 TP_CPU_PCH_TRIGGER_OUT @BASEBOARD_FAB2_LIB.BASEBOARD_FAB2(SCH_1):TP_CPU_PCH_TRIGGER_OUT    I73 @BASEBOARD_FAB2_LIB.BASEBOARD_FAB2(SCH_1):PAGE118
    K9 IRQ_LVC3_WAKE_N @BASEBOARD_FAB2_LIB.BASEBOARD_FAB2(SCH_1):IRQ_LVC3_WAKE_N    I73 @BASEBOARD_FAB2_LIB.BASEBOARD_FAB2(SCH_1):PAGE118
    N3 PU_FM_RCIN_N @BASEBOARD_FAB2_LIB.BASEBOARD_FAB2(SCH_1):PU_FM_RCIN_N   I115 @BASEBOARD_FAB2_LIB.BASEBOARD_FAB2(SCH_1):PAGE119
   AA4     NC     NC   I115 @BASEBOARD_FAB2_LIB.BASEBOARD_FAB2(SCH_1):PAGE119
   AC2 PU_LPC_PME_N @BASEBOARD_FAB2_LIB.BASEBOARD_FAB2(SCH_1):PU_LPC_PME_N   I115 @BASEBOARD_FAB2_LIB.BASEBOARD_FAB2(SCH_1):PAGE119
    R1 PU_IRQ_PCH_SCI_WHEA_N @BASEBOARD_FAB2_LIB.BASEBOARD_FAB2(SCH_1):PU_IRQ_PCH_SCI_WHEA_N   I115 @BASEBOARD_FAB2_LIB.BASEBOARD_FAB2(SCH_1):PAGE119
    T4 FM_MB_SLOT_ID0 @BASEBOARD_FAB2_LIB.BASEBOARD_FAB2(SCH_1):FM_MB_SLOT_ID0   I115 @BASEBOARD_FAB2_LIB.BASEBOARD_FAB2(SCH_1):PAGE119
   AB3 FM_MB_SLOT_ID1 @BASEBOARD_FAB2_LIB.BASEBOARD_FAB2(SCH_1):FM_MB_SLOT_ID1   I115 @BASEBOARD_FAB2_LIB.BASEBOARD_FAB2(SCH_1):PAGE119
   AC4 FM_MB_SLOT_ID2 @BASEBOARD_FAB2_LIB.BASEBOARD_FAB2(SCH_1):FM_MB_SLOT_ID2   I115 @BASEBOARD_FAB2_LIB.BASEBOARD_FAB2(SCH_1):PAGE119
    T2 FM_UART_PRES_N @BASEBOARD_FAB2_LIB.BASEBOARD_FAB2(SCH_1):FM_UART_PRES_N   I115 @BASEBOARD_FAB2_LIB.BASEBOARD_FAB2(SCH_1):PAGE119
   AD1 FM_CPU_BMC_INIT @BASEBOARD_FAB2_LIB.BASEBOARD_FAB2(SCH_1):FM_CPU_BMC_INIT   I115 @BASEBOARD_FAB2_LIB.BASEBOARD_FAB2(SCH_1):PAGE119
   AD3 RST_PCH_SYSRST_BTN_OUT_N @BASEBOARD_FAB2_LIB.BASEBOARD_FAB2(SCH_1):RST_PCH_SYSRST_BTN_OUT_N   I115 @BASEBOARD_FAB2_LIB.BASEBOARD_FAB2(SCH_1):PAGE119
    V3 FM_ME_RECOVER_N @BASEBOARD_FAB2_LIB.BASEBOARD_FAB2(SCH_1):FM_ME_RECOVER_N   I115 @BASEBOARD_FAB2_LIB.BASEBOARD_FAB2(SCH_1):PAGE119
    Y3 LPC_LAD0_IO0 @BASEBOARD_FAB2_LIB.BASEBOARD_FAB2(SCH_1):LPC_LAD0_IO0   I115 @BASEBOARD_FAB2_LIB.BASEBOARD_FAB2(SCH_1):PAGE119
    W4     NC     NC   I115 @BASEBOARD_FAB2_LIB.BASEBOARD_FAB2(SCH_1):PAGE119
   AE2 FM_OCP_MEZZA_PRES_R @BASEBOARD_FAB2_LIB.BASEBOARD_FAB2(SCH_1):FM_OCP_MEZZA_PRES_R   I115 @BASEBOARD_FAB2_LIB.BASEBOARD_FAB2(SCH_1):PAGE119
   AE4 FM_TPM_PRES_N @BASEBOARD_FAB2_LIB.BASEBOARD_FAB2(SCH_1):FM_TPM_PRES_N   I115 @BASEBOARD_FAB2_LIB.BASEBOARD_FAB2(SCH_1):PAGE119
    V1 FM_BMC_READY_R_N @BASEBOARD_FAB2_LIB.BASEBOARD_FAB2(SCH_1):FM_BMC_READY_R_N   I115 @BASEBOARD_FAB2_LIB.BASEBOARD_FAB2(SCH_1):PAGE119
    N1 LPC_LAD1_IO1 @BASEBOARD_FAB2_LIB.BASEBOARD_FAB2(SCH_1):LPC_LAD1_IO1   I115 @BASEBOARD_FAB2_LIB.BASEBOARD_FAB2(SCH_1):PAGE119
    W2 LPC_LAD2_IO2 @BASEBOARD_FAB2_LIB.BASEBOARD_FAB2(SCH_1):LPC_LAD2_IO2   I115 @BASEBOARD_FAB2_LIB.BASEBOARD_FAB2(SCH_1):PAGE119
    Y1 LPC_LAD3_IO3 @BASEBOARD_FAB2_LIB.BASEBOARD_FAB2(SCH_1):LPC_LAD3_IO3   I115 @BASEBOARD_FAB2_LIB.BASEBOARD_FAB2(SCH_1):PAGE119
    P4 LPC_LFRAME_N_CS0_N @BASEBOARD_FAB2_LIB.BASEBOARD_FAB2(SCH_1):LPC_LFRAME_N_CS0_N   I115 @BASEBOARD_FAB2_LIB.BASEBOARD_FAB2(SCH_1):PAGE119
    P2 IRQ_LPC_SERIRQ_N @BASEBOARD_FAB2_LIB.BASEBOARD_FAB2(SCH_1):IRQ_LPC_SERIRQ_N   I115 @BASEBOARD_FAB2_LIB.BASEBOARD_FAB2(SCH_1):PAGE119
   AA2 IRQ_PIRQA_SPI_TPM_N @BASEBOARD_FAB2_LIB.BASEBOARD_FAB2(SCH_1):IRQ_PIRQA_SPI_TPM_N   I115 @BASEBOARD_FAB2_LIB.BASEBOARD_FAB2(SCH_1):PAGE119
   AB1 PU_LPC_CLKRUN_N @BASEBOARD_FAB2_LIB.BASEBOARD_FAB2(SCH_1):PU_LPC_CLKRUN_N   I115 @BASEBOARD_FAB2_LIB.BASEBOARD_FAB2(SCH_1):PAGE119
    R3 CLK_24M_BMC_LPC_R @BASEBOARD_FAB2_LIB.BASEBOARD_FAB2(SCH_1):CLK_24M_BMC_LPC_R   I115 @BASEBOARD_FAB2_LIB.BASEBOARD_FAB2(SCH_1):PAGE119
   BL7 VID_PCH_CORE_PVNN_AUX_VID_0 @BASEBOARD_FAB2_LIB.BASEBOARD_FAB2(SCH_1):VID_PCH_CORE_PVNN_AUX_VID_0   I115 @BASEBOARD_FAB2_LIB.BASEBOARD_FAB2(SCH_1):PAGE119
  BL11 RST_SYSTEM_BTN_N @BASEBOARD_FAB2_LIB.BASEBOARD_FAB2(SCH_1):RST_SYSTEM_BTN_N   I115 @BASEBOARD_FAB2_LIB.BASEBOARD_FAB2(SCH_1):PAGE119
   BK9 FM_PMBUS_ALERT_BUF_EN_R2_N @BASEBOARD_FAB2_LIB.BASEBOARD_FAB2(SCH_1):FM_PMBUS_ALERT_BUF_EN_R2_N   I115 @BASEBOARD_FAB2_LIB.BASEBOARD_FAB2(SCH_1):PAGE119
  BL18 FM_GLOBAL_RST_WARN_N @BASEBOARD_FAB2_LIB.BASEBOARD_FAB2(SCH_1):FM_GLOBAL_RST_WARN_N   I115 @BASEBOARD_FAB2_LIB.BASEBOARD_FAB2(SCH_1):PAGE119
  BN18 RST_PLTRST_N @BASEBOARD_FAB2_LIB.BASEBOARD_FAB2(SCH_1):RST_PLTRST_N   I115 @BASEBOARD_FAB2_LIB.BASEBOARD_FAB2(SCH_1):PAGE119
  BH13 FM_BIOS_TOP_SWAP_SPKR @BASEBOARD_FAB2_LIB.BASEBOARD_FAB2(SCH_1):FM_BIOS_TOP_SWAP_SPKR   I115 @BASEBOARD_FAB2_LIB.BASEBOARD_FAB2(SCH_1):PAGE119
  BK13 FM_UART_ALERT_N @BASEBOARD_FAB2_LIB.BASEBOARD_FAB2(SCH_1):FM_UART_ALERT_N   I115 @BASEBOARD_FAB2_LIB.BASEBOARD_FAB2(SCH_1):PAGE119
  BG22 IRQ_PCH_NIC_ALERT_N @BASEBOARD_FAB2_LIB.BASEBOARD_FAB2(SCH_1):IRQ_PCH_NIC_ALERT_N   I115 @BASEBOARD_FAB2_LIB.BASEBOARD_FAB2(SCH_1):PAGE119
  BG15 FM_PCH_PWRBTN_OUT_N @BASEBOARD_FAB2_LIB.BASEBOARD_FAB2(SCH_1):FM_PCH_PWRBTN_OUT_N   I115 @BASEBOARD_FAB2_LIB.BASEBOARD_FAB2(SCH_1):PAGE119
  BL15 FM_UV_ADR_TRIGGER_EN @BASEBOARD_FAB2_LIB.BASEBOARD_FAB2(SCH_1):FM_UV_ADR_TRIGGER_EN   I115 @BASEBOARD_FAB2_LIB.BASEBOARD_FAB2(SCH_1):PAGE119
  BK20 FM_BIOS_PREFRB2_GOOD @BASEBOARD_FAB2_LIB.BASEBOARD_FAB2(SCH_1):FM_BIOS_PREFRB2_GOOD   I115 @BASEBOARD_FAB2_LIB.BASEBOARD_FAB2(SCH_1):PAGE119
   BH9 VID_PCH_CORE_PVNN_AUX_VID_1 @BASEBOARD_FAB2_LIB.BASEBOARD_FAB2(SCH_1):VID_PCH_CORE_PVNN_AUX_VID_1   I115 @BASEBOARD_FAB2_LIB.BASEBOARD_FAB2(SCH_1):PAGE119
  BN15 PU_IRQ_VRALERT_N @BASEBOARD_FAB2_LIB.BASEBOARD_FAB2(SCH_1):PU_IRQ_VRALERT_N   I115 @BASEBOARD_FAB2_LIB.BASEBOARD_FAB2(SCH_1):PAGE119
  BJ22 FM_BIOS_POST_CMPLT_N @BASEBOARD_FAB2_LIB.BASEBOARD_FAB2(SCH_1):FM_BIOS_POST_CMPLT_N   I115 @BASEBOARD_FAB2_LIB.BASEBOARD_FAB2(SCH_1):PAGE119
  BH17 FM_FAST_PROCHOT_EN_N @BASEBOARD_FAB2_LIB.BASEBOARD_FAB2(SCH_1):FM_FAST_PROCHOT_EN_N   I115 @BASEBOARD_FAB2_LIB.BASEBOARD_FAB2(SCH_1):PAGE119
  BR17 FM_USB_P0_EN_BOOT_BIOS_STRAP_N @BASEBOARD_FAB2_LIB.BASEBOARD_FAB2(SCH_1):FM_USB_P0_EN_BOOT_BIOS_STRAP_N   I115 @BASEBOARD_FAB2_LIB.BASEBOARD_FAB2(SCH_1):PAGE119
  BM20 FM_PCH_BMC_THERMTRIP_EXI_STRAP_ @BASEBOARD_FAB2_LIB.BASEBOARD_FAB2(SCH_1):FM_PCH_BMC_THERMTRIP_EXI_STRAP_N   I115 @BASEBOARD_FAB2_LIB.BASEBOARD_FAB2(SCH_1):PAGE119
   BR9 FM_QAT_EN_N @BASEBOARD_FAB2_LIB.BASEBOARD_FAB2(SCH_1):FM_QAT_EN_N   I115 @BASEBOARD_FAB2_LIB.BASEBOARD_FAB2(SCH_1):PAGE119
   BN7 IRQ_PVDDQ_ABC_VRHOT_LVT3_N @BASEBOARD_FAB2_LIB.BASEBOARD_FAB2(SCH_1):IRQ_PVDDQ_ABC_VRHOT_LVT3_N   I115 @BASEBOARD_FAB2_LIB.BASEBOARD_FAB2(SCH_1):PAGE119
  BK17 IRQ_PVDDQ_DEF_VRHOT_LVT3_N @BASEBOARD_FAB2_LIB.BASEBOARD_FAB2(SCH_1):IRQ_PVDDQ_DEF_VRHOT_LVT3_N   I115 @BASEBOARD_FAB2_LIB.BASEBOARD_FAB2(SCH_1):PAGE119
  BG18 IRQ_PVDDQ_GHJ_VRHOT_LVT3_N @BASEBOARD_FAB2_LIB.BASEBOARD_FAB2(SCH_1):IRQ_PVDDQ_GHJ_VRHOT_LVT3_N   I115 @BASEBOARD_FAB2_LIB.BASEBOARD_FAB2(SCH_1):PAGE119
  BR13 IRQ_PVDDQ_KLM_VRHOT_LVT3_N @BASEBOARD_FAB2_LIB.BASEBOARD_FAB2(SCH_1):IRQ_PVDDQ_KLM_VRHOT_LVT3_N   I115 @BASEBOARD_FAB2_LIB.BASEBOARD_FAB2(SCH_1):PAGE119
  BN11 FP_NMI_BTN_N @BASEBOARD_FAB2_LIB.BASEBOARD_FAB2(SCH_1):FP_NMI_BTN_N   I115 @BASEBOARD_FAB2_LIB.BASEBOARD_FAB2(SCH_1):PAGE119
  BH20 FM_PWR_BTN_N @BASEBOARD_FAB2_LIB.BASEBOARD_FAB2(SCH_1):FM_PWR_BTN_N   I115 @BASEBOARD_FAB2_LIB.BASEBOARD_FAB2(SCH_1):PAGE119
  BW28 SMB_HOST_STBY_LVC3_SCL_R1 @BASEBOARD_FAB2_LIB.BASEBOARD_FAB2(SCH_1):SMB_HOST_STBY_LVC3_SCL_R1   I115 @BASEBOARD_FAB2_LIB.BASEBOARD_FAB2(SCH_1):PAGE119
  BV31 FM_PCH_SATA_RAID_KEY @BASEBOARD_FAB2_LIB.BASEBOARD_FAB2(SCH_1):FM_PCH_SATA_RAID_KEY   I115 @BASEBOARD_FAB2_LIB.BASEBOARD_FAB2(SCH_1):PAGE119
  BV33 FM_BOARD_REV_ID2 @BASEBOARD_FAB2_LIB.BASEBOARD_FAB2(SCH_1):FM_BOARD_REV_ID2   I115 @BASEBOARD_FAB2_LIB.BASEBOARD_FAB2(SCH_1):PAGE119
  CA30 FM_BOARD_REV_ID0 @BASEBOARD_FAB2_LIB.BASEBOARD_FAB2(SCH_1):FM_BOARD_REV_ID0   I115 @BASEBOARD_FAB2_LIB.BASEBOARD_FAB2(SCH_1):PAGE119
  BV38 FM_BOARD_REV_ID1 @BASEBOARD_FAB2_LIB.BASEBOARD_FAB2(SCH_1):FM_BOARD_REV_ID1   I115 @BASEBOARD_FAB2_LIB.BASEBOARD_FAB2(SCH_1):PAGE119
  BY38 IRQ_BMC_PCH_SCI_LPC_N @BASEBOARD_FAB2_LIB.BASEBOARD_FAB2(SCH_1):IRQ_BMC_PCH_SCI_LPC_N   I115 @BASEBOARD_FAB2_LIB.BASEBOARD_FAB2(SCH_1):PAGE119
  CA32 FM_SLT_CFG0 @BASEBOARD_FAB2_LIB.BASEBOARD_FAB2(SCH_1):FM_SLT_CFG0   I115 @BASEBOARD_FAB2_LIB.BASEBOARD_FAB2(SCH_1):PAGE119
  BW37 FM_SLT_CFG1 @BASEBOARD_FAB2_LIB.BASEBOARD_FAB2(SCH_1):FM_SLT_CFG1   I115 @BASEBOARD_FAB2_LIB.BASEBOARD_FAB2(SCH_1):PAGE119
  BY31 FM_SLT_CFG2_R @BASEBOARD_FAB2_LIB.BASEBOARD_FAB2(SCH_1):FM_SLT_CFG2_R   I115 @BASEBOARD_FAB2_LIB.BASEBOARD_FAB2(SCH_1):PAGE119
  BY35 FM_PMBUS_ALERT_BUF_EN_R_N @BASEBOARD_FAB2_LIB.BASEBOARD_FAB2(SCH_1):FM_PMBUS_ALERT_BUF_EN_R_N   I115 @BASEBOARD_FAB2_LIB.BASEBOARD_FAB2(SCH_1):PAGE119
  BW39 FM_BB_BMC_MP_GPIO @BASEBOARD_FAB2_LIB.BASEBOARD_FAB2(SCH_1):FM_BB_BMC_MP_GPIO   I115 @BASEBOARD_FAB2_LIB.BASEBOARD_FAB2(SCH_1):PAGE119
  BV27 SMB_HOST_STBY_LVC3_SDA_R1 @BASEBOARD_FAB2_LIB.BASEBOARD_FAB2(SCH_1):SMB_HOST_STBY_LVC3_SDA_R1   I115 @BASEBOARD_FAB2_LIB.BASEBOARD_FAB2(SCH_1):PAGE119
  CA39 FM_THROTTLE_R2_N @BASEBOARD_FAB2_LIB.BASEBOARD_FAB2(SCH_1):FM_THROTTLE_R2_N   I115 @BASEBOARD_FAB2_LIB.BASEBOARD_FAB2(SCH_1):PAGE119
  BY33 FM_BIOS_POST_CMPLT_N @BASEBOARD_FAB2_LIB.BASEBOARD_FAB2(SCH_1):FM_BIOS_POST_CMPLT_N   I115 @BASEBOARD_FAB2_LIB.BASEBOARD_FAB2(SCH_1):PAGE119
  CA34 IRQ_BMC_PCH_SMI_LPC_N @BASEBOARD_FAB2_LIB.BASEBOARD_FAB2(SCH_1):IRQ_BMC_PCH_SMI_LPC_N   I115 @BASEBOARD_FAB2_LIB.BASEBOARD_FAB2(SCH_1):PAGE119
  CA37 FM_CPU_CATERR_DLY_LVT3_R_N @BASEBOARD_FAB2_LIB.BASEBOARD_FAB2(SCH_1):FM_CPU_CATERR_DLY_LVT3_R_N   I115 @BASEBOARD_FAB2_LIB.BASEBOARD_FAB2(SCH_1):PAGE119
  BY27 PU_PCH_TLS_ENABLE_STRAP @BASEBOARD_FAB2_LIB.BASEBOARD_FAB2(SCH_1):PU_PCH_TLS_ENABLE_STRAP   I115 @BASEBOARD_FAB2_LIB.BASEBOARD_FAB2(SCH_1):PAGE119
  BV29 SMB_SMLINK0_STBY_LVC3_SCL_R1 @BASEBOARD_FAB2_LIB.BASEBOARD_FAB2(SCH_1):SMB_SMLINK0_STBY_LVC3_SCL_R1   I115 @BASEBOARD_FAB2_LIB.BASEBOARD_FAB2(SCH_1):PAGE119
  BW30 SMB_SMLINK0_STBY_LVC3_SDA_R1 @BASEBOARD_FAB2_LIB.BASEBOARD_FAB2(SCH_1):SMB_SMLINK0_STBY_LVC3_SDA_R1   I115 @BASEBOARD_FAB2_LIB.BASEBOARD_FAB2(SCH_1):PAGE119
  BW34 IRQ_SML0_ALERT_N @BASEBOARD_FAB2_LIB.BASEBOARD_FAB2(SCH_1):IRQ_SML0_ALERT_N   I115 @BASEBOARD_FAB2_LIB.BASEBOARD_FAB2(SCH_1):PAGE119
  CA28 SMB_PMBUS_BMC_STBY_LVC3_SCL_R1 @BASEBOARD_FAB2_LIB.BASEBOARD_FAB2(SCH_1):SMB_PMBUS_BMC_STBY_LVC3_SCL_R1   I115 @BASEBOARD_FAB2_LIB.BASEBOARD_FAB2(SCH_1):PAGE119
  BV35 SMB_PMBUS_BMC_STBY_LVC3_SDA_R1 @BASEBOARD_FAB2_LIB.BASEBOARD_FAB2(SCH_1):SMB_PMBUS_BMC_STBY_LVC3_SDA_R1   I115 @BASEBOARD_FAB2_LIB.BASEBOARD_FAB2(SCH_1):PAGE119
  BW32 FM_PASSWORD_CLEAR_N @BASEBOARD_FAB2_LIB.BASEBOARD_FAB2(SCH_1):FM_PASSWORD_CLEAR_N   I115 @BASEBOARD_FAB2_LIB.BASEBOARD_FAB2(SCH_1):PAGE119
  BY29 FM_CPU1_RC_EN @BASEBOARD_FAB2_LIB.BASEBOARD_FAB2(SCH_1):FM_CPU1_RC_EN   I115 @BASEBOARD_FAB2_LIB.BASEBOARD_FAB2(SCH_1):PAGE119
  BR42 IRQ_BMC_PCH_NMI_STBY_R_N @BASEBOARD_FAB2_LIB.BASEBOARD_FAB2(SCH_1):IRQ_BMC_PCH_NMI_STBY_R_N   I115 @BASEBOARD_FAB2_LIB.BASEBOARD_FAB2(SCH_1):PAGE119
  BK46 FM_PWR_LED_N @BASEBOARD_FAB2_LIB.BASEBOARD_FAB2(SCH_1):FM_PWR_LED_N   I115 @BASEBOARD_FAB2_LIB.BASEBOARD_FAB2(SCH_1):PAGE119
  BV47 H_CPU0_FAST_WAKE_LVT3_N @BASEBOARD_FAB2_LIB.BASEBOARD_FAB2(SCH_1):H_CPU0_FAST_WAKE_LVT3_N   I115 @BASEBOARD_FAB2_LIB.BASEBOARD_FAB2(SCH_1):PAGE119
  BY47 IRQ_LOM_ALERT_N @BASEBOARD_FAB2_LIB.BASEBOARD_FAB2(SCH_1):IRQ_LOM_ALERT_N   I115 @BASEBOARD_FAB2_LIB.BASEBOARD_FAB2(SCH_1):PAGE119
  BN40 FM_TPM_PRES_RST_N @BASEBOARD_FAB2_LIB.BASEBOARD_FAB2(SCH_1):FM_TPM_PRES_RST_N   I115 @BASEBOARD_FAB2_LIB.BASEBOARD_FAB2(SCH_1):PAGE119
  BY44 SMB_SLOTX24_PCH_STBY_LVC3_SCL @BASEBOARD_FAB2_LIB.BASEBOARD_FAB2(SCH_1):SMB_SLOTX24_PCH_STBY_LVC3_SCL   I115 @BASEBOARD_FAB2_LIB.BASEBOARD_FAB2(SCH_1):PAGE119
  BL44 SMB_SLOTX24_PCH_STBY_LVC3_SDA @BASEBOARD_FAB2_LIB.BASEBOARD_FAB2(SCH_1):SMB_SLOTX24_PCH_STBY_LVC3_SDA   I115 @BASEBOARD_FAB2_LIB.BASEBOARD_FAB2(SCH_1):PAGE119
  BW43 SGPIO_PCH_SSATA_DOUT0 @BASEBOARD_FAB2_LIB.BASEBOARD_FAB2(SCH_1):SGPIO_PCH_SSATA_DOUT0   I115 @BASEBOARD_FAB2_LIB.BASEBOARD_FAB2(SCH_1):PAGE119
  BV42 IRQ_OOB_MGMT_RISER_ALERT_N @BASEBOARD_FAB2_LIB.BASEBOARD_FAB2(SCH_1):IRQ_OOB_MGMT_RISER_ALERT_N   I115 @BASEBOARD_FAB2_LIB.BASEBOARD_FAB2(SCH_1):PAGE119
  BW48 FM_XRC_PRESENT_N @BASEBOARD_FAB2_LIB.BASEBOARD_FAB2(SCH_1):FM_XRC_PRESENT_N   I115 @BASEBOARD_FAB2_LIB.BASEBOARD_FAB2(SCH_1):PAGE119
  CA41 FM_XRC_READY_N @BASEBOARD_FAB2_LIB.BASEBOARD_FAB2(SCH_1):FM_XRC_READY_N   I115 @BASEBOARD_FAB2_LIB.BASEBOARD_FAB2(SCH_1):PAGE119
  CA43 FM_ADR_MODE_SEL_R @BASEBOARD_FAB2_LIB.BASEBOARD_FAB2(SCH_1):FM_ADR_MODE_SEL_R   I115 @BASEBOARD_FAB2_LIB.BASEBOARD_FAB2(SCH_1):PAGE119
  BJ44 IRQ_HSC_FAULT_N @BASEBOARD_FAB2_LIB.BASEBOARD_FAB2(SCH_1):IRQ_HSC_FAULT_N   I115 @BASEBOARD_FAB2_LIB.BASEBOARD_FAB2(SCH_1):PAGE119
  CA48 FM_BMC_HEARTBEAT_N @BASEBOARD_FAB2_LIB.BASEBOARD_FAB2(SCH_1):FM_BMC_HEARTBEAT_N   I115 @BASEBOARD_FAB2_LIB.BASEBOARD_FAB2(SCH_1):PAGE119
  BV44     NC     NC   I115 @BASEBOARD_FAB2_LIB.BASEBOARD_FAB2(SCH_1):PAGE119
  BR46     NC     NC   I115 @BASEBOARD_FAB2_LIB.BASEBOARD_FAB2(SCH_1):PAGE119
  BN44 FM_CPU0_THERMTRIP_LATCH_LVT3_N @BASEBOARD_FAB2_LIB.BASEBOARD_FAB2(SCH_1):FM_CPU0_THERMTRIP_LATCH_LVT3_N   I115 @BASEBOARD_FAB2_LIB.BASEBOARD_FAB2(SCH_1):PAGE119
  BW45 IRQ_MEZZ_LAN_ALERT_N @BASEBOARD_FAB2_LIB.BASEBOARD_FAB2(SCH_1):IRQ_MEZZ_LAN_ALERT_N   I115 @BASEBOARD_FAB2_LIB.BASEBOARD_FAB2(SCH_1):PAGE119
  BM42 FM_PCH_PLD_DATA_R @BASEBOARD_FAB2_LIB.BASEBOARD_FAB2(SCH_1):FM_PCH_PLD_DATA_R   I115 @BASEBOARD_FAB2_LIB.BASEBOARD_FAB2(SCH_1):PAGE119
  BM38 FM_BMC_ENABLE_N @BASEBOARD_FAB2_LIB.BASEBOARD_FAB2(SCH_1):FM_BMC_ENABLE_N   I115 @BASEBOARD_FAB2_LIB.BASEBOARD_FAB2(SCH_1):PAGE119
  BW41 FM_CPLD_BMC_PWRDN_N @BASEBOARD_FAB2_LIB.BASEBOARD_FAB2(SCH_1):FM_CPLD_BMC_PWRDN_N   I115 @BASEBOARD_FAB2_LIB.BASEBOARD_FAB2(SCH_1):PAGE119
  CA45 FM_BMC_CPLD_GPO @BASEBOARD_FAB2_LIB.BASEBOARD_FAB2(SCH_1):FM_BMC_CPLD_GPO   I115 @BASEBOARD_FAB2_LIB.BASEBOARD_FAB2(SCH_1):PAGE119
  BR38 FM_BMC_FAULT_LED_N @BASEBOARD_FAB2_LIB.BASEBOARD_FAB2(SCH_1):FM_BMC_FAULT_LED_N   I115 @BASEBOARD_FAB2_LIB.BASEBOARD_FAB2(SCH_1):PAGE119
  BY42 IRQ_FORCE_NM_THROTTLE_N @BASEBOARD_FAB2_LIB.BASEBOARD_FAB2(SCH_1):IRQ_FORCE_NM_THROTTLE_N   I115 @BASEBOARD_FAB2_LIB.BASEBOARD_FAB2(SCH_1):PAGE119
  BY25 A_RCOMP_3P3 @BASEBOARD_FAB2_LIB.BASEBOARD_FAB2(SCH_1):A_RCOMP_3P3   I147 @BASEBOARD_FAB2_LIB.BASEBOARD_FAB2(SCH_1):PAGE120
  BH50 FM_CPU0_RC_ERROR_R1_N @BASEBOARD_FAB2_LIB.BASEBOARD_FAB2(SCH_1):FM_CPU0_RC_ERROR_R1_N   I147 @BASEBOARD_FAB2_LIB.BASEBOARD_FAB2(SCH_1):PAGE120
  BN48 IRQ_BMC_PCH_SCI_LPC_N @BASEBOARD_FAB2_LIB.BASEBOARD_FAB2(SCH_1):IRQ_BMC_PCH_SCI_LPC_N   I147 @BASEBOARD_FAB2_LIB.BASEBOARD_FAB2(SCH_1):PAGE120
  AW54 IRQ_BMC_PCH_SMI_LPC_N @BASEBOARD_FAB2_LIB.BASEBOARD_FAB2(SCH_1):IRQ_BMC_PCH_SMI_LPC_N   I147 @BASEBOARD_FAB2_LIB.BASEBOARD_FAB2(SCH_1):PAGE120
  AU58 IRQ_UV_DETECT_N @BASEBOARD_FAB2_LIB.BASEBOARD_FAB2(SCH_1):IRQ_UV_DETECT_N   I147 @BASEBOARD_FAB2_LIB.BASEBOARD_FAB2(SCH_1):PAGE120
  AY52 FM_CPU1_RC_ERROR_R1_N @BASEBOARD_FAB2_LIB.BASEBOARD_FAB2(SCH_1):FM_CPU1_RC_ERROR_R1_N   I147 @BASEBOARD_FAB2_LIB.BASEBOARD_FAB2(SCH_1):PAGE120
  BG52 FM_POST_CARD_PRES_BMC_R1_N @BASEBOARD_FAB2_LIB.BASEBOARD_FAB2(SCH_1):FM_POST_CARD_PRES_BMC_R1_N   I147 @BASEBOARD_FAB2_LIB.BASEBOARD_FAB2(SCH_1):PAGE120
  BE52 FM_CPLD_ADR_TRIGGER_R_N @BASEBOARD_FAB2_LIB.BASEBOARD_FAB2(SCH_1):FM_CPLD_ADR_TRIGGER_R_N   I147 @BASEBOARD_FAB2_LIB.BASEBOARD_FAB2(SCH_1):PAGE120
  AV52 FM_CPU_ERR2_LVT3_N @BASEBOARD_FAB2_LIB.BASEBOARD_FAB2(SCH_1):FM_CPU_ERR2_LVT3_N   I147 @BASEBOARD_FAB2_LIB.BASEBOARD_FAB2(SCH_1):PAGE120
  AT52 FM_CPU_MSMI_LVT3_N @BASEBOARD_FAB2_LIB.BASEBOARD_FAB2(SCH_1):FM_CPU_MSMI_LVT3_N   I147 @BASEBOARD_FAB2_LIB.BASEBOARD_FAB2(SCH_1):PAGE120
  BB52 IRQ_BMC_PCH_NMI_STBY_N @BASEBOARD_FAB2_LIB.BASEBOARD_FAB2(SCH_1):IRQ_BMC_PCH_NMI_STBY_N   I147 @BASEBOARD_FAB2_LIB.BASEBOARD_FAB2(SCH_1):PAGE120
  BJ48 FM_ADR_SMI_GPIO_N @BASEBOARD_FAB2_LIB.BASEBOARD_FAB2(SCH_1):FM_ADR_SMI_GPIO_N   I147 @BASEBOARD_FAB2_LIB.BASEBOARD_FAB2(SCH_1):PAGE120
  AV56 LED_PCH_SATA_HDD_N @BASEBOARD_FAB2_LIB.BASEBOARD_FAB2(SCH_1):LED_PCH_SATA_HDD_N   I147 @BASEBOARD_FAB2_LIB.BASEBOARD_FAB2(SCH_1):PAGE120
  BL48 FM_OC0_USB_N @BASEBOARD_FAB2_LIB.BASEBOARD_FAB2(SCH_1):FM_OC0_USB_N   I147 @BASEBOARD_FAB2_LIB.BASEBOARD_FAB2(SCH_1):PAGE120
   AG7 IRQ_OC_DETECT_N @BASEBOARD_FAB2_LIB.BASEBOARD_FAB2(SCH_1):IRQ_OC_DETECT_N   I147 @BASEBOARD_FAB2_LIB.BASEBOARD_FAB2(SCH_1):PAGE120
   AL7 SGPIO_PCH_SATA_CLOCK @BASEBOARD_FAB2_LIB.BASEBOARD_FAB2(SCH_1):SGPIO_PCH_SATA_CLOCK   I147 @BASEBOARD_FAB2_LIB.BASEBOARD_FAB2(SCH_1):PAGE120
   AR9 SGPIO_PCH_SATA_LOAD @BASEBOARD_FAB2_LIB.BASEBOARD_FAB2(SCH_1):SGPIO_PCH_SATA_LOAD   I147 @BASEBOARD_FAB2_LIB.BASEBOARD_FAB2(SCH_1):PAGE120
   AP7 IRQ_SML1_PMBUS_ALERT_R1_N @BASEBOARD_FAB2_LIB.BASEBOARD_FAB2(SCH_1):IRQ_SML1_PMBUS_ALERT_R1_N   I147 @BASEBOARD_FAB2_LIB.BASEBOARD_FAB2(SCH_1):PAGE120
  AP11 SGPIO_PCH_SATA_DOUT0 @BASEBOARD_FAB2_LIB.BASEBOARD_FAB2(SCH_1):SGPIO_PCH_SATA_DOUT0   I147 @BASEBOARD_FAB2_LIB.BASEBOARD_FAB2(SCH_1):PAGE120
  AL11 LED_PCH_SSATA_HDD_N @BASEBOARD_FAB2_LIB.BASEBOARD_FAB2(SCH_1):LED_PCH_SSATA_HDD_N   I147 @BASEBOARD_FAB2_LIB.BASEBOARD_FAB2(SCH_1):PAGE120
  AR13 FM_FORCE_ADR_N @BASEBOARD_FAB2_LIB.BASEBOARD_FAB2(SCH_1):FM_FORCE_ADR_N   I147 @BASEBOARD_FAB2_LIB.BASEBOARD_FAB2(SCH_1):PAGE120
  AU13 FM_IE_DISABLE_N @BASEBOARD_FAB2_LIB.BASEBOARD_FAB2(SCH_1):FM_IE_DISABLE_N   I147 @BASEBOARD_FAB2_LIB.BASEBOARD_FAB2(SCH_1):PAGE120
  AP15 FM_BIOS_TOP_SWAP @BASEBOARD_FAB2_LIB.BASEBOARD_FAB2(SCH_1):FM_BIOS_TOP_SWAP   I147 @BASEBOARD_FAB2_LIB.BASEBOARD_FAB2(SCH_1):PAGE120
  AL15 FM_MEM_THERM_EVENT_PCH_N @BASEBOARD_FAB2_LIB.BASEBOARD_FAB2(SCH_1):FM_MEM_THERM_EVENT_PCH_N   I147 @BASEBOARD_FAB2_LIB.BASEBOARD_FAB2(SCH_1):PAGE120
   AU9 SMB_LAN_STBY_LVC3_SCL_R2 @BASEBOARD_FAB2_LIB.BASEBOARD_FAB2(SCH_1):SMB_LAN_STBY_LVC3_SCL_R2   I147 @BASEBOARD_FAB2_LIB.BASEBOARD_FAB2(SCH_1):PAGE120
   AK9 FM_HSC_TIMER_EXP_N @BASEBOARD_FAB2_LIB.BASEBOARD_FAB2(SCH_1):FM_HSC_TIMER_EXP_N   I147 @BASEBOARD_FAB2_LIB.BASEBOARD_FAB2(SCH_1):PAGE120
  AU20 SMB_LAN_STBY_LVC3_SDA_R2 @BASEBOARD_FAB2_LIB.BASEBOARD_FAB2(SCH_1):SMB_LAN_STBY_LVC3_SDA_R2   I147 @BASEBOARD_FAB2_LIB.BASEBOARD_FAB2(SCH_1):PAGE120
  AR17 IRQ_PCH_NIC_ALERT_N @BASEBOARD_FAB2_LIB.BASEBOARD_FAB2(SCH_1):IRQ_PCH_NIC_ALERT_N   I147 @BASEBOARD_FAB2_LIB.BASEBOARD_FAB2(SCH_1):PAGE120
  AP18 SGPIO_PCH_SSATA_CLOCK @BASEBOARD_FAB2_LIB.BASEBOARD_FAB2(SCH_1):SGPIO_PCH_SSATA_CLOCK   I147 @BASEBOARD_FAB2_LIB.BASEBOARD_FAB2(SCH_1):PAGE120
  AU17 SGPIO_PCH_SSATA_LOAD @BASEBOARD_FAB2_LIB.BASEBOARD_FAB2(SCH_1):SGPIO_PCH_SSATA_LOAD   I147 @BASEBOARD_FAB2_LIB.BASEBOARD_FAB2(SCH_1):PAGE120
  AK20 FM_MP_PS_FAIL_N @BASEBOARD_FAB2_LIB.BASEBOARD_FAB2(SCH_1):FM_MP_PS_FAIL_N   I147 @BASEBOARD_FAB2_LIB.BASEBOARD_FAB2(SCH_1):PAGE120
  AK13 FM_MP_PS_REDUNDANT_LOST_N @BASEBOARD_FAB2_LIB.BASEBOARD_FAB2(SCH_1):FM_MP_PS_REDUNDANT_LOST_N   I147 @BASEBOARD_FAB2_LIB.BASEBOARD_FAB2(SCH_1):PAGE120
  AH13 FM_BMC_READY_R1_N @BASEBOARD_FAB2_LIB.BASEBOARD_FAB2(SCH_1):FM_BMC_READY_R1_N   I147 @BASEBOARD_FAB2_LIB.BASEBOARD_FAB2(SCH_1):PAGE120
  AH17 FM_BIOS_USB_RECOVERY @BASEBOARD_FAB2_LIB.BASEBOARD_FAB2(SCH_1):FM_BIOS_USB_RECOVERY   I147 @BASEBOARD_FAB2_LIB.BASEBOARD_FAB2(SCH_1):PAGE120
  AL18 JTAG_PCH_PLD_TCK @BASEBOARD_FAB2_LIB.BASEBOARD_FAB2(SCH_1):JTAG_PCH_PLD_TCK   I147 @BASEBOARD_FAB2_LIB.BASEBOARD_FAB2(SCH_1):PAGE120
  AK17 JTAG_PCH_PLD_TDI @BASEBOARD_FAB2_LIB.BASEBOARD_FAB2(SCH_1):JTAG_PCH_PLD_TDI   I147 @BASEBOARD_FAB2_LIB.BASEBOARD_FAB2(SCH_1):PAGE120
   AH9 JTAG_PCH_PLD_TMS @BASEBOARD_FAB2_LIB.BASEBOARD_FAB2(SCH_1):JTAG_PCH_PLD_TMS   I147 @BASEBOARD_FAB2_LIB.BASEBOARD_FAB2(SCH_1):PAGE120
  AR20 JTAG_PCH_PLD_TDO @BASEBOARD_FAB2_LIB.BASEBOARD_FAB2(SCH_1):JTAG_PCH_PLD_TDO   I147 @BASEBOARD_FAB2_LIB.BASEBOARD_FAB2(SCH_1):PAGE120
  AY11     NC     NC   I147 @BASEBOARD_FAB2_LIB.BASEBOARD_FAB2(SCH_1):PAGE120
  BE11     NC     NC   I147 @BASEBOARD_FAB2_LIB.BASEBOARD_FAB2(SCH_1):PAGE120
  BA20     NC     NC   I147 @BASEBOARD_FAB2_LIB.BASEBOARD_FAB2(SCH_1):PAGE120
  BD13 FM_BOARD_SKU_ID0 @BASEBOARD_FAB2_LIB.BASEBOARD_FAB2(SCH_1):FM_BOARD_SKU_ID0   I147 @BASEBOARD_FAB2_LIB.BASEBOARD_FAB2(SCH_1):PAGE120
  AY18 FM_BOARD_SKU_ID1 @BASEBOARD_FAB2_LIB.BASEBOARD_FAB2(SCH_1):FM_BOARD_SKU_ID1   I147 @BASEBOARD_FAB2_LIB.BASEBOARD_FAB2(SCH_1):PAGE120
   AV7 FM_BOARD_SKU_ID2 @BASEBOARD_FAB2_LIB.BASEBOARD_FAB2(SCH_1):FM_BOARD_SKU_ID2   I147 @BASEBOARD_FAB2_LIB.BASEBOARD_FAB2(SCH_1):PAGE120
  BE18 FM_BOARD_SKU_ID3 @BASEBOARD_FAB2_LIB.BASEBOARD_FAB2(SCH_1):FM_BOARD_SKU_ID3   I147 @BASEBOARD_FAB2_LIB.BASEBOARD_FAB2(SCH_1):PAGE120
  BD17 FM_BOARD_SKU_ID4 @BASEBOARD_FAB2_LIB.BASEBOARD_FAB2(SCH_1):FM_BOARD_SKU_ID4   I147 @BASEBOARD_FAB2_LIB.BASEBOARD_FAB2(SCH_1):PAGE120
   BD9 FM_ADR_COMPLETE_R1 @BASEBOARD_FAB2_LIB.BASEBOARD_FAB2(SCH_1):FM_ADR_COMPLETE_R1   I147 @BASEBOARD_FAB2_LIB.BASEBOARD_FAB2(SCH_1):PAGE120
   BE7 FM_NMI_EVENT_N @BASEBOARD_FAB2_LIB.BASEBOARD_FAB2(SCH_1):FM_NMI_EVENT_N   I147 @BASEBOARD_FAB2_LIB.BASEBOARD_FAB2(SCH_1):PAGE120
  BE15 FM_BIOS_SMI_ACTIVE_N @BASEBOARD_FAB2_LIB.BASEBOARD_FAB2(SCH_1):FM_BIOS_SMI_ACTIVE_N   I147 @BASEBOARD_FAB2_LIB.BASEBOARD_FAB2(SCH_1):PAGE120
  AV15     NC     NC   I147 @BASEBOARD_FAB2_LIB.BASEBOARD_FAB2(SCH_1):PAGE120
  BA17 IRQ_FORCE_NM_THROTTLE_N @BASEBOARD_FAB2_LIB.BASEBOARD_FAB2(SCH_1):IRQ_FORCE_NM_THROTTLE_N   I147 @BASEBOARD_FAB2_LIB.BASEBOARD_FAB2(SCH_1):PAGE120
   BG7 FM_SOL_UART_CH_SEL @BASEBOARD_FAB2_LIB.BASEBOARD_FAB2(SCH_1):FM_SOL_UART_CH_SEL   I147 @BASEBOARD_FAB2_LIB.BASEBOARD_FAB2(SCH_1):PAGE120
  BD20 FM_CPU0_RC_EN @BASEBOARD_FAB2_LIB.BASEBOARD_FAB2(SCH_1):FM_CPU0_RC_EN   I147 @BASEBOARD_FAB2_LIB.BASEBOARD_FAB2(SCH_1):PAGE120
  BA13 FM_UARTSW_MSB_N @BASEBOARD_FAB2_LIB.BASEBOARD_FAB2(SCH_1):FM_UARTSW_MSB_N   I147 @BASEBOARD_FAB2_LIB.BASEBOARD_FAB2(SCH_1):PAGE120
  BE22     NC     NC   I147 @BASEBOARD_FAB2_LIB.BASEBOARD_FAB2(SCH_1):PAGE120
   AY7     NC     NC   I147 @BASEBOARD_FAB2_LIB.BASEBOARD_FAB2(SCH_1):PAGE120
   BA9     NC     NC   I147 @BASEBOARD_FAB2_LIB.BASEBOARD_FAB2(SCH_1):PAGE120
  AW20     NC     NC   I147 @BASEBOARD_FAB2_LIB.BASEBOARD_FAB2(SCH_1):PAGE120
  AV18 FM_CPU1_THERMTRIP_LATCH_LVT3_N @BASEBOARD_FAB2_LIB.BASEBOARD_FAB2(SCH_1):FM_CPU1_THERMTRIP_LATCH_LVT3_N   I147 @BASEBOARD_FAB2_LIB.BASEBOARD_FAB2(SCH_1):PAGE120
  AY15     NC     NC   I147 @BASEBOARD_FAB2_LIB.BASEBOARD_FAB2(SCH_1):PAGE120
  BG11     NC     NC   I147 @BASEBOARD_FAB2_LIB.BASEBOARD_FAB2(SCH_1):PAGE120
  AV11     NC     NC   I147 @BASEBOARD_FAB2_LIB.BASEBOARD_FAB2(SCH_1):PAGE120
   AT4 FM_UARTSW_LSB_N @BASEBOARD_FAB2_LIB.BASEBOARD_FAB2(SCH_1):FM_UARTSW_LSB_N   I147 @BASEBOARD_FAB2_LIB.BASEBOARD_FAB2(SCH_1):PAGE120
   BA4 SMB_VR_STBY_LVC3_SCL_R1 @BASEBOARD_FAB2_LIB.BASEBOARD_FAB2(SCH_1):SMB_VR_STBY_LVC3_SCL_R1   I147 @BASEBOARD_FAB2_LIB.BASEBOARD_FAB2(SCH_1):PAGE120
   BD1 SMB_VR_STBY_LVC3_SDA_R1 @BASEBOARD_FAB2_LIB.BASEBOARD_FAB2(SCH_1):SMB_VR_STBY_LVC3_SDA_R1   I147 @BASEBOARD_FAB2_LIB.BASEBOARD_FAB2(SCH_1):PAGE120
   BB1 FM_FLASH_ATTACH_CFG_STRAP @BASEBOARD_FAB2_LIB.BASEBOARD_FAB2(SCH_1):FM_FLASH_ATTACH_CFG_STRAP   I147 @BASEBOARD_FAB2_LIB.BASEBOARD_FAB2(SCH_1):PAGE120
   AY1     NC     NC   I147 @BASEBOARD_FAB2_LIB.BASEBOARD_FAB2(SCH_1):PAGE120
   BC2     NC     NC   I147 @BASEBOARD_FAB2_LIB.BASEBOARD_FAB2(SCH_1):PAGE120
   BB3 PU_ADR_TIMER_HOLD_OFF_N @BASEBOARD_FAB2_LIB.BASEBOARD_FAB2(SCH_1):PU_ADR_TIMER_HOLD_OFF_N   I147 @BASEBOARD_FAB2_LIB.BASEBOARD_FAB2(SCH_1):PAGE120
   BF1 SMB_LAN_STBY_LVC3_SCL_R1 @BASEBOARD_FAB2_LIB.BASEBOARD_FAB2(SCH_1):SMB_LAN_STBY_LVC3_SCL_R1   I147 @BASEBOARD_FAB2_LIB.BASEBOARD_FAB2(SCH_1):PAGE120
   BE4 SMB_LAN_STBY_LVC3_SDA_R1 @BASEBOARD_FAB2_LIB.BASEBOARD_FAB2(SCH_1):SMB_LAN_STBY_LVC3_SDA_R1   I147 @BASEBOARD_FAB2_LIB.BASEBOARD_FAB2(SCH_1):PAGE120
   BC4 FM_OC_DETECT_EN_N @BASEBOARD_FAB2_LIB.BASEBOARD_FAB2(SCH_1):FM_OC_DETECT_EN_N   I147 @BASEBOARD_FAB2_LIB.BASEBOARD_FAB2(SCH_1):PAGE120
   BD3 FP_PWR_ID_LED_N @BASEBOARD_FAB2_LIB.BASEBOARD_FAB2(SCH_1):FP_PWR_ID_LED_N   I147 @BASEBOARD_FAB2_LIB.BASEBOARD_FAB2(SCH_1):PAGE120
   AW4 FM_BACKUP_BIOS_SEL_N @BASEBOARD_FAB2_LIB.BASEBOARD_FAB2(SCH_1):FM_BACKUP_BIOS_SEL_N   I147 @BASEBOARD_FAB2_LIB.BASEBOARD_FAB2(SCH_1):PAGE120
   BF3 FM_BMC_NMI_N @BASEBOARD_FAB2_LIB.BASEBOARD_FAB2(SCH_1):FM_BMC_NMI_N   I147 @BASEBOARD_FAB2_LIB.BASEBOARD_FAB2(SCH_1):PAGE120
   BA2 FM_BIOS_SMI_ACTIVE_N @BASEBOARD_FAB2_LIB.BASEBOARD_FAB2(SCH_1):FM_BIOS_SMI_ACTIVE_N   I147 @BASEBOARD_FAB2_LIB.BASEBOARD_FAB2(SCH_1):PAGE120
   BH2 FM_PCH_BMC_THERMTRIP_N @BASEBOARD_FAB2_LIB.BASEBOARD_FAB2(SCH_1):FM_PCH_BMC_THERMTRIP_N   I147 @BASEBOARD_FAB2_LIB.BASEBOARD_FAB2(SCH_1):PAGE120
   BH4 FM_SSATA_PCIE_M2_SEL @BASEBOARD_FAB2_LIB.BASEBOARD_FAB2(SCH_1):FM_SSATA_PCIE_M2_SEL   I147 @BASEBOARD_FAB2_LIB.BASEBOARD_FAB2(SCH_1):PAGE120
   AV3     NC     NC   I147 @BASEBOARD_FAB2_LIB.BASEBOARD_FAB2(SCH_1):PAGE120
   AR1     NC     NC   I147 @BASEBOARD_FAB2_LIB.BASEBOARD_FAB2(SCH_1):PAGE120
   AT2     NC     NC   I147 @BASEBOARD_FAB2_LIB.BASEBOARD_FAB2(SCH_1):PAGE120
   AY3     NC     NC   I147 @BASEBOARD_FAB2_LIB.BASEBOARD_FAB2(SCH_1):PAGE120
   AW2     NC     NC   I147 @BASEBOARD_FAB2_LIB.BASEBOARD_FAB2(SCH_1):PAGE120
   AV1     NC     NC   I147 @BASEBOARD_FAB2_LIB.BASEBOARD_FAB2(SCH_1):PAGE120
   AR3     NC     NC   I147 @BASEBOARD_FAB2_LIB.BASEBOARD_FAB2(SCH_1):PAGE120
   BE2     NC     NC   I147 @BASEBOARD_FAB2_LIB.BASEBOARD_FAB2(SCH_1):PAGE120
  CA20 JTAG_PCH_GBE_TDO @BASEBOARD_FAB2_LIB.BASEBOARD_FAB2(SCH_1):JTAG_PCH_GBE_TDO   I147 @BASEBOARD_FAB2_LIB.BASEBOARD_FAB2(SCH_1):PAGE120
  BV25 FM_BIOS_MRC_DEBUG_MSG_DIS_N @BASEBOARD_FAB2_LIB.BASEBOARD_FAB2(SCH_1):FM_BIOS_MRC_DEBUG_MSG_DIS_N   I147 @BASEBOARD_FAB2_LIB.BASEBOARD_FAB2(SCH_1):PAGE120
  BV21 JTAG_PCH_GBE_CLK @BASEBOARD_FAB2_LIB.BASEBOARD_FAB2(SCH_1):JTAG_PCH_GBE_CLK   I147 @BASEBOARD_FAB2_LIB.BASEBOARD_FAB2(SCH_1):PAGE120
  CA22 JTAG_PCH_GBE_TMS @BASEBOARD_FAB2_LIB.BASEBOARD_FAB2(SCH_1):JTAG_PCH_GBE_TMS   I147 @BASEBOARD_FAB2_LIB.BASEBOARD_FAB2(SCH_1):PAGE120
  BY23 JTAG_PCH_GBE_TDI @BASEBOARD_FAB2_LIB.BASEBOARD_FAB2(SCH_1):JTAG_PCH_GBE_TDI   I147 @BASEBOARD_FAB2_LIB.BASEBOARD_FAB2(SCH_1):PAGE120
  BW20 IRQ_DIMM_SAVE_LVT3_R_N @BASEBOARD_FAB2_LIB.BASEBOARD_FAB2(SCH_1):IRQ_DIMM_SAVE_LVT3_R_N   I147 @BASEBOARD_FAB2_LIB.BASEBOARD_FAB2(SCH_1):PAGE120
  BW24 IRQ_BOARD_BMC_ALERT_N @BASEBOARD_FAB2_LIB.BASEBOARD_FAB2(SCH_1):IRQ_BOARD_BMC_ALERT_N   I147 @BASEBOARD_FAB2_LIB.BASEBOARD_FAB2(SCH_1):PAGE120
  BV23 FM_CPU1_RC_ERROR_R_N @BASEBOARD_FAB2_LIB.BASEBOARD_FAB2(SCH_1):FM_CPU1_RC_ERROR_R_N   I147 @BASEBOARD_FAB2_LIB.BASEBOARD_FAB2(SCH_1):PAGE120
  CA24 JTAG_PCH_GBE_TRST_N @BASEBOARD_FAB2_LIB.BASEBOARD_FAB2(SCH_1):JTAG_PCH_GBE_TRST_N   I147 @BASEBOARD_FAB2_LIB.BASEBOARD_FAB2(SCH_1):PAGE120
  BW22 PU_10GBE_LOM_PCI_DISABLE_N @BASEBOARD_FAB2_LIB.BASEBOARD_FAB2(SCH_1):PU_10GBE_LOM_PCI_DISABLE_N   I147 @BASEBOARD_FAB2_LIB.BASEBOARD_FAB2(SCH_1):PAGE120
  BY21 FM_10GBE_LOM_DISABLE_N @BASEBOARD_FAB2_LIB.BASEBOARD_FAB2(SCH_1):FM_10GBE_LOM_DISABLE_N   I147 @BASEBOARD_FAB2_LIB.BASEBOARD_FAB2(SCH_1):PAGE120
   BL1 LED_GBE_P0_0 @BASEBOARD_FAB2_LIB.BASEBOARD_FAB2(SCH_1):LED_GBE_P0_0   I147 @BASEBOARD_FAB2_LIB.BASEBOARD_FAB2(SCH_1):PAGE120
   BW5 SMB_PCH_MEZZ_LOM1_SCL @BASEBOARD_FAB2_LIB.BASEBOARD_FAB2(SCH_1):SMB_PCH_MEZZ_LOM1_SCL   I147 @BASEBOARD_FAB2_LIB.BASEBOARD_FAB2(SCH_1):PAGE120
   BV8 SMB_PCH_MEZZ_LOM1_SDA @BASEBOARD_FAB2_LIB.BASEBOARD_FAB2(SCH_1):SMB_PCH_MEZZ_LOM1_SDA   I147 @BASEBOARD_FAB2_LIB.BASEBOARD_FAB2(SCH_1):PAGE120
   BT5 SMB_PCH_MEZZ_LOM2_SCL @BASEBOARD_FAB2_LIB.BASEBOARD_FAB2(SCH_1):SMB_PCH_MEZZ_LOM2_SCL   I147 @BASEBOARD_FAB2_LIB.BASEBOARD_FAB2(SCH_1):PAGE120
  BW11 SMB_PCH_MEZZ_LOM2_SDA @BASEBOARD_FAB2_LIB.BASEBOARD_FAB2(SCH_1):SMB_PCH_MEZZ_LOM2_SDA   I147 @BASEBOARD_FAB2_LIB.BASEBOARD_FAB2(SCH_1):PAGE120
   BW6 SMB_PCH_MEZZ_LOM3_SCL @BASEBOARD_FAB2_LIB.BASEBOARD_FAB2(SCH_1):SMB_PCH_MEZZ_LOM3_SCL   I147 @BASEBOARD_FAB2_LIB.BASEBOARD_FAB2(SCH_1):PAGE120
   BW9 SMB_PCH_MEZZ_LOM3_SDA @BASEBOARD_FAB2_LIB.BASEBOARD_FAB2(SCH_1):SMB_PCH_MEZZ_LOM3_SDA   I147 @BASEBOARD_FAB2_LIB.BASEBOARD_FAB2(SCH_1):PAGE120
  BV10 FM_GBE0_LVC3_MOD_ABS @BASEBOARD_FAB2_LIB.BASEBOARD_FAB2(SCH_1):FM_GBE0_LVC3_MOD_ABS   I147 @BASEBOARD_FAB2_LIB.BASEBOARD_FAB2(SCH_1):PAGE120
  CA11 TP_PCH_GPP_J17 @BASEBOARD_FAB2_LIB.BASEBOARD_FAB2(SCH_1):TP_PCH_GPP_J17   I147 @BASEBOARD_FAB2_LIB.BASEBOARD_FAB2(SCH_1):PAGE120
  BY10 FM_GBE1_LVC3_MOD_ABS @BASEBOARD_FAB2_LIB.BASEBOARD_FAB2(SCH_1):FM_GBE1_LVC3_MOD_ABS   I147 @BASEBOARD_FAB2_LIB.BASEBOARD_FAB2(SCH_1):PAGE120
  BY14 TP_PCH_GPP_J19 @BASEBOARD_FAB2_LIB.BASEBOARD_FAB2(SCH_1):TP_PCH_GPP_J19   I147 @BASEBOARD_FAB2_LIB.BASEBOARD_FAB2(SCH_1):PAGE120
   BK4 LED_GBE_P0_1 @BASEBOARD_FAB2_LIB.BASEBOARD_FAB2(SCH_1):LED_GBE_P0_1   I147 @BASEBOARD_FAB2_LIB.BASEBOARD_FAB2(SCH_1):PAGE120
  BW13 FM_GBE2_LVC3_MOD_ABS @BASEBOARD_FAB2_LIB.BASEBOARD_FAB2(SCH_1):FM_GBE2_LVC3_MOD_ABS   I147 @BASEBOARD_FAB2_LIB.BASEBOARD_FAB2(SCH_1):PAGE120
  BV12 TP_PCH_GPP_J21 @BASEBOARD_FAB2_LIB.BASEBOARD_FAB2(SCH_1):TP_PCH_GPP_J21   I147 @BASEBOARD_FAB2_LIB.BASEBOARD_FAB2(SCH_1):PAGE120
  BY12 FM_GBE3_LVC3_MOD_ABS @BASEBOARD_FAB2_LIB.BASEBOARD_FAB2(SCH_1):FM_GBE3_LVC3_MOD_ABS   I147 @BASEBOARD_FAB2_LIB.BASEBOARD_FAB2(SCH_1):PAGE120
  BV14 TP_PCH_GPP_J23 @BASEBOARD_FAB2_LIB.BASEBOARD_FAB2(SCH_1):TP_PCH_GPP_J23   I147 @BASEBOARD_FAB2_LIB.BASEBOARD_FAB2(SCH_1):PAGE120
   BP4 LED_GBE_P1_0 @BASEBOARD_FAB2_LIB.BASEBOARD_FAB2(SCH_1):LED_GBE_P1_0   I147 @BASEBOARD_FAB2_LIB.BASEBOARD_FAB2(SCH_1):PAGE120
   BK2 LED_GBE_P1_1 @BASEBOARD_FAB2_LIB.BASEBOARD_FAB2(SCH_1):LED_GBE_P1_1   I147 @BASEBOARD_FAB2_LIB.BASEBOARD_FAB2(SCH_1):PAGE120
   BL3 LED_GBE_P2_0 @BASEBOARD_FAB2_LIB.BASEBOARD_FAB2(SCH_1):LED_GBE_P2_0   I147 @BASEBOARD_FAB2_LIB.BASEBOARD_FAB2(SCH_1):PAGE120
   BU6 LED_GBE_P2_1 @BASEBOARD_FAB2_LIB.BASEBOARD_FAB2(SCH_1):LED_GBE_P2_1   I147 @BASEBOARD_FAB2_LIB.BASEBOARD_FAB2(SCH_1):PAGE120
  CA13 LED_GBE_P3_0 @BASEBOARD_FAB2_LIB.BASEBOARD_FAB2(SCH_1):LED_GBE_P3_0   I147 @BASEBOARD_FAB2_LIB.BASEBOARD_FAB2(SCH_1):PAGE120
   BM2 LED_GBE_P3_1 @BASEBOARD_FAB2_LIB.BASEBOARD_FAB2(SCH_1):LED_GBE_P3_1   I147 @BASEBOARD_FAB2_LIB.BASEBOARD_FAB2(SCH_1):PAGE120
   BM4 SMB_PCH_MEZZ_LOM0_SCL @BASEBOARD_FAB2_LIB.BASEBOARD_FAB2(SCH_1):SMB_PCH_MEZZ_LOM0_SCL   I147 @BASEBOARD_FAB2_LIB.BASEBOARD_FAB2(SCH_1):PAGE120
   BN3 SMB_PCH_MEZZ_LOM0_SDA @BASEBOARD_FAB2_LIB.BASEBOARD_FAB2(SCH_1):SMB_PCH_MEZZ_LOM0_SDA   I147 @BASEBOARD_FAB2_LIB.BASEBOARD_FAB2(SCH_1):PAGE120
   C70 FM_PCH_PRSNT_N @BASEBOARD_FAB2_LIB.BASEBOARD_FAB2(SCH_1):FM_PCH_PRSNT_N    I34 @BASEBOARD_FAB2_LIB.BASEBOARD_FAB2(SCH_1):PAGE121
   AM4 A_1P8_3P3_RCOMP @BASEBOARD_FAB2_LIB.BASEBOARD_FAB2(SCH_1):A_1P8_3P3_RCOMP    I34 @BASEBOARD_FAB2_LIB.BASEBOARD_FAB2(SCH_1):PAGE121
   AJ1 CLK_50M_CKMNG_PCH_10GBE @BASEBOARD_FAB2_LIB.BASEBOARD_FAB2(SCH_1):CLK_50M_CKMNG_PCH_10GBE    I34 @BASEBOARD_FAB2_LIB.BASEBOARD_FAB2(SCH_1):PAGE121
   AH4 RST_PCIE_PCH_PERST_N @BASEBOARD_FAB2_LIB.BASEBOARD_FAB2(SCH_1):RST_PCIE_PCH_PERST_N    I34 @BASEBOARD_FAB2_LIB.BASEBOARD_FAB2(SCH_1):PAGE121
   AM2 RMII_BMC_PCH_SPRNGVLLE_TXD0 @BASEBOARD_FAB2_LIB.BASEBOARD_FAB2(SCH_1):RMII_BMC_PCH_SPRNGVLLE_TXD0    I34 @BASEBOARD_FAB2_LIB.BASEBOARD_FAB2(SCH_1):PAGE121
   AK2 RMII_BMC_PCH_SPRNGVLLE_TXD1 @BASEBOARD_FAB2_LIB.BASEBOARD_FAB2(SCH_1):RMII_BMC_PCH_SPRNGVLLE_TXD1    I34 @BASEBOARD_FAB2_LIB.BASEBOARD_FAB2(SCH_1):PAGE121
   AL3 RMII_BMC_PCH_SPRNGVLLE_TXEN @BASEBOARD_FAB2_LIB.BASEBOARD_FAB2(SCH_1):RMII_BMC_PCH_SPRNGVLLE_TXEN    I34 @BASEBOARD_FAB2_LIB.BASEBOARD_FAB2(SCH_1):PAGE121
   AN3 RMII_BMC_PCH_SPRNGVLLE_CRSDV_R1 @BASEBOARD_FAB2_LIB.BASEBOARD_FAB2(SCH_1):RMII_BMC_PCH_SPRNGVLLE_CRSDV_R1    I34 @BASEBOARD_FAB2_LIB.BASEBOARD_FAB2(SCH_1):PAGE121
   AL1 RMII_SPRNGVLLE_BMC_PCH_RXD0_R1 @BASEBOARD_FAB2_LIB.BASEBOARD_FAB2(SCH_1):RMII_SPRNGVLLE_BMC_PCH_RXD0_R1    I34 @BASEBOARD_FAB2_LIB.BASEBOARD_FAB2(SCH_1):PAGE121
   AN1 RMII_SPRNGVLLE_BMC_PCH_RXD1_R1 @BASEBOARD_FAB2_LIB.BASEBOARD_FAB2(SCH_1):RMII_SPRNGVLLE_BMC_PCH_RXD1_R1    I34 @BASEBOARD_FAB2_LIB.BASEBOARD_FAB2(SCH_1):PAGE121
   AH2 RMII_BMC_PCH_SPRNGVLLE_RXER_R @BASEBOARD_FAB2_LIB.BASEBOARD_FAB2(SCH_1):RMII_BMC_PCH_SPRNGVLLE_RXER_R    I34 @BASEBOARD_FAB2_LIB.BASEBOARD_FAB2(SCH_1):PAGE121
   AJ3 RMII_PCH_SPRNGVLLE_ARB_IN @BASEBOARD_FAB2_LIB.BASEBOARD_FAB2(SCH_1):RMII_PCH_SPRNGVLLE_ARB_IN    I34 @BASEBOARD_FAB2_LIB.BASEBOARD_FAB2(SCH_1):PAGE121
   AK4 RMII_PCH_SPRNGVLLE_ARB_OUT_R @BASEBOARD_FAB2_LIB.BASEBOARD_FAB2(SCH_1):RMII_PCH_SPRNGVLLE_ARB_OUT_R    I34 @BASEBOARD_FAB2_LIB.BASEBOARD_FAB2(SCH_1):PAGE121
  AF20 TP_PCH_GPP_L10 @BASEBOARD_FAB2_LIB.BASEBOARD_FAB2(SCH_1):TP_PCH_GPP_L10    I34 @BASEBOARD_FAB2_LIB.BASEBOARD_FAB2(SCH_1):PAGE121
  AD20 TP_PCH_GPP_L11 @BASEBOARD_FAB2_LIB.BASEBOARD_FAB2(SCH_1):TP_PCH_GPP_L11    I34 @BASEBOARD_FAB2_LIB.BASEBOARD_FAB2(SCH_1):PAGE121
   Y15 H_CPU0_MEMABC_MEMHOT_PCH_N @BASEBOARD_FAB2_LIB.BASEBOARD_FAB2(SCH_1):H_CPU0_MEMABC_MEMHOT_PCH_N    I34 @BASEBOARD_FAB2_LIB.BASEBOARD_FAB2(SCH_1):PAGE121
  AD13 H_CPU0_MEMDEF_MEMHOT_PCH_N @BASEBOARD_FAB2_LIB.BASEBOARD_FAB2(SCH_1):H_CPU0_MEMDEF_MEMHOT_PCH_N    I34 @BASEBOARD_FAB2_LIB.BASEBOARD_FAB2(SCH_1):PAGE121
  AA13 H_CPU1_MEMGHJ_MEMHOT_PCH_N @BASEBOARD_FAB2_LIB.BASEBOARD_FAB2(SCH_1):H_CPU1_MEMGHJ_MEMHOT_PCH_N    I34 @BASEBOARD_FAB2_LIB.BASEBOARD_FAB2(SCH_1):PAGE121
   Y11 H_CPU1_MEMKLM_MEMHOT_PCH_N @BASEBOARD_FAB2_LIB.BASEBOARD_FAB2(SCH_1):H_CPU1_MEMKLM_MEMHOT_PCH_N    I34 @BASEBOARD_FAB2_LIB.BASEBOARD_FAB2(SCH_1):PAGE121
    Y7 FM_CPU0_PROCHOT_PCH_N @BASEBOARD_FAB2_LIB.BASEBOARD_FAB2(SCH_1):FM_CPU0_PROCHOT_PCH_N    I34 @BASEBOARD_FAB2_LIB.BASEBOARD_FAB2(SCH_1):PAGE121
   AA9 FM_CPU1_PROCHOT_PCH_N @BASEBOARD_FAB2_LIB.BASEBOARD_FAB2(SCH_1):FM_CPU1_PROCHOT_PCH_N    I34 @BASEBOARD_FAB2_LIB.BASEBOARD_FAB2(SCH_1):PAGE121
   AE7 FM_CPU_ERR0_PCH_N @BASEBOARD_FAB2_LIB.BASEBOARD_FAB2(SCH_1):FM_CPU_ERR0_PCH_N    I34 @BASEBOARD_FAB2_LIB.BASEBOARD_FAB2(SCH_1):PAGE121
  AG11 FM_CPU_ERR1_PCH_N @BASEBOARD_FAB2_LIB.BASEBOARD_FAB2(SCH_1):FM_CPU_ERR1_PCH_N    I34 @BASEBOARD_FAB2_LIB.BASEBOARD_FAB2(SCH_1):PAGE121
  AE18 FM_PRSNT_2_1_N @BASEBOARD_FAB2_LIB.BASEBOARD_FAB2(SCH_1):FM_PRSNT_2_1_N    I34 @BASEBOARD_FAB2_LIB.BASEBOARD_FAB2(SCH_1):PAGE121
  AE15 FM_PRSNT_2_2_N @BASEBOARD_FAB2_LIB.BASEBOARD_FAB2(SCH_1):FM_PRSNT_2_2_N    I34 @BASEBOARD_FAB2_LIB.BASEBOARD_FAB2(SCH_1):PAGE121
  AE11 FM_PRSNT_2_3_N @BASEBOARD_FAB2_LIB.BASEBOARD_FAB2(SCH_1):FM_PRSNT_2_3_N    I34 @BASEBOARD_FAB2_LIB.BASEBOARD_FAB2(SCH_1):PAGE121
   Y18 FM_PRSNT_2_4_N @BASEBOARD_FAB2_LIB.BASEBOARD_FAB2(SCH_1):FM_PRSNT_2_4_N    I34 @BASEBOARD_FAB2_LIB.BASEBOARD_FAB2(SCH_1):PAGE121
  AA20 FM_PRSNT_2_5_N @BASEBOARD_FAB2_LIB.BASEBOARD_FAB2(SCH_1):FM_PRSNT_2_5_N    I34 @BASEBOARD_FAB2_LIB.BASEBOARD_FAB2(SCH_1):PAGE121
  AA17 FM_PRSNT_2_6_N @BASEBOARD_FAB2_LIB.BASEBOARD_FAB2(SCH_1):FM_PRSNT_2_6_N    I34 @BASEBOARD_FAB2_LIB.BASEBOARD_FAB2(SCH_1):PAGE121
   AD9 FM_OCP_MEZZB_PRES_1V05_PCH_N @BASEBOARD_FAB2_LIB.BASEBOARD_FAB2(SCH_1):FM_OCP_MEZZB_PRES_1V05_PCH_N    I34 @BASEBOARD_FAB2_LIB.BASEBOARD_FAB2(SCH_1):PAGE121
  AD17 FM_OCP_MEZZC_PRES_1V05_PCH_N @BASEBOARD_FAB2_LIB.BASEBOARD_FAB2(SCH_1):FM_OCP_MEZZC_PRES_1V05_PCH_N    I34 @BASEBOARD_FAB2_LIB.BASEBOARD_FAB2(SCH_1):PAGE121
   P18 TP_PCH_HDA_BCLK @BASEBOARD_FAB2_LIB.BASEBOARD_FAB2(SCH_1):TP_PCH_HDA_BCLK    I34 @BASEBOARD_FAB2_LIB.BASEBOARD_FAB2(SCH_1):PAGE121
   M18 TP_PCH_HSA_RST_N @BASEBOARD_FAB2_LIB.BASEBOARD_FAB2(SCH_1):TP_PCH_HSA_RST_N    I34 @BASEBOARD_FAB2_LIB.BASEBOARD_FAB2(SCH_1):PAGE121
   K20 TP_PCH_HDA_SDI_0 @BASEBOARD_FAB2_LIB.BASEBOARD_FAB2(SCH_1):TP_PCH_HDA_SDI_0    I34 @BASEBOARD_FAB2_LIB.BASEBOARD_FAB2(SCH_1):PAGE121
   V18 TP_PCH_HDA_SDI_1 @BASEBOARD_FAB2_LIB.BASEBOARD_FAB2(SCH_1):TP_PCH_HDA_SDI_1    I34 @BASEBOARD_FAB2_LIB.BASEBOARD_FAB2(SCH_1):PAGE121
   U24 FM_FLASH_DESC_OVERRIDE @BASEBOARD_FAB2_LIB.BASEBOARD_FAB2(SCH_1):FM_FLASH_DESC_OVERRIDE    I34 @BASEBOARD_FAB2_LIB.BASEBOARD_FAB2(SCH_1):PAGE121
   H20 TP_PCH_HDA_SYNC @BASEBOARD_FAB2_LIB.BASEBOARD_FAB2(SCH_1):TP_PCH_HDA_SYNC    I34 @BASEBOARD_FAB2_LIB.BASEBOARD_FAB2(SCH_1):PAGE121
  AG18 FM_INTRUDER_HDR_PCH_N @BASEBOARD_FAB2_LIB.BASEBOARD_FAB2(SCH_1):FM_INTRUDER_HDR_PCH_N    I34 @BASEBOARD_FAB2_LIB.BASEBOARD_FAB2(SCH_1):PAGE121
   V22 TP_PCH_DISPA_SDO @BASEBOARD_FAB2_LIB.BASEBOARD_FAB2(SCH_1):TP_PCH_DISPA_SDO    I34 @BASEBOARD_FAB2_LIB.BASEBOARD_FAB2(SCH_1):PAGE121
   R20 TP_PCH_DISPA_SDI @BASEBOARD_FAB2_LIB.BASEBOARD_FAB2(SCH_1):TP_PCH_DISPA_SDI    I34 @BASEBOARD_FAB2_LIB.BASEBOARD_FAB2(SCH_1):PAGE121
   U20 TP_PCH_DISPA_BCLK @BASEBOARD_FAB2_LIB.BASEBOARD_FAB2(SCH_1):TP_PCH_DISPA_BCLK    I34 @BASEBOARD_FAB2_LIB.BASEBOARD_FAB2(SCH_1):PAGE121
   BW3 TP_PCH_RSVD46 @BASEBOARD_FAB2_LIB.BASEBOARD_FAB2(SCH_1):TP_PCH_RSVD46    I34 @BASEBOARD_FAB2_LIB.BASEBOARD_FAB2(SCH_1):PAGE121
  BG26 TP_PCH_RSVD27 @BASEBOARD_FAB2_LIB.BASEBOARD_FAB2(SCH_1):TP_PCH_RSVD27    I34 @BASEBOARD_FAB2_LIB.BASEBOARD_FAB2(SCH_1):PAGE121
  BH24 TP_PCH_RSVD26 @BASEBOARD_FAB2_LIB.BASEBOARD_FAB2(SCH_1):TP_PCH_RSVD26    I34 @BASEBOARD_FAB2_LIB.BASEBOARD_FAB2(SCH_1):PAGE121
   P48 TP_PCH_RSVD25 @BASEBOARD_FAB2_LIB.BASEBOARD_FAB2(SCH_1):TP_PCH_RSVD25    I34 @BASEBOARD_FAB2_LIB.BASEBOARD_FAB2(SCH_1):PAGE121
   P44 TP_PCH_RSVD24 @BASEBOARD_FAB2_LIB.BASEBOARD_FAB2(SCH_1):TP_PCH_RSVD24    I34 @BASEBOARD_FAB2_LIB.BASEBOARD_FAB2(SCH_1):PAGE121
   P40 TP_PCH_RSVD23 @BASEBOARD_FAB2_LIB.BASEBOARD_FAB2(SCH_1):TP_PCH_RSVD23    I34 @BASEBOARD_FAB2_LIB.BASEBOARD_FAB2(SCH_1):PAGE121
  AT71 TP_PCH_RSVD22 @BASEBOARD_FAB2_LIB.BASEBOARD_FAB2(SCH_1):TP_PCH_RSVD22    I34 @BASEBOARD_FAB2_LIB.BASEBOARD_FAB2(SCH_1):PAGE121
   A11 TP_PCH_RSVD21 @BASEBOARD_FAB2_LIB.BASEBOARD_FAB2(SCH_1):TP_PCH_RSVD21    I34 @BASEBOARD_FAB2_LIB.BASEBOARD_FAB2(SCH_1):PAGE121
   D10 TP_PCH_RSVD20 @BASEBOARD_FAB2_LIB.BASEBOARD_FAB2(SCH_1):TP_PCH_RSVD20    I34 @BASEBOARD_FAB2_LIB.BASEBOARD_FAB2(SCH_1):PAGE121
    C9 TP_PCH_RSVD19 @BASEBOARD_FAB2_LIB.BASEBOARD_FAB2(SCH_1):TP_PCH_RSVD19    I34 @BASEBOARD_FAB2_LIB.BASEBOARD_FAB2(SCH_1):PAGE121
   C11 TP_PCH_RSVD18 @BASEBOARD_FAB2_LIB.BASEBOARD_FAB2(SCH_1):TP_PCH_RSVD18    I34 @BASEBOARD_FAB2_LIB.BASEBOARD_FAB2(SCH_1):PAGE121
   B10 TP_PCH_RSVD17 @BASEBOARD_FAB2_LIB.BASEBOARD_FAB2(SCH_1):TP_PCH_RSVD17    I34 @BASEBOARD_FAB2_LIB.BASEBOARD_FAB2(SCH_1):PAGE121
    C5 TP_PCH_RSVD16 @BASEBOARD_FAB2_LIB.BASEBOARD_FAB2(SCH_1):TP_PCH_RSVD16    I34 @BASEBOARD_FAB2_LIB.BASEBOARD_FAB2(SCH_1):PAGE121
    C6 TP_PCH_RSVD15 @BASEBOARD_FAB2_LIB.BASEBOARD_FAB2(SCH_1):TP_PCH_RSVD15    I34 @BASEBOARD_FAB2_LIB.BASEBOARD_FAB2(SCH_1):PAGE121
   E18 TP_PCH_RSVD14 @BASEBOARD_FAB2_LIB.BASEBOARD_FAB2(SCH_1):TP_PCH_RSVD14    I34 @BASEBOARD_FAB2_LIB.BASEBOARD_FAB2(SCH_1):PAGE121
   C67 TP_PCH_RSVD13 @BASEBOARD_FAB2_LIB.BASEBOARD_FAB2(SCH_1):TP_PCH_RSVD13    I34 @BASEBOARD_FAB2_LIB.BASEBOARD_FAB2(SCH_1):PAGE121
   C68 TP_PCH_RSVD12 @BASEBOARD_FAB2_LIB.BASEBOARD_FAB2(SCH_1):TP_PCH_RSVD12    I34 @BASEBOARD_FAB2_LIB.BASEBOARD_FAB2(SCH_1):PAGE121
   C18 FM_SINT_PRSNT_N @BASEBOARD_FAB2_LIB.BASEBOARD_FAB2(SCH_1):FM_SINT_PRSNT_N    I34 @BASEBOARD_FAB2_LIB.BASEBOARD_FAB2(SCH_1):PAGE121
    D8 FM_WBG_PRSNT_N @BASEBOARD_FAB2_LIB.BASEBOARD_FAB2(SCH_1):FM_WBG_PRSNT_N    I34 @BASEBOARD_FAB2_LIB.BASEBOARD_FAB2(SCH_1):PAGE121
   F66 TP_PCH_RSVD9 @BASEBOARD_FAB2_LIB.BASEBOARD_FAB2(SCH_1):TP_PCH_RSVD9    I34 @BASEBOARD_FAB2_LIB.BASEBOARD_FAB2(SCH_1):PAGE121
   F69 TP_PCH_RSVD8 @BASEBOARD_FAB2_LIB.BASEBOARD_FAB2(SCH_1):TP_PCH_RSVD8    I34 @BASEBOARD_FAB2_LIB.BASEBOARD_FAB2(SCH_1):PAGE121
    F8 TP_PCH_RSVD7 @BASEBOARD_FAB2_LIB.BASEBOARD_FAB2(SCH_1):TP_PCH_RSVD7    I34 @BASEBOARD_FAB2_LIB.BASEBOARD_FAB2(SCH_1):PAGE121
  AT69 TP_PCH_RSVD6 @BASEBOARD_FAB2_LIB.BASEBOARD_FAB2(SCH_1):TP_PCH_RSVD6    I34 @BASEBOARD_FAB2_LIB.BASEBOARD_FAB2(SCH_1):PAGE121
  AG15 TP_PCH_RSVD5 @BASEBOARD_FAB2_LIB.BASEBOARD_FAB2(SCH_1):TP_PCH_RSVD5    I34 @BASEBOARD_FAB2_LIB.BASEBOARD_FAB2(SCH_1):PAGE121
   P37 TP_PCH_RSVD4 @BASEBOARD_FAB2_LIB.BASEBOARD_FAB2(SCH_1):TP_PCH_RSVD4    I34 @BASEBOARD_FAB2_LIB.BASEBOARD_FAB2(SCH_1):PAGE121
   V11 TP_PCH_RSVD3 @BASEBOARD_FAB2_LIB.BASEBOARD_FAB2(SCH_1):TP_PCH_RSVD3    I34 @BASEBOARD_FAB2_LIB.BASEBOARD_FAB2(SCH_1):PAGE121
  AA58 TP_PCH_RSVD2 @BASEBOARD_FAB2_LIB.BASEBOARD_FAB2(SCH_1):TP_PCH_RSVD2    I34 @BASEBOARD_FAB2_LIB.BASEBOARD_FAB2(SCH_1):PAGE121
  AC56 TP_PCH_RSVD1 @BASEBOARD_FAB2_LIB.BASEBOARD_FAB2(SCH_1):TP_PCH_RSVD1    I34 @BASEBOARD_FAB2_LIB.BASEBOARD_FAB2(SCH_1):PAGE121
  AF61 TP_PCH_RSVD0 @BASEBOARD_FAB2_LIB.BASEBOARD_FAB2(SCH_1):TP_PCH_RSVD0    I34 @BASEBOARD_FAB2_LIB.BASEBOARD_FAB2(SCH_1):PAGE121
   P11 RST_RTCRST_N @BASEBOARD_FAB2_LIB.BASEBOARD_FAB2(SCH_1):RST_RTCRST_N    I34 @BASEBOARD_FAB2_LIB.BASEBOARD_FAB2(SCH_1):PAGE121
    K2 SPI_PCH_CLK @BASEBOARD_FAB2_LIB.BASEBOARD_FAB2(SCH_1):SPI_PCH_CLK    I34 @BASEBOARD_FAB2_LIB.BASEBOARD_FAB2(SCH_1):PAGE121
    J3 SPI_PCH_CS0_R_N @BASEBOARD_FAB2_LIB.BASEBOARD_FAB2(SCH_1):SPI_PCH_CS0_R_N    I34 @BASEBOARD_FAB2_LIB.BASEBOARD_FAB2(SCH_1):PAGE121
    G7 TP_SPI_PCH_CS1_R1_N @BASEBOARD_FAB2_LIB.BASEBOARD_FAB2(SCH_1):TP_SPI_PCH_CS1_R1_N    I34 @BASEBOARD_FAB2_LIB.BASEBOARD_FAB2(SCH_1):PAGE121
    F5 SPI_PCH_IO2 @BASEBOARD_FAB2_LIB.BASEBOARD_FAB2(SCH_1):SPI_PCH_IO2    I34 @BASEBOARD_FAB2_LIB.BASEBOARD_FAB2(SCH_1):PAGE121
    L1 SPI_PCH_IO3 @BASEBOARD_FAB2_LIB.BASEBOARD_FAB2(SCH_1):SPI_PCH_IO3    I34 @BASEBOARD_FAB2_LIB.BASEBOARD_FAB2(SCH_1):PAGE121
    L3 SPI_PCH_MISO @BASEBOARD_FAB2_LIB.BASEBOARD_FAB2(SCH_1):SPI_PCH_MISO    I34 @BASEBOARD_FAB2_LIB.BASEBOARD_FAB2(SCH_1):PAGE121
    H4 SPI_PCH_MOSI_R @BASEBOARD_FAB2_LIB.BASEBOARD_FAB2(SCH_1):SPI_PCH_MOSI_R    I34 @BASEBOARD_FAB2_LIB.BASEBOARD_FAB2(SCH_1):PAGE121
    K4 SPI_PCH_TPM_CS_N @BASEBOARD_FAB2_LIB.BASEBOARD_FAB2(SCH_1):SPI_PCH_TPM_CS_N    I34 @BASEBOARD_FAB2_LIB.BASEBOARD_FAB2(SCH_1):PAGE121
   G18 RST_SRTCRST_N @BASEBOARD_FAB2_LIB.BASEBOARD_FAB2(SCH_1):RST_SRTCRST_N    I34 @BASEBOARD_FAB2_LIB.BASEBOARD_FAB2(SCH_1):PAGE121
  AT27 TP_PCH_RSVD59 @BASEBOARD_FAB2_LIB.BASEBOARD_FAB2(SCH_1):TP_PCH_RSVD59    I63 @BASEBOARD_FAB2_LIB.BASEBOARD_FAB2(SCH_1):PAGE122
  AP27 TP_PCH_RSVD58 @BASEBOARD_FAB2_LIB.BASEBOARD_FAB2(SCH_1):TP_PCH_RSVD58    I63 @BASEBOARD_FAB2_LIB.BASEBOARD_FAB2(SCH_1):PAGE122
   P29 TP_PCH_RSVD31 @BASEBOARD_FAB2_LIB.BASEBOARD_FAB2(SCH_1):TP_PCH_RSVD31    I63 @BASEBOARD_FAB2_LIB.BASEBOARD_FAB2(SCH_1):PAGE122
   R31 TP_PCH_RSVD30 @BASEBOARD_FAB2_LIB.BASEBOARD_FAB2(SCH_1):TP_PCH_RSVD30    I63 @BASEBOARD_FAB2_LIB.BASEBOARD_FAB2(SCH_1):PAGE122
   P33 TP_PCH_RSVD29 @BASEBOARD_FAB2_LIB.BASEBOARD_FAB2(SCH_1):TP_PCH_RSVD29    I63 @BASEBOARD_FAB2_LIB.BASEBOARD_FAB2(SCH_1):PAGE122
   R35 TP_PCH_RSVD28 @BASEBOARD_FAB2_LIB.BASEBOARD_FAB2(SCH_1):TP_PCH_RSVD28    I63 @BASEBOARD_FAB2_LIB.BASEBOARD_FAB2(SCH_1):PAGE122
  AE46 P1V05_PCH_STBY_ISCLK_PLL @BASEBOARD_FAB2_LIB.BASEBOARD_FAB2(SCH_1):P1V05_PCH_STBY_ISCLK_PLL    I63 @BASEBOARD_FAB2_LIB.BASEBOARD_FAB2(SCH_1):PAGE122
  AJ48 P1V05_PCH_STBY_ISCLK_PLL @BASEBOARD_FAB2_LIB.BASEBOARD_FAB2(SCH_1):P1V05_PCH_STBY_ISCLK_PLL    I63 @BASEBOARD_FAB2_LIB.BASEBOARD_FAB2(SCH_1):PAGE122
  AJ46 P1V05_PCH_STBY_ISCLK_PLL @BASEBOARD_FAB2_LIB.BASEBOARD_FAB2(SCH_1):P1V05_PCH_STBY_ISCLK_PLL    I63 @BASEBOARD_FAB2_LIB.BASEBOARD_FAB2(SCH_1):PAGE122
  AG45 P1V05_PCH_STBY_ISCLK_PLL @BASEBOARD_FAB2_LIB.BASEBOARD_FAB2(SCH_1):P1V05_PCH_STBY_ISCLK_PLL    I63 @BASEBOARD_FAB2_LIB.BASEBOARD_FAB2(SCH_1):PAGE122
   W50 P1V05_PCH_STBY_ISCLK_PLL @BASEBOARD_FAB2_LIB.BASEBOARD_FAB2(SCH_1):P1V05_PCH_STBY_ISCLK_PLL    I63 @BASEBOARD_FAB2_LIB.BASEBOARD_FAB2(SCH_1):PAGE122
   U50 P1V05_PCH_STBY @BASEBOARD_FAB2_LIB.BASEBOARD_FAB2(SCH_1):P1V05_PCH_STBY    I63 @BASEBOARD_FAB2_LIB.BASEBOARD_FAB2(SCH_1):PAGE122
  AH50 P1V05_PCH_STBY @BASEBOARD_FAB2_LIB.BASEBOARD_FAB2(SCH_1):P1V05_PCH_STBY    I63 @BASEBOARD_FAB2_LIB.BASEBOARD_FAB2(SCH_1):PAGE122
  AD50 P1V05_PCH_STBY_VCCA_XTAL @BASEBOARD_FAB2_LIB.BASEBOARD_FAB2(SCH_1):P1V05_PCH_STBY_VCCA_XTAL    I63 @BASEBOARD_FAB2_LIB.BASEBOARD_FAB2(SCH_1):PAGE122
  AG48 P1V05_PCH_STBY_VCCA_PLL0 @BASEBOARD_FAB2_LIB.BASEBOARD_FAB2(SCH_1):P1V05_PCH_STBY_VCCA_PLL0    I63 @BASEBOARD_FAB2_LIB.BASEBOARD_FAB2(SCH_1):PAGE122
  AE45 P1V05_PCH_STBY_VCCA_PLL1 @BASEBOARD_FAB2_LIB.BASEBOARD_FAB2(SCH_1):P1V05_PCH_STBY_VCCA_PLL1    I63 @BASEBOARD_FAB2_LIB.BASEBOARD_FAB2(SCH_1):PAGE122
  AK43 P1V05_PCH_STBY @BASEBOARD_FAB2_LIB.BASEBOARD_FAB2(SCH_1):P1V05_PCH_STBY    I63 @BASEBOARD_FAB2_LIB.BASEBOARD_FAB2(SCH_1):PAGE122
  AK45 P1V05_PCH_STBY @BASEBOARD_FAB2_LIB.BASEBOARD_FAB2(SCH_1):P1V05_PCH_STBY    I63 @BASEBOARD_FAB2_LIB.BASEBOARD_FAB2(SCH_1):PAGE122
  AM43 P1V05_PCH_STBY @BASEBOARD_FAB2_LIB.BASEBOARD_FAB2(SCH_1):P1V05_PCH_STBY    I63 @BASEBOARD_FAB2_LIB.BASEBOARD_FAB2(SCH_1):PAGE122
  AM45 P1V05_PCH_STBY @BASEBOARD_FAB2_LIB.BASEBOARD_FAB2(SCH_1):P1V05_PCH_STBY    I63 @BASEBOARD_FAB2_LIB.BASEBOARD_FAB2(SCH_1):PAGE122
  AP43 P1V05_PCH_STBY @BASEBOARD_FAB2_LIB.BASEBOARD_FAB2(SCH_1):P1V05_PCH_STBY    I63 @BASEBOARD_FAB2_LIB.BASEBOARD_FAB2(SCH_1):PAGE122
  AP45 P1V05_PCH_STBY @BASEBOARD_FAB2_LIB.BASEBOARD_FAB2(SCH_1):P1V05_PCH_STBY    I63 @BASEBOARD_FAB2_LIB.BASEBOARD_FAB2(SCH_1):PAGE122
  AT43 P1V05_PCH_STBY @BASEBOARD_FAB2_LIB.BASEBOARD_FAB2(SCH_1):P1V05_PCH_STBY    I63 @BASEBOARD_FAB2_LIB.BASEBOARD_FAB2(SCH_1):PAGE122
  AT45 P1V05_PCH_STBY @BASEBOARD_FAB2_LIB.BASEBOARD_FAB2(SCH_1):P1V05_PCH_STBY    I63 @BASEBOARD_FAB2_LIB.BASEBOARD_FAB2(SCH_1):PAGE122
  AU43 P1V05_PCH_STBY @BASEBOARD_FAB2_LIB.BASEBOARD_FAB2(SCH_1):P1V05_PCH_STBY    I63 @BASEBOARD_FAB2_LIB.BASEBOARD_FAB2(SCH_1):PAGE122
  AU45 P1V05_PCH_STBY @BASEBOARD_FAB2_LIB.BASEBOARD_FAB2(SCH_1):P1V05_PCH_STBY    I63 @BASEBOARD_FAB2_LIB.BASEBOARD_FAB2(SCH_1):PAGE122
  AJ43 P1V05_PCH_STBY @BASEBOARD_FAB2_LIB.BASEBOARD_FAB2(SCH_1):P1V05_PCH_STBY    I63 @BASEBOARD_FAB2_LIB.BASEBOARD_FAB2(SCH_1):PAGE122
  AW43 P1V05_PCH_STBY @BASEBOARD_FAB2_LIB.BASEBOARD_FAB2(SCH_1):P1V05_PCH_STBY    I63 @BASEBOARD_FAB2_LIB.BASEBOARD_FAB2(SCH_1):PAGE122
  AW45 P1V05_PCH_STBY @BASEBOARD_FAB2_LIB.BASEBOARD_FAB2(SCH_1):P1V05_PCH_STBY    I63 @BASEBOARD_FAB2_LIB.BASEBOARD_FAB2(SCH_1):PAGE122
  BA39 P1V05_PCH_STBY_KR_PLL @BASEBOARD_FAB2_LIB.BASEBOARD_FAB2(SCH_1):P1V05_PCH_STBY_KR_PLL    I63 @BASEBOARD_FAB2_LIB.BASEBOARD_FAB2(SCH_1):PAGE122
  BA41 P1V05_PCH_STBY_KR_PLL @BASEBOARD_FAB2_LIB.BASEBOARD_FAB2(SCH_1):P1V05_PCH_STBY_KR_PLL    I63 @BASEBOARD_FAB2_LIB.BASEBOARD_FAB2(SCH_1):PAGE122
  BB40 P1V05_PCH_STBY_KR_PLL @BASEBOARD_FAB2_LIB.BASEBOARD_FAB2(SCH_1):P1V05_PCH_STBY_KR_PLL    I63 @BASEBOARD_FAB2_LIB.BASEBOARD_FAB2(SCH_1):PAGE122
  BD38 P1V05_PCH_STBY_KR_PLL @BASEBOARD_FAB2_LIB.BASEBOARD_FAB2(SCH_1):P1V05_PCH_STBY_KR_PLL    I63 @BASEBOARD_FAB2_LIB.BASEBOARD_FAB2(SCH_1):PAGE122
  BA27 P1V8_PCH_STBY @BASEBOARD_FAB2_LIB.BASEBOARD_FAB2(SCH_1):P1V8_PCH_STBY    I63 @BASEBOARD_FAB2_LIB.BASEBOARD_FAB2(SCH_1):PAGE122
  BA29 P1V8_PCH_STBY @BASEBOARD_FAB2_LIB.BASEBOARD_FAB2(SCH_1):P1V8_PCH_STBY    I63 @BASEBOARD_FAB2_LIB.BASEBOARD_FAB2(SCH_1):PAGE122
  BA30 P1V05_PCH_STBY @BASEBOARD_FAB2_LIB.BASEBOARD_FAB2(SCH_1):P1V05_PCH_STBY    I63 @BASEBOARD_FAB2_LIB.BASEBOARD_FAB2(SCH_1):PAGE122
  BA32 P1V05_PCH_STBY @BASEBOARD_FAB2_LIB.BASEBOARD_FAB2(SCH_1):P1V05_PCH_STBY    I63 @BASEBOARD_FAB2_LIB.BASEBOARD_FAB2(SCH_1):PAGE122
  BA34 P1V05_PCH_STBY @BASEBOARD_FAB2_LIB.BASEBOARD_FAB2(SCH_1):P1V05_PCH_STBY    I63 @BASEBOARD_FAB2_LIB.BASEBOARD_FAB2(SCH_1):PAGE122
  BA36 P1V05_PCH_STBY @BASEBOARD_FAB2_LIB.BASEBOARD_FAB2(SCH_1):P1V05_PCH_STBY    I63 @BASEBOARD_FAB2_LIB.BASEBOARD_FAB2(SCH_1):PAGE122
  BA37 P1V05_PCH_STBY @BASEBOARD_FAB2_LIB.BASEBOARD_FAB2(SCH_1):P1V05_PCH_STBY    I63 @BASEBOARD_FAB2_LIB.BASEBOARD_FAB2(SCH_1):PAGE122
  BB33 P1V05_PCH_STBY @BASEBOARD_FAB2_LIB.BASEBOARD_FAB2(SCH_1):P1V05_PCH_STBY    I63 @BASEBOARD_FAB2_LIB.BASEBOARD_FAB2(SCH_1):PAGE122
  BB37 P1V05_PCH_STBY @BASEBOARD_FAB2_LIB.BASEBOARD_FAB2(SCH_1):P1V05_PCH_STBY    I63 @BASEBOARD_FAB2_LIB.BASEBOARD_FAB2(SCH_1):PAGE122
  AH24 P3V3_STBY @BASEBOARD_FAB2_LIB.BASEBOARD_FAB2(SCH_1):P3V3_STBY    I63 @BASEBOARD_FAB2_LIB.BASEBOARD_FAB2(SCH_1):PAGE122
  AW24 P3V3_STBY @BASEBOARD_FAB2_LIB.BASEBOARD_FAB2(SCH_1):P3V3_STBY    I63 @BASEBOARD_FAB2_LIB.BASEBOARD_FAB2(SCH_1):PAGE122
  BE26 P3V3_STBY @BASEBOARD_FAB2_LIB.BASEBOARD_FAB2(SCH_1):P3V3_STBY    I63 @BASEBOARD_FAB2_LIB.BASEBOARD_FAB2(SCH_1):PAGE122
  BE40 P3V3_STBY @BASEBOARD_FAB2_LIB.BASEBOARD_FAB2(SCH_1):P3V3_STBY    I63 @BASEBOARD_FAB2_LIB.BASEBOARD_FAB2(SCH_1):PAGE122
  BA43 P3V3_STBY @BASEBOARD_FAB2_LIB.BASEBOARD_FAB2(SCH_1):P3V3_STBY    I63 @BASEBOARD_FAB2_LIB.BASEBOARD_FAB2(SCH_1):PAGE122
  BE44 P3V3_STBY @BASEBOARD_FAB2_LIB.BASEBOARD_FAB2(SCH_1):P3V3_STBY    I63 @BASEBOARD_FAB2_LIB.BASEBOARD_FAB2(SCH_1):PAGE122
  AU27 P3V3_STBY @BASEBOARD_FAB2_LIB.BASEBOARD_FAB2(SCH_1):P3V3_STBY    I63 @BASEBOARD_FAB2_LIB.BASEBOARD_FAB2(SCH_1):PAGE122
  BA26 P3V3_STBY @BASEBOARD_FAB2_LIB.BASEBOARD_FAB2(SCH_1):P3V3_STBY    I63 @BASEBOARD_FAB2_LIB.BASEBOARD_FAB2(SCH_1):PAGE122
  BA24 P3V3_STBY @BASEBOARD_FAB2_LIB.BASEBOARD_FAB2(SCH_1):P3V3_STBY    I63 @BASEBOARD_FAB2_LIB.BASEBOARD_FAB2(SCH_1):PAGE122
  BB26 P3V3_STBY @BASEBOARD_FAB2_LIB.BASEBOARD_FAB2(SCH_1):P3V3_STBY    I63 @BASEBOARD_FAB2_LIB.BASEBOARD_FAB2(SCH_1):PAGE122
  AU24 P3V3_STBY @BASEBOARD_FAB2_LIB.BASEBOARD_FAB2(SCH_1):P3V3_STBY    I63 @BASEBOARD_FAB2_LIB.BASEBOARD_FAB2(SCH_1):PAGE122
  AK24 P1V8_PCH_STBY @BASEBOARD_FAB2_LIB.BASEBOARD_FAB2(SCH_1):P1V8_PCH_STBY    I63 @BASEBOARD_FAB2_LIB.BASEBOARD_FAB2(SCH_1):PAGE122
  AW27 P1V8_PCH_STBY @BASEBOARD_FAB2_LIB.BASEBOARD_FAB2(SCH_1):P1V8_PCH_STBY    I63 @BASEBOARD_FAB2_LIB.BASEBOARD_FAB2(SCH_1):PAGE122
  AP29 P1V8_PCH_STBY @BASEBOARD_FAB2_LIB.BASEBOARD_FAB2(SCH_1):P1V8_PCH_STBY    I63 @BASEBOARD_FAB2_LIB.BASEBOARD_FAB2(SCH_1):PAGE122
  AM29 P1V8_PCH_STBY @BASEBOARD_FAB2_LIB.BASEBOARD_FAB2(SCH_1):P1V8_PCH_STBY    I63 @BASEBOARD_FAB2_LIB.BASEBOARD_FAB2(SCH_1):PAGE122
  AT29 P1V8_PCH_STBY @BASEBOARD_FAB2_LIB.BASEBOARD_FAB2(SCH_1):P1V8_PCH_STBY    I63 @BASEBOARD_FAB2_LIB.BASEBOARD_FAB2(SCH_1):PAGE122
  AW29 P1V8_PCH_STBY @BASEBOARD_FAB2_LIB.BASEBOARD_FAB2(SCH_1):P1V8_PCH_STBY    I63 @BASEBOARD_FAB2_LIB.BASEBOARD_FAB2(SCH_1):PAGE122
  AU29 P1V8_PCH_STBY @BASEBOARD_FAB2_LIB.BASEBOARD_FAB2(SCH_1):P1V8_PCH_STBY    I63 @BASEBOARD_FAB2_LIB.BASEBOARD_FAB2(SCH_1):PAGE122
  AG27 P1V8_PCH_STBY @BASEBOARD_FAB2_LIB.BASEBOARD_FAB2(SCH_1):P1V8_PCH_STBY    I63 @BASEBOARD_FAB2_LIB.BASEBOARD_FAB2(SCH_1):PAGE122
   Y26 P1V05_PCH_STBY @BASEBOARD_FAB2_LIB.BASEBOARD_FAB2(SCH_1):P1V05_PCH_STBY    I63 @BASEBOARD_FAB2_LIB.BASEBOARD_FAB2(SCH_1):PAGE122
  AA24 P1V05_PCH_STBY @BASEBOARD_FAB2_LIB.BASEBOARD_FAB2(SCH_1):P1V05_PCH_STBY    I63 @BASEBOARD_FAB2_LIB.BASEBOARD_FAB2(SCH_1):PAGE122
  AK27 P1V05_PCH_STBY @BASEBOARD_FAB2_LIB.BASEBOARD_FAB2(SCH_1):P1V05_PCH_STBY    I63 @BASEBOARD_FAB2_LIB.BASEBOARD_FAB2(SCH_1):PAGE122
   R42 P1V05_PCH_STBY @BASEBOARD_FAB2_LIB.BASEBOARD_FAB2(SCH_1):P1V05_PCH_STBY    I63 @BASEBOARD_FAB2_LIB.BASEBOARD_FAB2(SCH_1):PAGE122
   R46 P1V05_PCH_STBY @BASEBOARD_FAB2_LIB.BASEBOARD_FAB2(SCH_1):P1V05_PCH_STBY    I63 @BASEBOARD_FAB2_LIB.BASEBOARD_FAB2(SCH_1):PAGE122
   T44 P1V05_PCH_STBY @BASEBOARD_FAB2_LIB.BASEBOARD_FAB2(SCH_1):P1V05_PCH_STBY    I63 @BASEBOARD_FAB2_LIB.BASEBOARD_FAB2(SCH_1):PAGE122
   U46 P1V05_PCH_STBY @BASEBOARD_FAB2_LIB.BASEBOARD_FAB2(SCH_1):P1V05_PCH_STBY    I63 @BASEBOARD_FAB2_LIB.BASEBOARD_FAB2(SCH_1):PAGE122
   V44 P1V05_PCH_STBY @BASEBOARD_FAB2_LIB.BASEBOARD_FAB2(SCH_1):P1V05_PCH_STBY    I63 @BASEBOARD_FAB2_LIB.BASEBOARD_FAB2(SCH_1):PAGE122
   Y45 P1V05_PCH_STBY @BASEBOARD_FAB2_LIB.BASEBOARD_FAB2(SCH_1):P1V05_PCH_STBY    I63 @BASEBOARD_FAB2_LIB.BASEBOARD_FAB2(SCH_1):PAGE122
   Y46 P1V05_PCH_STBY @BASEBOARD_FAB2_LIB.BASEBOARD_FAB2(SCH_1):P1V05_PCH_STBY    I63 @BASEBOARD_FAB2_LIB.BASEBOARD_FAB2(SCH_1):PAGE122
  AA45 P1V05_PCH_STBY @BASEBOARD_FAB2_LIB.BASEBOARD_FAB2(SCH_1):P1V05_PCH_STBY    I63 @BASEBOARD_FAB2_LIB.BASEBOARD_FAB2(SCH_1):PAGE122
  AA46 P1V05_PCH_STBY @BASEBOARD_FAB2_LIB.BASEBOARD_FAB2(SCH_1):P1V05_PCH_STBY    I63 @BASEBOARD_FAB2_LIB.BASEBOARD_FAB2(SCH_1):PAGE122
  AC26 P1V05_PCH_STBY @BASEBOARD_FAB2_LIB.BASEBOARD_FAB2(SCH_1):P1V05_PCH_STBY    I63 @BASEBOARD_FAB2_LIB.BASEBOARD_FAB2(SCH_1):PAGE122
  AJ29 P1V05_PCH_STBY @BASEBOARD_FAB2_LIB.BASEBOARD_FAB2(SCH_1):P1V05_PCH_STBY    I63 @BASEBOARD_FAB2_LIB.BASEBOARD_FAB2(SCH_1):PAGE122
  AM27 P1V05_PCH_STBY @BASEBOARD_FAB2_LIB.BASEBOARD_FAB2(SCH_1):P1V05_PCH_STBY    I63 @BASEBOARD_FAB2_LIB.BASEBOARD_FAB2(SCH_1):PAGE122
  AT39 P1V05_PCH_STBY @BASEBOARD_FAB2_LIB.BASEBOARD_FAB2(SCH_1):P1V05_PCH_STBY    I63 @BASEBOARD_FAB2_LIB.BASEBOARD_FAB2(SCH_1):PAGE122
  AU37 P1V05_PCH_STBY @BASEBOARD_FAB2_LIB.BASEBOARD_FAB2(SCH_1):P1V05_PCH_STBY    I63 @BASEBOARD_FAB2_LIB.BASEBOARD_FAB2(SCH_1):PAGE122
  AU39 P1V05_PCH_STBY @BASEBOARD_FAB2_LIB.BASEBOARD_FAB2(SCH_1):P1V05_PCH_STBY    I63 @BASEBOARD_FAB2_LIB.BASEBOARD_FAB2(SCH_1):PAGE122
  BE48 P1V05_PCH_STBY @BASEBOARD_FAB2_LIB.BASEBOARD_FAB2(SCH_1):P1V05_PCH_STBY    I63 @BASEBOARD_FAB2_LIB.BASEBOARD_FAB2(SCH_1):PAGE122
  BF46 P1V05_PCH_STBY @BASEBOARD_FAB2_LIB.BASEBOARD_FAB2(SCH_1):P1V05_PCH_STBY    I63 @BASEBOARD_FAB2_LIB.BASEBOARD_FAB2(SCH_1):PAGE122
  AJ27 P3V3_RTC_STBY @BASEBOARD_FAB2_LIB.BASEBOARD_FAB2(SCH_1):P3V3_RTC_STBY    I63 @BASEBOARD_FAB2_LIB.BASEBOARD_FAB2(SCH_1):PAGE122
  AG29 P3V3_STBY @BASEBOARD_FAB2_LIB.BASEBOARD_FAB2(SCH_1):P3V3_STBY    I63 @BASEBOARD_FAB2_LIB.BASEBOARD_FAB2(SCH_1):PAGE122
  AR24 P3V3_STBY @BASEBOARD_FAB2_LIB.BASEBOARD_FAB2(SCH_1):P3V3_STBY    I63 @BASEBOARD_FAB2_LIB.BASEBOARD_FAB2(SCH_1):PAGE122
  AK29 P1V8_PCH_STBY @BASEBOARD_FAB2_LIB.BASEBOARD_FAB2(SCH_1):P1V8_PCH_STBY    I63 @BASEBOARD_FAB2_LIB.BASEBOARD_FAB2(SCH_1):PAGE122
  BA48 P3V3_STBY @BASEBOARD_FAB2_LIB.BASEBOARD_FAB2(SCH_1):P3V3_STBY    I63 @BASEBOARD_FAB2_LIB.BASEBOARD_FAB2(SCH_1):PAGE122
  AE26 P1V8_PCH_STBY @BASEBOARD_FAB2_LIB.BASEBOARD_FAB2(SCH_1):P1V8_PCH_STBY    I63 @BASEBOARD_FAB2_LIB.BASEBOARD_FAB2(SCH_1):PAGE122
  BD46 P1V8_PCH_STBY @BASEBOARD_FAB2_LIB.BASEBOARD_FAB2(SCH_1):P1V8_PCH_STBY    I63 @BASEBOARD_FAB2_LIB.BASEBOARD_FAB2(SCH_1):PAGE122
  AN24 P3V3_STBY @BASEBOARD_FAB2_LIB.BASEBOARD_FAB2(SCH_1):P3V3_STBY    I63 @BASEBOARD_FAB2_LIB.BASEBOARD_FAB2(SCH_1):PAGE122
  AD24 P3V3_STBY @BASEBOARD_FAB2_LIB.BASEBOARD_FAB2(SCH_1):P3V3_STBY    I63 @BASEBOARD_FAB2_LIB.BASEBOARD_FAB2(SCH_1):PAGE122
  BA45 P3V3_STBY @BASEBOARD_FAB2_LIB.BASEBOARD_FAB2(SCH_1):P3V3_STBY    I63 @BASEBOARD_FAB2_LIB.BASEBOARD_FAB2(SCH_1):PAGE122
  BA46 P3V3_STBY @BASEBOARD_FAB2_LIB.BASEBOARD_FAB2(SCH_1):P3V3_STBY    I63 @BASEBOARD_FAB2_LIB.BASEBOARD_FAB2(SCH_1):PAGE122
  AT48 P1V05_PCH_STBY @BASEBOARD_FAB2_LIB.BASEBOARD_FAB2(SCH_1):P1V05_PCH_STBY    I63 @BASEBOARD_FAB2_LIB.BASEBOARD_FAB2(SCH_1):PAGE122
  AP48 P1V05_PCH_STBY_WM26_PLL @BASEBOARD_FAB2_LIB.BASEBOARD_FAB2(SCH_1):P1V05_PCH_STBY_WM26_PLL    I63 @BASEBOARD_FAB2_LIB.BASEBOARD_FAB2(SCH_1):PAGE122
  AU48 P1V05_PCH_STBY_WM26_PLL @BASEBOARD_FAB2_LIB.BASEBOARD_FAB2(SCH_1):P1V05_PCH_STBY_WM26_PLL    I63 @BASEBOARD_FAB2_LIB.BASEBOARD_FAB2(SCH_1):PAGE122
  AW48 P1V05_PCH_STBY_WM26_PLL @BASEBOARD_FAB2_LIB.BASEBOARD_FAB2(SCH_1):P1V05_PCH_STBY_WM26_PLL    I63 @BASEBOARD_FAB2_LIB.BASEBOARD_FAB2(SCH_1):PAGE122
  AM48 P1V05_PCH_STBY @BASEBOARD_FAB2_LIB.BASEBOARD_FAB2(SCH_1):P1V05_PCH_STBY    I63 @BASEBOARD_FAB2_LIB.BASEBOARD_FAB2(SCH_1):PAGE122
  AK50 P1V05_PCH_STBY_WM20_PLL @BASEBOARD_FAB2_LIB.BASEBOARD_FAB2(SCH_1):P1V05_PCH_STBY_WM20_PLL    I63 @BASEBOARD_FAB2_LIB.BASEBOARD_FAB2(SCH_1):PAGE122
  AN50 P1V05_PCH_STBY_WM20_PLL @BASEBOARD_FAB2_LIB.BASEBOARD_FAB2(SCH_1):P1V05_PCH_STBY_WM20_PLL    I63 @BASEBOARD_FAB2_LIB.BASEBOARD_FAB2(SCH_1):PAGE122
  AG22 A_PVCCRTC_EXT_CAP @BASEBOARD_FAB2_LIB.BASEBOARD_FAB2(SCH_1):A_PVCCRTC_EXT_CAP    I63 @BASEBOARD_FAB2_LIB.BASEBOARD_FAB2(SCH_1):PAGE122
  AE27 P1V05_PCH_STBY @BASEBOARD_FAB2_LIB.BASEBOARD_FAB2(SCH_1):P1V05_PCH_STBY    I21 @BASEBOARD_FAB2_LIB.BASEBOARD_FAB2(SCH_1):PAGE123
  AK32 PVNN_PCH_STBY @BASEBOARD_FAB2_LIB.BASEBOARD_FAB2(SCH_1):PVNN_PCH_STBY    I21 @BASEBOARD_FAB2_LIB.BASEBOARD_FAB2(SCH_1):PAGE123
   U31 PVNN_PCH_STBY @BASEBOARD_FAB2_LIB.BASEBOARD_FAB2(SCH_1):PVNN_PCH_STBY    I21 @BASEBOARD_FAB2_LIB.BASEBOARD_FAB2(SCH_1):PAGE123
   U35 PVNN_PCH_STBY @BASEBOARD_FAB2_LIB.BASEBOARD_FAB2(SCH_1):PVNN_PCH_STBY    I21 @BASEBOARD_FAB2_LIB.BASEBOARD_FAB2(SCH_1):PAGE123
   U38 PVNN_PCH_STBY @BASEBOARD_FAB2_LIB.BASEBOARD_FAB2(SCH_1):PVNN_PCH_STBY    I21 @BASEBOARD_FAB2_LIB.BASEBOARD_FAB2(SCH_1):PAGE123
   V29 PVNN_PCH_STBY @BASEBOARD_FAB2_LIB.BASEBOARD_FAB2(SCH_1):PVNN_PCH_STBY    I21 @BASEBOARD_FAB2_LIB.BASEBOARD_FAB2(SCH_1):PAGE123
   V33 PVNN_PCH_STBY @BASEBOARD_FAB2_LIB.BASEBOARD_FAB2(SCH_1):PVNN_PCH_STBY    I21 @BASEBOARD_FAB2_LIB.BASEBOARD_FAB2(SCH_1):PAGE123
   V40 PVNN_PCH_STBY @BASEBOARD_FAB2_LIB.BASEBOARD_FAB2(SCH_1):PVNN_PCH_STBY    I21 @BASEBOARD_FAB2_LIB.BASEBOARD_FAB2(SCH_1):PAGE123
   Y29 PVNN_PCH_STBY @BASEBOARD_FAB2_LIB.BASEBOARD_FAB2(SCH_1):PVNN_PCH_STBY    I21 @BASEBOARD_FAB2_LIB.BASEBOARD_FAB2(SCH_1):PAGE123
   Y30 PVNN_PCH_STBY @BASEBOARD_FAB2_LIB.BASEBOARD_FAB2(SCH_1):PVNN_PCH_STBY    I21 @BASEBOARD_FAB2_LIB.BASEBOARD_FAB2(SCH_1):PAGE123
   Y32 PVNN_PCH_STBY @BASEBOARD_FAB2_LIB.BASEBOARD_FAB2(SCH_1):PVNN_PCH_STBY    I21 @BASEBOARD_FAB2_LIB.BASEBOARD_FAB2(SCH_1):PAGE123
   Y34 PVNN_PCH_STBY @BASEBOARD_FAB2_LIB.BASEBOARD_FAB2(SCH_1):PVNN_PCH_STBY    I21 @BASEBOARD_FAB2_LIB.BASEBOARD_FAB2(SCH_1):PAGE123
   Y36 PVNN_PCH_STBY @BASEBOARD_FAB2_LIB.BASEBOARD_FAB2(SCH_1):PVNN_PCH_STBY    I21 @BASEBOARD_FAB2_LIB.BASEBOARD_FAB2(SCH_1):PAGE123
   Y37 PVNN_PCH_STBY @BASEBOARD_FAB2_LIB.BASEBOARD_FAB2(SCH_1):PVNN_PCH_STBY    I21 @BASEBOARD_FAB2_LIB.BASEBOARD_FAB2(SCH_1):PAGE123
   Y39 PVNN_PCH_STBY @BASEBOARD_FAB2_LIB.BASEBOARD_FAB2(SCH_1):PVNN_PCH_STBY    I21 @BASEBOARD_FAB2_LIB.BASEBOARD_FAB2(SCH_1):PAGE123
   Y41 PVNN_PCH_STBY @BASEBOARD_FAB2_LIB.BASEBOARD_FAB2(SCH_1):PVNN_PCH_STBY    I21 @BASEBOARD_FAB2_LIB.BASEBOARD_FAB2(SCH_1):PAGE123
  AA29 PVNN_PCH_STBY @BASEBOARD_FAB2_LIB.BASEBOARD_FAB2(SCH_1):PVNN_PCH_STBY    I21 @BASEBOARD_FAB2_LIB.BASEBOARD_FAB2(SCH_1):PAGE123
  AA30 PVNN_PCH_STBY @BASEBOARD_FAB2_LIB.BASEBOARD_FAB2(SCH_1):PVNN_PCH_STBY    I21 @BASEBOARD_FAB2_LIB.BASEBOARD_FAB2(SCH_1):PAGE123
  AA32 PVNN_PCH_STBY @BASEBOARD_FAB2_LIB.BASEBOARD_FAB2(SCH_1):PVNN_PCH_STBY    I21 @BASEBOARD_FAB2_LIB.BASEBOARD_FAB2(SCH_1):PAGE123
  AA34 PVNN_PCH_STBY @BASEBOARD_FAB2_LIB.BASEBOARD_FAB2(SCH_1):PVNN_PCH_STBY    I21 @BASEBOARD_FAB2_LIB.BASEBOARD_FAB2(SCH_1):PAGE123
  AA36 PVNN_PCH_STBY @BASEBOARD_FAB2_LIB.BASEBOARD_FAB2(SCH_1):PVNN_PCH_STBY    I21 @BASEBOARD_FAB2_LIB.BASEBOARD_FAB2(SCH_1):PAGE123
  AA37 PVNN_PCH_STBY @BASEBOARD_FAB2_LIB.BASEBOARD_FAB2(SCH_1):PVNN_PCH_STBY    I21 @BASEBOARD_FAB2_LIB.BASEBOARD_FAB2(SCH_1):PAGE123
  AA39 PVNN_PCH_STBY @BASEBOARD_FAB2_LIB.BASEBOARD_FAB2(SCH_1):PVNN_PCH_STBY    I21 @BASEBOARD_FAB2_LIB.BASEBOARD_FAB2(SCH_1):PAGE123
  AA41 PVNN_PCH_STBY @BASEBOARD_FAB2_LIB.BASEBOARD_FAB2(SCH_1):PVNN_PCH_STBY    I21 @BASEBOARD_FAB2_LIB.BASEBOARD_FAB2(SCH_1):PAGE123
  AC29 PVNN_PCH_STBY @BASEBOARD_FAB2_LIB.BASEBOARD_FAB2(SCH_1):PVNN_PCH_STBY    I21 @BASEBOARD_FAB2_LIB.BASEBOARD_FAB2(SCH_1):PAGE123
  AC30 PVNN_PCH_STBY @BASEBOARD_FAB2_LIB.BASEBOARD_FAB2(SCH_1):PVNN_PCH_STBY    I21 @BASEBOARD_FAB2_LIB.BASEBOARD_FAB2(SCH_1):PAGE123
  AC32 PVNN_PCH_STBY @BASEBOARD_FAB2_LIB.BASEBOARD_FAB2(SCH_1):PVNN_PCH_STBY    I21 @BASEBOARD_FAB2_LIB.BASEBOARD_FAB2(SCH_1):PAGE123
  AC34 PVNN_PCH_STBY @BASEBOARD_FAB2_LIB.BASEBOARD_FAB2(SCH_1):PVNN_PCH_STBY    I21 @BASEBOARD_FAB2_LIB.BASEBOARD_FAB2(SCH_1):PAGE123
  AC36 PVNN_PCH_STBY @BASEBOARD_FAB2_LIB.BASEBOARD_FAB2(SCH_1):PVNN_PCH_STBY    I21 @BASEBOARD_FAB2_LIB.BASEBOARD_FAB2(SCH_1):PAGE123
  AC37 PVNN_PCH_STBY @BASEBOARD_FAB2_LIB.BASEBOARD_FAB2(SCH_1):PVNN_PCH_STBY    I21 @BASEBOARD_FAB2_LIB.BASEBOARD_FAB2(SCH_1):PAGE123
  AC39 PVNN_PCH_STBY @BASEBOARD_FAB2_LIB.BASEBOARD_FAB2(SCH_1):PVNN_PCH_STBY    I21 @BASEBOARD_FAB2_LIB.BASEBOARD_FAB2(SCH_1):PAGE123
  AC41 PVNN_PCH_STBY @BASEBOARD_FAB2_LIB.BASEBOARD_FAB2(SCH_1):PVNN_PCH_STBY    I21 @BASEBOARD_FAB2_LIB.BASEBOARD_FAB2(SCH_1):PAGE123
   U27 PVNN_PCH_STBY @BASEBOARD_FAB2_LIB.BASEBOARD_FAB2(SCH_1):PVNN_PCH_STBY    I21 @BASEBOARD_FAB2_LIB.BASEBOARD_FAB2(SCH_1):PAGE123
  AE30 PVNN_PCH_STBY @BASEBOARD_FAB2_LIB.BASEBOARD_FAB2(SCH_1):PVNN_PCH_STBY    I21 @BASEBOARD_FAB2_LIB.BASEBOARD_FAB2(SCH_1):PAGE123
  AE32 PVNN_PCH_STBY @BASEBOARD_FAB2_LIB.BASEBOARD_FAB2(SCH_1):PVNN_PCH_STBY    I21 @BASEBOARD_FAB2_LIB.BASEBOARD_FAB2(SCH_1):PAGE123
  AE34 PVNN_PCH_STBY @BASEBOARD_FAB2_LIB.BASEBOARD_FAB2(SCH_1):PVNN_PCH_STBY    I21 @BASEBOARD_FAB2_LIB.BASEBOARD_FAB2(SCH_1):PAGE123
  AE36 PVNN_PCH_STBY @BASEBOARD_FAB2_LIB.BASEBOARD_FAB2(SCH_1):PVNN_PCH_STBY    I21 @BASEBOARD_FAB2_LIB.BASEBOARD_FAB2(SCH_1):PAGE123
  AE37 PVNN_PCH_STBY @BASEBOARD_FAB2_LIB.BASEBOARD_FAB2(SCH_1):PVNN_PCH_STBY    I21 @BASEBOARD_FAB2_LIB.BASEBOARD_FAB2(SCH_1):PAGE123
  AE39 PVNN_PCH_STBY @BASEBOARD_FAB2_LIB.BASEBOARD_FAB2(SCH_1):PVNN_PCH_STBY    I21 @BASEBOARD_FAB2_LIB.BASEBOARD_FAB2(SCH_1):PAGE123
  AE41 PVNN_PCH_STBY @BASEBOARD_FAB2_LIB.BASEBOARD_FAB2(SCH_1):PVNN_PCH_STBY    I21 @BASEBOARD_FAB2_LIB.BASEBOARD_FAB2(SCH_1):PAGE123
  AG32 PVNN_PCH_STBY @BASEBOARD_FAB2_LIB.BASEBOARD_FAB2(SCH_1):PVNN_PCH_STBY    I21 @BASEBOARD_FAB2_LIB.BASEBOARD_FAB2(SCH_1):PAGE123
  AG34 PVNN_PCH_STBY @BASEBOARD_FAB2_LIB.BASEBOARD_FAB2(SCH_1):PVNN_PCH_STBY    I21 @BASEBOARD_FAB2_LIB.BASEBOARD_FAB2(SCH_1):PAGE123
  AG36 PVNN_PCH_STBY @BASEBOARD_FAB2_LIB.BASEBOARD_FAB2(SCH_1):PVNN_PCH_STBY    I21 @BASEBOARD_FAB2_LIB.BASEBOARD_FAB2(SCH_1):PAGE123
  AG37 PVNN_PCH_STBY @BASEBOARD_FAB2_LIB.BASEBOARD_FAB2(SCH_1):PVNN_PCH_STBY    I21 @BASEBOARD_FAB2_LIB.BASEBOARD_FAB2(SCH_1):PAGE123
  AG39 PVNN_PCH_STBY @BASEBOARD_FAB2_LIB.BASEBOARD_FAB2(SCH_1):PVNN_PCH_STBY    I21 @BASEBOARD_FAB2_LIB.BASEBOARD_FAB2(SCH_1):PAGE123
  AK34 PVNN_PCH_STBY @BASEBOARD_FAB2_LIB.BASEBOARD_FAB2(SCH_1):PVNN_PCH_STBY    I21 @BASEBOARD_FAB2_LIB.BASEBOARD_FAB2(SCH_1):PAGE123
  AK37 PVNN_PCH_STBY @BASEBOARD_FAB2_LIB.BASEBOARD_FAB2(SCH_1):PVNN_PCH_STBY    I21 @BASEBOARD_FAB2_LIB.BASEBOARD_FAB2(SCH_1):PAGE123
  AK39 PVNN_PCH_STBY @BASEBOARD_FAB2_LIB.BASEBOARD_FAB2(SCH_1):PVNN_PCH_STBY    I21 @BASEBOARD_FAB2_LIB.BASEBOARD_FAB2(SCH_1):PAGE123
  AM32 PVNN_PCH_STBY @BASEBOARD_FAB2_LIB.BASEBOARD_FAB2(SCH_1):PVNN_PCH_STBY    I21 @BASEBOARD_FAB2_LIB.BASEBOARD_FAB2(SCH_1):PAGE123
  AM34 PVNN_PCH_STBY @BASEBOARD_FAB2_LIB.BASEBOARD_FAB2(SCH_1):PVNN_PCH_STBY    I21 @BASEBOARD_FAB2_LIB.BASEBOARD_FAB2(SCH_1):PAGE123
  AM36 PVNN_PCH_STBY @BASEBOARD_FAB2_LIB.BASEBOARD_FAB2(SCH_1):PVNN_PCH_STBY    I21 @BASEBOARD_FAB2_LIB.BASEBOARD_FAB2(SCH_1):PAGE123
  AM37 PVNN_PCH_STBY @BASEBOARD_FAB2_LIB.BASEBOARD_FAB2(SCH_1):PVNN_PCH_STBY    I21 @BASEBOARD_FAB2_LIB.BASEBOARD_FAB2(SCH_1):PAGE123
  AM39 PVNN_PCH_STBY @BASEBOARD_FAB2_LIB.BASEBOARD_FAB2(SCH_1):PVNN_PCH_STBY    I21 @BASEBOARD_FAB2_LIB.BASEBOARD_FAB2(SCH_1):PAGE123
  AP32 PVNN_PCH_STBY @BASEBOARD_FAB2_LIB.BASEBOARD_FAB2(SCH_1):PVNN_PCH_STBY    I21 @BASEBOARD_FAB2_LIB.BASEBOARD_FAB2(SCH_1):PAGE123
  AP34 PVNN_PCH_STBY @BASEBOARD_FAB2_LIB.BASEBOARD_FAB2(SCH_1):PVNN_PCH_STBY    I21 @BASEBOARD_FAB2_LIB.BASEBOARD_FAB2(SCH_1):PAGE123
  AP36 PVNN_PCH_STBY @BASEBOARD_FAB2_LIB.BASEBOARD_FAB2(SCH_1):PVNN_PCH_STBY    I21 @BASEBOARD_FAB2_LIB.BASEBOARD_FAB2(SCH_1):PAGE123
  AP37 PVNN_PCH_STBY @BASEBOARD_FAB2_LIB.BASEBOARD_FAB2(SCH_1):PVNN_PCH_STBY    I21 @BASEBOARD_FAB2_LIB.BASEBOARD_FAB2(SCH_1):PAGE123
  AP39 PVNN_PCH_STBY @BASEBOARD_FAB2_LIB.BASEBOARD_FAB2(SCH_1):PVNN_PCH_STBY    I21 @BASEBOARD_FAB2_LIB.BASEBOARD_FAB2(SCH_1):PAGE123
  AT32 PVNN_PCH_STBY @BASEBOARD_FAB2_LIB.BASEBOARD_FAB2(SCH_1):PVNN_PCH_STBY    I21 @BASEBOARD_FAB2_LIB.BASEBOARD_FAB2(SCH_1):PAGE123
  AT34 PVNN_PCH_STBY @BASEBOARD_FAB2_LIB.BASEBOARD_FAB2(SCH_1):PVNN_PCH_STBY    I21 @BASEBOARD_FAB2_LIB.BASEBOARD_FAB2(SCH_1):PAGE123
  AT36 PVNN_PCH_STBY @BASEBOARD_FAB2_LIB.BASEBOARD_FAB2(SCH_1):PVNN_PCH_STBY    I21 @BASEBOARD_FAB2_LIB.BASEBOARD_FAB2(SCH_1):PAGE123
  AU32 PVNN_PCH_STBY @BASEBOARD_FAB2_LIB.BASEBOARD_FAB2(SCH_1):PVNN_PCH_STBY    I21 @BASEBOARD_FAB2_LIB.BASEBOARD_FAB2(SCH_1):PAGE123
  AU34 PVNN_PCH_STBY @BASEBOARD_FAB2_LIB.BASEBOARD_FAB2(SCH_1):PVNN_PCH_STBY    I21 @BASEBOARD_FAB2_LIB.BASEBOARD_FAB2(SCH_1):PAGE123
  AU36 PVNN_PCH_STBY @BASEBOARD_FAB2_LIB.BASEBOARD_FAB2(SCH_1):PVNN_PCH_STBY    I21 @BASEBOARD_FAB2_LIB.BASEBOARD_FAB2(SCH_1):PAGE123
   V37 VSENSE_PVNN_PCH_STBY_QAT @BASEBOARD_FAB2_LIB.BASEBOARD_FAB2(SCH_1):VSENSE_PVNN_PCH_STBY_QAT    I21 @BASEBOARD_FAB2_LIB.BASEBOARD_FAB2(SCH_1):PAGE123
  AK36 VSENSE_PVNN_PCH_STBY_FPK @BASEBOARD_FAB2_LIB.BASEBOARD_FAB2(SCH_1):VSENSE_PVNN_PCH_STBY_FPK    I21 @BASEBOARD_FAB2_LIB.BASEBOARD_FAB2(SCH_1):PAGE123
  BP69    GND @BASEBOARD_FAB2_LIB.BASEBOARD_FAB2(SCH_1):GND    I13 @BASEBOARD_FAB2_LIB.BASEBOARD_FAB2(SCH_1):PAGE123
  BT69    GND @BASEBOARD_FAB2_LIB.BASEBOARD_FAB2(SCH_1):GND    I13 @BASEBOARD_FAB2_LIB.BASEBOARD_FAB2(SCH_1):PAGE123
  BU70    GND @BASEBOARD_FAB2_LIB.BASEBOARD_FAB2(SCH_1):GND    I13 @BASEBOARD_FAB2_LIB.BASEBOARD_FAB2(SCH_1):PAGE123
  BR70    GND @BASEBOARD_FAB2_LIB.BASEBOARD_FAB2(SCH_1):GND    I13 @BASEBOARD_FAB2_LIB.BASEBOARD_FAB2(SCH_1):PAGE123
   F70    GND @BASEBOARD_FAB2_LIB.BASEBOARD_FAB2(SCH_1):GND    I13 @BASEBOARD_FAB2_LIB.BASEBOARD_FAB2(SCH_1):PAGE123
   E70    GND @BASEBOARD_FAB2_LIB.BASEBOARD_FAB2(SCH_1):GND    I13 @BASEBOARD_FAB2_LIB.BASEBOARD_FAB2(SCH_1):PAGE123
   BU3    GND @BASEBOARD_FAB2_LIB.BASEBOARD_FAB2(SCH_1):GND    I13 @BASEBOARD_FAB2_LIB.BASEBOARD_FAB2(SCH_1):PAGE123
   BR3    GND @BASEBOARD_FAB2_LIB.BASEBOARD_FAB2(SCH_1):GND    I13 @BASEBOARD_FAB2_LIB.BASEBOARD_FAB2(SCH_1):PAGE123
    F3    GND @BASEBOARD_FAB2_LIB.BASEBOARD_FAB2(SCH_1):GND    I13 @BASEBOARD_FAB2_LIB.BASEBOARD_FAB2(SCH_1):PAGE123
    E3    GND @BASEBOARD_FAB2_LIB.BASEBOARD_FAB2(SCH_1):GND    I13 @BASEBOARD_FAB2_LIB.BASEBOARD_FAB2(SCH_1):PAGE123
    A5    GND @BASEBOARD_FAB2_LIB.BASEBOARD_FAB2(SCH_1):GND    I13 @BASEBOARD_FAB2_LIB.BASEBOARD_FAB2(SCH_1):PAGE123
    A7    GND @BASEBOARD_FAB2_LIB.BASEBOARD_FAB2(SCH_1):GND    I13 @BASEBOARD_FAB2_LIB.BASEBOARD_FAB2(SCH_1):PAGE123
    A9    GND @BASEBOARD_FAB2_LIB.BASEBOARD_FAB2(SCH_1):GND    I13 @BASEBOARD_FAB2_LIB.BASEBOARD_FAB2(SCH_1):PAGE123
   A65    GND @BASEBOARD_FAB2_LIB.BASEBOARD_FAB2(SCH_1):GND    I13 @BASEBOARD_FAB2_LIB.BASEBOARD_FAB2(SCH_1):PAGE123
   A66    GND @BASEBOARD_FAB2_LIB.BASEBOARD_FAB2(SCH_1):GND    I13 @BASEBOARD_FAB2_LIB.BASEBOARD_FAB2(SCH_1):PAGE123
   A68    GND @BASEBOARD_FAB2_LIB.BASEBOARD_FAB2(SCH_1):GND    I13 @BASEBOARD_FAB2_LIB.BASEBOARD_FAB2(SCH_1):PAGE123
    J1    GND @BASEBOARD_FAB2_LIB.BASEBOARD_FAB2(SCH_1):GND    I13 @BASEBOARD_FAB2_LIB.BASEBOARD_FAB2(SCH_1):PAGE123
   J72    GND @BASEBOARD_FAB2_LIB.BASEBOARD_FAB2(SCH_1):GND    I13 @BASEBOARD_FAB2_LIB.BASEBOARD_FAB2(SCH_1):PAGE123
   BN1    GND @BASEBOARD_FAB2_LIB.BASEBOARD_FAB2(SCH_1):GND    I13 @BASEBOARD_FAB2_LIB.BASEBOARD_FAB2(SCH_1):PAGE123
  BN72    GND @BASEBOARD_FAB2_LIB.BASEBOARD_FAB2(SCH_1):GND    I13 @BASEBOARD_FAB2_LIB.BASEBOARD_FAB2(SCH_1):PAGE123
  CA68    GND @BASEBOARD_FAB2_LIB.BASEBOARD_FAB2(SCH_1):GND    I13 @BASEBOARD_FAB2_LIB.BASEBOARD_FAB2(SCH_1):PAGE123
  CA66    GND @BASEBOARD_FAB2_LIB.BASEBOARD_FAB2(SCH_1):GND    I13 @BASEBOARD_FAB2_LIB.BASEBOARD_FAB2(SCH_1):PAGE123
  CA65    GND @BASEBOARD_FAB2_LIB.BASEBOARD_FAB2(SCH_1):GND    I13 @BASEBOARD_FAB2_LIB.BASEBOARD_FAB2(SCH_1):PAGE123
   CA9    GND @BASEBOARD_FAB2_LIB.BASEBOARD_FAB2(SCH_1):GND    I13 @BASEBOARD_FAB2_LIB.BASEBOARD_FAB2(SCH_1):PAGE123
   CA7    GND @BASEBOARD_FAB2_LIB.BASEBOARD_FAB2(SCH_1):GND    I13 @BASEBOARD_FAB2_LIB.BASEBOARD_FAB2(SCH_1):PAGE123
   CA5    GND @BASEBOARD_FAB2_LIB.BASEBOARD_FAB2(SCH_1):GND    I13 @BASEBOARD_FAB2_LIB.BASEBOARD_FAB2(SCH_1):PAGE123
   A70    GND @BASEBOARD_FAB2_LIB.BASEBOARD_FAB2(SCH_1):GND    I13 @BASEBOARD_FAB2_LIB.BASEBOARD_FAB2(SCH_1):PAGE123
   CA3    GND @BASEBOARD_FAB2_LIB.BASEBOARD_FAB2(SCH_1):GND    I13 @BASEBOARD_FAB2_LIB.BASEBOARD_FAB2(SCH_1):PAGE123
   BW1    GND @BASEBOARD_FAB2_LIB.BASEBOARD_FAB2(SCH_1):GND    I13 @BASEBOARD_FAB2_LIB.BASEBOARD_FAB2(SCH_1):PAGE123
   BU1    GND @BASEBOARD_FAB2_LIB.BASEBOARD_FAB2(SCH_1):GND    I13 @BASEBOARD_FAB2_LIB.BASEBOARD_FAB2(SCH_1):PAGE123
   BR1    GND @BASEBOARD_FAB2_LIB.BASEBOARD_FAB2(SCH_1):GND    I13 @BASEBOARD_FAB2_LIB.BASEBOARD_FAB2(SCH_1):PAGE123
    C3    GND @BASEBOARD_FAB2_LIB.BASEBOARD_FAB2(SCH_1):GND    I13 @BASEBOARD_FAB2_LIB.BASEBOARD_FAB2(SCH_1):PAGE123
   C72    GND @BASEBOARD_FAB2_LIB.BASEBOARD_FAB2(SCH_1):GND    I13 @BASEBOARD_FAB2_LIB.BASEBOARD_FAB2(SCH_1):PAGE123
    E1    GND @BASEBOARD_FAB2_LIB.BASEBOARD_FAB2(SCH_1):GND    I13 @BASEBOARD_FAB2_LIB.BASEBOARD_FAB2(SCH_1):PAGE123
   E72    GND @BASEBOARD_FAB2_LIB.BASEBOARD_FAB2(SCH_1):GND    I13 @BASEBOARD_FAB2_LIB.BASEBOARD_FAB2(SCH_1):PAGE123
    G1    GND @BASEBOARD_FAB2_LIB.BASEBOARD_FAB2(SCH_1):GND    I13 @BASEBOARD_FAB2_LIB.BASEBOARD_FAB2(SCH_1):PAGE123
   G72    GND @BASEBOARD_FAB2_LIB.BASEBOARD_FAB2(SCH_1):GND    I13 @BASEBOARD_FAB2_LIB.BASEBOARD_FAB2(SCH_1):PAGE123
  BR72    GND @BASEBOARD_FAB2_LIB.BASEBOARD_FAB2(SCH_1):GND    I13 @BASEBOARD_FAB2_LIB.BASEBOARD_FAB2(SCH_1):PAGE123
  BU72    GND @BASEBOARD_FAB2_LIB.BASEBOARD_FAB2(SCH_1):GND    I13 @BASEBOARD_FAB2_LIB.BASEBOARD_FAB2(SCH_1):PAGE123
  BW70    GND @BASEBOARD_FAB2_LIB.BASEBOARD_FAB2(SCH_1):GND    I13 @BASEBOARD_FAB2_LIB.BASEBOARD_FAB2(SCH_1):PAGE123
  BW72    GND @BASEBOARD_FAB2_LIB.BASEBOARD_FAB2(SCH_1):GND    I13 @BASEBOARD_FAB2_LIB.BASEBOARD_FAB2(SCH_1):PAGE123
  CA70    GND @BASEBOARD_FAB2_LIB.BASEBOARD_FAB2(SCH_1):GND    I13 @BASEBOARD_FAB2_LIB.BASEBOARD_FAB2(SCH_1):PAGE123
  BB48    GND @BASEBOARD_FAB2_LIB.BASEBOARD_FAB2(SCH_1):GND    I13 @BASEBOARD_FAB2_LIB.BASEBOARD_FAB2(SCH_1):PAGE123
  AT37    GND @BASEBOARD_FAB2_LIB.BASEBOARD_FAB2(SCH_1):GND    I13 @BASEBOARD_FAB2_LIB.BASEBOARD_FAB2(SCH_1):PAGE123
   Y72    GND @BASEBOARD_FAB2_LIB.BASEBOARD_FAB2(SCH_1):GND    I13 @BASEBOARD_FAB2_LIB.BASEBOARD_FAB2(SCH_1):PAGE123
   Y70    GND @BASEBOARD_FAB2_LIB.BASEBOARD_FAB2(SCH_1):GND    I13 @BASEBOARD_FAB2_LIB.BASEBOARD_FAB2(SCH_1):PAGE123
   A18    GND @BASEBOARD_FAB2_LIB.BASEBOARD_FAB2(SCH_1):GND    I13 @BASEBOARD_FAB2_LIB.BASEBOARD_FAB2(SCH_1):PAGE123
   A22    GND @BASEBOARD_FAB2_LIB.BASEBOARD_FAB2(SCH_1):GND    I13 @BASEBOARD_FAB2_LIB.BASEBOARD_FAB2(SCH_1):PAGE123
   A30    GND @BASEBOARD_FAB2_LIB.BASEBOARD_FAB2(SCH_1):GND    I13 @BASEBOARD_FAB2_LIB.BASEBOARD_FAB2(SCH_1):PAGE123
   A34    GND @BASEBOARD_FAB2_LIB.BASEBOARD_FAB2(SCH_1):GND    I13 @BASEBOARD_FAB2_LIB.BASEBOARD_FAB2(SCH_1):PAGE123
   A37    GND @BASEBOARD_FAB2_LIB.BASEBOARD_FAB2(SCH_1):GND    I13 @BASEBOARD_FAB2_LIB.BASEBOARD_FAB2(SCH_1):PAGE123
   A41    GND @BASEBOARD_FAB2_LIB.BASEBOARD_FAB2(SCH_1):GND    I13 @BASEBOARD_FAB2_LIB.BASEBOARD_FAB2(SCH_1):PAGE123
   B12    GND @BASEBOARD_FAB2_LIB.BASEBOARD_FAB2(SCH_1):GND    I13 @BASEBOARD_FAB2_LIB.BASEBOARD_FAB2(SCH_1):PAGE123
   B19    GND @BASEBOARD_FAB2_LIB.BASEBOARD_FAB2(SCH_1):GND    I13 @BASEBOARD_FAB2_LIB.BASEBOARD_FAB2(SCH_1):PAGE123
   B25    GND @BASEBOARD_FAB2_LIB.BASEBOARD_FAB2(SCH_1):GND    I13 @BASEBOARD_FAB2_LIB.BASEBOARD_FAB2(SCH_1):PAGE123
   B27    GND @BASEBOARD_FAB2_LIB.BASEBOARD_FAB2(SCH_1):GND    I13 @BASEBOARD_FAB2_LIB.BASEBOARD_FAB2(SCH_1):PAGE123
   B47    GND @BASEBOARD_FAB2_LIB.BASEBOARD_FAB2(SCH_1):GND    I13 @BASEBOARD_FAB2_LIB.BASEBOARD_FAB2(SCH_1):PAGE123
   C22    GND @BASEBOARD_FAB2_LIB.BASEBOARD_FAB2(SCH_1):GND    I13 @BASEBOARD_FAB2_LIB.BASEBOARD_FAB2(SCH_1):PAGE123
   C30    GND @BASEBOARD_FAB2_LIB.BASEBOARD_FAB2(SCH_1):GND    I13 @BASEBOARD_FAB2_LIB.BASEBOARD_FAB2(SCH_1):PAGE123
   C34    GND @BASEBOARD_FAB2_LIB.BASEBOARD_FAB2(SCH_1):GND    I13 @BASEBOARD_FAB2_LIB.BASEBOARD_FAB2(SCH_1):PAGE123
   C37    GND @BASEBOARD_FAB2_LIB.BASEBOARD_FAB2(SCH_1):GND    I13 @BASEBOARD_FAB2_LIB.BASEBOARD_FAB2(SCH_1):PAGE123
   C41    GND @BASEBOARD_FAB2_LIB.BASEBOARD_FAB2(SCH_1):GND    I13 @BASEBOARD_FAB2_LIB.BASEBOARD_FAB2(SCH_1):PAGE123
   C65    GND @BASEBOARD_FAB2_LIB.BASEBOARD_FAB2(SCH_1):GND    I13 @BASEBOARD_FAB2_LIB.BASEBOARD_FAB2(SCH_1):PAGE123
   D12    GND @BASEBOARD_FAB2_LIB.BASEBOARD_FAB2(SCH_1):GND    I13 @BASEBOARD_FAB2_LIB.BASEBOARD_FAB2(SCH_1):PAGE123
   D16    GND @BASEBOARD_FAB2_LIB.BASEBOARD_FAB2(SCH_1):GND    I13 @BASEBOARD_FAB2_LIB.BASEBOARD_FAB2(SCH_1):PAGE123
   D19    GND @BASEBOARD_FAB2_LIB.BASEBOARD_FAB2(SCH_1):GND    I13 @BASEBOARD_FAB2_LIB.BASEBOARD_FAB2(SCH_1):PAGE123
   D25    GND @BASEBOARD_FAB2_LIB.BASEBOARD_FAB2(SCH_1):GND    I13 @BASEBOARD_FAB2_LIB.BASEBOARD_FAB2(SCH_1):PAGE123
   D27    GND @BASEBOARD_FAB2_LIB.BASEBOARD_FAB2(SCH_1):GND    I13 @BASEBOARD_FAB2_LIB.BASEBOARD_FAB2(SCH_1):PAGE123
   E59    GND @BASEBOARD_FAB2_LIB.BASEBOARD_FAB2(SCH_1):GND    I13 @BASEBOARD_FAB2_LIB.BASEBOARD_FAB2(SCH_1):PAGE123
   E65    GND @BASEBOARD_FAB2_LIB.BASEBOARD_FAB2(SCH_1):GND    I13 @BASEBOARD_FAB2_LIB.BASEBOARD_FAB2(SCH_1):PAGE123
   D47    GND @BASEBOARD_FAB2_LIB.BASEBOARD_FAB2(SCH_1):GND    I13 @BASEBOARD_FAB2_LIB.BASEBOARD_FAB2(SCH_1):PAGE123
   E11    GND @BASEBOARD_FAB2_LIB.BASEBOARD_FAB2(SCH_1):GND    I13 @BASEBOARD_FAB2_LIB.BASEBOARD_FAB2(SCH_1):PAGE123
   E13    GND @BASEBOARD_FAB2_LIB.BASEBOARD_FAB2(SCH_1):GND    I13 @BASEBOARD_FAB2_LIB.BASEBOARD_FAB2(SCH_1):PAGE123
   E15    GND @BASEBOARD_FAB2_LIB.BASEBOARD_FAB2(SCH_1):GND    I13 @BASEBOARD_FAB2_LIB.BASEBOARD_FAB2(SCH_1):PAGE123
   E20    GND @BASEBOARD_FAB2_LIB.BASEBOARD_FAB2(SCH_1):GND    I13 @BASEBOARD_FAB2_LIB.BASEBOARD_FAB2(SCH_1):PAGE123
   E22    GND @BASEBOARD_FAB2_LIB.BASEBOARD_FAB2(SCH_1):GND    I13 @BASEBOARD_FAB2_LIB.BASEBOARD_FAB2(SCH_1):PAGE123
   E24    GND @BASEBOARD_FAB2_LIB.BASEBOARD_FAB2(SCH_1):GND    I13 @BASEBOARD_FAB2_LIB.BASEBOARD_FAB2(SCH_1):PAGE123
   E26    GND @BASEBOARD_FAB2_LIB.BASEBOARD_FAB2(SCH_1):GND    I13 @BASEBOARD_FAB2_LIB.BASEBOARD_FAB2(SCH_1):PAGE123
   E28    GND @BASEBOARD_FAB2_LIB.BASEBOARD_FAB2(SCH_1):GND    I13 @BASEBOARD_FAB2_LIB.BASEBOARD_FAB2(SCH_1):PAGE123
   E30    GND @BASEBOARD_FAB2_LIB.BASEBOARD_FAB2(SCH_1):GND    I13 @BASEBOARD_FAB2_LIB.BASEBOARD_FAB2(SCH_1):PAGE123
   E32    GND @BASEBOARD_FAB2_LIB.BASEBOARD_FAB2(SCH_1):GND    I13 @BASEBOARD_FAB2_LIB.BASEBOARD_FAB2(SCH_1):PAGE123
   E34    GND @BASEBOARD_FAB2_LIB.BASEBOARD_FAB2(SCH_1):GND    I13 @BASEBOARD_FAB2_LIB.BASEBOARD_FAB2(SCH_1):PAGE123
   E37    GND @BASEBOARD_FAB2_LIB.BASEBOARD_FAB2(SCH_1):GND    I13 @BASEBOARD_FAB2_LIB.BASEBOARD_FAB2(SCH_1):PAGE123
   E39    GND @BASEBOARD_FAB2_LIB.BASEBOARD_FAB2(SCH_1):GND    I13 @BASEBOARD_FAB2_LIB.BASEBOARD_FAB2(SCH_1):PAGE123
   E41    GND @BASEBOARD_FAB2_LIB.BASEBOARD_FAB2(SCH_1):GND    I13 @BASEBOARD_FAB2_LIB.BASEBOARD_FAB2(SCH_1):PAGE123
   E43    GND @BASEBOARD_FAB2_LIB.BASEBOARD_FAB2(SCH_1):GND    I13 @BASEBOARD_FAB2_LIB.BASEBOARD_FAB2(SCH_1):PAGE123
   E45    GND @BASEBOARD_FAB2_LIB.BASEBOARD_FAB2(SCH_1):GND    I13 @BASEBOARD_FAB2_LIB.BASEBOARD_FAB2(SCH_1):PAGE123
   E48    GND @BASEBOARD_FAB2_LIB.BASEBOARD_FAB2(SCH_1):GND    I13 @BASEBOARD_FAB2_LIB.BASEBOARD_FAB2(SCH_1):PAGE123
   E50    GND @BASEBOARD_FAB2_LIB.BASEBOARD_FAB2(SCH_1):GND    I13 @BASEBOARD_FAB2_LIB.BASEBOARD_FAB2(SCH_1):PAGE123
   E52    GND @BASEBOARD_FAB2_LIB.BASEBOARD_FAB2(SCH_1):GND    I13 @BASEBOARD_FAB2_LIB.BASEBOARD_FAB2(SCH_1):PAGE123
   E54    GND @BASEBOARD_FAB2_LIB.BASEBOARD_FAB2(SCH_1):GND    I13 @BASEBOARD_FAB2_LIB.BASEBOARD_FAB2(SCH_1):PAGE123
   E57    GND @BASEBOARD_FAB2_LIB.BASEBOARD_FAB2(SCH_1):GND    I13 @BASEBOARD_FAB2_LIB.BASEBOARD_FAB2(SCH_1):PAGE123
    E6    GND @BASEBOARD_FAB2_LIB.BASEBOARD_FAB2(SCH_1):GND    I13 @BASEBOARD_FAB2_LIB.BASEBOARD_FAB2(SCH_1):PAGE123
   E61    GND @BASEBOARD_FAB2_LIB.BASEBOARD_FAB2(SCH_1):GND    I13 @BASEBOARD_FAB2_LIB.BASEBOARD_FAB2(SCH_1):PAGE123
   E63    GND @BASEBOARD_FAB2_LIB.BASEBOARD_FAB2(SCH_1):GND    I13 @BASEBOARD_FAB2_LIB.BASEBOARD_FAB2(SCH_1):PAGE123
   G59    GND @BASEBOARD_FAB2_LIB.BASEBOARD_FAB2(SCH_1):GND    I13 @BASEBOARD_FAB2_LIB.BASEBOARD_FAB2(SCH_1):PAGE123
    E9    GND @BASEBOARD_FAB2_LIB.BASEBOARD_FAB2(SCH_1):GND    I13 @BASEBOARD_FAB2_LIB.BASEBOARD_FAB2(SCH_1):PAGE123
   G22    GND @BASEBOARD_FAB2_LIB.BASEBOARD_FAB2(SCH_1):GND    I13 @BASEBOARD_FAB2_LIB.BASEBOARD_FAB2(SCH_1):PAGE123
   G29    GND @BASEBOARD_FAB2_LIB.BASEBOARD_FAB2(SCH_1):GND    I13 @BASEBOARD_FAB2_LIB.BASEBOARD_FAB2(SCH_1):PAGE123
   G37    GND @BASEBOARD_FAB2_LIB.BASEBOARD_FAB2(SCH_1):GND    I13 @BASEBOARD_FAB2_LIB.BASEBOARD_FAB2(SCH_1):PAGE123
   G48    GND @BASEBOARD_FAB2_LIB.BASEBOARD_FAB2(SCH_1):GND    I13 @BASEBOARD_FAB2_LIB.BASEBOARD_FAB2(SCH_1):PAGE123
    G6    GND @BASEBOARD_FAB2_LIB.BASEBOARD_FAB2(SCH_1):GND    I13 @BASEBOARD_FAB2_LIB.BASEBOARD_FAB2(SCH_1):PAGE123
   G63    GND @BASEBOARD_FAB2_LIB.BASEBOARD_FAB2(SCH_1):GND    I13 @BASEBOARD_FAB2_LIB.BASEBOARD_FAB2(SCH_1):PAGE123
   G66    GND @BASEBOARD_FAB2_LIB.BASEBOARD_FAB2(SCH_1):GND    I13 @BASEBOARD_FAB2_LIB.BASEBOARD_FAB2(SCH_1):PAGE123
   H58    GND @BASEBOARD_FAB2_LIB.BASEBOARD_FAB2(SCH_1):GND    I13 @BASEBOARD_FAB2_LIB.BASEBOARD_FAB2(SCH_1):PAGE123
   J29    GND @BASEBOARD_FAB2_LIB.BASEBOARD_FAB2(SCH_1):GND    I13 @BASEBOARD_FAB2_LIB.BASEBOARD_FAB2(SCH_1):PAGE123
    J5    GND @BASEBOARD_FAB2_LIB.BASEBOARD_FAB2(SCH_1):GND    I13 @BASEBOARD_FAB2_LIB.BASEBOARD_FAB2(SCH_1):PAGE123
    J7    GND @BASEBOARD_FAB2_LIB.BASEBOARD_FAB2(SCH_1):GND    I13 @BASEBOARD_FAB2_LIB.BASEBOARD_FAB2(SCH_1):PAGE123
   H65    GND @BASEBOARD_FAB2_LIB.BASEBOARD_FAB2(SCH_1):GND    I13 @BASEBOARD_FAB2_LIB.BASEBOARD_FAB2(SCH_1):PAGE123
   J11    GND @BASEBOARD_FAB2_LIB.BASEBOARD_FAB2(SCH_1):GND    I13 @BASEBOARD_FAB2_LIB.BASEBOARD_FAB2(SCH_1):PAGE123
   J15    GND @BASEBOARD_FAB2_LIB.BASEBOARD_FAB2(SCH_1):GND    I13 @BASEBOARD_FAB2_LIB.BASEBOARD_FAB2(SCH_1):PAGE123
   J22    GND @BASEBOARD_FAB2_LIB.BASEBOARD_FAB2(SCH_1):GND    I13 @BASEBOARD_FAB2_LIB.BASEBOARD_FAB2(SCH_1):PAGE123
   J37    GND @BASEBOARD_FAB2_LIB.BASEBOARD_FAB2(SCH_1):GND    I13 @BASEBOARD_FAB2_LIB.BASEBOARD_FAB2(SCH_1):PAGE123
   J44    GND @BASEBOARD_FAB2_LIB.BASEBOARD_FAB2(SCH_1):GND    I13 @BASEBOARD_FAB2_LIB.BASEBOARD_FAB2(SCH_1):PAGE123
   J59    GND @BASEBOARD_FAB2_LIB.BASEBOARD_FAB2(SCH_1):GND    I13 @BASEBOARD_FAB2_LIB.BASEBOARD_FAB2(SCH_1):PAGE123
   J68    GND @BASEBOARD_FAB2_LIB.BASEBOARD_FAB2(SCH_1):GND    I13 @BASEBOARD_FAB2_LIB.BASEBOARD_FAB2(SCH_1):PAGE123
   J70    GND @BASEBOARD_FAB2_LIB.BASEBOARD_FAB2(SCH_1):GND    I13 @BASEBOARD_FAB2_LIB.BASEBOARD_FAB2(SCH_1):PAGE123
   K54    GND @BASEBOARD_FAB2_LIB.BASEBOARD_FAB2(SCH_1):GND    I13 @BASEBOARD_FAB2_LIB.BASEBOARD_FAB2(SCH_1):PAGE123
   K69    GND @BASEBOARD_FAB2_LIB.BASEBOARD_FAB2(SCH_1):GND    I13 @BASEBOARD_FAB2_LIB.BASEBOARD_FAB2(SCH_1):PAGE123
   K71    GND @BASEBOARD_FAB2_LIB.BASEBOARD_FAB2(SCH_1):GND    I13 @BASEBOARD_FAB2_LIB.BASEBOARD_FAB2(SCH_1):PAGE123
    L5    GND @BASEBOARD_FAB2_LIB.BASEBOARD_FAB2(SCH_1):GND    I13 @BASEBOARD_FAB2_LIB.BASEBOARD_FAB2(SCH_1):PAGE123
   L68    GND @BASEBOARD_FAB2_LIB.BASEBOARD_FAB2(SCH_1):GND    I13 @BASEBOARD_FAB2_LIB.BASEBOARD_FAB2(SCH_1):PAGE123
    M2    GND @BASEBOARD_FAB2_LIB.BASEBOARD_FAB2(SCH_1):GND    I13 @BASEBOARD_FAB2_LIB.BASEBOARD_FAB2(SCH_1):PAGE123
   M22    GND @BASEBOARD_FAB2_LIB.BASEBOARD_FAB2(SCH_1):GND    I13 @BASEBOARD_FAB2_LIB.BASEBOARD_FAB2(SCH_1):PAGE123
   M26    GND @BASEBOARD_FAB2_LIB.BASEBOARD_FAB2(SCH_1):GND    I13 @BASEBOARD_FAB2_LIB.BASEBOARD_FAB2(SCH_1):PAGE123
   M29    GND @BASEBOARD_FAB2_LIB.BASEBOARD_FAB2(SCH_1):GND    I13 @BASEBOARD_FAB2_LIB.BASEBOARD_FAB2(SCH_1):PAGE123
   M33    GND @BASEBOARD_FAB2_LIB.BASEBOARD_FAB2(SCH_1):GND    I13 @BASEBOARD_FAB2_LIB.BASEBOARD_FAB2(SCH_1):PAGE123
   M37    GND @BASEBOARD_FAB2_LIB.BASEBOARD_FAB2(SCH_1):GND    I13 @BASEBOARD_FAB2_LIB.BASEBOARD_FAB2(SCH_1):PAGE123
    M4    GND @BASEBOARD_FAB2_LIB.BASEBOARD_FAB2(SCH_1):GND    I13 @BASEBOARD_FAB2_LIB.BASEBOARD_FAB2(SCH_1):PAGE123
   M40    GND @BASEBOARD_FAB2_LIB.BASEBOARD_FAB2(SCH_1):GND    I13 @BASEBOARD_FAB2_LIB.BASEBOARD_FAB2(SCH_1):PAGE123
   N42    GND @BASEBOARD_FAB2_LIB.BASEBOARD_FAB2(SCH_1):GND    I13 @BASEBOARD_FAB2_LIB.BASEBOARD_FAB2(SCH_1):PAGE123
   N50    GND @BASEBOARD_FAB2_LIB.BASEBOARD_FAB2(SCH_1):GND    I13 @BASEBOARD_FAB2_LIB.BASEBOARD_FAB2(SCH_1):PAGE123
   M44    GND @BASEBOARD_FAB2_LIB.BASEBOARD_FAB2(SCH_1):GND    I13 @BASEBOARD_FAB2_LIB.BASEBOARD_FAB2(SCH_1):PAGE123
   M48    GND @BASEBOARD_FAB2_LIB.BASEBOARD_FAB2(SCH_1):GND    I13 @BASEBOARD_FAB2_LIB.BASEBOARD_FAB2(SCH_1):PAGE123
   N13    GND @BASEBOARD_FAB2_LIB.BASEBOARD_FAB2(SCH_1):GND    I13 @BASEBOARD_FAB2_LIB.BASEBOARD_FAB2(SCH_1):PAGE123
   N17    GND @BASEBOARD_FAB2_LIB.BASEBOARD_FAB2(SCH_1):GND    I13 @BASEBOARD_FAB2_LIB.BASEBOARD_FAB2(SCH_1):PAGE123
   N20    GND @BASEBOARD_FAB2_LIB.BASEBOARD_FAB2(SCH_1):GND    I13 @BASEBOARD_FAB2_LIB.BASEBOARD_FAB2(SCH_1):PAGE123
   N24    GND @BASEBOARD_FAB2_LIB.BASEBOARD_FAB2(SCH_1):GND    I13 @BASEBOARD_FAB2_LIB.BASEBOARD_FAB2(SCH_1):PAGE123
   N27    GND @BASEBOARD_FAB2_LIB.BASEBOARD_FAB2(SCH_1):GND    I13 @BASEBOARD_FAB2_LIB.BASEBOARD_FAB2(SCH_1):PAGE123
   N31    GND @BASEBOARD_FAB2_LIB.BASEBOARD_FAB2(SCH_1):GND    I13 @BASEBOARD_FAB2_LIB.BASEBOARD_FAB2(SCH_1):PAGE123
   N35    GND @BASEBOARD_FAB2_LIB.BASEBOARD_FAB2(SCH_1):GND    I17 @BASEBOARD_FAB2_LIB.BASEBOARD_FAB2(SCH_1):PAGE124
   N38    GND @BASEBOARD_FAB2_LIB.BASEBOARD_FAB2(SCH_1):GND    I17 @BASEBOARD_FAB2_LIB.BASEBOARD_FAB2(SCH_1):PAGE124
   N46    GND @BASEBOARD_FAB2_LIB.BASEBOARD_FAB2(SCH_1):GND    I17 @BASEBOARD_FAB2_LIB.BASEBOARD_FAB2(SCH_1):PAGE124
    N5    GND @BASEBOARD_FAB2_LIB.BASEBOARD_FAB2(SCH_1):GND    I17 @BASEBOARD_FAB2_LIB.BASEBOARD_FAB2(SCH_1):PAGE124
   R38    GND @BASEBOARD_FAB2_LIB.BASEBOARD_FAB2(SCH_1):GND    I17 @BASEBOARD_FAB2_LIB.BASEBOARD_FAB2(SCH_1):PAGE124
   N68    GND @BASEBOARD_FAB2_LIB.BASEBOARD_FAB2(SCH_1):GND    I17 @BASEBOARD_FAB2_LIB.BASEBOARD_FAB2(SCH_1):PAGE124
    N9    GND @BASEBOARD_FAB2_LIB.BASEBOARD_FAB2(SCH_1):GND    I17 @BASEBOARD_FAB2_LIB.BASEBOARD_FAB2(SCH_1):PAGE124
  AE43    GND @BASEBOARD_FAB2_LIB.BASEBOARD_FAB2(SCH_1):GND    I17 @BASEBOARD_FAB2_LIB.BASEBOARD_FAB2(SCH_1):PAGE124
   P63    GND @BASEBOARD_FAB2_LIB.BASEBOARD_FAB2(SCH_1):GND    I17 @BASEBOARD_FAB2_LIB.BASEBOARD_FAB2(SCH_1):PAGE124
   R27    GND @BASEBOARD_FAB2_LIB.BASEBOARD_FAB2(SCH_1):GND    I17 @BASEBOARD_FAB2_LIB.BASEBOARD_FAB2(SCH_1):PAGE124
   U42    GND @BASEBOARD_FAB2_LIB.BASEBOARD_FAB2(SCH_1):GND    I17 @BASEBOARD_FAB2_LIB.BASEBOARD_FAB2(SCH_1):PAGE124
    R5    GND @BASEBOARD_FAB2_LIB.BASEBOARD_FAB2(SCH_1):GND    I17 @BASEBOARD_FAB2_LIB.BASEBOARD_FAB2(SCH_1):PAGE124
   R50    GND @BASEBOARD_FAB2_LIB.BASEBOARD_FAB2(SCH_1):GND    I17 @BASEBOARD_FAB2_LIB.BASEBOARD_FAB2(SCH_1):PAGE124
   R54    GND @BASEBOARD_FAB2_LIB.BASEBOARD_FAB2(SCH_1):GND    I17 @BASEBOARD_FAB2_LIB.BASEBOARD_FAB2(SCH_1):PAGE124
   T56    GND @BASEBOARD_FAB2_LIB.BASEBOARD_FAB2(SCH_1):GND    I17 @BASEBOARD_FAB2_LIB.BASEBOARD_FAB2(SCH_1):PAGE124
   R58    GND @BASEBOARD_FAB2_LIB.BASEBOARD_FAB2(SCH_1):GND    I17 @BASEBOARD_FAB2_LIB.BASEBOARD_FAB2(SCH_1):PAGE124
   R68    GND @BASEBOARD_FAB2_LIB.BASEBOARD_FAB2(SCH_1):GND    I17 @BASEBOARD_FAB2_LIB.BASEBOARD_FAB2(SCH_1):PAGE124
   T11    GND @BASEBOARD_FAB2_LIB.BASEBOARD_FAB2(SCH_1):GND    I17 @BASEBOARD_FAB2_LIB.BASEBOARD_FAB2(SCH_1):PAGE124
   T15    GND @BASEBOARD_FAB2_LIB.BASEBOARD_FAB2(SCH_1):GND    I17 @BASEBOARD_FAB2_LIB.BASEBOARD_FAB2(SCH_1):PAGE124
   T18    GND @BASEBOARD_FAB2_LIB.BASEBOARD_FAB2(SCH_1):GND    I17 @BASEBOARD_FAB2_LIB.BASEBOARD_FAB2(SCH_1):PAGE124
   T22    GND @BASEBOARD_FAB2_LIB.BASEBOARD_FAB2(SCH_1):GND    I17 @BASEBOARD_FAB2_LIB.BASEBOARD_FAB2(SCH_1):PAGE124
   T26    GND @BASEBOARD_FAB2_LIB.BASEBOARD_FAB2(SCH_1):GND    I17 @BASEBOARD_FAB2_LIB.BASEBOARD_FAB2(SCH_1):PAGE124
   T29    GND @BASEBOARD_FAB2_LIB.BASEBOARD_FAB2(SCH_1):GND    I17 @BASEBOARD_FAB2_LIB.BASEBOARD_FAB2(SCH_1):PAGE124
   T33    GND @BASEBOARD_FAB2_LIB.BASEBOARD_FAB2(SCH_1):GND    I17 @BASEBOARD_FAB2_LIB.BASEBOARD_FAB2(SCH_1):PAGE124
   T37    GND @BASEBOARD_FAB2_LIB.BASEBOARD_FAB2(SCH_1):GND    I17 @BASEBOARD_FAB2_LIB.BASEBOARD_FAB2(SCH_1):PAGE124
   T40    GND @BASEBOARD_FAB2_LIB.BASEBOARD_FAB2(SCH_1):GND    I17 @BASEBOARD_FAB2_LIB.BASEBOARD_FAB2(SCH_1):PAGE124
  AJ45    GND @BASEBOARD_FAB2_LIB.BASEBOARD_FAB2(SCH_1):GND    I17 @BASEBOARD_FAB2_LIB.BASEBOARD_FAB2(SCH_1):PAGE124
   T48    GND @BASEBOARD_FAB2_LIB.BASEBOARD_FAB2(SCH_1):GND    I17 @BASEBOARD_FAB2_LIB.BASEBOARD_FAB2(SCH_1):PAGE124
   T52    GND @BASEBOARD_FAB2_LIB.BASEBOARD_FAB2(SCH_1):GND    I17 @BASEBOARD_FAB2_LIB.BASEBOARD_FAB2(SCH_1):PAGE124
   T66    GND @BASEBOARD_FAB2_LIB.BASEBOARD_FAB2(SCH_1):GND    I17 @BASEBOARD_FAB2_LIB.BASEBOARD_FAB2(SCH_1):PAGE124
    T7    GND @BASEBOARD_FAB2_LIB.BASEBOARD_FAB2(SCH_1):GND    I17 @BASEBOARD_FAB2_LIB.BASEBOARD_FAB2(SCH_1):PAGE124
  AF50    GND @BASEBOARD_FAB2_LIB.BASEBOARD_FAB2(SCH_1):GND    I17 @BASEBOARD_FAB2_LIB.BASEBOARD_FAB2(SCH_1):PAGE124
  AG46    GND @BASEBOARD_FAB2_LIB.BASEBOARD_FAB2(SCH_1):GND    I17 @BASEBOARD_FAB2_LIB.BASEBOARD_FAB2(SCH_1):PAGE124
   U58    GND @BASEBOARD_FAB2_LIB.BASEBOARD_FAB2(SCH_1):GND    I17 @BASEBOARD_FAB2_LIB.BASEBOARD_FAB2(SCH_1):PAGE124
   V26    GND @BASEBOARD_FAB2_LIB.BASEBOARD_FAB2(SCH_1):GND    I17 @BASEBOARD_FAB2_LIB.BASEBOARD_FAB2(SCH_1):PAGE124
   V48    GND @BASEBOARD_FAB2_LIB.BASEBOARD_FAB2(SCH_1):GND    I17 @BASEBOARD_FAB2_LIB.BASEBOARD_FAB2(SCH_1):PAGE124
    V5    GND @BASEBOARD_FAB2_LIB.BASEBOARD_FAB2(SCH_1):GND    I17 @BASEBOARD_FAB2_LIB.BASEBOARD_FAB2(SCH_1):PAGE124
   V52    GND @BASEBOARD_FAB2_LIB.BASEBOARD_FAB2(SCH_1):GND    I17 @BASEBOARD_FAB2_LIB.BASEBOARD_FAB2(SCH_1):PAGE124
   W58    GND @BASEBOARD_FAB2_LIB.BASEBOARD_FAB2(SCH_1):GND    I17 @BASEBOARD_FAB2_LIB.BASEBOARD_FAB2(SCH_1):PAGE124
   V66    GND @BASEBOARD_FAB2_LIB.BASEBOARD_FAB2(SCH_1):GND    I17 @BASEBOARD_FAB2_LIB.BASEBOARD_FAB2(SCH_1):PAGE124
   V68    GND @BASEBOARD_FAB2_LIB.BASEBOARD_FAB2(SCH_1):GND    I17 @BASEBOARD_FAB2_LIB.BASEBOARD_FAB2(SCH_1):PAGE124
   W13    GND @BASEBOARD_FAB2_LIB.BASEBOARD_FAB2(SCH_1):GND    I17 @BASEBOARD_FAB2_LIB.BASEBOARD_FAB2(SCH_1):PAGE124
   W17    GND @BASEBOARD_FAB2_LIB.BASEBOARD_FAB2(SCH_1):GND    I17 @BASEBOARD_FAB2_LIB.BASEBOARD_FAB2(SCH_1):PAGE124
   W20    GND @BASEBOARD_FAB2_LIB.BASEBOARD_FAB2(SCH_1):GND    I17 @BASEBOARD_FAB2_LIB.BASEBOARD_FAB2(SCH_1):PAGE124
   W24    GND @BASEBOARD_FAB2_LIB.BASEBOARD_FAB2(SCH_1):GND    I17 @BASEBOARD_FAB2_LIB.BASEBOARD_FAB2(SCH_1):PAGE124
  AA50    GND @BASEBOARD_FAB2_LIB.BASEBOARD_FAB2(SCH_1):GND    I17 @BASEBOARD_FAB2_LIB.BASEBOARD_FAB2(SCH_1):PAGE124
   Y43    GND @BASEBOARD_FAB2_LIB.BASEBOARD_FAB2(SCH_1):GND    I17 @BASEBOARD_FAB2_LIB.BASEBOARD_FAB2(SCH_1):PAGE124
   W61    GND @BASEBOARD_FAB2_LIB.BASEBOARD_FAB2(SCH_1):GND    I17 @BASEBOARD_FAB2_LIB.BASEBOARD_FAB2(SCH_1):PAGE124
    W9    GND @BASEBOARD_FAB2_LIB.BASEBOARD_FAB2(SCH_1):GND    I17 @BASEBOARD_FAB2_LIB.BASEBOARD_FAB2(SCH_1):PAGE124
   Y22    GND @BASEBOARD_FAB2_LIB.BASEBOARD_FAB2(SCH_1):GND    I17 @BASEBOARD_FAB2_LIB.BASEBOARD_FAB2(SCH_1):PAGE124
   Y27    GND @BASEBOARD_FAB2_LIB.BASEBOARD_FAB2(SCH_1):GND    I17 @BASEBOARD_FAB2_LIB.BASEBOARD_FAB2(SCH_1):PAGE124
   Y48    GND @BASEBOARD_FAB2_LIB.BASEBOARD_FAB2(SCH_1):GND    I17 @BASEBOARD_FAB2_LIB.BASEBOARD_FAB2(SCH_1):PAGE124
    Y5    GND @BASEBOARD_FAB2_LIB.BASEBOARD_FAB2(SCH_1):GND    I17 @BASEBOARD_FAB2_LIB.BASEBOARD_FAB2(SCH_1):PAGE124
   Y52    GND @BASEBOARD_FAB2_LIB.BASEBOARD_FAB2(SCH_1):GND    I17 @BASEBOARD_FAB2_LIB.BASEBOARD_FAB2(SCH_1):PAGE124
   Y59    GND @BASEBOARD_FAB2_LIB.BASEBOARD_FAB2(SCH_1):GND    I17 @BASEBOARD_FAB2_LIB.BASEBOARD_FAB2(SCH_1):PAGE124
   Y63    GND @BASEBOARD_FAB2_LIB.BASEBOARD_FAB2(SCH_1):GND    I17 @BASEBOARD_FAB2_LIB.BASEBOARD_FAB2(SCH_1):PAGE124
   Y68    GND @BASEBOARD_FAB2_LIB.BASEBOARD_FAB2(SCH_1):GND    I17 @BASEBOARD_FAB2_LIB.BASEBOARD_FAB2(SCH_1):PAGE124
  AA26    GND @BASEBOARD_FAB2_LIB.BASEBOARD_FAB2(SCH_1):GND    I17 @BASEBOARD_FAB2_LIB.BASEBOARD_FAB2(SCH_1):PAGE124
  AA27    GND @BASEBOARD_FAB2_LIB.BASEBOARD_FAB2(SCH_1):GND    I17 @BASEBOARD_FAB2_LIB.BASEBOARD_FAB2(SCH_1):PAGE124
  AA43    GND @BASEBOARD_FAB2_LIB.BASEBOARD_FAB2(SCH_1):GND    I17 @BASEBOARD_FAB2_LIB.BASEBOARD_FAB2(SCH_1):PAGE124
  AA48    GND @BASEBOARD_FAB2_LIB.BASEBOARD_FAB2(SCH_1):GND    I17 @BASEBOARD_FAB2_LIB.BASEBOARD_FAB2(SCH_1):PAGE124
   AB5    GND @BASEBOARD_FAB2_LIB.BASEBOARD_FAB2(SCH_1):GND    I17 @BASEBOARD_FAB2_LIB.BASEBOARD_FAB2(SCH_1):PAGE124
  AB68    GND @BASEBOARD_FAB2_LIB.BASEBOARD_FAB2(SCH_1):GND    I17 @BASEBOARD_FAB2_LIB.BASEBOARD_FAB2(SCH_1):PAGE124
  AB70    GND @BASEBOARD_FAB2_LIB.BASEBOARD_FAB2(SCH_1):GND    I17 @BASEBOARD_FAB2_LIB.BASEBOARD_FAB2(SCH_1):PAGE124
  AB72    GND @BASEBOARD_FAB2_LIB.BASEBOARD_FAB2(SCH_1):GND    I17 @BASEBOARD_FAB2_LIB.BASEBOARD_FAB2(SCH_1):PAGE124
  AC11    GND @BASEBOARD_FAB2_LIB.BASEBOARD_FAB2(SCH_1):GND    I17 @BASEBOARD_FAB2_LIB.BASEBOARD_FAB2(SCH_1):PAGE124
  AC15    GND @BASEBOARD_FAB2_LIB.BASEBOARD_FAB2(SCH_1):GND    I17 @BASEBOARD_FAB2_LIB.BASEBOARD_FAB2(SCH_1):PAGE124
  AC18    GND @BASEBOARD_FAB2_LIB.BASEBOARD_FAB2(SCH_1):GND    I17 @BASEBOARD_FAB2_LIB.BASEBOARD_FAB2(SCH_1):PAGE124
  AC22    GND @BASEBOARD_FAB2_LIB.BASEBOARD_FAB2(SCH_1):GND    I17 @BASEBOARD_FAB2_LIB.BASEBOARD_FAB2(SCH_1):PAGE124
  AC45    GND @BASEBOARD_FAB2_LIB.BASEBOARD_FAB2(SCH_1):GND    I17 @BASEBOARD_FAB2_LIB.BASEBOARD_FAB2(SCH_1):PAGE124
  AD58    GND @BASEBOARD_FAB2_LIB.BASEBOARD_FAB2(SCH_1):GND    I17 @BASEBOARD_FAB2_LIB.BASEBOARD_FAB2(SCH_1):PAGE124
  AC27    GND @BASEBOARD_FAB2_LIB.BASEBOARD_FAB2(SCH_1):GND    I17 @BASEBOARD_FAB2_LIB.BASEBOARD_FAB2(SCH_1):PAGE124
  AC43    GND @BASEBOARD_FAB2_LIB.BASEBOARD_FAB2(SCH_1):GND    I17 @BASEBOARD_FAB2_LIB.BASEBOARD_FAB2(SCH_1):PAGE124
  AC46    GND @BASEBOARD_FAB2_LIB.BASEBOARD_FAB2(SCH_1):GND    I17 @BASEBOARD_FAB2_LIB.BASEBOARD_FAB2(SCH_1):PAGE124
  AC48    GND @BASEBOARD_FAB2_LIB.BASEBOARD_FAB2(SCH_1):GND    I17 @BASEBOARD_FAB2_LIB.BASEBOARD_FAB2(SCH_1):PAGE124
  AC52    GND @BASEBOARD_FAB2_LIB.BASEBOARD_FAB2(SCH_1):GND    I17 @BASEBOARD_FAB2_LIB.BASEBOARD_FAB2(SCH_1):PAGE124
  AC59    GND @BASEBOARD_FAB2_LIB.BASEBOARD_FAB2(SCH_1):GND    I17 @BASEBOARD_FAB2_LIB.BASEBOARD_FAB2(SCH_1):PAGE124
  AC63    GND @BASEBOARD_FAB2_LIB.BASEBOARD_FAB2(SCH_1):GND    I17 @BASEBOARD_FAB2_LIB.BASEBOARD_FAB2(SCH_1):PAGE124
  AC66    GND @BASEBOARD_FAB2_LIB.BASEBOARD_FAB2(SCH_1):GND    I17 @BASEBOARD_FAB2_LIB.BASEBOARD_FAB2(SCH_1):PAGE124
   AC7    GND @BASEBOARD_FAB2_LIB.BASEBOARD_FAB2(SCH_1):GND    I17 @BASEBOARD_FAB2_LIB.BASEBOARD_FAB2(SCH_1):PAGE124
   AD5    GND @BASEBOARD_FAB2_LIB.BASEBOARD_FAB2(SCH_1):GND    I17 @BASEBOARD_FAB2_LIB.BASEBOARD_FAB2(SCH_1):PAGE124
  AD65    GND @BASEBOARD_FAB2_LIB.BASEBOARD_FAB2(SCH_1):GND    I17 @BASEBOARD_FAB2_LIB.BASEBOARD_FAB2(SCH_1):PAGE124
  AD68    GND @BASEBOARD_FAB2_LIB.BASEBOARD_FAB2(SCH_1):GND    I17 @BASEBOARD_FAB2_LIB.BASEBOARD_FAB2(SCH_1):PAGE124
  AE29    GND @BASEBOARD_FAB2_LIB.BASEBOARD_FAB2(SCH_1):GND    I17 @BASEBOARD_FAB2_LIB.BASEBOARD_FAB2(SCH_1):PAGE124
   J18    GND @BASEBOARD_FAB2_LIB.BASEBOARD_FAB2(SCH_1):GND    I17 @BASEBOARD_FAB2_LIB.BASEBOARD_FAB2(SCH_1):PAGE124
  AE48    GND @BASEBOARD_FAB2_LIB.BASEBOARD_FAB2(SCH_1):GND    I17 @BASEBOARD_FAB2_LIB.BASEBOARD_FAB2(SCH_1):PAGE124
  AE52    GND @BASEBOARD_FAB2_LIB.BASEBOARD_FAB2(SCH_1):GND    I17 @BASEBOARD_FAB2_LIB.BASEBOARD_FAB2(SCH_1):PAGE124
  AE56    GND @BASEBOARD_FAB2_LIB.BASEBOARD_FAB2(SCH_1):GND    I17 @BASEBOARD_FAB2_LIB.BASEBOARD_FAB2(SCH_1):PAGE124
  AE59    GND @BASEBOARD_FAB2_LIB.BASEBOARD_FAB2(SCH_1):GND    I17 @BASEBOARD_FAB2_LIB.BASEBOARD_FAB2(SCH_1):PAGE124
  AE63    GND @BASEBOARD_FAB2_LIB.BASEBOARD_FAB2(SCH_1):GND    I17 @BASEBOARD_FAB2_LIB.BASEBOARD_FAB2(SCH_1):PAGE124
  AE66    GND @BASEBOARD_FAB2_LIB.BASEBOARD_FAB2(SCH_1):GND    I17 @BASEBOARD_FAB2_LIB.BASEBOARD_FAB2(SCH_1):PAGE124
   AF1    GND @BASEBOARD_FAB2_LIB.BASEBOARD_FAB2(SCH_1):GND    I17 @BASEBOARD_FAB2_LIB.BASEBOARD_FAB2(SCH_1):PAGE124
  AF13    GND @BASEBOARD_FAB2_LIB.BASEBOARD_FAB2(SCH_1):GND    I17 @BASEBOARD_FAB2_LIB.BASEBOARD_FAB2(SCH_1):PAGE124
   AF5    GND @BASEBOARD_FAB2_LIB.BASEBOARD_FAB2(SCH_1):GND    I17 @BASEBOARD_FAB2_LIB.BASEBOARD_FAB2(SCH_1):PAGE124
   AF9    GND @BASEBOARD_FAB2_LIB.BASEBOARD_FAB2(SCH_1):GND    I17 @BASEBOARD_FAB2_LIB.BASEBOARD_FAB2(SCH_1):PAGE124
  AF17    GND @BASEBOARD_FAB2_LIB.BASEBOARD_FAB2(SCH_1):GND    I17 @BASEBOARD_FAB2_LIB.BASEBOARD_FAB2(SCH_1):PAGE124
  AF24    GND @BASEBOARD_FAB2_LIB.BASEBOARD_FAB2(SCH_1):GND    I17 @BASEBOARD_FAB2_LIB.BASEBOARD_FAB2(SCH_1):PAGE124
   AF3    GND @BASEBOARD_FAB2_LIB.BASEBOARD_FAB2(SCH_1):GND    I17 @BASEBOARD_FAB2_LIB.BASEBOARD_FAB2(SCH_1):PAGE124
  AF68    GND @BASEBOARD_FAB2_LIB.BASEBOARD_FAB2(SCH_1):GND    I17 @BASEBOARD_FAB2_LIB.BASEBOARD_FAB2(SCH_1):PAGE124
  AG26    GND @BASEBOARD_FAB2_LIB.BASEBOARD_FAB2(SCH_1):GND    I17 @BASEBOARD_FAB2_LIB.BASEBOARD_FAB2(SCH_1):PAGE124
  AG30    GND @BASEBOARD_FAB2_LIB.BASEBOARD_FAB2(SCH_1):GND    I17 @BASEBOARD_FAB2_LIB.BASEBOARD_FAB2(SCH_1):PAGE124
  AG41    GND @BASEBOARD_FAB2_LIB.BASEBOARD_FAB2(SCH_1):GND    I17 @BASEBOARD_FAB2_LIB.BASEBOARD_FAB2(SCH_1):PAGE124
  AG43    GND @BASEBOARD_FAB2_LIB.BASEBOARD_FAB2(SCH_1):GND    I17 @BASEBOARD_FAB2_LIB.BASEBOARD_FAB2(SCH_1):PAGE124
  AG52    GND @BASEBOARD_FAB2_LIB.BASEBOARD_FAB2(SCH_1):GND    I17 @BASEBOARD_FAB2_LIB.BASEBOARD_FAB2(SCH_1):PAGE124
  AG56    GND @BASEBOARD_FAB2_LIB.BASEBOARD_FAB2(SCH_1):GND    I17 @BASEBOARD_FAB2_LIB.BASEBOARD_FAB2(SCH_1):PAGE124
  AG59    GND @BASEBOARD_FAB2_LIB.BASEBOARD_FAB2(SCH_1):GND    I17 @BASEBOARD_FAB2_LIB.BASEBOARD_FAB2(SCH_1):PAGE124
  AG66    GND @BASEBOARD_FAB2_LIB.BASEBOARD_FAB2(SCH_1):GND    I17 @BASEBOARD_FAB2_LIB.BASEBOARD_FAB2(SCH_1):PAGE124
  AH20    GND @BASEBOARD_FAB2_LIB.BASEBOARD_FAB2(SCH_1):GND    I17 @BASEBOARD_FAB2_LIB.BASEBOARD_FAB2(SCH_1):PAGE124
  AJ11    GND @BASEBOARD_FAB2_LIB.BASEBOARD_FAB2(SCH_1):GND    I17 @BASEBOARD_FAB2_LIB.BASEBOARD_FAB2(SCH_1):PAGE124
  AJ32    GND @BASEBOARD_FAB2_LIB.BASEBOARD_FAB2(SCH_1):GND    I17 @BASEBOARD_FAB2_LIB.BASEBOARD_FAB2(SCH_1):PAGE124
  AJ56    GND @BASEBOARD_FAB2_LIB.BASEBOARD_FAB2(SCH_1):GND    I17 @BASEBOARD_FAB2_LIB.BASEBOARD_FAB2(SCH_1):PAGE124
  AK30    GND @BASEBOARD_FAB2_LIB.BASEBOARD_FAB2(SCH_1):GND    I17 @BASEBOARD_FAB2_LIB.BASEBOARD_FAB2(SCH_1):PAGE124
  AJ15    GND @BASEBOARD_FAB2_LIB.BASEBOARD_FAB2(SCH_1):GND    I17 @BASEBOARD_FAB2_LIB.BASEBOARD_FAB2(SCH_1):PAGE124
  AJ18    GND @BASEBOARD_FAB2_LIB.BASEBOARD_FAB2(SCH_1):GND    I17 @BASEBOARD_FAB2_LIB.BASEBOARD_FAB2(SCH_1):PAGE124
  AJ22    GND @BASEBOARD_FAB2_LIB.BASEBOARD_FAB2(SCH_1):GND    I17 @BASEBOARD_FAB2_LIB.BASEBOARD_FAB2(SCH_1):PAGE124
  AJ26    GND @BASEBOARD_FAB2_LIB.BASEBOARD_FAB2(SCH_1):GND    I17 @BASEBOARD_FAB2_LIB.BASEBOARD_FAB2(SCH_1):PAGE124
  AJ30    GND @BASEBOARD_FAB2_LIB.BASEBOARD_FAB2(SCH_1):GND    I17 @BASEBOARD_FAB2_LIB.BASEBOARD_FAB2(SCH_1):PAGE124
  AJ34    GND @BASEBOARD_FAB2_LIB.BASEBOARD_FAB2(SCH_1):GND    I17 @BASEBOARD_FAB2_LIB.BASEBOARD_FAB2(SCH_1):PAGE124
  AJ36    GND @BASEBOARD_FAB2_LIB.BASEBOARD_FAB2(SCH_1):GND    I17 @BASEBOARD_FAB2_LIB.BASEBOARD_FAB2(SCH_1):PAGE124
  AJ37    GND @BASEBOARD_FAB2_LIB.BASEBOARD_FAB2(SCH_1):GND    I17 @BASEBOARD_FAB2_LIB.BASEBOARD_FAB2(SCH_1):PAGE124
  AJ39    GND @BASEBOARD_FAB2_LIB.BASEBOARD_FAB2(SCH_1):GND    I17 @BASEBOARD_FAB2_LIB.BASEBOARD_FAB2(SCH_1):PAGE124
  AJ41    GND @BASEBOARD_FAB2_LIB.BASEBOARD_FAB2(SCH_1):GND    I17 @BASEBOARD_FAB2_LIB.BASEBOARD_FAB2(SCH_1):PAGE124
   AJ5    GND @BASEBOARD_FAB2_LIB.BASEBOARD_FAB2(SCH_1):GND    I17 @BASEBOARD_FAB2_LIB.BASEBOARD_FAB2(SCH_1):PAGE124
  AJ52    GND @BASEBOARD_FAB2_LIB.BASEBOARD_FAB2(SCH_1):GND    I17 @BASEBOARD_FAB2_LIB.BASEBOARD_FAB2(SCH_1):PAGE124
  AJ59    GND @BASEBOARD_FAB2_LIB.BASEBOARD_FAB2(SCH_1):GND    I17 @BASEBOARD_FAB2_LIB.BASEBOARD_FAB2(SCH_1):PAGE124
  AJ66    GND @BASEBOARD_FAB2_LIB.BASEBOARD_FAB2(SCH_1):GND    I17 @BASEBOARD_FAB2_LIB.BASEBOARD_FAB2(SCH_1):PAGE124
  AJ68    GND @BASEBOARD_FAB2_LIB.BASEBOARD_FAB2(SCH_1):GND    I17 @BASEBOARD_FAB2_LIB.BASEBOARD_FAB2(SCH_1):PAGE124
   AJ7    GND @BASEBOARD_FAB2_LIB.BASEBOARD_FAB2(SCH_1):GND    I17 @BASEBOARD_FAB2_LIB.BASEBOARD_FAB2(SCH_1):PAGE124
  AK26    GND @BASEBOARD_FAB2_LIB.BASEBOARD_FAB2(SCH_1):GND    I17 @BASEBOARD_FAB2_LIB.BASEBOARD_FAB2(SCH_1):PAGE124
  AK41    GND @BASEBOARD_FAB2_LIB.BASEBOARD_FAB2(SCH_1):GND    I17 @BASEBOARD_FAB2_LIB.BASEBOARD_FAB2(SCH_1):PAGE124
  AK46    GND @BASEBOARD_FAB2_LIB.BASEBOARD_FAB2(SCH_1):GND    I17 @BASEBOARD_FAB2_LIB.BASEBOARD_FAB2(SCH_1):PAGE124
  AK48    GND @BASEBOARD_FAB2_LIB.BASEBOARD_FAB2(SCH_1):GND    I17 @BASEBOARD_FAB2_LIB.BASEBOARD_FAB2(SCH_1):PAGE124
  AK58    GND @BASEBOARD_FAB2_LIB.BASEBOARD_FAB2(SCH_1):GND    I17 @BASEBOARD_FAB2_LIB.BASEBOARD_FAB2(SCH_1):PAGE124
  AK61    GND @BASEBOARD_FAB2_LIB.BASEBOARD_FAB2(SCH_1):GND    I17 @BASEBOARD_FAB2_LIB.BASEBOARD_FAB2(SCH_1):PAGE124
  AK69    GND @BASEBOARD_FAB2_LIB.BASEBOARD_FAB2(SCH_1):GND    I17 @BASEBOARD_FAB2_LIB.BASEBOARD_FAB2(SCH_1):PAGE124
  AK71    GND @BASEBOARD_FAB2_LIB.BASEBOARD_FAB2(SCH_1):GND    I17 @BASEBOARD_FAB2_LIB.BASEBOARD_FAB2(SCH_1):PAGE124
  AL22    GND @BASEBOARD_FAB2_LIB.BASEBOARD_FAB2(SCH_1):GND    I17 @BASEBOARD_FAB2_LIB.BASEBOARD_FAB2(SCH_1):PAGE124
   AL5    GND @BASEBOARD_FAB2_LIB.BASEBOARD_FAB2(SCH_1):GND    I17 @BASEBOARD_FAB2_LIB.BASEBOARD_FAB2(SCH_1):PAGE124
  AL52    GND @BASEBOARD_FAB2_LIB.BASEBOARD_FAB2(SCH_1):GND    I17 @BASEBOARD_FAB2_LIB.BASEBOARD_FAB2(SCH_1):PAGE124
  AL59    GND @BASEBOARD_FAB2_LIB.BASEBOARD_FAB2(SCH_1):GND    I17 @BASEBOARD_FAB2_LIB.BASEBOARD_FAB2(SCH_1):PAGE124
  AL68    GND @BASEBOARD_FAB2_LIB.BASEBOARD_FAB2(SCH_1):GND    I16 @BASEBOARD_FAB2_LIB.BASEBOARD_FAB2(SCH_1):PAGE124
  AL70    GND @BASEBOARD_FAB2_LIB.BASEBOARD_FAB2(SCH_1):GND    I16 @BASEBOARD_FAB2_LIB.BASEBOARD_FAB2(SCH_1):PAGE124
  AL72    GND @BASEBOARD_FAB2_LIB.BASEBOARD_FAB2(SCH_1):GND    I16 @BASEBOARD_FAB2_LIB.BASEBOARD_FAB2(SCH_1):PAGE124
  AM26    GND @BASEBOARD_FAB2_LIB.BASEBOARD_FAB2(SCH_1):GND    I16 @BASEBOARD_FAB2_LIB.BASEBOARD_FAB2(SCH_1):PAGE124
  AM30    GND @BASEBOARD_FAB2_LIB.BASEBOARD_FAB2(SCH_1):GND    I16 @BASEBOARD_FAB2_LIB.BASEBOARD_FAB2(SCH_1):PAGE124
  AM41    GND @BASEBOARD_FAB2_LIB.BASEBOARD_FAB2(SCH_1):GND    I16 @BASEBOARD_FAB2_LIB.BASEBOARD_FAB2(SCH_1):PAGE124
  AM46    GND @BASEBOARD_FAB2_LIB.BASEBOARD_FAB2(SCH_1):GND    I16 @BASEBOARD_FAB2_LIB.BASEBOARD_FAB2(SCH_1):PAGE124
  AN13    GND @BASEBOARD_FAB2_LIB.BASEBOARD_FAB2(SCH_1):GND    I16 @BASEBOARD_FAB2_LIB.BASEBOARD_FAB2(SCH_1):PAGE124
  AN17    GND @BASEBOARD_FAB2_LIB.BASEBOARD_FAB2(SCH_1):GND    I16 @BASEBOARD_FAB2_LIB.BASEBOARD_FAB2(SCH_1):PAGE124
  AN68    GND @BASEBOARD_FAB2_LIB.BASEBOARD_FAB2(SCH_1):GND    I16 @BASEBOARD_FAB2_LIB.BASEBOARD_FAB2(SCH_1):PAGE124
  AP22    GND @BASEBOARD_FAB2_LIB.BASEBOARD_FAB2(SCH_1):GND    I16 @BASEBOARD_FAB2_LIB.BASEBOARD_FAB2(SCH_1):PAGE124
  AN20    GND @BASEBOARD_FAB2_LIB.BASEBOARD_FAB2(SCH_1):GND    I16 @BASEBOARD_FAB2_LIB.BASEBOARD_FAB2(SCH_1):PAGE124
   AN5    GND @BASEBOARD_FAB2_LIB.BASEBOARD_FAB2(SCH_1):GND    I16 @BASEBOARD_FAB2_LIB.BASEBOARD_FAB2(SCH_1):PAGE124
  AN58    GND @BASEBOARD_FAB2_LIB.BASEBOARD_FAB2(SCH_1):GND    I16 @BASEBOARD_FAB2_LIB.BASEBOARD_FAB2(SCH_1):PAGE124
   AN9    GND @BASEBOARD_FAB2_LIB.BASEBOARD_FAB2(SCH_1):GND    I16 @BASEBOARD_FAB2_LIB.BASEBOARD_FAB2(SCH_1):PAGE124
   AP2    GND @BASEBOARD_FAB2_LIB.BASEBOARD_FAB2(SCH_1):GND    I16 @BASEBOARD_FAB2_LIB.BASEBOARD_FAB2(SCH_1):PAGE124
  AP26    GND @BASEBOARD_FAB2_LIB.BASEBOARD_FAB2(SCH_1):GND    I16 @BASEBOARD_FAB2_LIB.BASEBOARD_FAB2(SCH_1):PAGE124
  AP30    GND @BASEBOARD_FAB2_LIB.BASEBOARD_FAB2(SCH_1):GND    I16 @BASEBOARD_FAB2_LIB.BASEBOARD_FAB2(SCH_1):PAGE124
   AP4    GND @BASEBOARD_FAB2_LIB.BASEBOARD_FAB2(SCH_1):GND    I16 @BASEBOARD_FAB2_LIB.BASEBOARD_FAB2(SCH_1):PAGE124
  AP41    GND @BASEBOARD_FAB2_LIB.BASEBOARD_FAB2(SCH_1):GND    I16 @BASEBOARD_FAB2_LIB.BASEBOARD_FAB2(SCH_1):PAGE124
  AP46    GND @BASEBOARD_FAB2_LIB.BASEBOARD_FAB2(SCH_1):GND    I16 @BASEBOARD_FAB2_LIB.BASEBOARD_FAB2(SCH_1):PAGE124
  AP52    GND @BASEBOARD_FAB2_LIB.BASEBOARD_FAB2(SCH_1):GND    I16 @BASEBOARD_FAB2_LIB.BASEBOARD_FAB2(SCH_1):PAGE124
  AP66    GND @BASEBOARD_FAB2_LIB.BASEBOARD_FAB2(SCH_1):GND    I16 @BASEBOARD_FAB2_LIB.BASEBOARD_FAB2(SCH_1):PAGE124
   AR5    GND @BASEBOARD_FAB2_LIB.BASEBOARD_FAB2(SCH_1):GND    I16 @BASEBOARD_FAB2_LIB.BASEBOARD_FAB2(SCH_1):PAGE124
  AR50    GND @BASEBOARD_FAB2_LIB.BASEBOARD_FAB2(SCH_1):GND    I16 @BASEBOARD_FAB2_LIB.BASEBOARD_FAB2(SCH_1):PAGE124
  AR58    GND @BASEBOARD_FAB2_LIB.BASEBOARD_FAB2(SCH_1):GND    I16 @BASEBOARD_FAB2_LIB.BASEBOARD_FAB2(SCH_1):PAGE124
  AR65    GND @BASEBOARD_FAB2_LIB.BASEBOARD_FAB2(SCH_1):GND    I16 @BASEBOARD_FAB2_LIB.BASEBOARD_FAB2(SCH_1):PAGE124
  AR68    GND @BASEBOARD_FAB2_LIB.BASEBOARD_FAB2(SCH_1):GND    I16 @BASEBOARD_FAB2_LIB.BASEBOARD_FAB2(SCH_1):PAGE124
  AR70    GND @BASEBOARD_FAB2_LIB.BASEBOARD_FAB2(SCH_1):GND    I16 @BASEBOARD_FAB2_LIB.BASEBOARD_FAB2(SCH_1):PAGE124
  AR72    GND @BASEBOARD_FAB2_LIB.BASEBOARD_FAB2(SCH_1):GND    I16 @BASEBOARD_FAB2_LIB.BASEBOARD_FAB2(SCH_1):PAGE124
   AT7    GND @BASEBOARD_FAB2_LIB.BASEBOARD_FAB2(SCH_1):GND    I16 @BASEBOARD_FAB2_LIB.BASEBOARD_FAB2(SCH_1):PAGE124
  AT11    GND @BASEBOARD_FAB2_LIB.BASEBOARD_FAB2(SCH_1):GND    I16 @BASEBOARD_FAB2_LIB.BASEBOARD_FAB2(SCH_1):PAGE124
  AT15    GND @BASEBOARD_FAB2_LIB.BASEBOARD_FAB2(SCH_1):GND    I16 @BASEBOARD_FAB2_LIB.BASEBOARD_FAB2(SCH_1):PAGE124
  AT18    GND @BASEBOARD_FAB2_LIB.BASEBOARD_FAB2(SCH_1):GND    I16 @BASEBOARD_FAB2_LIB.BASEBOARD_FAB2(SCH_1):PAGE124
  AT22    GND @BASEBOARD_FAB2_LIB.BASEBOARD_FAB2(SCH_1):GND    I16 @BASEBOARD_FAB2_LIB.BASEBOARD_FAB2(SCH_1):PAGE124
  AT26    GND @BASEBOARD_FAB2_LIB.BASEBOARD_FAB2(SCH_1):GND    I16 @BASEBOARD_FAB2_LIB.BASEBOARD_FAB2(SCH_1):PAGE124
  AT30    GND @BASEBOARD_FAB2_LIB.BASEBOARD_FAB2(SCH_1):GND    I16 @BASEBOARD_FAB2_LIB.BASEBOARD_FAB2(SCH_1):PAGE124
  AT41    GND @BASEBOARD_FAB2_LIB.BASEBOARD_FAB2(SCH_1):GND    I16 @BASEBOARD_FAB2_LIB.BASEBOARD_FAB2(SCH_1):PAGE124
  AT46    GND @BASEBOARD_FAB2_LIB.BASEBOARD_FAB2(SCH_1):GND    I16 @BASEBOARD_FAB2_LIB.BASEBOARD_FAB2(SCH_1):PAGE124
  AT59    GND @BASEBOARD_FAB2_LIB.BASEBOARD_FAB2(SCH_1):GND    I16 @BASEBOARD_FAB2_LIB.BASEBOARD_FAB2(SCH_1):PAGE124
  AU26    GND @BASEBOARD_FAB2_LIB.BASEBOARD_FAB2(SCH_1):GND    I16 @BASEBOARD_FAB2_LIB.BASEBOARD_FAB2(SCH_1):PAGE124
  AU30    GND @BASEBOARD_FAB2_LIB.BASEBOARD_FAB2(SCH_1):GND    I16 @BASEBOARD_FAB2_LIB.BASEBOARD_FAB2(SCH_1):PAGE124
  AE22    GND @BASEBOARD_FAB2_LIB.BASEBOARD_FAB2(SCH_1):GND    I16 @BASEBOARD_FAB2_LIB.BASEBOARD_FAB2(SCH_1):PAGE124
  AU41    GND @BASEBOARD_FAB2_LIB.BASEBOARD_FAB2(SCH_1):GND    I16 @BASEBOARD_FAB2_LIB.BASEBOARD_FAB2(SCH_1):PAGE124
  AU46    GND @BASEBOARD_FAB2_LIB.BASEBOARD_FAB2(SCH_1):GND    I16 @BASEBOARD_FAB2_LIB.BASEBOARD_FAB2(SCH_1):PAGE124
  AU50    GND @BASEBOARD_FAB2_LIB.BASEBOARD_FAB2(SCH_1):GND    I16 @BASEBOARD_FAB2_LIB.BASEBOARD_FAB2(SCH_1):PAGE124
  AU54    GND @BASEBOARD_FAB2_LIB.BASEBOARD_FAB2(SCH_1):GND    I16 @BASEBOARD_FAB2_LIB.BASEBOARD_FAB2(SCH_1):PAGE124
  AU61    GND @BASEBOARD_FAB2_LIB.BASEBOARD_FAB2(SCH_1):GND    I16 @BASEBOARD_FAB2_LIB.BASEBOARD_FAB2(SCH_1):PAGE124
   AV5    GND @BASEBOARD_FAB2_LIB.BASEBOARD_FAB2(SCH_1):GND    I16 @BASEBOARD_FAB2_LIB.BASEBOARD_FAB2(SCH_1):PAGE124
  AV22    GND @BASEBOARD_FAB2_LIB.BASEBOARD_FAB2(SCH_1):GND    I16 @BASEBOARD_FAB2_LIB.BASEBOARD_FAB2(SCH_1):PAGE124
  AV59    GND @BASEBOARD_FAB2_LIB.BASEBOARD_FAB2(SCH_1):GND    I16 @BASEBOARD_FAB2_LIB.BASEBOARD_FAB2(SCH_1):PAGE124
  AV68    GND @BASEBOARD_FAB2_LIB.BASEBOARD_FAB2(SCH_1):GND    I16 @BASEBOARD_FAB2_LIB.BASEBOARD_FAB2(SCH_1):PAGE124
   AW9    GND @BASEBOARD_FAB2_LIB.BASEBOARD_FAB2(SCH_1):GND    I16 @BASEBOARD_FAB2_LIB.BASEBOARD_FAB2(SCH_1):PAGE124
  AW13    GND @BASEBOARD_FAB2_LIB.BASEBOARD_FAB2(SCH_1):GND    I16 @BASEBOARD_FAB2_LIB.BASEBOARD_FAB2(SCH_1):PAGE124
  AW17    GND @BASEBOARD_FAB2_LIB.BASEBOARD_FAB2(SCH_1):GND    I16 @BASEBOARD_FAB2_LIB.BASEBOARD_FAB2(SCH_1):PAGE124
  AW26    GND @BASEBOARD_FAB2_LIB.BASEBOARD_FAB2(SCH_1):GND    I16 @BASEBOARD_FAB2_LIB.BASEBOARD_FAB2(SCH_1):PAGE124
  AW30    GND @BASEBOARD_FAB2_LIB.BASEBOARD_FAB2(SCH_1):GND    I16 @BASEBOARD_FAB2_LIB.BASEBOARD_FAB2(SCH_1):PAGE124
  AW32    GND @BASEBOARD_FAB2_LIB.BASEBOARD_FAB2(SCH_1):GND    I16 @BASEBOARD_FAB2_LIB.BASEBOARD_FAB2(SCH_1):PAGE124
  AW34    GND @BASEBOARD_FAB2_LIB.BASEBOARD_FAB2(SCH_1):GND    I16 @BASEBOARD_FAB2_LIB.BASEBOARD_FAB2(SCH_1):PAGE124
  AW36    GND @BASEBOARD_FAB2_LIB.BASEBOARD_FAB2(SCH_1):GND    I16 @BASEBOARD_FAB2_LIB.BASEBOARD_FAB2(SCH_1):PAGE124
  AW37    GND @BASEBOARD_FAB2_LIB.BASEBOARD_FAB2(SCH_1):GND    I16 @BASEBOARD_FAB2_LIB.BASEBOARD_FAB2(SCH_1):PAGE124
  AW39    GND @BASEBOARD_FAB2_LIB.BASEBOARD_FAB2(SCH_1):GND    I16 @BASEBOARD_FAB2_LIB.BASEBOARD_FAB2(SCH_1):PAGE124
  AW41    GND @BASEBOARD_FAB2_LIB.BASEBOARD_FAB2(SCH_1):GND    I16 @BASEBOARD_FAB2_LIB.BASEBOARD_FAB2(SCH_1):PAGE124
  AW46    GND @BASEBOARD_FAB2_LIB.BASEBOARD_FAB2(SCH_1):GND    I16 @BASEBOARD_FAB2_LIB.BASEBOARD_FAB2(SCH_1):PAGE124
  AW50    GND @BASEBOARD_FAB2_LIB.BASEBOARD_FAB2(SCH_1):GND    I16 @BASEBOARD_FAB2_LIB.BASEBOARD_FAB2(SCH_1):PAGE124
  AW58    GND @BASEBOARD_FAB2_LIB.BASEBOARD_FAB2(SCH_1):GND    I16 @BASEBOARD_FAB2_LIB.BASEBOARD_FAB2(SCH_1):PAGE124
  AW61    GND @BASEBOARD_FAB2_LIB.BASEBOARD_FAB2(SCH_1):GND    I16 @BASEBOARD_FAB2_LIB.BASEBOARD_FAB2(SCH_1):PAGE124
   AY5    GND @BASEBOARD_FAB2_LIB.BASEBOARD_FAB2(SCH_1):GND    I16 @BASEBOARD_FAB2_LIB.BASEBOARD_FAB2(SCH_1):PAGE124
  AY22    GND @BASEBOARD_FAB2_LIB.BASEBOARD_FAB2(SCH_1):GND    I16 @BASEBOARD_FAB2_LIB.BASEBOARD_FAB2(SCH_1):PAGE124
  AY56    GND @BASEBOARD_FAB2_LIB.BASEBOARD_FAB2(SCH_1):GND    I16 @BASEBOARD_FAB2_LIB.BASEBOARD_FAB2(SCH_1):PAGE124
  AY63    GND @BASEBOARD_FAB2_LIB.BASEBOARD_FAB2(SCH_1):GND    I16 @BASEBOARD_FAB2_LIB.BASEBOARD_FAB2(SCH_1):PAGE124
  AY68    GND @BASEBOARD_FAB2_LIB.BASEBOARD_FAB2(SCH_1):GND    I16 @BASEBOARD_FAB2_LIB.BASEBOARD_FAB2(SCH_1):PAGE124
  BA50    GND @BASEBOARD_FAB2_LIB.BASEBOARD_FAB2(SCH_1):GND    I16 @BASEBOARD_FAB2_LIB.BASEBOARD_FAB2(SCH_1):PAGE124
  BA54    GND @BASEBOARD_FAB2_LIB.BASEBOARD_FAB2(SCH_1):GND    I16 @BASEBOARD_FAB2_LIB.BASEBOARD_FAB2(SCH_1):PAGE124
  BA58    GND @BASEBOARD_FAB2_LIB.BASEBOARD_FAB2(SCH_1):GND    I16 @BASEBOARD_FAB2_LIB.BASEBOARD_FAB2(SCH_1):PAGE124
   BB5    GND @BASEBOARD_FAB2_LIB.BASEBOARD_FAB2(SCH_1):GND    I16 @BASEBOARD_FAB2_LIB.BASEBOARD_FAB2(SCH_1):PAGE124
   BB7    GND @BASEBOARD_FAB2_LIB.BASEBOARD_FAB2(SCH_1):GND    I16 @BASEBOARD_FAB2_LIB.BASEBOARD_FAB2(SCH_1):PAGE124
  BB11    GND @BASEBOARD_FAB2_LIB.BASEBOARD_FAB2(SCH_1):GND    I16 @BASEBOARD_FAB2_LIB.BASEBOARD_FAB2(SCH_1):PAGE124
  BB15    GND @BASEBOARD_FAB2_LIB.BASEBOARD_FAB2(SCH_1):GND    I16 @BASEBOARD_FAB2_LIB.BASEBOARD_FAB2(SCH_1):PAGE124
  BB18    GND @BASEBOARD_FAB2_LIB.BASEBOARD_FAB2(SCH_1):GND    I16 @BASEBOARD_FAB2_LIB.BASEBOARD_FAB2(SCH_1):PAGE124
  BB22    GND @BASEBOARD_FAB2_LIB.BASEBOARD_FAB2(SCH_1):GND    I16 @BASEBOARD_FAB2_LIB.BASEBOARD_FAB2(SCH_1):PAGE124
  BB44    GND @BASEBOARD_FAB2_LIB.BASEBOARD_FAB2(SCH_1):GND    I16 @BASEBOARD_FAB2_LIB.BASEBOARD_FAB2(SCH_1):PAGE124
  BB59    GND @BASEBOARD_FAB2_LIB.BASEBOARD_FAB2(SCH_1):GND    I16 @BASEBOARD_FAB2_LIB.BASEBOARD_FAB2(SCH_1):PAGE124
  BB66    GND @BASEBOARD_FAB2_LIB.BASEBOARD_FAB2(SCH_1):GND    I16 @BASEBOARD_FAB2_LIB.BASEBOARD_FAB2(SCH_1):PAGE124
  BB68    GND @BASEBOARD_FAB2_LIB.BASEBOARD_FAB2(SCH_1):GND    I16 @BASEBOARD_FAB2_LIB.BASEBOARD_FAB2(SCH_1):PAGE124
  BB70    GND @BASEBOARD_FAB2_LIB.BASEBOARD_FAB2(SCH_1):GND    I16 @BASEBOARD_FAB2_LIB.BASEBOARD_FAB2(SCH_1):PAGE124
  BB72    GND @BASEBOARD_FAB2_LIB.BASEBOARD_FAB2(SCH_1):GND    I16 @BASEBOARD_FAB2_LIB.BASEBOARD_FAB2(SCH_1):PAGE124
  BC69    GND @BASEBOARD_FAB2_LIB.BASEBOARD_FAB2(SCH_1):GND    I16 @BASEBOARD_FAB2_LIB.BASEBOARD_FAB2(SCH_1):PAGE124
  BC71    GND @BASEBOARD_FAB2_LIB.BASEBOARD_FAB2(SCH_1):GND    I16 @BASEBOARD_FAB2_LIB.BASEBOARD_FAB2(SCH_1):PAGE124
  BD24    GND @BASEBOARD_FAB2_LIB.BASEBOARD_FAB2(SCH_1):GND    I16 @BASEBOARD_FAB2_LIB.BASEBOARD_FAB2(SCH_1):PAGE124
  BD27    GND @BASEBOARD_FAB2_LIB.BASEBOARD_FAB2(SCH_1):GND    I16 @BASEBOARD_FAB2_LIB.BASEBOARD_FAB2(SCH_1):PAGE124
  BD31    GND @BASEBOARD_FAB2_LIB.BASEBOARD_FAB2(SCH_1):GND    I16 @BASEBOARD_FAB2_LIB.BASEBOARD_FAB2(SCH_1):PAGE124
  BD35    GND @BASEBOARD_FAB2_LIB.BASEBOARD_FAB2(SCH_1):GND    I16 @BASEBOARD_FAB2_LIB.BASEBOARD_FAB2(SCH_1):PAGE124
   BD5    GND @BASEBOARD_FAB2_LIB.BASEBOARD_FAB2(SCH_1):GND    I16 @BASEBOARD_FAB2_LIB.BASEBOARD_FAB2(SCH_1):PAGE124
  BD50    GND @BASEBOARD_FAB2_LIB.BASEBOARD_FAB2(SCH_1):GND    I16 @BASEBOARD_FAB2_LIB.BASEBOARD_FAB2(SCH_1):PAGE124
  BD54    GND @BASEBOARD_FAB2_LIB.BASEBOARD_FAB2(SCH_1):GND    I16 @BASEBOARD_FAB2_LIB.BASEBOARD_FAB2(SCH_1):PAGE124
  BD68    GND @BASEBOARD_FAB2_LIB.BASEBOARD_FAB2(SCH_1):GND    I16 @BASEBOARD_FAB2_LIB.BASEBOARD_FAB2(SCH_1):PAGE124
  BE29    GND @BASEBOARD_FAB2_LIB.BASEBOARD_FAB2(SCH_1):GND    I16 @BASEBOARD_FAB2_LIB.BASEBOARD_FAB2(SCH_1):PAGE124
  BE33    GND @BASEBOARD_FAB2_LIB.BASEBOARD_FAB2(SCH_1):GND    I16 @BASEBOARD_FAB2_LIB.BASEBOARD_FAB2(SCH_1):PAGE124
  BE37    GND @BASEBOARD_FAB2_LIB.BASEBOARD_FAB2(SCH_1):GND    I16 @BASEBOARD_FAB2_LIB.BASEBOARD_FAB2(SCH_1):PAGE124
  BE56    GND @BASEBOARD_FAB2_LIB.BASEBOARD_FAB2(SCH_1):GND    I16 @BASEBOARD_FAB2_LIB.BASEBOARD_FAB2(SCH_1):PAGE124
  BE59    GND @BASEBOARD_FAB2_LIB.BASEBOARD_FAB2(SCH_1):GND    I16 @BASEBOARD_FAB2_LIB.BASEBOARD_FAB2(SCH_1):PAGE124
  BE63    GND @BASEBOARD_FAB2_LIB.BASEBOARD_FAB2(SCH_1):GND    I16 @BASEBOARD_FAB2_LIB.BASEBOARD_FAB2(SCH_1):PAGE124
  BE66    GND @BASEBOARD_FAB2_LIB.BASEBOARD_FAB2(SCH_1):GND    I16 @BASEBOARD_FAB2_LIB.BASEBOARD_FAB2(SCH_1):PAGE124
  BF13    GND @BASEBOARD_FAB2_LIB.BASEBOARD_FAB2(SCH_1):GND    I16 @BASEBOARD_FAB2_LIB.BASEBOARD_FAB2(SCH_1):PAGE124
  BF17    GND @BASEBOARD_FAB2_LIB.BASEBOARD_FAB2(SCH_1):GND    I16 @BASEBOARD_FAB2_LIB.BASEBOARD_FAB2(SCH_1):PAGE124
  BF54    GND @BASEBOARD_FAB2_LIB.BASEBOARD_FAB2(SCH_1):GND    I16 @BASEBOARD_FAB2_LIB.BASEBOARD_FAB2(SCH_1):PAGE124
  BG44    GND @BASEBOARD_FAB2_LIB.BASEBOARD_FAB2(SCH_1):GND    I16 @BASEBOARD_FAB2_LIB.BASEBOARD_FAB2(SCH_1):PAGE124
  BF20    GND @BASEBOARD_FAB2_LIB.BASEBOARD_FAB2(SCH_1):GND    I16 @BASEBOARD_FAB2_LIB.BASEBOARD_FAB2(SCH_1):PAGE124
  BF24    GND @BASEBOARD_FAB2_LIB.BASEBOARD_FAB2(SCH_1):GND    I16 @BASEBOARD_FAB2_LIB.BASEBOARD_FAB2(SCH_1):PAGE124
  BF27    GND @BASEBOARD_FAB2_LIB.BASEBOARD_FAB2(SCH_1):GND    I16 @BASEBOARD_FAB2_LIB.BASEBOARD_FAB2(SCH_1):PAGE124
  BF38    GND @BASEBOARD_FAB2_LIB.BASEBOARD_FAB2(SCH_1):GND    I16 @BASEBOARD_FAB2_LIB.BASEBOARD_FAB2(SCH_1):PAGE124
  BF42    GND @BASEBOARD_FAB2_LIB.BASEBOARD_FAB2(SCH_1):GND    I16 @BASEBOARD_FAB2_LIB.BASEBOARD_FAB2(SCH_1):PAGE124
   BF5    GND @BASEBOARD_FAB2_LIB.BASEBOARD_FAB2(SCH_1):GND    I16 @BASEBOARD_FAB2_LIB.BASEBOARD_FAB2(SCH_1):PAGE124
  BF50    GND @BASEBOARD_FAB2_LIB.BASEBOARD_FAB2(SCH_1):GND    I16 @BASEBOARD_FAB2_LIB.BASEBOARD_FAB2(SCH_1):PAGE124
  BF58    GND @BASEBOARD_FAB2_LIB.BASEBOARD_FAB2(SCH_1):GND    I16 @BASEBOARD_FAB2_LIB.BASEBOARD_FAB2(SCH_1):PAGE124
  BF61    GND @BASEBOARD_FAB2_LIB.BASEBOARD_FAB2(SCH_1):GND    I16 @BASEBOARD_FAB2_LIB.BASEBOARD_FAB2(SCH_1):PAGE124
  BF65    GND @BASEBOARD_FAB2_LIB.BASEBOARD_FAB2(SCH_1):GND    I16 @BASEBOARD_FAB2_LIB.BASEBOARD_FAB2(SCH_1):PAGE124
  BF68    GND @BASEBOARD_FAB2_LIB.BASEBOARD_FAB2(SCH_1):GND    I16 @BASEBOARD_FAB2_LIB.BASEBOARD_FAB2(SCH_1):PAGE124
   BF9    GND @BASEBOARD_FAB2_LIB.BASEBOARD_FAB2(SCH_1):GND    I16 @BASEBOARD_FAB2_LIB.BASEBOARD_FAB2(SCH_1):PAGE124
  BG33    GND @BASEBOARD_FAB2_LIB.BASEBOARD_FAB2(SCH_1):GND    I16 @BASEBOARD_FAB2_LIB.BASEBOARD_FAB2(SCH_1):PAGE124
  BG48    GND @BASEBOARD_FAB2_LIB.BASEBOARD_FAB2(SCH_1):GND    I16 @BASEBOARD_FAB2_LIB.BASEBOARD_FAB2(SCH_1):PAGE124
  BG59    GND @BASEBOARD_FAB2_LIB.BASEBOARD_FAB2(SCH_1):GND    I16 @BASEBOARD_FAB2_LIB.BASEBOARD_FAB2(SCH_1):PAGE124
  BG63    GND @BASEBOARD_FAB2_LIB.BASEBOARD_FAB2(SCH_1):GND    I16 @BASEBOARD_FAB2_LIB.BASEBOARD_FAB2(SCH_1):PAGE124
  BH27    GND @BASEBOARD_FAB2_LIB.BASEBOARD_FAB2(SCH_1):GND    I16 @BASEBOARD_FAB2_LIB.BASEBOARD_FAB2(SCH_1):PAGE124
  BH38    GND @BASEBOARD_FAB2_LIB.BASEBOARD_FAB2(SCH_1):GND    I16 @BASEBOARD_FAB2_LIB.BASEBOARD_FAB2(SCH_1):PAGE124
  BH42    GND @BASEBOARD_FAB2_LIB.BASEBOARD_FAB2(SCH_1):GND    I16 @BASEBOARD_FAB2_LIB.BASEBOARD_FAB2(SCH_1):PAGE124
  BH46    GND @BASEBOARD_FAB2_LIB.BASEBOARD_FAB2(SCH_1):GND    I16 @BASEBOARD_FAB2_LIB.BASEBOARD_FAB2(SCH_1):PAGE124
  BH54    GND @BASEBOARD_FAB2_LIB.BASEBOARD_FAB2(SCH_1):GND    I16 @BASEBOARD_FAB2_LIB.BASEBOARD_FAB2(SCH_1):PAGE124
   BJ1    GND @BASEBOARD_FAB2_LIB.BASEBOARD_FAB2(SCH_1):GND    I16 @BASEBOARD_FAB2_LIB.BASEBOARD_FAB2(SCH_1):PAGE124
  BJ11    GND @BASEBOARD_FAB2_LIB.BASEBOARD_FAB2(SCH_1):GND    I16 @BASEBOARD_FAB2_LIB.BASEBOARD_FAB2(SCH_1):PAGE124
   BJ5    GND @BASEBOARD_FAB2_LIB.BASEBOARD_FAB2(SCH_1):GND    I16 @BASEBOARD_FAB2_LIB.BASEBOARD_FAB2(SCH_1):PAGE124
   BJ7    GND @BASEBOARD_FAB2_LIB.BASEBOARD_FAB2(SCH_1):GND    I16 @BASEBOARD_FAB2_LIB.BASEBOARD_FAB2(SCH_1):PAGE124
  BJ15    GND @BASEBOARD_FAB2_LIB.BASEBOARD_FAB2(SCH_1):GND    I16 @BASEBOARD_FAB2_LIB.BASEBOARD_FAB2(SCH_1):PAGE124
  BJ18    GND @BASEBOARD_FAB2_LIB.BASEBOARD_FAB2(SCH_1):GND    I16 @BASEBOARD_FAB2_LIB.BASEBOARD_FAB2(SCH_1):PAGE124
  BJ26    GND @BASEBOARD_FAB2_LIB.BASEBOARD_FAB2(SCH_1):GND    I16 @BASEBOARD_FAB2_LIB.BASEBOARD_FAB2(SCH_1):PAGE124
   BJ3    GND @BASEBOARD_FAB2_LIB.BASEBOARD_FAB2(SCH_1):GND    I16 @BASEBOARD_FAB2_LIB.BASEBOARD_FAB2(SCH_1):PAGE124
  BJ33    GND @BASEBOARD_FAB2_LIB.BASEBOARD_FAB2(SCH_1):GND    I16 @BASEBOARD_FAB2_LIB.BASEBOARD_FAB2(SCH_1):PAGE124
  BJ52    GND @BASEBOARD_FAB2_LIB.BASEBOARD_FAB2(SCH_1):GND    I16 @BASEBOARD_FAB2_LIB.BASEBOARD_FAB2(SCH_1):PAGE124
  BJ68    GND @BASEBOARD_FAB2_LIB.BASEBOARD_FAB2(SCH_1):GND    I16 @BASEBOARD_FAB2_LIB.BASEBOARD_FAB2(SCH_1):PAGE124
  BK24    GND @BASEBOARD_FAB2_LIB.BASEBOARD_FAB2(SCH_1):GND    I15 @BASEBOARD_FAB2_LIB.BASEBOARD_FAB2(SCH_1):PAGE124
  BK27    GND @BASEBOARD_FAB2_LIB.BASEBOARD_FAB2(SCH_1):GND    I15 @BASEBOARD_FAB2_LIB.BASEBOARD_FAB2(SCH_1):PAGE124
  BK31    GND @BASEBOARD_FAB2_LIB.BASEBOARD_FAB2(SCH_1):GND    I15 @BASEBOARD_FAB2_LIB.BASEBOARD_FAB2(SCH_1):PAGE124
  BK35    GND @BASEBOARD_FAB2_LIB.BASEBOARD_FAB2(SCH_1):GND    I15 @BASEBOARD_FAB2_LIB.BASEBOARD_FAB2(SCH_1):PAGE124
  BK38    GND @BASEBOARD_FAB2_LIB.BASEBOARD_FAB2(SCH_1):GND    I15 @BASEBOARD_FAB2_LIB.BASEBOARD_FAB2(SCH_1):PAGE124
  BK42    GND @BASEBOARD_FAB2_LIB.BASEBOARD_FAB2(SCH_1):GND    I15 @BASEBOARD_FAB2_LIB.BASEBOARD_FAB2(SCH_1):PAGE124
  BK50    GND @BASEBOARD_FAB2_LIB.BASEBOARD_FAB2(SCH_1):GND    I15 @BASEBOARD_FAB2_LIB.BASEBOARD_FAB2(SCH_1):PAGE124
  BL22    GND @BASEBOARD_FAB2_LIB.BASEBOARD_FAB2(SCH_1):GND    I15 @BASEBOARD_FAB2_LIB.BASEBOARD_FAB2(SCH_1):PAGE124
  BL40    GND @BASEBOARD_FAB2_LIB.BASEBOARD_FAB2(SCH_1):GND    I15 @BASEBOARD_FAB2_LIB.BASEBOARD_FAB2(SCH_1):PAGE124
  BL68    GND @BASEBOARD_FAB2_LIB.BASEBOARD_FAB2(SCH_1):GND    I15 @BASEBOARD_FAB2_LIB.BASEBOARD_FAB2(SCH_1):PAGE124
  BL37    GND @BASEBOARD_FAB2_LIB.BASEBOARD_FAB2(SCH_1):GND    I15 @BASEBOARD_FAB2_LIB.BASEBOARD_FAB2(SCH_1):PAGE124
   BL5    GND @BASEBOARD_FAB2_LIB.BASEBOARD_FAB2(SCH_1):GND    I15 @BASEBOARD_FAB2_LIB.BASEBOARD_FAB2(SCH_1):PAGE124
  BL63    GND @BASEBOARD_FAB2_LIB.BASEBOARD_FAB2(SCH_1):GND    I15 @BASEBOARD_FAB2_LIB.BASEBOARD_FAB2(SCH_1):PAGE124
  BL70    GND @BASEBOARD_FAB2_LIB.BASEBOARD_FAB2(SCH_1):GND    I15 @BASEBOARD_FAB2_LIB.BASEBOARD_FAB2(SCH_1):PAGE124
  BL72    GND @BASEBOARD_FAB2_LIB.BASEBOARD_FAB2(SCH_1):GND    I15 @BASEBOARD_FAB2_LIB.BASEBOARD_FAB2(SCH_1):PAGE124
  BM13    GND @BASEBOARD_FAB2_LIB.BASEBOARD_FAB2(SCH_1):GND    I15 @BASEBOARD_FAB2_LIB.BASEBOARD_FAB2(SCH_1):PAGE124
  BM17    GND @BASEBOARD_FAB2_LIB.BASEBOARD_FAB2(SCH_1):GND    I15 @BASEBOARD_FAB2_LIB.BASEBOARD_FAB2(SCH_1):PAGE124
  BN37    GND @BASEBOARD_FAB2_LIB.BASEBOARD_FAB2(SCH_1):GND    I15 @BASEBOARD_FAB2_LIB.BASEBOARD_FAB2(SCH_1):PAGE124
  BM46    GND @BASEBOARD_FAB2_LIB.BASEBOARD_FAB2(SCH_1):GND    I15 @BASEBOARD_FAB2_LIB.BASEBOARD_FAB2(SCH_1):PAGE124
  BM50    GND @BASEBOARD_FAB2_LIB.BASEBOARD_FAB2(SCH_1):GND    I15 @BASEBOARD_FAB2_LIB.BASEBOARD_FAB2(SCH_1):PAGE124
  BM58    GND @BASEBOARD_FAB2_LIB.BASEBOARD_FAB2(SCH_1):GND    I15 @BASEBOARD_FAB2_LIB.BASEBOARD_FAB2(SCH_1):PAGE124
  BM69    GND @BASEBOARD_FAB2_LIB.BASEBOARD_FAB2(SCH_1):GND    I15 @BASEBOARD_FAB2_LIB.BASEBOARD_FAB2(SCH_1):PAGE124
  BM71    GND @BASEBOARD_FAB2_LIB.BASEBOARD_FAB2(SCH_1):GND    I15 @BASEBOARD_FAB2_LIB.BASEBOARD_FAB2(SCH_1):PAGE124
   BM9    GND @BASEBOARD_FAB2_LIB.BASEBOARD_FAB2(SCH_1):GND    I15 @BASEBOARD_FAB2_LIB.BASEBOARD_FAB2(SCH_1):PAGE124
  BN22    GND @BASEBOARD_FAB2_LIB.BASEBOARD_FAB2(SCH_1):GND    I15 @BASEBOARD_FAB2_LIB.BASEBOARD_FAB2(SCH_1):PAGE124
  BN59    GND @BASEBOARD_FAB2_LIB.BASEBOARD_FAB2(SCH_1):GND    I15 @BASEBOARD_FAB2_LIB.BASEBOARD_FAB2(SCH_1):PAGE124
   BN5    GND @BASEBOARD_FAB2_LIB.BASEBOARD_FAB2(SCH_1):GND    I15 @BASEBOARD_FAB2_LIB.BASEBOARD_FAB2(SCH_1):PAGE124
  BN52    GND @BASEBOARD_FAB2_LIB.BASEBOARD_FAB2(SCH_1):GND    I15 @BASEBOARD_FAB2_LIB.BASEBOARD_FAB2(SCH_1):PAGE124
  BN66    GND @BASEBOARD_FAB2_LIB.BASEBOARD_FAB2(SCH_1):GND    I15 @BASEBOARD_FAB2_LIB.BASEBOARD_FAB2(SCH_1):PAGE124
  BR20    GND @BASEBOARD_FAB2_LIB.BASEBOARD_FAB2(SCH_1):GND    I15 @BASEBOARD_FAB2_LIB.BASEBOARD_FAB2(SCH_1):PAGE124
  BR50    GND @BASEBOARD_FAB2_LIB.BASEBOARD_FAB2(SCH_1):GND    I15 @BASEBOARD_FAB2_LIB.BASEBOARD_FAB2(SCH_1):PAGE124
   BT8    GND @BASEBOARD_FAB2_LIB.BASEBOARD_FAB2(SCH_1):GND    I15 @BASEBOARD_FAB2_LIB.BASEBOARD_FAB2(SCH_1):PAGE124
  BR54    GND @BASEBOARD_FAB2_LIB.BASEBOARD_FAB2(SCH_1):GND    I15 @BASEBOARD_FAB2_LIB.BASEBOARD_FAB2(SCH_1):PAGE124
  BR58    GND @BASEBOARD_FAB2_LIB.BASEBOARD_FAB2(SCH_1):GND    I15 @BASEBOARD_FAB2_LIB.BASEBOARD_FAB2(SCH_1):PAGE124
   BR6    GND @BASEBOARD_FAB2_LIB.BASEBOARD_FAB2(SCH_1):GND    I15 @BASEBOARD_FAB2_LIB.BASEBOARD_FAB2(SCH_1):PAGE124
  BT66    GND @BASEBOARD_FAB2_LIB.BASEBOARD_FAB2(SCH_1):GND    I15 @BASEBOARD_FAB2_LIB.BASEBOARD_FAB2(SCH_1):PAGE124
  BU13    GND @BASEBOARD_FAB2_LIB.BASEBOARD_FAB2(SCH_1):GND    I15 @BASEBOARD_FAB2_LIB.BASEBOARD_FAB2(SCH_1):PAGE124
  BU11    GND @BASEBOARD_FAB2_LIB.BASEBOARD_FAB2(SCH_1):GND    I15 @BASEBOARD_FAB2_LIB.BASEBOARD_FAB2(SCH_1):PAGE124
  BV49    GND @BASEBOARD_FAB2_LIB.BASEBOARD_FAB2(SCH_1):GND    I15 @BASEBOARD_FAB2_LIB.BASEBOARD_FAB2(SCH_1):PAGE124
  BU15    GND @BASEBOARD_FAB2_LIB.BASEBOARD_FAB2(SCH_1):GND    I15 @BASEBOARD_FAB2_LIB.BASEBOARD_FAB2(SCH_1):PAGE124
  BU18    GND @BASEBOARD_FAB2_LIB.BASEBOARD_FAB2(SCH_1):GND    I15 @BASEBOARD_FAB2_LIB.BASEBOARD_FAB2(SCH_1):PAGE124
  BU20    GND @BASEBOARD_FAB2_LIB.BASEBOARD_FAB2(SCH_1):GND    I15 @BASEBOARD_FAB2_LIB.BASEBOARD_FAB2(SCH_1):PAGE124
  BU22    GND @BASEBOARD_FAB2_LIB.BASEBOARD_FAB2(SCH_1):GND    I15 @BASEBOARD_FAB2_LIB.BASEBOARD_FAB2(SCH_1):PAGE124
  BU24    GND @BASEBOARD_FAB2_LIB.BASEBOARD_FAB2(SCH_1):GND    I15 @BASEBOARD_FAB2_LIB.BASEBOARD_FAB2(SCH_1):PAGE124
  BU26    GND @BASEBOARD_FAB2_LIB.BASEBOARD_FAB2(SCH_1):GND    I15 @BASEBOARD_FAB2_LIB.BASEBOARD_FAB2(SCH_1):PAGE124
  BU28    GND @BASEBOARD_FAB2_LIB.BASEBOARD_FAB2(SCH_1):GND    I15 @BASEBOARD_FAB2_LIB.BASEBOARD_FAB2(SCH_1):PAGE124
  BU30    GND @BASEBOARD_FAB2_LIB.BASEBOARD_FAB2(SCH_1):GND    I15 @BASEBOARD_FAB2_LIB.BASEBOARD_FAB2(SCH_1):PAGE124
  BU32    GND @BASEBOARD_FAB2_LIB.BASEBOARD_FAB2(SCH_1):GND    I15 @BASEBOARD_FAB2_LIB.BASEBOARD_FAB2(SCH_1):PAGE124
  BU34    GND @BASEBOARD_FAB2_LIB.BASEBOARD_FAB2(SCH_1):GND    I15 @BASEBOARD_FAB2_LIB.BASEBOARD_FAB2(SCH_1):PAGE124
  BU37    GND @BASEBOARD_FAB2_LIB.BASEBOARD_FAB2(SCH_1):GND    I15 @BASEBOARD_FAB2_LIB.BASEBOARD_FAB2(SCH_1):PAGE124
  BU39    GND @BASEBOARD_FAB2_LIB.BASEBOARD_FAB2(SCH_1):GND    I15 @BASEBOARD_FAB2_LIB.BASEBOARD_FAB2(SCH_1):PAGE124
  BU41    GND @BASEBOARD_FAB2_LIB.BASEBOARD_FAB2(SCH_1):GND    I15 @BASEBOARD_FAB2_LIB.BASEBOARD_FAB2(SCH_1):PAGE124
  BU43    GND @BASEBOARD_FAB2_LIB.BASEBOARD_FAB2(SCH_1):GND    I15 @BASEBOARD_FAB2_LIB.BASEBOARD_FAB2(SCH_1):PAGE124
  BU45    GND @BASEBOARD_FAB2_LIB.BASEBOARD_FAB2(SCH_1):GND    I15 @BASEBOARD_FAB2_LIB.BASEBOARD_FAB2(SCH_1):PAGE124
  BU48    GND @BASEBOARD_FAB2_LIB.BASEBOARD_FAB2(SCH_1):GND    I15 @BASEBOARD_FAB2_LIB.BASEBOARD_FAB2(SCH_1):PAGE124
  BU50    GND @BASEBOARD_FAB2_LIB.BASEBOARD_FAB2(SCH_1):GND    I15 @BASEBOARD_FAB2_LIB.BASEBOARD_FAB2(SCH_1):PAGE124
  BU52    GND @BASEBOARD_FAB2_LIB.BASEBOARD_FAB2(SCH_1):GND    I15 @BASEBOARD_FAB2_LIB.BASEBOARD_FAB2(SCH_1):PAGE124
  BU54    GND @BASEBOARD_FAB2_LIB.BASEBOARD_FAB2(SCH_1):GND    I15 @BASEBOARD_FAB2_LIB.BASEBOARD_FAB2(SCH_1):PAGE124
  BU57    GND @BASEBOARD_FAB2_LIB.BASEBOARD_FAB2(SCH_1):GND    I15 @BASEBOARD_FAB2_LIB.BASEBOARD_FAB2(SCH_1):PAGE124
  BU59    GND @BASEBOARD_FAB2_LIB.BASEBOARD_FAB2(SCH_1):GND    I15 @BASEBOARD_FAB2_LIB.BASEBOARD_FAB2(SCH_1):PAGE124
  BU61    GND @BASEBOARD_FAB2_LIB.BASEBOARD_FAB2(SCH_1):GND    I15 @BASEBOARD_FAB2_LIB.BASEBOARD_FAB2(SCH_1):PAGE124
  BU63    GND @BASEBOARD_FAB2_LIB.BASEBOARD_FAB2(SCH_1):GND    I15 @BASEBOARD_FAB2_LIB.BASEBOARD_FAB2(SCH_1):PAGE124
   BU9    GND @BASEBOARD_FAB2_LIB.BASEBOARD_FAB2(SCH_1):GND    I15 @BASEBOARD_FAB2_LIB.BASEBOARD_FAB2(SCH_1):PAGE124
  BV40    GND @BASEBOARD_FAB2_LIB.BASEBOARD_FAB2(SCH_1):GND    I15 @BASEBOARD_FAB2_LIB.BASEBOARD_FAB2(SCH_1):PAGE124
  BW15    GND @BASEBOARD_FAB2_LIB.BASEBOARD_FAB2(SCH_1):GND    I15 @BASEBOARD_FAB2_LIB.BASEBOARD_FAB2(SCH_1):PAGE124
  BW18    GND @BASEBOARD_FAB2_LIB.BASEBOARD_FAB2(SCH_1):GND    I15 @BASEBOARD_FAB2_LIB.BASEBOARD_FAB2(SCH_1):PAGE124
  BW26    GND @BASEBOARD_FAB2_LIB.BASEBOARD_FAB2(SCH_1):GND    I15 @BASEBOARD_FAB2_LIB.BASEBOARD_FAB2(SCH_1):PAGE124
  BW52    GND @BASEBOARD_FAB2_LIB.BASEBOARD_FAB2(SCH_1):GND    I15 @BASEBOARD_FAB2_LIB.BASEBOARD_FAB2(SCH_1):PAGE124
  BY40    GND @BASEBOARD_FAB2_LIB.BASEBOARD_FAB2(SCH_1):GND    I15 @BASEBOARD_FAB2_LIB.BASEBOARD_FAB2(SCH_1):PAGE124
  BY49    GND @BASEBOARD_FAB2_LIB.BASEBOARD_FAB2(SCH_1):GND    I15 @BASEBOARD_FAB2_LIB.BASEBOARD_FAB2(SCH_1):PAGE124
  CA15    GND @BASEBOARD_FAB2_LIB.BASEBOARD_FAB2(SCH_1):GND    I15 @BASEBOARD_FAB2_LIB.BASEBOARD_FAB2(SCH_1):PAGE124
  CA18    GND @BASEBOARD_FAB2_LIB.BASEBOARD_FAB2(SCH_1):GND    I15 @BASEBOARD_FAB2_LIB.BASEBOARD_FAB2(SCH_1):PAGE124
  CA26    GND @BASEBOARD_FAB2_LIB.BASEBOARD_FAB2(SCH_1):GND    I15 @BASEBOARD_FAB2_LIB.BASEBOARD_FAB2(SCH_1):PAGE124
  CA50    GND @BASEBOARD_FAB2_LIB.BASEBOARD_FAB2(SCH_1):GND    I15 @BASEBOARD_FAB2_LIB.BASEBOARD_FAB2(SCH_1):PAGE124
  CA52    GND @BASEBOARD_FAB2_LIB.BASEBOARD_FAB2(SCH_1):GND    I15 @BASEBOARD_FAB2_LIB.BASEBOARD_FAB2(SCH_1):PAGE124

U7D1 74CBTLV1G125_SMLF-IC,C88177-00A
     4 XDP_CPU_PWR_DEBUG_N @BASEBOARD_FAB2_LIB.BASEBOARD_FAB2(SCH_1):XDP_CPU_PWR_DEBUG_N   I142 @BASEBOARD_FAB2_LIB.BASEBOARD_FAB2(SCH_1):PAGE118
     1 PWRGD_PVCCIO_CPU0 @BASEBOARD_FAB2_LIB.BASEBOARD_FAB2(SCH_1):PWRGD_PVCCIO_CPU0   I142 @BASEBOARD_FAB2_LIB.BASEBOARD_FAB2(SCH_1):PAGE118
     2 XDP_PCH_PWR_DEBUG_N @BASEBOARD_FAB2_LIB.BASEBOARD_FAB2(SCH_1):XDP_PCH_PWR_DEBUG_N   I142 @BASEBOARD_FAB2_LIB.BASEBOARD_FAB2(SCH_1):PAGE118

U7D2 GTL2014_SM-IC,D66151-001
    13 FM_CPU_MSMI_LVT3_R_N @BASEBOARD_FAB2_LIB.BASEBOARD_FAB2(SCH_1):FM_CPU_MSMI_LVT3_R_N    I32 @BASEBOARD_FAB2_LIB.BASEBOARD_FAB2(SCH_1):PAGE92
    12 FM_CPU0_FIVR_FAULT_R_LVT3 @BASEBOARD_FAB2_LIB.BASEBOARD_FAB2(SCH_1):FM_CPU0_FIVR_FAULT_R_LVT3    I32 @BASEBOARD_FAB2_LIB.BASEBOARD_FAB2(SCH_1):PAGE92
    10 FM_CPU_ERR2_LVT3_R_N @BASEBOARD_FAB2_LIB.BASEBOARD_FAB2(SCH_1):FM_CPU_ERR2_LVT3_R_N    I32 @BASEBOARD_FAB2_LIB.BASEBOARD_FAB2(SCH_1):PAGE92
     9 FM_CPU0_THERMTRIP_LVT3_R_N @BASEBOARD_FAB2_LIB.BASEBOARD_FAB2(SCH_1):FM_CPU0_THERMTRIP_LVT3_R_N    I32 @BASEBOARD_FAB2_LIB.BASEBOARD_FAB2(SCH_1):PAGE92
     2 H_CPU_MSMI_G_N @BASEBOARD_FAB2_LIB.BASEBOARD_FAB2(SCH_1):H_CPU_MSMI_G_N    I32 @BASEBOARD_FAB2_LIB.BASEBOARD_FAB2(SCH_1):PAGE92
     3 H_CPU0_FIVR_FAULT_G @BASEBOARD_FAB2_LIB.BASEBOARD_FAB2(SCH_1):H_CPU0_FIVR_FAULT_G    I32 @BASEBOARD_FAB2_LIB.BASEBOARD_FAB2(SCH_1):PAGE92
     5 H_CPU_ERR2_GTL_N @BASEBOARD_FAB2_LIB.BASEBOARD_FAB2(SCH_1):H_CPU_ERR2_GTL_N    I32 @BASEBOARD_FAB2_LIB.BASEBOARD_FAB2(SCH_1):PAGE92
     6 H_CPU0_THERMTRIP_G_N @BASEBOARD_FAB2_LIB.BASEBOARD_FAB2(SCH_1):H_CPU0_THERMTRIP_G_N    I32 @BASEBOARD_FAB2_LIB.BASEBOARD_FAB2(SCH_1):PAGE92
     1 PD_GTL2104_DIR_0 @BASEBOARD_FAB2_LIB.BASEBOARD_FAB2(SCH_1):PD_GTL2104_DIR_0    I32 @BASEBOARD_FAB2_LIB.BASEBOARD_FAB2(SCH_1):PAGE92
    11    GND @BASEBOARD_FAB2_LIB.BASEBOARD_FAB2(SCH_1):GND    I32 @BASEBOARD_FAB2_LIB.BASEBOARD_FAB2(SCH_1):PAGE92
     8    GND @BASEBOARD_FAB2_LIB.BASEBOARD_FAB2(SCH_1):GND    I32 @BASEBOARD_FAB2_LIB.BASEBOARD_FAB2(SCH_1):PAGE92
     7    GND @BASEBOARD_FAB2_LIB.BASEBOARD_FAB2(SCH_1):GND    I32 @BASEBOARD_FAB2_LIB.BASEBOARD_FAB2(SCH_1):PAGE92
    14   P3V3 @BASEBOARD_FAB2_LIB.BASEBOARD_FAB2(SCH_1):P3V3    I32 @BASEBOARD_FAB2_LIB.BASEBOARD_FAB2(SCH_1):PAGE92
     4 P0V7_GTL2104_VREF_0 @BASEBOARD_FAB2_LIB.BASEBOARD_FAB2(SCH_1):P0V7_GTL2104_VREF_0    I32 @BASEBOARD_FAB2_LIB.BASEBOARD_FAB2(SCH_1):PAGE92

U7D3 ADM1085_SMT-IC,H46130-001
     5 A_ADM1085_CEXT @BASEBOARD_FAB2_LIB.BASEBOARD_FAB2(SCH_1):A_ADM1085_CEXT    I70 @BASEBOARD_FAB2_LIB.BASEBOARD_FAB2(SCH_1):PAGE196
     1 PWRGD_P3V3_STBY @BASEBOARD_FAB2_LIB.BASEBOARD_FAB2(SCH_1):PWRGD_P3V3_STBY    I70 @BASEBOARD_FAB2_LIB.BASEBOARD_FAB2(SCH_1):PAGE196
     4 PWRGD_DSW_PWROK @BASEBOARD_FAB2_LIB.BASEBOARD_FAB2(SCH_1):PWRGD_DSW_PWROK    I70 @BASEBOARD_FAB2_LIB.BASEBOARD_FAB2(SCH_1):PAGE196
     2    GND @BASEBOARD_FAB2_LIB.BASEBOARD_FAB2(SCH_1):GND    I70 @BASEBOARD_FAB2_LIB.BASEBOARD_FAB2(SCH_1):PAGE196
     6 P3V3_STBY @BASEBOARD_FAB2_LIB.BASEBOARD_FAB2(SCH_1):P3V3_STBY    I70 @BASEBOARD_FAB2_LIB.BASEBOARD_FAB2(SCH_1):PAGE196
     3 VSENSE_P12V_ADM1085 @BASEBOARD_FAB2_LIB.BASEBOARD_FAB2(SCH_1):VSENSE_P12V_ADM1085    I70 @BASEBOARD_FAB2_LIB.BASEBOARD_FAB2(SCH_1):PAGE196

U7E1 PCA9617_SSOP-IC,G81764-001-GNDA
     5 TP_SMB_DDR_DEF_EN @BASEBOARD_FAB2_LIB.BASEBOARD_FAB2(SCH_1):TP_SMB_DDR_DEF_EN    I61 @BASEBOARD_FAB2_LIB.BASEBOARD_FAB2(SCH_1):PAGE99
     2 SMB_DDR_DEF_SCL_G @BASEBOARD_FAB2_LIB.BASEBOARD_FAB2(SCH_1):SMB_DDR_DEF_SCL_G    I61 @BASEBOARD_FAB2_LIB.BASEBOARD_FAB2(SCH_1):PAGE99
     7 SMB_DDR_DEF_VPP_SCL_R @BASEBOARD_FAB2_LIB.BASEBOARD_FAB2(SCH_1):SMB_DDR_DEF_VPP_SCL_R    I61 @BASEBOARD_FAB2_LIB.BASEBOARD_FAB2(SCH_1):PAGE99
     3 SMB_DDR_DEF_SDA_G @BASEBOARD_FAB2_LIB.BASEBOARD_FAB2(SCH_1):SMB_DDR_DEF_SDA_G    I61 @BASEBOARD_FAB2_LIB.BASEBOARD_FAB2(SCH_1):PAGE99
     6 SMB_DDR_DEF_VPP_SDA_R @BASEBOARD_FAB2_LIB.BASEBOARD_FAB2(SCH_1):SMB_DDR_DEF_VPP_SDA_R    I61 @BASEBOARD_FAB2_LIB.BASEBOARD_FAB2(SCH_1):PAGE99
     1 PVCCIO_CPU0 @BASEBOARD_FAB2_LIB.BASEBOARD_FAB2(SCH_1):PVCCIO_CPU0    I61 @BASEBOARD_FAB2_LIB.BASEBOARD_FAB2(SCH_1):PAGE99
     8 PVPP_DEF @BASEBOARD_FAB2_LIB.BASEBOARD_FAB2(SCH_1):PVPP_DEF    I61 @BASEBOARD_FAB2_LIB.BASEBOARD_FAB2(SCH_1):PAGE99

U7E2 TTL1G08_SOTLF-NC7SZ08,IC,D1032B
     4 IRQ_CPU0_PROCHOT_G_N @BASEBOARD_FAB2_LIB.BASEBOARD_FAB2(SCH_1):IRQ_CPU0_PROCHOT_G_N   I117 @BASEBOARD_FAB2_LIB.BASEBOARD_FAB2(SCH_1):PAGE95
     1 FM_PVCCIN_CPU0_PWR_IN_ALERT_N @BASEBOARD_FAB2_LIB.BASEBOARD_FAB2(SCH_1):FM_PVCCIN_CPU0_PWR_IN_ALERT_N   I117 @BASEBOARD_FAB2_LIB.BASEBOARD_FAB2(SCH_1):PAGE95
     2 IRQ_PVCCIN_CPU0_VRHOT_LVC3_N @BASEBOARD_FAB2_LIB.BASEBOARD_FAB2(SCH_1):IRQ_PVCCIN_CPU0_VRHOT_LVC3_N   I117 @BASEBOARD_FAB2_LIB.BASEBOARD_FAB2(SCH_1):PAGE95

U7E3 TTL1G08_SOTLF-NC7SZ08,IC,D1032B
     4 IRQ_CPU1_PROCHOT_G_N @BASEBOARD_FAB2_LIB.BASEBOARD_FAB2(SCH_1):IRQ_CPU1_PROCHOT_G_N   I118 @BASEBOARD_FAB2_LIB.BASEBOARD_FAB2(SCH_1):PAGE95
     1 FM_PVCCIN_CPU1_PWR_IN_ALERT_N @BASEBOARD_FAB2_LIB.BASEBOARD_FAB2(SCH_1):FM_PVCCIN_CPU1_PWR_IN_ALERT_N   I118 @BASEBOARD_FAB2_LIB.BASEBOARD_FAB2(SCH_1):PAGE95
     2 IRQ_PVCCIN_CPU1_VRHOT_LVC3_N @BASEBOARD_FAB2_LIB.BASEBOARD_FAB2(SCH_1):IRQ_PVCCIN_CPU1_VRHOT_LVC3_N   I118 @BASEBOARD_FAB2_LIB.BASEBOARD_FAB2(SCH_1):PAGE95

U7F1 W25Q256_XSOI-IC,H25002-001
     9 PU_BIOS_SPI_WP0_N @BASEBOARD_FAB2_LIB.BASEBOARD_FAB2(SCH_1):PU_BIOS_SPI_WP0_N   I146 @BASEBOARD_FAB2_LIB.BASEBOARD_FAB2(SCH_1):PAGE153
    14 TP_SPI_0_0 @BASEBOARD_FAB2_LIB.BASEBOARD_FAB2(SCH_1):TP_SPI_0_0   I146 @BASEBOARD_FAB2_LIB.BASEBOARD_FAB2(SCH_1):PAGE153
    13 TP_SPI_0_1 @BASEBOARD_FAB2_LIB.BASEBOARD_FAB2(SCH_1):TP_SPI_0_1   I146 @BASEBOARD_FAB2_LIB.BASEBOARD_FAB2(SCH_1):PAGE153
    12 TP_SPI_0_2 @BASEBOARD_FAB2_LIB.BASEBOARD_FAB2(SCH_1):TP_SPI_0_2   I146 @BASEBOARD_FAB2_LIB.BASEBOARD_FAB2(SCH_1):PAGE153
    11 TP_SPI_0_3 @BASEBOARD_FAB2_LIB.BASEBOARD_FAB2(SCH_1):TP_SPI_0_3   I146 @BASEBOARD_FAB2_LIB.BASEBOARD_FAB2(SCH_1):PAGE153
     6 TP_SPI_0_4 @BASEBOARD_FAB2_LIB.BASEBOARD_FAB2(SCH_1):TP_SPI_0_4   I146 @BASEBOARD_FAB2_LIB.BASEBOARD_FAB2(SCH_1):PAGE153
     5 TP_SPI_0_5 @BASEBOARD_FAB2_LIB.BASEBOARD_FAB2(SCH_1):TP_SPI_0_5   I146 @BASEBOARD_FAB2_LIB.BASEBOARD_FAB2(SCH_1):PAGE153
     4 TP_SPI_0_6 @BASEBOARD_FAB2_LIB.BASEBOARD_FAB2(SCH_1):TP_SPI_0_6   I146 @BASEBOARD_FAB2_LIB.BASEBOARD_FAB2(SCH_1):PAGE153
    10    GND @BASEBOARD_FAB2_LIB.BASEBOARD_FAB2(SCH_1):GND   I146 @BASEBOARD_FAB2_LIB.BASEBOARD_FAB2(SCH_1):PAGE153
     8 SPI_MISO_R0 @BASEBOARD_FAB2_LIB.BASEBOARD_FAB2(SCH_1):SPI_MISO_R0   I146 @BASEBOARD_FAB2_LIB.BASEBOARD_FAB2(SCH_1):PAGE153
    16 SPI_CLK_R0 @BASEBOARD_FAB2_LIB.BASEBOARD_FAB2(SCH_1):SPI_CLK_R0   I146 @BASEBOARD_FAB2_LIB.BASEBOARD_FAB2(SCH_1):PAGE153
     2 P3V3_STBY @BASEBOARD_FAB2_LIB.BASEBOARD_FAB2(SCH_1):P3V3_STBY   I146 @BASEBOARD_FAB2_LIB.BASEBOARD_FAB2(SCH_1):PAGE153
     7 SPI_CS0_PRIMARY_R_N @BASEBOARD_FAB2_LIB.BASEBOARD_FAB2(SCH_1):SPI_CS0_PRIMARY_R_N   I146 @BASEBOARD_FAB2_LIB.BASEBOARD_FAB2(SCH_1):PAGE153
    15 SPI_SWITCH_MOSI_R0 @BASEBOARD_FAB2_LIB.BASEBOARD_FAB2(SCH_1):SPI_SWITCH_MOSI_R0   I146 @BASEBOARD_FAB2_LIB.BASEBOARD_FAB2(SCH_1):PAGE153
     3 PU_SPI0_RST @BASEBOARD_FAB2_LIB.BASEBOARD_FAB2(SCH_1):PU_SPI0_RST   I146 @BASEBOARD_FAB2_LIB.BASEBOARD_FAB2(SCH_1):PAGE153
     1 PU_BIOS_SPI_HOLD0_N @BASEBOARD_FAB2_LIB.BASEBOARD_FAB2(SCH_1):PU_BIOS_SPI_HOLD0_N   I146 @BASEBOARD_FAB2_LIB.BASEBOARD_FAB2(SCH_1):PAGE153

U7W1 PI5A3157BC6E-GP_DISCRET-GC2-PIA
     1 PECI_BMC @BASEBOARD_FAB2_LIB.BASEBOARD_FAB2(SCH_1):PECI_BMC    I34 @BASEBOARD_FAB2_LIB.BASEBOARD_FAB2(SCH_1):PAGE166
     2    GND @BASEBOARD_FAB2_LIB.BASEBOARD_FAB2(SCH_1):GND    I34 @BASEBOARD_FAB2_LIB.BASEBOARD_FAB2(SCH_1):PAGE166
     3 PECI_PCH @BASEBOARD_FAB2_LIB.BASEBOARD_FAB2(SCH_1):PECI_PCH    I34 @BASEBOARD_FAB2_LIB.BASEBOARD_FAB2(SCH_1):PAGE166
     4 PECI_CPU_G @BASEBOARD_FAB2_LIB.BASEBOARD_FAB2(SCH_1):PECI_CPU_G    I34 @BASEBOARD_FAB2_LIB.BASEBOARD_FAB2(SCH_1):PAGE166
     5 P3V3_STBY @BASEBOARD_FAB2_LIB.BASEBOARD_FAB2(SCH_1):P3V3_STBY    I34 @BASEBOARD_FAB2_LIB.BASEBOARD_FAB2(SCH_1):PAGE166
     6 PECI_SEL @BASEBOARD_FAB2_LIB.BASEBOARD_FAB2(SCH_1):PECI_SEL    I34 @BASEBOARD_FAB2_LIB.BASEBOARD_FAB2(SCH_1):PAGE166

U8D2 TTL1G07_A_SOP-74LVC1G07,IC,C88B
     2 PWRGD_DSW_PWROK @BASEBOARD_FAB2_LIB.BASEBOARD_FAB2(SCH_1):PWRGD_DSW_PWROK   I374 @BASEBOARD_FAB2_LIB.BASEBOARD_FAB2(SCH_1):PAGE157
     4 RST_BMC_SRST_R2_N @BASEBOARD_FAB2_LIB.BASEBOARD_FAB2(SCH_1):RST_BMC_SRST_R2_N   I374 @BASEBOARD_FAB2_LIB.BASEBOARD_FAB2(SCH_1):PAGE157

U8D3 TTL1G07_A_SOP-74LVC1G07,IC,C88B
     2 IRQ_SML1_PMBUS_ALERT_BUF_N @BASEBOARD_FAB2_LIB.BASEBOARD_FAB2(SCH_1):IRQ_SML1_PMBUS_ALERT_BUF_N     I4 @BASEBOARD_FAB2_LIB.BASEBOARD_FAB2(SCH_1):PAGE170
     4 IRQ_FORCE_NM_THROTTLE_R_N @BASEBOARD_FAB2_LIB.BASEBOARD_FAB2(SCH_1):IRQ_FORCE_NM_THROTTLE_R_N     I4 @BASEBOARD_FAB2_LIB.BASEBOARD_FAB2(SCH_1):PAGE170

U8D4 AT24C64_SOICLF-IC,C47049-001-GA
     1    GND @BASEBOARD_FAB2_LIB.BASEBOARD_FAB2(SCH_1):GND    I49 @BASEBOARD_FAB2_LIB.BASEBOARD_FAB2(SCH_1):PAGE167
     2    GND @BASEBOARD_FAB2_LIB.BASEBOARD_FAB2(SCH_1):GND    I49 @BASEBOARD_FAB2_LIB.BASEBOARD_FAB2(SCH_1):PAGE167
     3 PU_AT24C64_A2 @BASEBOARD_FAB2_LIB.BASEBOARD_FAB2(SCH_1):PU_AT24C64_A2    I49 @BASEBOARD_FAB2_LIB.BASEBOARD_FAB2(SCH_1):PAGE167
     6 SMB_SENSOR_STBY_LVC3_SCL_R2 @BASEBOARD_FAB2_LIB.BASEBOARD_FAB2(SCH_1):SMB_SENSOR_STBY_LVC3_SCL_R2    I49 @BASEBOARD_FAB2_LIB.BASEBOARD_FAB2(SCH_1):PAGE167
     7 PD_FRU_WP @BASEBOARD_FAB2_LIB.BASEBOARD_FAB2(SCH_1):PD_FRU_WP    I49 @BASEBOARD_FAB2_LIB.BASEBOARD_FAB2(SCH_1):PAGE167
     5 SMB_SENSOR_STBY_LVC3_SDA_R2 @BASEBOARD_FAB2_LIB.BASEBOARD_FAB2(SCH_1):SMB_SENSOR_STBY_LVC3_SDA_R2    I49 @BASEBOARD_FAB2_LIB.BASEBOARD_FAB2(SCH_1):PAGE167

U8D5 TTL1G126_A_SOT-74HC1G126,IC,A7B
     1 FM_PMBUS_ALERT_BUF_EN @BASEBOARD_FAB2_LIB.BASEBOARD_FAB2(SCH_1):FM_PMBUS_ALERT_BUF_EN    I38 @BASEBOARD_FAB2_LIB.BASEBOARD_FAB2(SCH_1):PAGE170
     2 IRQ_SML1_PMBUS_ALERT_N @BASEBOARD_FAB2_LIB.BASEBOARD_FAB2(SCH_1):IRQ_SML1_PMBUS_ALERT_N    I38 @BASEBOARD_FAB2_LIB.BASEBOARD_FAB2(SCH_1):PAGE170
     4 IRQ_SML1_PMBUS_ALERT_BUF_N @BASEBOARD_FAB2_LIB.BASEBOARD_FAB2(SCH_1):IRQ_SML1_PMBUS_ALERT_BUF_N    I38 @BASEBOARD_FAB2_LIB.BASEBOARD_FAB2(SCH_1):PAGE170

U8D7 LCMXO2_A_256BGA-IC,H63395-001
    P4 FM_CPU1_RC_EN @BASEBOARD_FAB2_LIB.BASEBOARD_FAB2(SCH_1):FM_CPU1_RC_EN   I179 @BASEBOARD_FAB2_LIB.BASEBOARD_FAB2(SCH_1):PAGE190
    T4 PWRGD_PVSA_CPU1 @BASEBOARD_FAB2_LIB.BASEBOARD_FAB2(SCH_1):PWRGD_PVSA_CPU1   I179 @BASEBOARD_FAB2_LIB.BASEBOARD_FAB2(SCH_1):PAGE190
    T2 FM_ADR_MODE_SEL @BASEBOARD_FAB2_LIB.BASEBOARD_FAB2(SCH_1):FM_ADR_MODE_SEL   I179 @BASEBOARD_FAB2_LIB.BASEBOARD_FAB2(SCH_1):PAGE190
    R3 FM_CPU0_RC_EN @BASEBOARD_FAB2_LIB.BASEBOARD_FAB2(SCH_1):FM_CPU0_RC_EN   I179 @BASEBOARD_FAB2_LIB.BASEBOARD_FAB2(SCH_1):PAGE190
    R5 TP_CPLD1_PB5A_CSSPIN @BASEBOARD_FAB2_LIB.BASEBOARD_FAB2(SCH_1):TP_CPLD1_PB5A_CSSPIN   I179 @BASEBOARD_FAB2_LIB.BASEBOARD_FAB2(SCH_1):PAGE190
    P5 PWRGD_PVCCMCP_CPU0 @BASEBOARD_FAB2_LIB.BASEBOARD_FAB2(SCH_1):PWRGD_PVCCMCP_CPU0   I179 @BASEBOARD_FAB2_LIB.BASEBOARD_FAB2(SCH_1):PAGE190
    T5 PWRGD_PVCCIOMCP_CPU1 @BASEBOARD_FAB2_LIB.BASEBOARD_FAB2(SCH_1):PWRGD_PVCCIOMCP_CPU1   I179 @BASEBOARD_FAB2_LIB.BASEBOARD_FAB2(SCH_1):PAGE190
    R6 RST_PCIE_M2_DEV_N @BASEBOARD_FAB2_LIB.BASEBOARD_FAB2(SCH_1):RST_PCIE_M2_DEV_N   I179 @BASEBOARD_FAB2_LIB.BASEBOARD_FAB2(SCH_1):PAGE190
    T3 FM_DIS_ADR_DLY @BASEBOARD_FAB2_LIB.BASEBOARD_FAB2(SCH_1):FM_DIS_ADR_DLY   I179 @BASEBOARD_FAB2_LIB.BASEBOARD_FAB2(SCH_1):PAGE190
    R4 FM_BMC_CPLD_MP_RST_N @BASEBOARD_FAB2_LIB.BASEBOARD_FAB2(SCH_1):FM_BMC_CPLD_MP_RST_N   I179 @BASEBOARD_FAB2_LIB.BASEBOARD_FAB2(SCH_1):PAGE190
    P6 TP_CPLD1_PB8A_MCLK_CCLK @BASEBOARD_FAB2_LIB.BASEBOARD_FAB2(SCH_1):TP_CPLD1_PB8A_MCLK_CCLK   I179 @BASEBOARD_FAB2_LIB.BASEBOARD_FAB2(SCH_1):PAGE190
    T6 TP_CPLD1_PB8B_SO_SPISO @BASEBOARD_FAB2_LIB.BASEBOARD_FAB2(SCH_1):TP_CPLD1_PB8B_SO_SPISO   I179 @BASEBOARD_FAB2_LIB.BASEBOARD_FAB2(SCH_1):PAGE190
    N6 PWRGD_PVCCIOMCP_CPU0 @BASEBOARD_FAB2_LIB.BASEBOARD_FAB2(SCH_1):PWRGD_PVCCIOMCP_CPU0   I179 @BASEBOARD_FAB2_LIB.BASEBOARD_FAB2(SCH_1):PAGE190
    L7 FM_OC0_USB_N @BASEBOARD_FAB2_LIB.BASEBOARD_FAB2(SCH_1):FM_OC0_USB_N   I179 @BASEBOARD_FAB2_LIB.BASEBOARD_FAB2(SCH_1):PAGE190
    R7 PWRGD_PVTT_CPU1 @BASEBOARD_FAB2_LIB.BASEBOARD_FAB2(SCH_1):PWRGD_PVTT_CPU1   I179 @BASEBOARD_FAB2_LIB.BASEBOARD_FAB2(SCH_1):PAGE190
    P7 FM_PVCCIOMCP_CPU1_EN @BASEBOARD_FAB2_LIB.BASEBOARD_FAB2(SCH_1):FM_PVCCIOMCP_CPU1_EN   I179 @BASEBOARD_FAB2_LIB.BASEBOARD_FAB2(SCH_1):PAGE190
    M7 FM_PVCCIO_CPU0_EN @BASEBOARD_FAB2_LIB.BASEBOARD_FAB2(SCH_1):FM_PVCCIO_CPU0_EN   I179 @BASEBOARD_FAB2_LIB.BASEBOARD_FAB2(SCH_1):PAGE190
    N7 PWRGD_PVPP_ABC @BASEBOARD_FAB2_LIB.BASEBOARD_FAB2(SCH_1):PWRGD_PVPP_ABC   I179 @BASEBOARD_FAB2_LIB.BASEBOARD_FAB2(SCH_1):PAGE190
    T7 FM_PVCCIO_CPU1_EN @BASEBOARD_FAB2_LIB.BASEBOARD_FAB2(SCH_1):FM_PVCCIO_CPU1_EN   I179 @BASEBOARD_FAB2_LIB.BASEBOARD_FAB2(SCH_1):PAGE190
    R8 FM_CPLD_USB_P0_EN_N @BASEBOARD_FAB2_LIB.BASEBOARD_FAB2(SCH_1):FM_CPLD_USB_P0_EN_N   I179 @BASEBOARD_FAB2_LIB.BASEBOARD_FAB2(SCH_1):PAGE190
    M6 PWRGD_PVPP_DEF @BASEBOARD_FAB2_LIB.BASEBOARD_FAB2(SCH_1):PWRGD_PVPP_DEF   I179 @BASEBOARD_FAB2_LIB.BASEBOARD_FAB2(SCH_1):PAGE190
    L8 PWRGD_PVCCIO_CPU0 @BASEBOARD_FAB2_LIB.BASEBOARD_FAB2(SCH_1):PWRGD_PVCCIO_CPU0   I179 @BASEBOARD_FAB2_LIB.BASEBOARD_FAB2(SCH_1):PAGE190
    P8 PWRGD_PVNN_P1V05_PCH @BASEBOARD_FAB2_LIB.BASEBOARD_FAB2(SCH_1):PWRGD_PVNN_P1V05_PCH   I179 @BASEBOARD_FAB2_LIB.BASEBOARD_FAB2(SCH_1):PAGE190
    T8 FM_CPLD_DBG_PWR_EN_N @BASEBOARD_FAB2_LIB.BASEBOARD_FAB2(SCH_1):FM_CPLD_DBG_PWR_EN_N   I179 @BASEBOARD_FAB2_LIB.BASEBOARD_FAB2(SCH_1):PAGE190
    N8 FM_156M_CPU1_BRD_OSC_EN @BASEBOARD_FAB2_LIB.BASEBOARD_FAB2(SCH_1):FM_156M_CPU1_BRD_OSC_EN   I179 @BASEBOARD_FAB2_LIB.BASEBOARD_FAB2(SCH_1):PAGE190
    L9 FM_IE_DISABLE_N @BASEBOARD_FAB2_LIB.BASEBOARD_FAB2(SCH_1):FM_IE_DISABLE_N   I179 @BASEBOARD_FAB2_LIB.BASEBOARD_FAB2(SCH_1):PAGE190
    T9 TP_CPLD1_PB16A_PCLKT2_1 @BASEBOARD_FAB2_LIB.BASEBOARD_FAB2(SCH_1):TP_CPLD1_PB16A_PCLKT2_1   I179 @BASEBOARD_FAB2_LIB.BASEBOARD_FAB2(SCH_1):PAGE190
    P9 TP_CPLD1_PB16B_PCLKC2_1 @BASEBOARD_FAB2_LIB.BASEBOARD_FAB2(SCH_1):TP_CPLD1_PB16B_PCLKC2_1   I179 @BASEBOARD_FAB2_LIB.BASEBOARD_FAB2(SCH_1):PAGE190
    M8 FM_PVCCMCP_CPU1_EN @BASEBOARD_FAB2_LIB.BASEBOARD_FAB2(SCH_1):FM_PVCCMCP_CPU1_EN   I179 @BASEBOARD_FAB2_LIB.BASEBOARD_FAB2(SCH_1):PAGE190
    N9 FM_CPLD_BMC_PWRDN_N @BASEBOARD_FAB2_LIB.BASEBOARD_FAB2(SCH_1):FM_CPLD_BMC_PWRDN_N   I179 @BASEBOARD_FAB2_LIB.BASEBOARD_FAB2(SCH_1):PAGE190
    R9 FM_UARTSW_LSB_N @BASEBOARD_FAB2_LIB.BASEBOARD_FAB2(SCH_1):FM_UARTSW_LSB_N   I179 @BASEBOARD_FAB2_LIB.BASEBOARD_FAB2(SCH_1):PAGE190
   T10 FM_156M_CPU0_BRD_OSC_EN @BASEBOARD_FAB2_LIB.BASEBOARD_FAB2(SCH_1):FM_156M_CPU0_BRD_OSC_EN   I179 @BASEBOARD_FAB2_LIB.BASEBOARD_FAB2(SCH_1):PAGE190
    M9 FM_CPLD_UART_CH_LOCK_N @BASEBOARD_FAB2_LIB.BASEBOARD_FAB2(SCH_1):FM_CPLD_UART_CH_LOCK_N   I179 @BASEBOARD_FAB2_LIB.BASEBOARD_FAB2(SCH_1):PAGE190
   L10 FM_SOL_UART_CH_SEL @BASEBOARD_FAB2_LIB.BASEBOARD_FAB2(SCH_1):FM_SOL_UART_CH_SEL   I179 @BASEBOARD_FAB2_LIB.BASEBOARD_FAB2(SCH_1):PAGE190
   P10 RST_CD_CPU1_POR_N @BASEBOARD_FAB2_LIB.BASEBOARD_FAB2(SCH_1):RST_CD_CPU1_POR_N   I179 @BASEBOARD_FAB2_LIB.BASEBOARD_FAB2(SCH_1):PAGE190
   R10 RST_CPU0_LVC3_R1_N @BASEBOARD_FAB2_LIB.BASEBOARD_FAB2(SCH_1):RST_CPU0_LVC3_R1_N   I179 @BASEBOARD_FAB2_LIB.BASEBOARD_FAB2(SCH_1):PAGE190
   N10 RST_CPU1_LVC3_R1_N @BASEBOARD_FAB2_LIB.BASEBOARD_FAB2(SCH_1):RST_CPU1_LVC3_R1_N   I179 @BASEBOARD_FAB2_LIB.BASEBOARD_FAB2(SCH_1):PAGE190
   M11 XDP_PWRGD_RST_N @BASEBOARD_FAB2_LIB.BASEBOARD_FAB2(SCH_1):XDP_PWRGD_RST_N   I179 @BASEBOARD_FAB2_LIB.BASEBOARD_FAB2(SCH_1):PAGE190
   T11 FM_CPU1_PKGID2 @BASEBOARD_FAB2_LIB.BASEBOARD_FAB2(SCH_1):FM_CPU1_PKGID2   I179 @BASEBOARD_FAB2_LIB.BASEBOARD_FAB2(SCH_1):PAGE190
   P11 FM_UARTSW_MSB_N @BASEBOARD_FAB2_LIB.BASEBOARD_FAB2(SCH_1):FM_UARTSW_MSB_N   I179 @BASEBOARD_FAB2_LIB.BASEBOARD_FAB2(SCH_1):PAGE190
   M10 PWRGD_CPU1_LVC3 @BASEBOARD_FAB2_LIB.BASEBOARD_FAB2(SCH_1):PWRGD_CPU1_LVC3   I179 @BASEBOARD_FAB2_LIB.BASEBOARD_FAB2(SCH_1):PAGE190
   N11 XDP_SYSPWROK @BASEBOARD_FAB2_LIB.BASEBOARD_FAB2(SCH_1):XDP_SYSPWROK   I179 @BASEBOARD_FAB2_LIB.BASEBOARD_FAB2(SCH_1):PAGE190
   R11 FM_DB1200ZL_BCLKS_EN_N @BASEBOARD_FAB2_LIB.BASEBOARD_FAB2(SCH_1):FM_DB1200ZL_BCLKS_EN_N   I179 @BASEBOARD_FAB2_LIB.BASEBOARD_FAB2(SCH_1):PAGE190
   T12 FM_CPU1_SKTOCC_LVT3_N @BASEBOARD_FAB2_LIB.BASEBOARD_FAB2(SCH_1):FM_CPU1_SKTOCC_LVT3_N   I179 @BASEBOARD_FAB2_LIB.BASEBOARD_FAB2(SCH_1):PAGE190
   R13 FM_CPU0_VRM_OSC_EN @BASEBOARD_FAB2_LIB.BASEBOARD_FAB2(SCH_1):FM_CPU0_VRM_OSC_EN   I179 @BASEBOARD_FAB2_LIB.BASEBOARD_FAB2(SCH_1):PAGE190
   T14 FM_CPU0_SKTOCC_LVT3_N @BASEBOARD_FAB2_LIB.BASEBOARD_FAB2(SCH_1):FM_CPU0_SKTOCC_LVT3_N   I179 @BASEBOARD_FAB2_LIB.BASEBOARD_FAB2(SCH_1):PAGE190
   P12 FM_CPU1_PKGID1 @BASEBOARD_FAB2_LIB.BASEBOARD_FAB2(SCH_1):FM_CPU1_PKGID1   I179 @BASEBOARD_FAB2_LIB.BASEBOARD_FAB2(SCH_1):PAGE190
   T13 FM_CPU_MSMI_LVT3_N @BASEBOARD_FAB2_LIB.BASEBOARD_FAB2(SCH_1):FM_CPU_MSMI_LVT3_N   I179 @BASEBOARD_FAB2_LIB.BASEBOARD_FAB2(SCH_1):PAGE190
   R12 FM_CPU1_PKGID0 @BASEBOARD_FAB2_LIB.BASEBOARD_FAB2(SCH_1):FM_CPU1_PKGID0   I179 @BASEBOARD_FAB2_LIB.BASEBOARD_FAB2(SCH_1):PAGE190
   P13 TP_CPLD1_PB25B_SI_SISPI @BASEBOARD_FAB2_LIB.BASEBOARD_FAB2(SCH_1):TP_CPLD1_PB25B_SI_SISPI   I179 @BASEBOARD_FAB2_LIB.BASEBOARD_FAB2(SCH_1):PAGE190
   T15 PWRGD_DRAMPWRGD @BASEBOARD_FAB2_LIB.BASEBOARD_FAB2(SCH_1):PWRGD_DRAMPWRGD   I179 @BASEBOARD_FAB2_LIB.BASEBOARD_FAB2(SCH_1):PAGE190
   R14 FM_CPU_CATERR_LVT3_N @BASEBOARD_FAB2_LIB.BASEBOARD_FAB2(SCH_1):FM_CPU_CATERR_LVT3_N   I179 @BASEBOARD_FAB2_LIB.BASEBOARD_FAB2(SCH_1):PAGE190
    D3 TP_CPLD1_PL1A_L_GPLLT_FB @BASEBOARD_FAB2_LIB.BASEBOARD_FAB2(SCH_1):TP_CPLD1_PL1A_L_GPLLT_FB   I179 @BASEBOARD_FAB2_LIB.BASEBOARD_FAB2(SCH_1):PAGE190
    D1 TP_CPLD1_PL1B_L_GPLLC_FB @BASEBOARD_FAB2_LIB.BASEBOARD_FAB2(SCH_1):TP_CPLD1_PL1B_L_GPLLC_FB   I179 @BASEBOARD_FAB2_LIB.BASEBOARD_FAB2(SCH_1):PAGE190
    B1 RST_PCIE_PCH_PERST_N @BASEBOARD_FAB2_LIB.BASEBOARD_FAB2(SCH_1):RST_PCIE_PCH_PERST_N   I179 @BASEBOARD_FAB2_LIB.BASEBOARD_FAB2(SCH_1):PAGE190
    C2 FM_PCH_PLD_DATA @BASEBOARD_FAB2_LIB.BASEBOARD_FAB2(SCH_1):FM_PCH_PLD_DATA   I179 @BASEBOARD_FAB2_LIB.BASEBOARD_FAB2(SCH_1):PAGE190
    E2 FM_CPU_CATERR_DLY_LVT3_N @BASEBOARD_FAB2_LIB.BASEBOARD_FAB2(SCH_1):FM_CPU_CATERR_DLY_LVT3_N   I179 @BASEBOARD_FAB2_LIB.BASEBOARD_FAB2(SCH_1):PAGE190
    E3 TP_CPLD1_PL2B_L_GPLLC_IN @BASEBOARD_FAB2_LIB.BASEBOARD_FAB2(SCH_1):TP_CPLD1_PL2B_L_GPLLC_IN   I179 @BASEBOARD_FAB2_LIB.BASEBOARD_FAB2(SCH_1):PAGE190
    C1 RST_PCIE_CPU_DEV1_N @BASEBOARD_FAB2_LIB.BASEBOARD_FAB2(SCH_1):RST_PCIE_CPU_DEV1_N   I179 @BASEBOARD_FAB2_LIB.BASEBOARD_FAB2(SCH_1):PAGE190
    D2 FM_MEM_EVENT_FUNC @BASEBOARD_FAB2_LIB.BASEBOARD_FAB2(SCH_1):FM_MEM_EVENT_FUNC   I179 @BASEBOARD_FAB2_LIB.BASEBOARD_FAB2(SCH_1):PAGE190
    E1 CLK_32K_SUSCLK_PLD @BASEBOARD_FAB2_LIB.BASEBOARD_FAB2(SCH_1):CLK_32K_SUSCLK_PLD   I179 @BASEBOARD_FAB2_LIB.BASEBOARD_FAB2(SCH_1):PAGE190
    F2 FM_CPU0_PKGID0 @BASEBOARD_FAB2_LIB.BASEBOARD_FAB2(SCH_1):FM_CPU0_PKGID0   I179 @BASEBOARD_FAB2_LIB.BASEBOARD_FAB2(SCH_1):PAGE190
    F4 PU_RST_PERST_BIT0 @BASEBOARD_FAB2_LIB.BASEBOARD_FAB2(SCH_1):PU_RST_PERST_BIT0   I179 @BASEBOARD_FAB2_LIB.BASEBOARD_FAB2(SCH_1):PAGE190
    G6 FM_PWR_BTN_R2_N @BASEBOARD_FAB2_LIB.BASEBOARD_FAB2(SCH_1):FM_PWR_BTN_R2_N   I179 @BASEBOARD_FAB2_LIB.BASEBOARD_FAB2(SCH_1):PAGE190
    F3 FM_CPU0_PROC_ID1 @BASEBOARD_FAB2_LIB.BASEBOARD_FAB2(SCH_1):FM_CPU0_PROC_ID1   I179 @BASEBOARD_FAB2_LIB.BASEBOARD_FAB2(SCH_1):PAGE190
    F1 FM_CPU0_PROC_ID0 @BASEBOARD_FAB2_LIB.BASEBOARD_FAB2(SCH_1):FM_CPU0_PROC_ID0   I179 @BASEBOARD_FAB2_LIB.BASEBOARD_FAB2(SCH_1):PAGE190
    G5 FM_DEBUG_RST_BTN_N @BASEBOARD_FAB2_LIB.BASEBOARD_FAB2(SCH_1):FM_DEBUG_RST_BTN_N   I179 @BASEBOARD_FAB2_LIB.BASEBOARD_FAB2(SCH_1):PAGE190
    G4 RST_RSMRST_R_N @BASEBOARD_FAB2_LIB.BASEBOARD_FAB2(SCH_1):RST_RSMRST_R_N   I179 @BASEBOARD_FAB2_LIB.BASEBOARD_FAB2(SCH_1):PAGE190
    G2 FM_CPU0_PKGID2 @BASEBOARD_FAB2_LIB.BASEBOARD_FAB2(SCH_1):FM_CPU0_PKGID2   I179 @BASEBOARD_FAB2_LIB.BASEBOARD_FAB2(SCH_1):PAGE190
    G3 FM_CPU0_PKGID1 @BASEBOARD_FAB2_LIB.BASEBOARD_FAB2(SCH_1):FM_CPU0_PKGID1   I179 @BASEBOARD_FAB2_LIB.BASEBOARD_FAB2(SCH_1):PAGE190
    F5 FM_CPU0_FIVR_FAULT_LVT3_N @BASEBOARD_FAB2_LIB.BASEBOARD_FAB2(SCH_1):FM_CPU0_FIVR_FAULT_LVT3_N   I179 @BASEBOARD_FAB2_LIB.BASEBOARD_FAB2(SCH_1):PAGE190
    H6 PWRGD_P3V3 @BASEBOARD_FAB2_LIB.BASEBOARD_FAB2(SCH_1):PWRGD_P3V3   I179 @BASEBOARD_FAB2_LIB.BASEBOARD_FAB2(SCH_1):PAGE190
    G1 FM_SLPS3_N @BASEBOARD_FAB2_LIB.BASEBOARD_FAB2(SCH_1):FM_SLPS3_N   I179 @BASEBOARD_FAB2_LIB.BASEBOARD_FAB2(SCH_1):PAGE190
    H2 FM_PVCCMCP_CPU0_EN @BASEBOARD_FAB2_LIB.BASEBOARD_FAB2(SCH_1):FM_PVCCMCP_CPU0_EN   I179 @BASEBOARD_FAB2_LIB.BASEBOARD_FAB2(SCH_1):PAGE190
    H4 FM_MP_PS_FAIL_N @BASEBOARD_FAB2_LIB.BASEBOARD_FAB2(SCH_1):FM_MP_PS_FAIL_N   I179 @BASEBOARD_FAB2_LIB.BASEBOARD_FAB2(SCH_1):PAGE190
    J6 PWRGD_P5V @BASEBOARD_FAB2_LIB.BASEBOARD_FAB2(SCH_1):PWRGD_P5V   I179 @BASEBOARD_FAB2_LIB.BASEBOARD_FAB2(SCH_1):PAGE190
    H3 RST_PCIE_CPU_DEV2_N @BASEBOARD_FAB2_LIB.BASEBOARD_FAB2(SCH_1):RST_PCIE_CPU_DEV2_N   I179 @BASEBOARD_FAB2_LIB.BASEBOARD_FAB2(SCH_1):PAGE190
    H1 RST_PCIE_CPU_DEV3_N @BASEBOARD_FAB2_LIB.BASEBOARD_FAB2(SCH_1):RST_PCIE_CPU_DEV3_N   I179 @BASEBOARD_FAB2_LIB.BASEBOARD_FAB2(SCH_1):PAGE190
    J1 SGPIO_BMC_CLK @BASEBOARD_FAB2_LIB.BASEBOARD_FAB2(SCH_1):SGPIO_BMC_CLK   I179 @BASEBOARD_FAB2_LIB.BASEBOARD_FAB2(SCH_1):PAGE190
    J3 TP_CPLD1_PL7D_PCLKT4_0 @BASEBOARD_FAB2_LIB.BASEBOARD_FAB2(SCH_1):TP_CPLD1_PL7D_PCLKT4_0   I179 @BASEBOARD_FAB2_LIB.BASEBOARD_FAB2(SCH_1):PAGE190
    J2 SGPIO_BMC_DOUT @BASEBOARD_FAB2_LIB.BASEBOARD_FAB2(SCH_1):SGPIO_BMC_DOUT   I179 @BASEBOARD_FAB2_LIB.BASEBOARD_FAB2(SCH_1):PAGE190
    K1 FM_PVCCIOMCP_CPU0_EN @BASEBOARD_FAB2_LIB.BASEBOARD_FAB2(SCH_1):FM_PVCCIOMCP_CPU0_EN   I179 @BASEBOARD_FAB2_LIB.BASEBOARD_FAB2(SCH_1):PAGE190
    H5     NC     NC   I179 @BASEBOARD_FAB2_LIB.BASEBOARD_FAB2(SCH_1):PAGE190
    J4     NC     NC   I179 @BASEBOARD_FAB2_LIB.BASEBOARD_FAB2(SCH_1):PAGE190
    K3 SP1_BMC_HOST_UART_RX @BASEBOARD_FAB2_LIB.BASEBOARD_FAB2(SCH_1):SP1_BMC_HOST_UART_RX   I179 @BASEBOARD_FAB2_LIB.BASEBOARD_FAB2(SCH_1):PAGE190
    K2 SP1_BMC_HOST_UART_TX @BASEBOARD_FAB2_LIB.BASEBOARD_FAB2(SCH_1):SP1_BMC_HOST_UART_TX   I179 @BASEBOARD_FAB2_LIB.BASEBOARD_FAB2(SCH_1):PAGE190
    J5 UART_BMC_RXD5 @BASEBOARD_FAB2_LIB.BASEBOARD_FAB2(SCH_1):UART_BMC_RXD5   I179 @BASEBOARD_FAB2_LIB.BASEBOARD_FAB2(SCH_1):PAGE190
    K6 UART_BMC_TXD5 @BASEBOARD_FAB2_LIB.BASEBOARD_FAB2(SCH_1):UART_BMC_TXD5   I179 @BASEBOARD_FAB2_LIB.BASEBOARD_FAB2(SCH_1):PAGE190
    L1 PWRGD_PVSA_CPU0 @BASEBOARD_FAB2_LIB.BASEBOARD_FAB2(SCH_1):PWRGD_PVSA_CPU0   I179 @BASEBOARD_FAB2_LIB.BASEBOARD_FAB2(SCH_1):PAGE190
    L3 TP_CPLD1_PL11A @BASEBOARD_FAB2_LIB.BASEBOARD_FAB2(SCH_1):TP_CPLD1_PL11A   I179 @BASEBOARD_FAB2_LIB.BASEBOARD_FAB2(SCH_1):PAGE190
    K4 SGPIO_BMC_LD_N @BASEBOARD_FAB2_LIB.BASEBOARD_FAB2(SCH_1):SGPIO_BMC_LD_N   I179 @BASEBOARD_FAB2_LIB.BASEBOARD_FAB2(SCH_1):PAGE190
    L5 PWRGD_CPU0_LVC3 @BASEBOARD_FAB2_LIB.BASEBOARD_FAB2(SCH_1):PWRGD_CPU0_LVC3   I179 @BASEBOARD_FAB2_LIB.BASEBOARD_FAB2(SCH_1):PAGE190
    L2 CLK_25M_CPLD @BASEBOARD_FAB2_LIB.BASEBOARD_FAB2(SCH_1):CLK_25M_CPLD   I179 @BASEBOARD_FAB2_LIB.BASEBOARD_FAB2(SCH_1):PAGE190
    M1 RST_RSMRST_DLY @BASEBOARD_FAB2_LIB.BASEBOARD_FAB2(SCH_1):RST_RSMRST_DLY   I179 @BASEBOARD_FAB2_LIB.BASEBOARD_FAB2(SCH_1):PAGE190
    K5 PWRGD_PVCCIN_CPU0 @BASEBOARD_FAB2_LIB.BASEBOARD_FAB2(SCH_1):PWRGD_PVCCIN_CPU0   I179 @BASEBOARD_FAB2_LIB.BASEBOARD_FAB2(SCH_1):PAGE190
    L4 PWRGD_PVCCMCP_CPU1 @BASEBOARD_FAB2_LIB.BASEBOARD_FAB2(SCH_1):PWRGD_PVCCMCP_CPU1   I179 @BASEBOARD_FAB2_LIB.BASEBOARD_FAB2(SCH_1):PAGE190
    M3 RST_PCIE_RISER1_PERST_N @BASEBOARD_FAB2_LIB.BASEBOARD_FAB2(SCH_1):RST_PCIE_RISER1_PERST_N   I179 @BASEBOARD_FAB2_LIB.BASEBOARD_FAB2(SCH_1):PAGE190
    N1 PWRGD_PVCCIN_CPU1 @BASEBOARD_FAB2_LIB.BASEBOARD_FAB2(SCH_1):PWRGD_PVCCIN_CPU1   I179 @BASEBOARD_FAB2_LIB.BASEBOARD_FAB2(SCH_1):PAGE190
    N2 PWRGD_PVPP_KLM @BASEBOARD_FAB2_LIB.BASEBOARD_FAB2(SCH_1):PWRGD_PVPP_KLM   I179 @BASEBOARD_FAB2_LIB.BASEBOARD_FAB2(SCH_1):PAGE190
    P1 FM_GLOBAL_RST_WARN_N @BASEBOARD_FAB2_LIB.BASEBOARD_FAB2(SCH_1):FM_GLOBAL_RST_WARN_N   I179 @BASEBOARD_FAB2_LIB.BASEBOARD_FAB2(SCH_1):PAGE190
    M2 PWRGD_PVPP_GHJ @BASEBOARD_FAB2_LIB.BASEBOARD_FAB2(SCH_1):PWRGD_PVPP_GHJ   I179 @BASEBOARD_FAB2_LIB.BASEBOARD_FAB2(SCH_1):PAGE190
    N3 RST_CD_CPU0_POR_N @BASEBOARD_FAB2_LIB.BASEBOARD_FAB2(SCH_1):RST_CD_CPU0_POR_N   I179 @BASEBOARD_FAB2_LIB.BASEBOARD_FAB2(SCH_1):PAGE190
    R1 FM_BMC_CPLD_GPO @BASEBOARD_FAB2_LIB.BASEBOARD_FAB2(SCH_1):FM_BMC_CPLD_GPO   I179 @BASEBOARD_FAB2_LIB.BASEBOARD_FAB2(SCH_1):PAGE190
    P2 FM_UART_ALERT_N @BASEBOARD_FAB2_LIB.BASEBOARD_FAB2(SCH_1):FM_UART_ALERT_N   I179 @BASEBOARD_FAB2_LIB.BASEBOARD_FAB2(SCH_1):PAGE190
   D14 PWRGD_SYS_PWROK @BASEBOARD_FAB2_LIB.BASEBOARD_FAB2(SCH_1):PWRGD_SYS_PWROK    I59 @BASEBOARD_FAB2_LIB.BASEBOARD_FAB2(SCH_1):PAGE191
   E15 RST_PLTRST_N @BASEBOARD_FAB2_LIB.BASEBOARD_FAB2(SCH_1):RST_PLTRST_N    I59 @BASEBOARD_FAB2_LIB.BASEBOARD_FAB2(SCH_1):PAGE191
   C15 FM_DB1200_PWRGD @BASEBOARD_FAB2_LIB.BASEBOARD_FAB2(SCH_1):FM_DB1200_PWRGD    I59 @BASEBOARD_FAB2_LIB.BASEBOARD_FAB2(SCH_1):PAGE191
   B16 FM_ADR_COMPLETE_DLY @BASEBOARD_FAB2_LIB.BASEBOARD_FAB2(SCH_1):FM_ADR_COMPLETE_DLY    I59 @BASEBOARD_FAB2_LIB.BASEBOARD_FAB2(SCH_1):PAGE191
   D16 PWRGD_P1V8MCP_CPU1 @BASEBOARD_FAB2_LIB.BASEBOARD_FAB2(SCH_1):PWRGD_P1V8MCP_CPU1    I59 @BASEBOARD_FAB2_LIB.BASEBOARD_FAB2(SCH_1):PAGE191
   E14 FM_CPLD_ADR_TRIGGER_N @BASEBOARD_FAB2_LIB.BASEBOARD_FAB2(SCH_1):FM_CPLD_ADR_TRIGGER_N    I59 @BASEBOARD_FAB2_LIB.BASEBOARD_FAB2(SCH_1):PAGE191
   C16 PWRGD_PCH_PWROK @BASEBOARD_FAB2_LIB.BASEBOARD_FAB2(SCH_1):PWRGD_PCH_PWROK    I59 @BASEBOARD_FAB2_LIB.BASEBOARD_FAB2(SCH_1):PAGE191
   D15 PWRGD_P1V8MCP_CPU0 @BASEBOARD_FAB2_LIB.BASEBOARD_FAB2(SCH_1):PWRGD_P1V8MCP_CPU0    I59 @BASEBOARD_FAB2_LIB.BASEBOARD_FAB2(SCH_1):PAGE191
   E16 FM_P1V8MCP_CPU0_EN @BASEBOARD_FAB2_LIB.BASEBOARD_FAB2(SCH_1):FM_P1V8MCP_CPU0_EN    I59 @BASEBOARD_FAB2_LIB.BASEBOARD_FAB2(SCH_1):PAGE191
   F15 FM_CPU0_MCP_CLK_EN_N @BASEBOARD_FAB2_LIB.BASEBOARD_FAB2(SCH_1):FM_CPU0_MCP_CLK_EN_N    I59 @BASEBOARD_FAB2_LIB.BASEBOARD_FAB2(SCH_1):PAGE191
   F13 PWRGD_CPUPWRGD @BASEBOARD_FAB2_LIB.BASEBOARD_FAB2(SCH_1):PWRGD_CPUPWRGD    I59 @BASEBOARD_FAB2_LIB.BASEBOARD_FAB2(SCH_1):PAGE191
   G12 FM_CPU0_THERMTRIP_LATCH_LVT3_N @BASEBOARD_FAB2_LIB.BASEBOARD_FAB2(SCH_1):FM_CPU0_THERMTRIP_LATCH_LVT3_N    I59 @BASEBOARD_FAB2_LIB.BASEBOARD_FAB2(SCH_1):PAGE191
   F14 RST_BMC_SYSRST_BTN_OUT_B_R1_N @BASEBOARD_FAB2_LIB.BASEBOARD_FAB2(SCH_1):RST_BMC_SYSRST_BTN_OUT_B_R1_N    I59 @BASEBOARD_FAB2_LIB.BASEBOARD_FAB2(SCH_1):PAGE191
   F16 FM_CPU1_MCP_CLK_EN_N @BASEBOARD_FAB2_LIB.BASEBOARD_FAB2(SCH_1):FM_CPU1_MCP_CLK_EN_N    I59 @BASEBOARD_FAB2_LIB.BASEBOARD_FAB2(SCH_1):PAGE191
   F12 FM_P1V8MCP_CPU1_EN @BASEBOARD_FAB2_LIB.BASEBOARD_FAB2(SCH_1):FM_P1V8MCP_CPU1_EN    I59 @BASEBOARD_FAB2_LIB.BASEBOARD_FAB2(SCH_1):PAGE191
   G13 FM_CPU1_FIVR_FAULT_LVT3 @BASEBOARD_FAB2_LIB.BASEBOARD_FAB2(SCH_1):FM_CPU1_FIVR_FAULT_LVT3    I59 @BASEBOARD_FAB2_LIB.BASEBOARD_FAB2(SCH_1):PAGE191
   G15 FM_UV_ADR_TRIGGER_N @BASEBOARD_FAB2_LIB.BASEBOARD_FAB2(SCH_1):FM_UV_ADR_TRIGGER_N    I59 @BASEBOARD_FAB2_LIB.BASEBOARD_FAB2(SCH_1):PAGE191
   G14 FM_CPU1_THERMTRIP_LVT3_N @BASEBOARD_FAB2_LIB.BASEBOARD_FAB2(SCH_1):FM_CPU1_THERMTRIP_LVT3_N    I59 @BASEBOARD_FAB2_LIB.BASEBOARD_FAB2(SCH_1):PAGE191
   G11 FM_WBG_PRSNT_N @BASEBOARD_FAB2_LIB.BASEBOARD_FAB2(SCH_1):FM_WBG_PRSNT_N    I59 @BASEBOARD_FAB2_LIB.BASEBOARD_FAB2(SCH_1):PAGE191
   H12 FM_UV_ADR_TRIGGER_EN @BASEBOARD_FAB2_LIB.BASEBOARD_FAB2(SCH_1):FM_UV_ADR_TRIGGER_EN    I59 @BASEBOARD_FAB2_LIB.BASEBOARD_FAB2(SCH_1):PAGE191
   G16 FM_FAST_PROCHOT_THROTTLE_IN_N @BASEBOARD_FAB2_LIB.BASEBOARD_FAB2(SCH_1):FM_FAST_PROCHOT_THROTTLE_IN_N    I59 @BASEBOARD_FAB2_LIB.BASEBOARD_FAB2(SCH_1):PAGE191
   H15 FM_PVDDQ_KLM_EN @BASEBOARD_FAB2_LIB.BASEBOARD_FAB2(SCH_1):FM_PVDDQ_KLM_EN    I59 @BASEBOARD_FAB2_LIB.BASEBOARD_FAB2(SCH_1):PAGE191
   H13 FM_PVDDQ_GHJ_EN @BASEBOARD_FAB2_LIB.BASEBOARD_FAB2(SCH_1):FM_PVDDQ_GHJ_EN    I59 @BASEBOARD_FAB2_LIB.BASEBOARD_FAB2(SCH_1):PAGE191
   J12 FM_FAST_PROCHOT_THROTTLE_DLY_N @BASEBOARD_FAB2_LIB.BASEBOARD_FAB2(SCH_1):FM_FAST_PROCHOT_THROTTLE_DLY_N    I59 @BASEBOARD_FAB2_LIB.BASEBOARD_FAB2(SCH_1):PAGE191
   H14 TP_CPLD1_PR7A_PCLKT1_0 @BASEBOARD_FAB2_LIB.BASEBOARD_FAB2(SCH_1):TP_CPLD1_PR7A_PCLKT1_0    I59 @BASEBOARD_FAB2_LIB.BASEBOARD_FAB2(SCH_1):PAGE191
   H16 TP_CPLD1_PR7B_PCLKC1_0 @BASEBOARD_FAB2_LIB.BASEBOARD_FAB2(SCH_1):TP_CPLD1_PR7B_PCLKC1_0    I59 @BASEBOARD_FAB2_LIB.BASEBOARD_FAB2(SCH_1):PAGE191
   J16 TP_CPLD1_PR7C @BASEBOARD_FAB2_LIB.BASEBOARD_FAB2(SCH_1):TP_CPLD1_PR7C    I59 @BASEBOARD_FAB2_LIB.BASEBOARD_FAB2(SCH_1):PAGE191
   J14 TP_CPLD1_PR7D @BASEBOARD_FAB2_LIB.BASEBOARD_FAB2(SCH_1):TP_CPLD1_PR7D    I59 @BASEBOARD_FAB2_LIB.BASEBOARD_FAB2(SCH_1):PAGE191
   J15 TP_CPLD1_PR9A @BASEBOARD_FAB2_LIB.BASEBOARD_FAB2(SCH_1):TP_CPLD1_PR9A    I59 @BASEBOARD_FAB2_LIB.BASEBOARD_FAB2(SCH_1):PAGE191
   K16 PU_FAB2_MARKER_CPLD @BASEBOARD_FAB2_LIB.BASEBOARD_FAB2(SCH_1):PU_FAB2_MARKER_CPLD    I59 @BASEBOARD_FAB2_LIB.BASEBOARD_FAB2(SCH_1):PAGE191
   H11 TP_CPLD1_PR9C @BASEBOARD_FAB2_LIB.BASEBOARD_FAB2(SCH_1):TP_CPLD1_PR9C    I59 @BASEBOARD_FAB2_LIB.BASEBOARD_FAB2(SCH_1):PAGE191
   J13 TP_CPLD1_PR9D @BASEBOARD_FAB2_LIB.BASEBOARD_FAB2(SCH_1):TP_CPLD1_PR9D    I59 @BASEBOARD_FAB2_LIB.BASEBOARD_FAB2(SCH_1):PAGE191
   K14 FM_PVDDQ_ABC_EN @BASEBOARD_FAB2_LIB.BASEBOARD_FAB2(SCH_1):FM_PVDDQ_ABC_EN    I59 @BASEBOARD_FAB2_LIB.BASEBOARD_FAB2(SCH_1):PAGE191
   K15 FM_PVDDQ_DEF_EN @BASEBOARD_FAB2_LIB.BASEBOARD_FAB2(SCH_1):FM_PVDDQ_DEF_EN    I59 @BASEBOARD_FAB2_LIB.BASEBOARD_FAB2(SCH_1):PAGE191
   J11 TP_CPLD1_PR10C @BASEBOARD_FAB2_LIB.BASEBOARD_FAB2(SCH_1):TP_CPLD1_PR10C    I59 @BASEBOARD_FAB2_LIB.BASEBOARD_FAB2(SCH_1):PAGE191
   L12 PWRGD_P3V3_STBY @BASEBOARD_FAB2_LIB.BASEBOARD_FAB2(SCH_1):PWRGD_P3V3_STBY    I59 @BASEBOARD_FAB2_LIB.BASEBOARD_FAB2(SCH_1):PAGE191
   L16 PWRGD_PVCCIO_CPU1 @BASEBOARD_FAB2_LIB.BASEBOARD_FAB2(SCH_1):PWRGD_PVCCIO_CPU1    I59 @BASEBOARD_FAB2_LIB.BASEBOARD_FAB2(SCH_1):PAGE191
   L14 TP_CPLD1_PR11B @BASEBOARD_FAB2_LIB.BASEBOARD_FAB2(SCH_1):TP_CPLD1_PR11B    I59 @BASEBOARD_FAB2_LIB.BASEBOARD_FAB2(SCH_1):PAGE191
   K13 FM_MEM_THERM_EVENT_LVT3_N @BASEBOARD_FAB2_LIB.BASEBOARD_FAB2(SCH_1):FM_MEM_THERM_EVENT_LVT3_N    I59 @BASEBOARD_FAB2_LIB.BASEBOARD_FAB2(SCH_1):PAGE191
   K12 FM_MEM_THERM_EVENT_PCH_N @BASEBOARD_FAB2_LIB.BASEBOARD_FAB2(SCH_1):FM_MEM_THERM_EVENT_PCH_N    I59 @BASEBOARD_FAB2_LIB.BASEBOARD_FAB2(SCH_1):PAGE191
   L15 FM_THERMTRIP_DLY @BASEBOARD_FAB2_LIB.BASEBOARD_FAB2(SCH_1):FM_THERMTRIP_DLY    I59 @BASEBOARD_FAB2_LIB.BASEBOARD_FAB2(SCH_1):PAGE191
   M16 FM_CPU0_FIVR_FAULT_LVT3 @BASEBOARD_FAB2_LIB.BASEBOARD_FAB2(SCH_1):FM_CPU0_FIVR_FAULT_LVT3    I59 @BASEBOARD_FAB2_LIB.BASEBOARD_FAB2(SCH_1):PAGE191
   K11 RST_PLTRST_BUF_N @BASEBOARD_FAB2_LIB.BASEBOARD_FAB2(SCH_1):RST_PLTRST_BUF_N    I59 @BASEBOARD_FAB2_LIB.BASEBOARD_FAB2(SCH_1):PAGE191
   L13 TP_CPLD1_PR12D @BASEBOARD_FAB2_LIB.BASEBOARD_FAB2(SCH_1):TP_CPLD1_PR12D    I59 @BASEBOARD_FAB2_LIB.BASEBOARD_FAB2(SCH_1):PAGE191
   M14 FM_CPU1_PROC_ID1 @BASEBOARD_FAB2_LIB.BASEBOARD_FAB2(SCH_1):FM_CPU1_PROC_ID1    I59 @BASEBOARD_FAB2_LIB.BASEBOARD_FAB2(SCH_1):PAGE191
   M15 FM_CPU1_PROC_ID0 @BASEBOARD_FAB2_LIB.BASEBOARD_FAB2(SCH_1):FM_CPU1_PROC_ID0    I59 @BASEBOARD_FAB2_LIB.BASEBOARD_FAB2(SCH_1):PAGE191
   N15 FM_CPU0_THERMTRIP_LVT3_N @BASEBOARD_FAB2_LIB.BASEBOARD_FAB2(SCH_1):FM_CPU0_THERMTRIP_LVT3_N    I59 @BASEBOARD_FAB2_LIB.BASEBOARD_FAB2(SCH_1):PAGE191
   P16 FM_PVPP_CPU1_EN @BASEBOARD_FAB2_LIB.BASEBOARD_FAB2(SCH_1):FM_PVPP_CPU1_EN    I59 @BASEBOARD_FAB2_LIB.BASEBOARD_FAB2(SCH_1):PAGE191
   N16 FM_PVCCIN_PVCCSA_CPU1_EN_LVC1 @BASEBOARD_FAB2_LIB.BASEBOARD_FAB2(SCH_1):FM_PVCCIN_PVCCSA_CPU1_EN_LVC1    I59 @BASEBOARD_FAB2_LIB.BASEBOARD_FAB2(SCH_1):PAGE191
   N14 FM_CPU1_VRM_OSC_EN @BASEBOARD_FAB2_LIB.BASEBOARD_FAB2(SCH_1):FM_CPU1_VRM_OSC_EN    I59 @BASEBOARD_FAB2_LIB.BASEBOARD_FAB2(SCH_1):PAGE191
   P15 FM_PVPP_CPU0_EN @BASEBOARD_FAB2_LIB.BASEBOARD_FAB2(SCH_1):FM_PVPP_CPU0_EN    I59 @BASEBOARD_FAB2_LIB.BASEBOARD_FAB2(SCH_1):PAGE191
   R16 FM_P12V_MAIN_SW_EN @BASEBOARD_FAB2_LIB.BASEBOARD_FAB2(SCH_1):FM_P12V_MAIN_SW_EN    I59 @BASEBOARD_FAB2_LIB.BASEBOARD_FAB2(SCH_1):PAGE191
    C4 FM_ADR_SMI_GPIO_R_N @BASEBOARD_FAB2_LIB.BASEBOARD_FAB2(SCH_1):FM_ADR_SMI_GPIO_R_N    I59 @BASEBOARD_FAB2_LIB.BASEBOARD_FAB2(SCH_1):PAGE191
    B5 PWRGD_P12V_MAIN @BASEBOARD_FAB2_LIB.BASEBOARD_FAB2(SCH_1):PWRGD_P12V_MAIN    I59 @BASEBOARD_FAB2_LIB.BASEBOARD_FAB2(SCH_1):PAGE191
    B3 FM_CTNR_PS_ON @BASEBOARD_FAB2_LIB.BASEBOARD_FAB2(SCH_1):FM_CTNR_PS_ON    I59 @BASEBOARD_FAB2_LIB.BASEBOARD_FAB2(SCH_1):PAGE191
    A4 FM_P3V3_CPLD_EN @BASEBOARD_FAB2_LIB.BASEBOARD_FAB2(SCH_1):FM_P3V3_CPLD_EN    I59 @BASEBOARD_FAB2_LIB.BASEBOARD_FAB2(SCH_1):PAGE191
    C5 FM_CPU1_THERMTRIP_LATCH_LVT3_N @BASEBOARD_FAB2_LIB.BASEBOARD_FAB2(SCH_1):FM_CPU1_THERMTRIP_LATCH_LVT3_N    I59 @BASEBOARD_FAB2_LIB.BASEBOARD_FAB2(SCH_1):PAGE191
    A5 TP_CPLD1_PT11A @BASEBOARD_FAB2_LIB.BASEBOARD_FAB2(SCH_1):TP_CPLD1_PT11A    I59 @BASEBOARD_FAB2_LIB.BASEBOARD_FAB2(SCH_1):PAGE191
    B6 TP_CPLD1_PT11B @BASEBOARD_FAB2_LIB.BASEBOARD_FAB2(SCH_1):TP_CPLD1_PT11B    I59 @BASEBOARD_FAB2_LIB.BASEBOARD_FAB2(SCH_1):PAGE191
    A3 FM_PCH_PRSNT_N @BASEBOARD_FAB2_LIB.BASEBOARD_FAB2(SCH_1):FM_PCH_PRSNT_N    I59 @BASEBOARD_FAB2_LIB.BASEBOARD_FAB2(SCH_1):PAGE191
    B4 PWRGD_PVTT_CPU0 @BASEBOARD_FAB2_LIB.BASEBOARD_FAB2(SCH_1):PWRGD_PVTT_CPU0    I59 @BASEBOARD_FAB2_LIB.BASEBOARD_FAB2(SCH_1):PAGE191
    D6 RST_PCIE_CPU_DEV0_N @BASEBOARD_FAB2_LIB.BASEBOARD_FAB2(SCH_1):RST_PCIE_CPU_DEV0_N    I59 @BASEBOARD_FAB2_LIB.BASEBOARD_FAB2(SCH_1):PAGE191
    E7 PWRGD_P1V15_BMC_STBY @BASEBOARD_FAB2_LIB.BASEBOARD_FAB2(SCH_1):PWRGD_P1V15_BMC_STBY    I59 @BASEBOARD_FAB2_LIB.BASEBOARD_FAB2(SCH_1):PAGE191
    C6 JTAG_PLD_TDO @BASEBOARD_FAB2_LIB.BASEBOARD_FAB2(SCH_1):JTAG_PLD_TDO    I59 @BASEBOARD_FAB2_LIB.BASEBOARD_FAB2(SCH_1):PAGE191
    A6 JTAG_PLD_TDI @BASEBOARD_FAB2_LIB.BASEBOARD_FAB2(SCH_1):JTAG_PLD_TDI    I59 @BASEBOARD_FAB2_LIB.BASEBOARD_FAB2(SCH_1):PAGE191
    B7 TP_CPLD1_PT13A @BASEBOARD_FAB2_LIB.BASEBOARD_FAB2(SCH_1):TP_CPLD1_PT13A    I59 @BASEBOARD_FAB2_LIB.BASEBOARD_FAB2(SCH_1):PAGE191
    C7 FM_BMC_ONCTL_N @BASEBOARD_FAB2_LIB.BASEBOARD_FAB2(SCH_1):FM_BMC_ONCTL_N    I59 @BASEBOARD_FAB2_LIB.BASEBOARD_FAB2(SCH_1):PAGE191
    E6 FM_CPU1_FIVR_FAULT_LVT3_N @BASEBOARD_FAB2_LIB.BASEBOARD_FAB2(SCH_1):FM_CPU1_FIVR_FAULT_LVT3_N    I59 @BASEBOARD_FAB2_LIB.BASEBOARD_FAB2(SCH_1):PAGE191
    D7 FM_FORCE_ADR_N @BASEBOARD_FAB2_LIB.BASEBOARD_FAB2(SCH_1):FM_FORCE_ADR_N    I59 @BASEBOARD_FAB2_LIB.BASEBOARD_FAB2(SCH_1):PAGE191
    F7 FM_PLD_DEBUG_MODE_N @BASEBOARD_FAB2_LIB.BASEBOARD_FAB2(SCH_1):FM_PLD_DEBUG_MODE_N    I59 @BASEBOARD_FAB2_LIB.BASEBOARD_FAB2(SCH_1):PAGE191
    E8 TP_CPLD1_PT16B @BASEBOARD_FAB2_LIB.BASEBOARD_FAB2(SCH_1):TP_CPLD1_PT16B    I59 @BASEBOARD_FAB2_LIB.BASEBOARD_FAB2(SCH_1):PAGE191
    A7 JTAG_PLD_TCK @BASEBOARD_FAB2_LIB.BASEBOARD_FAB2(SCH_1):JTAG_PLD_TCK    I59 @BASEBOARD_FAB2_LIB.BASEBOARD_FAB2(SCH_1):PAGE191
    B8 JTAG_PLD_TMS @BASEBOARD_FAB2_LIB.BASEBOARD_FAB2(SCH_1):JTAG_PLD_TMS    I59 @BASEBOARD_FAB2_LIB.BASEBOARD_FAB2(SCH_1):PAGE191
    C8 FM_ADR_COMPLETE @BASEBOARD_FAB2_LIB.BASEBOARD_FAB2(SCH_1):FM_ADR_COMPLETE    I59 @BASEBOARD_FAB2_LIB.BASEBOARD_FAB2(SCH_1):PAGE191
    A8 TP_CPLD1_PT17B_PCLKC0_1 @BASEBOARD_FAB2_LIB.BASEBOARD_FAB2(SCH_1):TP_CPLD1_PT17B_PCLKC0_1    I59 @BASEBOARD_FAB2_LIB.BASEBOARD_FAB2(SCH_1):PAGE191
    D8 TP_CPLD1_PT17C @BASEBOARD_FAB2_LIB.BASEBOARD_FAB2(SCH_1):TP_CPLD1_PT17C    I59 @BASEBOARD_FAB2_LIB.BASEBOARD_FAB2(SCH_1):PAGE191
    E9 FM_SLP_SUS_N @BASEBOARD_FAB2_LIB.BASEBOARD_FAB2(SCH_1):FM_SLP_SUS_N    I59 @BASEBOARD_FAB2_LIB.BASEBOARD_FAB2(SCH_1):PAGE191
    F8 SGPIO_BMC_DIN_R @BASEBOARD_FAB2_LIB.BASEBOARD_FAB2(SCH_1):SGPIO_BMC_DIN_R    I59 @BASEBOARD_FAB2_LIB.BASEBOARD_FAB2(SCH_1):PAGE191
    D9 RST_PCIE_MIDPLANE_N @BASEBOARD_FAB2_LIB.BASEBOARD_FAB2(SCH_1):RST_PCIE_MIDPLANE_N    I59 @BASEBOARD_FAB2_LIB.BASEBOARD_FAB2(SCH_1):PAGE191
    A9 SMB_SENSOR_STBY_LVC3_SCL @BASEBOARD_FAB2_LIB.BASEBOARD_FAB2(SCH_1):SMB_SENSOR_STBY_LVC3_SCL    I59 @BASEBOARD_FAB2_LIB.BASEBOARD_FAB2(SCH_1):PAGE191
    C9 SMB_SENSOR_STBY_LVC3_SDA @BASEBOARD_FAB2_LIB.BASEBOARD_FAB2(SCH_1):SMB_SENSOR_STBY_LVC3_SDA    I59 @BASEBOARD_FAB2_LIB.BASEBOARD_FAB2(SCH_1):PAGE191
    B9 PU_RST_PERST_BIT1 @BASEBOARD_FAB2_LIB.BASEBOARD_FAB2(SCH_1):PU_RST_PERST_BIT1    I59 @BASEBOARD_FAB2_LIB.BASEBOARD_FAB2(SCH_1):PAGE191
   A10 FM_PVCCIN_PVCCSA_CPU0_EN_LVC1 @BASEBOARD_FAB2_LIB.BASEBOARD_FAB2(SCH_1):FM_PVCCIN_PVCCSA_CPU0_EN_LVC1    I59 @BASEBOARD_FAB2_LIB.BASEBOARD_FAB2(SCH_1):PAGE191
    F9 FM_PS_EN @BASEBOARD_FAB2_LIB.BASEBOARD_FAB2(SCH_1):FM_PS_EN    I59 @BASEBOARD_FAB2_LIB.BASEBOARD_FAB2(SCH_1):PAGE191
   E11 TP_CPLD1_PT19D @BASEBOARD_FAB2_LIB.BASEBOARD_FAB2(SCH_1):TP_CPLD1_PT19D    I59 @BASEBOARD_FAB2_LIB.BASEBOARD_FAB2(SCH_1):PAGE191
   D10 TP_CPLD1_PT20A @BASEBOARD_FAB2_LIB.BASEBOARD_FAB2(SCH_1):TP_CPLD1_PT20A    I59 @BASEBOARD_FAB2_LIB.BASEBOARD_FAB2(SCH_1):PAGE191
   E10 TP_CPLD1_PT20B @BASEBOARD_FAB2_LIB.BASEBOARD_FAB2(SCH_1):TP_CPLD1_PT20B    I59 @BASEBOARD_FAB2_LIB.BASEBOARD_FAB2(SCH_1):PAGE191
   C10 FM_JTAG_PLD_EN_DEBUG @BASEBOARD_FAB2_LIB.BASEBOARD_FAB2(SCH_1):FM_JTAG_PLD_EN_DEBUG    I59 @BASEBOARD_FAB2_LIB.BASEBOARD_FAB2(SCH_1):PAGE191
   B10 PU_CPLD1_PT20D_PROGRAMN @BASEBOARD_FAB2_LIB.BASEBOARD_FAB2(SCH_1):PU_CPLD1_PT20D_PROGRAMN    I59 @BASEBOARD_FAB2_LIB.BASEBOARD_FAB2(SCH_1):PAGE191
   A11 FM_CPU0_OR_CPU1_MCP_PRES @BASEBOARD_FAB2_LIB.BASEBOARD_FAB2(SCH_1):FM_CPU0_OR_CPU1_MCP_PRES    I59 @BASEBOARD_FAB2_LIB.BASEBOARD_FAB2(SCH_1):PAGE191
   C11 FM_CPU0_CD_PRES @BASEBOARD_FAB2_LIB.BASEBOARD_FAB2(SCH_1):FM_CPU0_CD_PRES    I59 @BASEBOARD_FAB2_LIB.BASEBOARD_FAB2(SCH_1):PAGE191
   F10 FM_CPU1_CD_PRES_N @BASEBOARD_FAB2_LIB.BASEBOARD_FAB2(SCH_1):FM_CPU1_CD_PRES_N    I59 @BASEBOARD_FAB2_LIB.BASEBOARD_FAB2(SCH_1):PAGE191
   D11 FM_CPU0_AND_CPU1_MCP_PRES @BASEBOARD_FAB2_LIB.BASEBOARD_FAB2(SCH_1):FM_CPU0_AND_CPU1_MCP_PRES    I59 @BASEBOARD_FAB2_LIB.BASEBOARD_FAB2(SCH_1):PAGE191
   B11 PWRGD_DSW_PWROK @BASEBOARD_FAB2_LIB.BASEBOARD_FAB2(SCH_1):PWRGD_DSW_PWROK    I59 @BASEBOARD_FAB2_LIB.BASEBOARD_FAB2(SCH_1):PAGE191
   A12 PU_THERMTRIP_FORCE_N @BASEBOARD_FAB2_LIB.BASEBOARD_FAB2(SCH_1):PU_THERMTRIP_FORCE_N    I59 @BASEBOARD_FAB2_LIB.BASEBOARD_FAB2(SCH_1):PAGE191
   B13 TP_CPLD1_PT22C @BASEBOARD_FAB2_LIB.BASEBOARD_FAB2(SCH_1):TP_CPLD1_PT22C    I59 @BASEBOARD_FAB2_LIB.BASEBOARD_FAB2(SCH_1):PAGE191
   A14 TP_CPLD1_PT22D @BASEBOARD_FAB2_LIB.BASEBOARD_FAB2(SCH_1):TP_CPLD1_PT22D    I59 @BASEBOARD_FAB2_LIB.BASEBOARD_FAB2(SCH_1):PAGE191
   C12 FM_SLPS4_N @BASEBOARD_FAB2_LIB.BASEBOARD_FAB2(SCH_1):FM_SLPS4_N    I59 @BASEBOARD_FAB2_LIB.BASEBOARD_FAB2(SCH_1):PAGE191
   B12 FM_PCH_PWRBTN_R1_N @BASEBOARD_FAB2_LIB.BASEBOARD_FAB2(SCH_1):FM_PCH_PWRBTN_R1_N    I59 @BASEBOARD_FAB2_LIB.BASEBOARD_FAB2(SCH_1):PAGE191
   B14 FM_SINT_PRSNT_N @BASEBOARD_FAB2_LIB.BASEBOARD_FAB2(SCH_1):FM_SINT_PRSNT_N    I59 @BASEBOARD_FAB2_LIB.BASEBOARD_FAB2(SCH_1):PAGE191
   A15 TP_CPLD1_PT24B @BASEBOARD_FAB2_LIB.BASEBOARD_FAB2(SCH_1):TP_CPLD1_PT24B    I59 @BASEBOARD_FAB2_LIB.BASEBOARD_FAB2(SCH_1):PAGE191
   A13 TP_CPLD1_PT24C_INITN @BASEBOARD_FAB2_LIB.BASEBOARD_FAB2(SCH_1):TP_CPLD1_PT24C_INITN    I59 @BASEBOARD_FAB2_LIB.BASEBOARD_FAB2(SCH_1):PAGE191
   C13 TP_CPLD1_PT24D_DONE @BASEBOARD_FAB2_LIB.BASEBOARD_FAB2(SCH_1):TP_CPLD1_PT24D_DONE    I59 @BASEBOARD_FAB2_LIB.BASEBOARD_FAB2(SCH_1):PAGE191
    B2    GND @BASEBOARD_FAB2_LIB.BASEBOARD_FAB2(SCH_1):GND    I14 @BASEBOARD_FAB2_LIB.BASEBOARD_FAB2(SCH_1):PAGE192
   B15    GND @BASEBOARD_FAB2_LIB.BASEBOARD_FAB2(SCH_1):GND    I14 @BASEBOARD_FAB2_LIB.BASEBOARD_FAB2(SCH_1):PAGE192
    C3    GND @BASEBOARD_FAB2_LIB.BASEBOARD_FAB2(SCH_1):GND    I14 @BASEBOARD_FAB2_LIB.BASEBOARD_FAB2(SCH_1):PAGE192
   C14    GND @BASEBOARD_FAB2_LIB.BASEBOARD_FAB2(SCH_1):GND    I14 @BASEBOARD_FAB2_LIB.BASEBOARD_FAB2(SCH_1):PAGE192
    D4    GND @BASEBOARD_FAB2_LIB.BASEBOARD_FAB2(SCH_1):GND    I14 @BASEBOARD_FAB2_LIB.BASEBOARD_FAB2(SCH_1):PAGE192
   D13    GND @BASEBOARD_FAB2_LIB.BASEBOARD_FAB2(SCH_1):GND    I14 @BASEBOARD_FAB2_LIB.BASEBOARD_FAB2(SCH_1):PAGE192
    E5    GND @BASEBOARD_FAB2_LIB.BASEBOARD_FAB2(SCH_1):GND    I14 @BASEBOARD_FAB2_LIB.BASEBOARD_FAB2(SCH_1):PAGE192
   E12    GND @BASEBOARD_FAB2_LIB.BASEBOARD_FAB2(SCH_1):GND    I14 @BASEBOARD_FAB2_LIB.BASEBOARD_FAB2(SCH_1):PAGE192
    F6    GND @BASEBOARD_FAB2_LIB.BASEBOARD_FAB2(SCH_1):GND    I14 @BASEBOARD_FAB2_LIB.BASEBOARD_FAB2(SCH_1):PAGE192
   F11    GND @BASEBOARD_FAB2_LIB.BASEBOARD_FAB2(SCH_1):GND    I14 @BASEBOARD_FAB2_LIB.BASEBOARD_FAB2(SCH_1):PAGE192
    H8    GND @BASEBOARD_FAB2_LIB.BASEBOARD_FAB2(SCH_1):GND    I14 @BASEBOARD_FAB2_LIB.BASEBOARD_FAB2(SCH_1):PAGE192
    H9    GND @BASEBOARD_FAB2_LIB.BASEBOARD_FAB2(SCH_1):GND    I14 @BASEBOARD_FAB2_LIB.BASEBOARD_FAB2(SCH_1):PAGE192
    J8    GND @BASEBOARD_FAB2_LIB.BASEBOARD_FAB2(SCH_1):GND    I14 @BASEBOARD_FAB2_LIB.BASEBOARD_FAB2(SCH_1):PAGE192
    J9    GND @BASEBOARD_FAB2_LIB.BASEBOARD_FAB2(SCH_1):GND    I14 @BASEBOARD_FAB2_LIB.BASEBOARD_FAB2(SCH_1):PAGE192
    L6    GND @BASEBOARD_FAB2_LIB.BASEBOARD_FAB2(SCH_1):GND    I14 @BASEBOARD_FAB2_LIB.BASEBOARD_FAB2(SCH_1):PAGE192
   L11    GND @BASEBOARD_FAB2_LIB.BASEBOARD_FAB2(SCH_1):GND    I14 @BASEBOARD_FAB2_LIB.BASEBOARD_FAB2(SCH_1):PAGE192
    M5    GND @BASEBOARD_FAB2_LIB.BASEBOARD_FAB2(SCH_1):GND    I14 @BASEBOARD_FAB2_LIB.BASEBOARD_FAB2(SCH_1):PAGE192
   M12    GND @BASEBOARD_FAB2_LIB.BASEBOARD_FAB2(SCH_1):GND    I14 @BASEBOARD_FAB2_LIB.BASEBOARD_FAB2(SCH_1):PAGE192
    N4    GND @BASEBOARD_FAB2_LIB.BASEBOARD_FAB2(SCH_1):GND    I14 @BASEBOARD_FAB2_LIB.BASEBOARD_FAB2(SCH_1):PAGE192
   N13    GND @BASEBOARD_FAB2_LIB.BASEBOARD_FAB2(SCH_1):GND    I14 @BASEBOARD_FAB2_LIB.BASEBOARD_FAB2(SCH_1):PAGE192
    P3    GND @BASEBOARD_FAB2_LIB.BASEBOARD_FAB2(SCH_1):GND    I14 @BASEBOARD_FAB2_LIB.BASEBOARD_FAB2(SCH_1):PAGE192
   P14    GND @BASEBOARD_FAB2_LIB.BASEBOARD_FAB2(SCH_1):GND    I14 @BASEBOARD_FAB2_LIB.BASEBOARD_FAB2(SCH_1):PAGE192
    R2    GND @BASEBOARD_FAB2_LIB.BASEBOARD_FAB2(SCH_1):GND    I14 @BASEBOARD_FAB2_LIB.BASEBOARD_FAB2(SCH_1):PAGE192
   R15    GND @BASEBOARD_FAB2_LIB.BASEBOARD_FAB2(SCH_1):GND    I14 @BASEBOARD_FAB2_LIB.BASEBOARD_FAB2(SCH_1):PAGE192
    A1 P3V3_STBY @BASEBOARD_FAB2_LIB.BASEBOARD_FAB2(SCH_1):P3V3_STBY    I14 @BASEBOARD_FAB2_LIB.BASEBOARD_FAB2(SCH_1):PAGE192
   A16 P3V3_STBY @BASEBOARD_FAB2_LIB.BASEBOARD_FAB2(SCH_1):P3V3_STBY    I14 @BASEBOARD_FAB2_LIB.BASEBOARD_FAB2(SCH_1):PAGE192
    T1 P3V3_STBY @BASEBOARD_FAB2_LIB.BASEBOARD_FAB2(SCH_1):P3V3_STBY    I14 @BASEBOARD_FAB2_LIB.BASEBOARD_FAB2(SCH_1):PAGE192
   T16 P3V3_STBY @BASEBOARD_FAB2_LIB.BASEBOARD_FAB2(SCH_1):P3V3_STBY    I14 @BASEBOARD_FAB2_LIB.BASEBOARD_FAB2(SCH_1):PAGE192
    G7 P3V3_STBY @BASEBOARD_FAB2_LIB.BASEBOARD_FAB2(SCH_1):P3V3_STBY    I14 @BASEBOARD_FAB2_LIB.BASEBOARD_FAB2(SCH_1):PAGE192
   G10 P3V3_STBY @BASEBOARD_FAB2_LIB.BASEBOARD_FAB2(SCH_1):P3V3_STBY    I14 @BASEBOARD_FAB2_LIB.BASEBOARD_FAB2(SCH_1):PAGE192
    K7 P3V3_STBY @BASEBOARD_FAB2_LIB.BASEBOARD_FAB2(SCH_1):P3V3_STBY    I14 @BASEBOARD_FAB2_LIB.BASEBOARD_FAB2(SCH_1):PAGE192
   K10 P3V3_STBY @BASEBOARD_FAB2_LIB.BASEBOARD_FAB2(SCH_1):P3V3_STBY    I14 @BASEBOARD_FAB2_LIB.BASEBOARD_FAB2(SCH_1):PAGE192
    G8 P3V3_STBY @BASEBOARD_FAB2_LIB.BASEBOARD_FAB2(SCH_1):P3V3_STBY    I14 @BASEBOARD_FAB2_LIB.BASEBOARD_FAB2(SCH_1):PAGE192
   D12 P3V3_STBY @BASEBOARD_FAB2_LIB.BASEBOARD_FAB2(SCH_1):P3V3_STBY    I14 @BASEBOARD_FAB2_LIB.BASEBOARD_FAB2(SCH_1):PAGE192
    G9 P3V3_STBY @BASEBOARD_FAB2_LIB.BASEBOARD_FAB2(SCH_1):P3V3_STBY    I14 @BASEBOARD_FAB2_LIB.BASEBOARD_FAB2(SCH_1):PAGE192
   E13 P3V3_STBY @BASEBOARD_FAB2_LIB.BASEBOARD_FAB2(SCH_1):P3V3_STBY    I14 @BASEBOARD_FAB2_LIB.BASEBOARD_FAB2(SCH_1):PAGE192
   H10 P3V3_STBY @BASEBOARD_FAB2_LIB.BASEBOARD_FAB2(SCH_1):P3V3_STBY    I14 @BASEBOARD_FAB2_LIB.BASEBOARD_FAB2(SCH_1):PAGE192
   J10 P3V3_STBY @BASEBOARD_FAB2_LIB.BASEBOARD_FAB2(SCH_1):P3V3_STBY    I14 @BASEBOARD_FAB2_LIB.BASEBOARD_FAB2(SCH_1):PAGE192
   M13 P3V3_STBY @BASEBOARD_FAB2_LIB.BASEBOARD_FAB2(SCH_1):P3V3_STBY    I14 @BASEBOARD_FAB2_LIB.BASEBOARD_FAB2(SCH_1):PAGE192
    K9 P3V3_STBY @BASEBOARD_FAB2_LIB.BASEBOARD_FAB2(SCH_1):P3V3_STBY    I14 @BASEBOARD_FAB2_LIB.BASEBOARD_FAB2(SCH_1):PAGE192
   N12 P3V3_STBY @BASEBOARD_FAB2_LIB.BASEBOARD_FAB2(SCH_1):P3V3_STBY    I14 @BASEBOARD_FAB2_LIB.BASEBOARD_FAB2(SCH_1):PAGE192
    K8 P3V3_STBY @BASEBOARD_FAB2_LIB.BASEBOARD_FAB2(SCH_1):P3V3_STBY    I14 @BASEBOARD_FAB2_LIB.BASEBOARD_FAB2(SCH_1):PAGE192
    N5 P3V3_STBY @BASEBOARD_FAB2_LIB.BASEBOARD_FAB2(SCH_1):P3V3_STBY    I14 @BASEBOARD_FAB2_LIB.BASEBOARD_FAB2(SCH_1):PAGE192
    J7 P3V3_STBY @BASEBOARD_FAB2_LIB.BASEBOARD_FAB2(SCH_1):P3V3_STBY    I14 @BASEBOARD_FAB2_LIB.BASEBOARD_FAB2(SCH_1):PAGE192
    H7 P3V3_STBY @BASEBOARD_FAB2_LIB.BASEBOARD_FAB2(SCH_1):P3V3_STBY    I14 @BASEBOARD_FAB2_LIB.BASEBOARD_FAB2(SCH_1):PAGE192
    E4 P3V3_STBY @BASEBOARD_FAB2_LIB.BASEBOARD_FAB2(SCH_1):P3V3_STBY    I14 @BASEBOARD_FAB2_LIB.BASEBOARD_FAB2(SCH_1):PAGE192
    D5 P3V3_STBY @BASEBOARD_FAB2_LIB.BASEBOARD_FAB2(SCH_1):P3V3_STBY    I14 @BASEBOARD_FAB2_LIB.BASEBOARD_FAB2(SCH_1):PAGE192
    A2     NC     NC    I14 @BASEBOARD_FAB2_LIB.BASEBOARD_FAB2(SCH_1):PAGE192
    M4 P3V3_STBY @BASEBOARD_FAB2_LIB.BASEBOARD_FAB2(SCH_1):P3V3_STBY    I14 @BASEBOARD_FAB2_LIB.BASEBOARD_FAB2(SCH_1):PAGE192

U8D8 TPS3700_SM-IC,H69492-001
     5    GND @BASEBOARD_FAB2_LIB.BASEBOARD_FAB2(SCH_1):GND   I104 @BASEBOARD_FAB2_LIB.BASEBOARD_FAB2(SCH_1):PAGE196
     4 A_PG_P12V_MAIN @BASEBOARD_FAB2_LIB.BASEBOARD_FAB2(SCH_1):A_PG_P12V_MAIN   I104 @BASEBOARD_FAB2_LIB.BASEBOARD_FAB2(SCH_1):PAGE196
     3 A_PG_P5V @BASEBOARD_FAB2_LIB.BASEBOARD_FAB2(SCH_1):A_PG_P5V   I104 @BASEBOARD_FAB2_LIB.BASEBOARD_FAB2(SCH_1):PAGE196
     6 PWRGD_P12V_MAIN_R @BASEBOARD_FAB2_LIB.BASEBOARD_FAB2(SCH_1):PWRGD_P12V_MAIN_R   I104 @BASEBOARD_FAB2_LIB.BASEBOARD_FAB2(SCH_1):PAGE196
     1 PWRGD_P5V_N @BASEBOARD_FAB2_LIB.BASEBOARD_FAB2(SCH_1):PWRGD_P5V_N   I104 @BASEBOARD_FAB2_LIB.BASEBOARD_FAB2(SCH_1):PAGE196
     2 P3V3_STBY @BASEBOARD_FAB2_LIB.BASEBOARD_FAB2(SCH_1):P3V3_STBY   I104 @BASEBOARD_FAB2_LIB.BASEBOARD_FAB2(SCH_1):PAGE196

U8E1 TTL08_QFN15-74LVC08A,IC,D90404B
    11 FM_FAST_PROCHOT_THROTTLE_IN_N @BASEBOARD_FAB2_LIB.BASEBOARD_FAB2(SCH_1):FM_FAST_PROCHOT_THROTTLE_IN_N    I12 @BASEBOARD_FAB2_LIB.BASEBOARD_FAB2(SCH_1):PAGE170
    13 FM_FAST_PROCHOT_AND_OUT_1_N @BASEBOARD_FAB2_LIB.BASEBOARD_FAB2(SCH_1):FM_FAST_PROCHOT_AND_OUT_1_N    I12 @BASEBOARD_FAB2_LIB.BASEBOARD_FAB2(SCH_1):PAGE170
    12 FM_FAST_PROCHOT_AND_OUT_0_N @BASEBOARD_FAB2_LIB.BASEBOARD_FAB2(SCH_1):FM_FAST_PROCHOT_AND_OUT_0_N    I12 @BASEBOARD_FAB2_LIB.BASEBOARD_FAB2(SCH_1):PAGE170
     8 FM_CTNR_PS_ON_R @BASEBOARD_FAB2_LIB.BASEBOARD_FAB2(SCH_1):FM_CTNR_PS_ON_R    I60 @BASEBOARD_FAB2_LIB.BASEBOARD_FAB2(SCH_1):PAGE181
    10 PWRGD_P12V_HSC_DLY @BASEBOARD_FAB2_LIB.BASEBOARD_FAB2(SCH_1):PWRGD_P12V_HSC_DLY    I60 @BASEBOARD_FAB2_LIB.BASEBOARD_FAB2(SCH_1):PAGE181
     9 FM_PS_EN @BASEBOARD_FAB2_LIB.BASEBOARD_FAB2(SCH_1):FM_PS_EN    I60 @BASEBOARD_FAB2_LIB.BASEBOARD_FAB2(SCH_1):PAGE181
     6 FM_FAST_PROCHOT_AND_OUT_1_N @BASEBOARD_FAB2_LIB.BASEBOARD_FAB2(SCH_1):FM_FAST_PROCHOT_AND_OUT_1_N    I11 @BASEBOARD_FAB2_LIB.BASEBOARD_FAB2(SCH_1):PAGE170
     5 FM_HSC_TIMER_EXP_N @BASEBOARD_FAB2_LIB.BASEBOARD_FAB2(SCH_1):FM_HSC_TIMER_EXP_N    I11 @BASEBOARD_FAB2_LIB.BASEBOARD_FAB2(SCH_1):PAGE170
     4 IRQ_UV_DETECT_N @BASEBOARD_FAB2_LIB.BASEBOARD_FAB2(SCH_1):IRQ_UV_DETECT_N    I11 @BASEBOARD_FAB2_LIB.BASEBOARD_FAB2(SCH_1):PAGE170
     3 FM_FAST_PROCHOT_AND_OUT_0_N @BASEBOARD_FAB2_LIB.BASEBOARD_FAB2(SCH_1):FM_FAST_PROCHOT_AND_OUT_0_N    I10 @BASEBOARD_FAB2_LIB.BASEBOARD_FAB2(SCH_1):PAGE170
     2 FM_OC_DETECT_N @BASEBOARD_FAB2_LIB.BASEBOARD_FAB2(SCH_1):FM_OC_DETECT_N    I10 @BASEBOARD_FAB2_LIB.BASEBOARD_FAB2(SCH_1):PAGE170
     1 IRQ_FORCE_NM_THROTTLE_N @BASEBOARD_FAB2_LIB.BASEBOARD_FAB2(SCH_1):IRQ_FORCE_NM_THROTTLE_N    I10 @BASEBOARD_FAB2_LIB.BASEBOARD_FAB2(SCH_1):PAGE170

U8E2 ADM809_SMLF-IC,D23047-001-GND=A
     3 PWRGD_P12V_HSC @BASEBOARD_FAB2_LIB.BASEBOARD_FAB2(SCH_1):PWRGD_P12V_HSC    I89 @BASEBOARD_FAB2_LIB.BASEBOARD_FAB2(SCH_1):PAGE196
     2 PWRGD_P12V_HSC_DLY_R @BASEBOARD_FAB2_LIB.BASEBOARD_FAB2(SCH_1):PWRGD_P12V_HSC_DLY_R    I89 @BASEBOARD_FAB2_LIB.BASEBOARD_FAB2(SCH_1):PAGE196

U8E3 TTL1G126_A_SOT-74HC1G126,IC,A7B
     1 RST_PLTRST_TOP_SWAP @BASEBOARD_FAB2_LIB.BASEBOARD_FAB2(SCH_1):RST_PLTRST_TOP_SWAP   I130 @BASEBOARD_FAB2_LIB.BASEBOARD_FAB2(SCH_1):PAGE136
     2 FM_BIOS_TOP_SWAP @BASEBOARD_FAB2_LIB.BASEBOARD_FAB2(SCH_1):FM_BIOS_TOP_SWAP   I130 @BASEBOARD_FAB2_LIB.BASEBOARD_FAB2(SCH_1):PAGE136
     4 FM_BIOS_TOP_SWAP_SPKR_R @BASEBOARD_FAB2_LIB.BASEBOARD_FAB2(SCH_1):FM_BIOS_TOP_SWAP_SPKR_R   I130 @BASEBOARD_FAB2_LIB.BASEBOARD_FAB2(SCH_1):PAGE136

U8E4 TTL1G126_A_SOT-74HC1G126,IC,A7B
     1 PU_TRI_STATE_EN @BASEBOARD_FAB2_LIB.BASEBOARD_FAB2(SCH_1):PU_TRI_STATE_EN     I1 @BASEBOARD_FAB2_LIB.BASEBOARD_FAB2(SCH_1):PAGE142
     2 FM_ALL_WAKE_N @BASEBOARD_FAB2_LIB.BASEBOARD_FAB2(SCH_1):FM_ALL_WAKE_N     I1 @BASEBOARD_FAB2_LIB.BASEBOARD_FAB2(SCH_1):PAGE142
     4 IRQ_LVC3_WAKE_R_N @BASEBOARD_FAB2_LIB.BASEBOARD_FAB2(SCH_1):IRQ_LVC3_WAKE_R_N     I1 @BASEBOARD_FAB2_LIB.BASEBOARD_FAB2(SCH_1):PAGE142

U8F1 PI3B3257A_TSSOPLF-IC,E16801-001
    16 P3V3_STBY @BASEBOARD_FAB2_LIB.BASEBOARD_FAB2(SCH_1):P3V3_STBY    I74 @BASEBOARD_FAB2_LIB.BASEBOARD_FAB2(SCH_1):PAGE154
     8    GND @BASEBOARD_FAB2_LIB.BASEBOARD_FAB2(SCH_1):GND    I74 @BASEBOARD_FAB2_LIB.BASEBOARD_FAB2(SCH_1):PAGE154
    15    GND @BASEBOARD_FAB2_LIB.BASEBOARD_FAB2(SCH_1):GND    I74 @BASEBOARD_FAB2_LIB.BASEBOARD_FAB2(SCH_1):PAGE154
     1 FM_BIOS_SPI_BMC_CTRL @BASEBOARD_FAB2_LIB.BASEBOARD_FAB2(SCH_1):FM_BIOS_SPI_BMC_CTRL    I74 @BASEBOARD_FAB2_LIB.BASEBOARD_FAB2(SCH_1):PAGE154
     4 SPI_SWITCH_CLK @BASEBOARD_FAB2_LIB.BASEBOARD_FAB2(SCH_1):SPI_SWITCH_CLK    I74 @BASEBOARD_FAB2_LIB.BASEBOARD_FAB2(SCH_1):PAGE154
     7 SPI_SWITCH_MOSI @BASEBOARD_FAB2_LIB.BASEBOARD_FAB2(SCH_1):SPI_SWITCH_MOSI    I74 @BASEBOARD_FAB2_LIB.BASEBOARD_FAB2(SCH_1):PAGE154
     9 SPI_SWITCH_CS0_N @BASEBOARD_FAB2_LIB.BASEBOARD_FAB2(SCH_1):SPI_SWITCH_CS0_N    I74 @BASEBOARD_FAB2_LIB.BASEBOARD_FAB2(SCH_1):PAGE154
    12 SPI_SWITCH_MISO @BASEBOARD_FAB2_LIB.BASEBOARD_FAB2(SCH_1):SPI_SWITCH_MISO    I74 @BASEBOARD_FAB2_LIB.BASEBOARD_FAB2(SCH_1):PAGE154
     2 SPI_PCH_CLK @BASEBOARD_FAB2_LIB.BASEBOARD_FAB2(SCH_1):SPI_PCH_CLK    I74 @BASEBOARD_FAB2_LIB.BASEBOARD_FAB2(SCH_1):PAGE154
     3 SPI_BMC_CLK @BASEBOARD_FAB2_LIB.BASEBOARD_FAB2(SCH_1):SPI_BMC_CLK    I74 @BASEBOARD_FAB2_LIB.BASEBOARD_FAB2(SCH_1):PAGE154
     5 SPI_PCH_MOSI @BASEBOARD_FAB2_LIB.BASEBOARD_FAB2(SCH_1):SPI_PCH_MOSI    I74 @BASEBOARD_FAB2_LIB.BASEBOARD_FAB2(SCH_1):PAGE154
     6 SPI_BMC_DO @BASEBOARD_FAB2_LIB.BASEBOARD_FAB2(SCH_1):SPI_BMC_DO    I74 @BASEBOARD_FAB2_LIB.BASEBOARD_FAB2(SCH_1):PAGE154
    11 SPI_PCH_CS0_N @BASEBOARD_FAB2_LIB.BASEBOARD_FAB2(SCH_1):SPI_PCH_CS0_N    I74 @BASEBOARD_FAB2_LIB.BASEBOARD_FAB2(SCH_1):PAGE154
    10 SPI_BMC_CS0_N @BASEBOARD_FAB2_LIB.BASEBOARD_FAB2(SCH_1):SPI_BMC_CS0_N    I74 @BASEBOARD_FAB2_LIB.BASEBOARD_FAB2(SCH_1):PAGE154
    14 SPI_PCH_MISO_R @BASEBOARD_FAB2_LIB.BASEBOARD_FAB2(SCH_1):SPI_PCH_MISO_R    I74 @BASEBOARD_FAB2_LIB.BASEBOARD_FAB2(SCH_1):PAGE154
    13 SPI_BMC_DI @BASEBOARD_FAB2_LIB.BASEBOARD_FAB2(SCH_1):SPI_BMC_DI    I74 @BASEBOARD_FAB2_LIB.BASEBOARD_FAB2(SCH_1):PAGE154

U8F2 W25Q128_SKT16-IC,H12709-001
     1 PU_SPI_BMC_BT_HOLD_N @BASEBOARD_FAB2_LIB.BASEBOARD_FAB2(SCH_1):PU_SPI_BMC_BT_HOLD_N    I32 @BASEBOARD_FAB2_LIB.BASEBOARD_FAB2(SCH_1):PAGE162
     2 P3V3_STBY @BASEBOARD_FAB2_LIB.BASEBOARD_FAB2(SCH_1):P3V3_STBY    I32 @BASEBOARD_FAB2_LIB.BASEBOARD_FAB2(SCH_1):PAGE162
     3 PU_SPI_FLASH_RESET_2_N @BASEBOARD_FAB2_LIB.BASEBOARD_FAB2(SCH_1):PU_SPI_FLASH_RESET_2_N    I32 @BASEBOARD_FAB2_LIB.BASEBOARD_FAB2(SCH_1):PAGE162
     4 TP_SPI_2_0 @BASEBOARD_FAB2_LIB.BASEBOARD_FAB2(SCH_1):TP_SPI_2_0    I32 @BASEBOARD_FAB2_LIB.BASEBOARD_FAB2(SCH_1):PAGE162
     5 TP_SPI_2_1 @BASEBOARD_FAB2_LIB.BASEBOARD_FAB2(SCH_1):TP_SPI_2_1    I32 @BASEBOARD_FAB2_LIB.BASEBOARD_FAB2(SCH_1):PAGE162
     6 TP_SPI_2_2 @BASEBOARD_FAB2_LIB.BASEBOARD_FAB2(SCH_1):TP_SPI_2_2    I32 @BASEBOARD_FAB2_LIB.BASEBOARD_FAB2(SCH_1):PAGE162
     7 SPI_BMC_BT_CS_N @BASEBOARD_FAB2_LIB.BASEBOARD_FAB2(SCH_1):SPI_BMC_BT_CS_N    I32 @BASEBOARD_FAB2_LIB.BASEBOARD_FAB2(SCH_1):PAGE162
     8 SPI_BMC_BT_DI_R @BASEBOARD_FAB2_LIB.BASEBOARD_FAB2(SCH_1):SPI_BMC_BT_DI_R    I32 @BASEBOARD_FAB2_LIB.BASEBOARD_FAB2(SCH_1):PAGE162
     9 PU_SPI_BMC_BT_WP_N @BASEBOARD_FAB2_LIB.BASEBOARD_FAB2(SCH_1):PU_SPI_BMC_BT_WP_N    I32 @BASEBOARD_FAB2_LIB.BASEBOARD_FAB2(SCH_1):PAGE162
    10    GND @BASEBOARD_FAB2_LIB.BASEBOARD_FAB2(SCH_1):GND    I32 @BASEBOARD_FAB2_LIB.BASEBOARD_FAB2(SCH_1):PAGE162
    11 TP_SPI_2_3 @BASEBOARD_FAB2_LIB.BASEBOARD_FAB2(SCH_1):TP_SPI_2_3    I32 @BASEBOARD_FAB2_LIB.BASEBOARD_FAB2(SCH_1):PAGE162
    12 TP_SPI_2_4 @BASEBOARD_FAB2_LIB.BASEBOARD_FAB2(SCH_1):TP_SPI_2_4    I32 @BASEBOARD_FAB2_LIB.BASEBOARD_FAB2(SCH_1):PAGE162
    13 TP_SPI_2_5 @BASEBOARD_FAB2_LIB.BASEBOARD_FAB2(SCH_1):TP_SPI_2_5    I32 @BASEBOARD_FAB2_LIB.BASEBOARD_FAB2(SCH_1):PAGE162
    14 TP_SPI_2_6 @BASEBOARD_FAB2_LIB.BASEBOARD_FAB2(SCH_1):TP_SPI_2_6    I32 @BASEBOARD_FAB2_LIB.BASEBOARD_FAB2(SCH_1):PAGE162
    15 SPI_BMC_BT_DO @BASEBOARD_FAB2_LIB.BASEBOARD_FAB2(SCH_1):SPI_BMC_BT_DO    I32 @BASEBOARD_FAB2_LIB.BASEBOARD_FAB2(SCH_1):PAGE162
    16 SPI_BMC_BT_CLK @BASEBOARD_FAB2_LIB.BASEBOARD_FAB2(SCH_1):SPI_BMC_BT_CLK    I32 @BASEBOARD_FAB2_LIB.BASEBOARD_FAB2(SCH_1):PAGE162

U8F3 SN74LVC2G07DCKR-GP_DISCRET-G4-A
     1 RST_BMC_SYSRST_BTN_OUT_N @BASEBOARD_FAB2_LIB.BASEBOARD_FAB2(SCH_1):RST_BMC_SYSRST_BTN_OUT_N   I340 @BASEBOARD_FAB2_LIB.BASEBOARD_FAB2(SCH_1):PAGE156
     2    GND @BASEBOARD_FAB2_LIB.BASEBOARD_FAB2(SCH_1):GND   I340 @BASEBOARD_FAB2_LIB.BASEBOARD_FAB2(SCH_1):PAGE156
     3 FM_BMC_PWRBTN_OUT_N @BASEBOARD_FAB2_LIB.BASEBOARD_FAB2(SCH_1):FM_BMC_PWRBTN_OUT_N   I340 @BASEBOARD_FAB2_LIB.BASEBOARD_FAB2(SCH_1):PAGE156
     4 FM_PCH_PWRBTN_R_N @BASEBOARD_FAB2_LIB.BASEBOARD_FAB2(SCH_1):FM_PCH_PWRBTN_R_N   I340 @BASEBOARD_FAB2_LIB.BASEBOARD_FAB2(SCH_1):PAGE156
     5 P3V3_STBY @BASEBOARD_FAB2_LIB.BASEBOARD_FAB2(SCH_1):P3V3_STBY   I340 @BASEBOARD_FAB2_LIB.BASEBOARD_FAB2(SCH_1):PAGE156
     6 RST_BMC_SYSRST_BTN_OUT_B_R_N @BASEBOARD_FAB2_LIB.BASEBOARD_FAB2(SCH_1):RST_BMC_SYSRST_BTN_OUT_B_R_N   I340 @BASEBOARD_FAB2_LIB.BASEBOARD_FAB2(SCH_1):PAGE156

U8G1 SN74LVC2G07DCKR-GP_DISCRET-G4-A
     1 RST_PCH_SYSRST_BTN_OUT_N @BASEBOARD_FAB2_LIB.BASEBOARD_FAB2(SCH_1):RST_PCH_SYSRST_BTN_OUT_N   I342 @BASEBOARD_FAB2_LIB.BASEBOARD_FAB2(SCH_1):PAGE156
     2    GND @BASEBOARD_FAB2_LIB.BASEBOARD_FAB2(SCH_1):GND   I342 @BASEBOARD_FAB2_LIB.BASEBOARD_FAB2(SCH_1):PAGE156
     3 FM_PCH_PWRBTN_OUT_N @BASEBOARD_FAB2_LIB.BASEBOARD_FAB2(SCH_1):FM_PCH_PWRBTN_OUT_N   I342 @BASEBOARD_FAB2_LIB.BASEBOARD_FAB2(SCH_1):PAGE156
     4 FM_PCH_PWRBTN_R_N @BASEBOARD_FAB2_LIB.BASEBOARD_FAB2(SCH_1):FM_PCH_PWRBTN_R_N   I342 @BASEBOARD_FAB2_LIB.BASEBOARD_FAB2(SCH_1):PAGE156
     5 P3V3_STBY @BASEBOARD_FAB2_LIB.BASEBOARD_FAB2(SCH_1):P3V3_STBY   I342 @BASEBOARD_FAB2_LIB.BASEBOARD_FAB2(SCH_1):PAGE156
     6 RST_BMC_SYSRST_BTN_OUT_B_R_N @BASEBOARD_FAB2_LIB.BASEBOARD_FAB2(SCH_1):RST_BMC_SYSRST_BTN_OUT_B_R_N   I342 @BASEBOARD_FAB2_LIB.BASEBOARD_FAB2(SCH_1):PAGE156

U8G2 TTL1G07_A_SOP-74LVC1G07,IC,C88B
     2 FAN_PWM_OUT_SYS0 @BASEBOARD_FAB2_LIB.BASEBOARD_FAB2(SCH_1):FAN_PWM_OUT_SYS0    I88 @BASEBOARD_FAB2_LIB.BASEBOARD_FAB2(SCH_1):PAGE161
     4 FAN_PWM_OUT_SYS0_BUF @BASEBOARD_FAB2_LIB.BASEBOARD_FAB2(SCH_1):FAN_PWM_OUT_SYS0_BUF    I88 @BASEBOARD_FAB2_LIB.BASEBOARD_FAB2(SCH_1):PAGE161

U8G3 TTL1G07_A_SOP-74LVC1G07,IC,C88B
     2 FAN_PWM_OUT_SYS1 @BASEBOARD_FAB2_LIB.BASEBOARD_FAB2(SCH_1):FAN_PWM_OUT_SYS1    I92 @BASEBOARD_FAB2_LIB.BASEBOARD_FAB2(SCH_1):PAGE161
     4 FAN_PWM_OUT_SYS1_BUF @BASEBOARD_FAB2_LIB.BASEBOARD_FAB2(SCH_1):FAN_PWM_OUT_SYS1_BUF    I92 @BASEBOARD_FAB2_LIB.BASEBOARD_FAB2(SCH_1):PAGE161

U8W1 74CBTLV1G125_SMLF-IC,C88177-00A
     4 JTAG_RISER_TDI_R @BASEBOARD_FAB2_LIB.BASEBOARD_FAB2(SCH_1):JTAG_RISER_TDI_R    I64 @BASEBOARD_FAB2_LIB.BASEBOARD_FAB2(SCH_1):PAGE245
     1 JTAG_RISER_N @BASEBOARD_FAB2_LIB.BASEBOARD_FAB2(SCH_1):JTAG_RISER_N    I64 @BASEBOARD_FAB2_LIB.BASEBOARD_FAB2(SCH_1):PAGE245
     2 JTAG_PLD_TDO @BASEBOARD_FAB2_LIB.BASEBOARD_FAB2(SCH_1):JTAG_PLD_TDO    I64 @BASEBOARD_FAB2_LIB.BASEBOARD_FAB2(SCH_1):PAGE245

U8W2 NC7SB3157_SMLF-IC,C99406-001
     6 JTAG_RISER_N @BASEBOARD_FAB2_LIB.BASEBOARD_FAB2(SCH_1):JTAG_RISER_N    I66 @BASEBOARD_FAB2_LIB.BASEBOARD_FAB2(SCH_1):PAGE245
     3 JTAG_RISER_TDO_R @BASEBOARD_FAB2_LIB.BASEBOARD_FAB2(SCH_1):JTAG_RISER_TDO_R    I66 @BASEBOARD_FAB2_LIB.BASEBOARD_FAB2(SCH_1):PAGE245
     1 JTAG_PLD_TDO @BASEBOARD_FAB2_LIB.BASEBOARD_FAB2(SCH_1):JTAG_PLD_TDO    I66 @BASEBOARD_FAB2_LIB.BASEBOARD_FAB2(SCH_1):PAGE245
     4 JTAG_PLD_TDO_MUX_R @BASEBOARD_FAB2_LIB.BASEBOARD_FAB2(SCH_1):JTAG_PLD_TDO_MUX_R    I66 @BASEBOARD_FAB2_LIB.BASEBOARD_FAB2(SCH_1):PAGE245
     5 P3V3_STBY @BASEBOARD_FAB2_LIB.BASEBOARD_FAB2(SCH_1):P3V3_STBY    I66 @BASEBOARD_FAB2_LIB.BASEBOARD_FAB2(SCH_1):PAGE245
     2    GND @BASEBOARD_FAB2_LIB.BASEBOARD_FAB2(SCH_1):GND    I66 @BASEBOARD_FAB2_LIB.BASEBOARD_FAB2(SCH_1):PAGE245

U9A1 TTL1G07_A_SOP-74LVC1G07,IC,C88B
     2 SPA_5V_SIN_SW_D @BASEBOARD_FAB2_LIB.BASEBOARD_FAB2(SCH_1):SPA_5V_SIN_SW_D   I178 @BASEBOARD_FAB2_LIB.BASEBOARD_FAB2(SCH_1):PAGE155
     4 SPA_SIN_SW_R @BASEBOARD_FAB2_LIB.BASEBOARD_FAB2(SCH_1):SPA_SIN_SW_R   I178 @BASEBOARD_FAB2_LIB.BASEBOARD_FAB2(SCH_1):PAGE155

U9A3 TC7PZ14FU-GP_DISCRET-GA1-TC7PZA
     1 FP_RST_BTN_R_N @BASEBOARD_FAB2_LIB.BASEBOARD_FAB2(SCH_1):FP_RST_BTN_R_N    I93 @BASEBOARD_FAB2_LIB.BASEBOARD_FAB2(SCH_1):PAGE175
     2    GND @BASEBOARD_FAB2_LIB.BASEBOARD_FAB2(SCH_1):GND    I93 @BASEBOARD_FAB2_LIB.BASEBOARD_FAB2(SCH_1):PAGE175
     3 FP_RST_BTN_BUF1_N @BASEBOARD_FAB2_LIB.BASEBOARD_FAB2(SCH_1):FP_RST_BTN_BUF1_N    I93 @BASEBOARD_FAB2_LIB.BASEBOARD_FAB2(SCH_1):PAGE175
     4 RST_SYSTEM_BTN_BUF_N @BASEBOARD_FAB2_LIB.BASEBOARD_FAB2(SCH_1):RST_SYSTEM_BTN_BUF_N    I93 @BASEBOARD_FAB2_LIB.BASEBOARD_FAB2(SCH_1):PAGE175
     5 P3V3_STBY @BASEBOARD_FAB2_LIB.BASEBOARD_FAB2(SCH_1):P3V3_STBY    I93 @BASEBOARD_FAB2_LIB.BASEBOARD_FAB2(SCH_1):PAGE175
     6 FP_RST_BTN_BUF1_N @BASEBOARD_FAB2_LIB.BASEBOARD_FAB2(SCH_1):FP_RST_BTN_BUF1_N    I93 @BASEBOARD_FAB2_LIB.BASEBOARD_FAB2(SCH_1):PAGE175

U9A4 TC7PZ14FU-GP_DISCRET-GA1-TC7PZA
     1 FP_PWR_BTN_R1_N @BASEBOARD_FAB2_LIB.BASEBOARD_FAB2(SCH_1):FP_PWR_BTN_R1_N    I97 @BASEBOARD_FAB2_LIB.BASEBOARD_FAB2(SCH_1):PAGE175
     2    GND @BASEBOARD_FAB2_LIB.BASEBOARD_FAB2(SCH_1):GND    I97 @BASEBOARD_FAB2_LIB.BASEBOARD_FAB2(SCH_1):PAGE175
     3 FP_PWR_BTN_BUF1_N @BASEBOARD_FAB2_LIB.BASEBOARD_FAB2(SCH_1):FP_PWR_BTN_BUF1_N    I97 @BASEBOARD_FAB2_LIB.BASEBOARD_FAB2(SCH_1):PAGE175
     4 FM_PWR_BTN_R_N @BASEBOARD_FAB2_LIB.BASEBOARD_FAB2(SCH_1):FM_PWR_BTN_R_N    I97 @BASEBOARD_FAB2_LIB.BASEBOARD_FAB2(SCH_1):PAGE175
     5 P3V3_STBY @BASEBOARD_FAB2_LIB.BASEBOARD_FAB2(SCH_1):P3V3_STBY    I97 @BASEBOARD_FAB2_LIB.BASEBOARD_FAB2(SCH_1):PAGE175
     6 FP_PWR_BTN_BUF1_N @BASEBOARD_FAB2_LIB.BASEBOARD_FAB2(SCH_1):FP_PWR_BTN_BUF1_N    I97 @BASEBOARD_FAB2_LIB.BASEBOARD_FAB2(SCH_1):PAGE175

U9A5 74CBTLV1G125_SMLF-IC,C88177-00A
     4    GND @BASEBOARD_FAB2_LIB.BASEBOARD_FAB2(SCH_1):GND   I185 @BASEBOARD_FAB2_LIB.BASEBOARD_FAB2(SCH_1):PAGE113
     1 FM_CPU0_OR_CPU1_MCP_PRES @BASEBOARD_FAB2_LIB.BASEBOARD_FAB2(SCH_1):FM_CPU0_OR_CPU1_MCP_PRES   I185 @BASEBOARD_FAB2_LIB.BASEBOARD_FAB2(SCH_1):PAGE113
     2 JTAG_MCP_TCK_R1 @BASEBOARD_FAB2_LIB.BASEBOARD_FAB2(SCH_1):JTAG_MCP_TCK_R1   I185 @BASEBOARD_FAB2_LIB.BASEBOARD_FAB2(SCH_1):PAGE113

U9B4 TMP421_TSSOP-IC,G62962-001
     3 PU_TMP421_1_A1 @BASEBOARD_FAB2_LIB.BASEBOARD_FAB2(SCH_1):PU_TMP421_1_A1     I1 @BASEBOARD_FAB2_LIB.BASEBOARD_FAB2(SCH_1):PAGE167
     4 PD_TMP421_1_A0 @BASEBOARD_FAB2_LIB.BASEBOARD_FAB2(SCH_1):PD_TMP421_1_A0     I1 @BASEBOARD_FAB2_LIB.BASEBOARD_FAB2(SCH_1):PAGE167
     2 ISENSE_TMP421_1_DXN @BASEBOARD_FAB2_LIB.BASEBOARD_FAB2(SCH_1):ISENSE_TMP421_1_DXN     I1 @BASEBOARD_FAB2_LIB.BASEBOARD_FAB2(SCH_1):PAGE167
     1 ISENSE_TMP421_1_DXP @BASEBOARD_FAB2_LIB.BASEBOARD_FAB2(SCH_1):ISENSE_TMP421_1_DXP     I1 @BASEBOARD_FAB2_LIB.BASEBOARD_FAB2(SCH_1):PAGE167
     5    GND @BASEBOARD_FAB2_LIB.BASEBOARD_FAB2(SCH_1):GND     I1 @BASEBOARD_FAB2_LIB.BASEBOARD_FAB2(SCH_1):PAGE167
     7 SMB_SENSOR_TMP421_1_SCL @BASEBOARD_FAB2_LIB.BASEBOARD_FAB2(SCH_1):SMB_SENSOR_TMP421_1_SCL     I1 @BASEBOARD_FAB2_LIB.BASEBOARD_FAB2(SCH_1):PAGE167
     6 SMB_SENSOR_TMP421_1_SDA @BASEBOARD_FAB2_LIB.BASEBOARD_FAB2(SCH_1):SMB_SENSOR_TMP421_1_SDA     I1 @BASEBOARD_FAB2_LIB.BASEBOARD_FAB2(SCH_1):PAGE167
     8 P3V3_STBY @BASEBOARD_FAB2_LIB.BASEBOARD_FAB2(SCH_1):P3V3_STBY     I1 @BASEBOARD_FAB2_LIB.BASEBOARD_FAB2(SCH_1):PAGE167

U9E1 M25PE16_SM-IC,H77797-001
     1 SPI_NIC_CS_N @BASEBOARD_FAB2_LIB.BASEBOARD_FAB2(SCH_1):SPI_NIC_CS_N     I1 @BASEBOARD_FAB2_LIB.BASEBOARD_FAB2(SCH_1):PAGE140
     7 PU_NV_HOLD_N @BASEBOARD_FAB2_LIB.BASEBOARD_FAB2(SCH_1):PU_NV_HOLD_N     I1 @BASEBOARD_FAB2_LIB.BASEBOARD_FAB2(SCH_1):PAGE140
     6 SPI_NIC_SCLK @BASEBOARD_FAB2_LIB.BASEBOARD_FAB2(SCH_1):SPI_NIC_SCLK     I1 @BASEBOARD_FAB2_LIB.BASEBOARD_FAB2(SCH_1):PAGE140
     5 SPI_NIC_MOSI @BASEBOARD_FAB2_LIB.BASEBOARD_FAB2(SCH_1):SPI_NIC_MOSI     I1 @BASEBOARD_FAB2_LIB.BASEBOARD_FAB2(SCH_1):PAGE140
     2 SPI_NIC_MISO_R @BASEBOARD_FAB2_LIB.BASEBOARD_FAB2(SCH_1):SPI_NIC_MISO_R     I1 @BASEBOARD_FAB2_LIB.BASEBOARD_FAB2(SCH_1):PAGE140
     8 P3V3_STBY @BASEBOARD_FAB2_LIB.BASEBOARD_FAB2(SCH_1):P3V3_STBY     I1 @BASEBOARD_FAB2_LIB.BASEBOARD_FAB2(SCH_1):PAGE140
     4    GND @BASEBOARD_FAB2_LIB.BASEBOARD_FAB2(SCH_1):GND     I1 @BASEBOARD_FAB2_LIB.BASEBOARD_FAB2(SCH_1):PAGE140
     3 PU_NV_WP_N @BASEBOARD_FAB2_LIB.BASEBOARD_FAB2(SCH_1):PU_NV_WP_N     I1 @BASEBOARD_FAB2_LIB.BASEBOARD_FAB2(SCH_1):PAGE140

U9F1 FSA3357_SM-IC,C63273-001
     7 UART_MUX_IN_R @BASEBOARD_FAB2_LIB.BASEBOARD_FAB2(SCH_1):UART_MUX_IN_R    I75 @BASEBOARD_FAB2_LIB.BASEBOARD_FAB2(SCH_1):PAGE158
     1 SP2_BMC_CM_UART_RX_R @BASEBOARD_FAB2_LIB.BASEBOARD_FAB2(SCH_1):SP2_BMC_CM_UART_RX_R    I75 @BASEBOARD_FAB2_LIB.BASEBOARD_FAB2(SCH_1):PAGE158
     2 UART_BMC_RXD5 @BASEBOARD_FAB2_LIB.BASEBOARD_FAB2(SCH_1):UART_BMC_RXD5    I75 @BASEBOARD_FAB2_LIB.BASEBOARD_FAB2(SCH_1):PAGE158
     3 SP1_BMC_HOST_UART_RX @BASEBOARD_FAB2_LIB.BASEBOARD_FAB2(SCH_1):SP1_BMC_HOST_UART_RX    I75 @BASEBOARD_FAB2_LIB.BASEBOARD_FAB2(SCH_1):PAGE158
     4    GND @BASEBOARD_FAB2_LIB.BASEBOARD_FAB2(SCH_1):GND    I75 @BASEBOARD_FAB2_LIB.BASEBOARD_FAB2(SCH_1):PAGE158
     6 FM_UARTSW_LSB_N @BASEBOARD_FAB2_LIB.BASEBOARD_FAB2(SCH_1):FM_UARTSW_LSB_N    I75 @BASEBOARD_FAB2_LIB.BASEBOARD_FAB2(SCH_1):PAGE158
     5 FM_UARTSW_MSB_N @BASEBOARD_FAB2_LIB.BASEBOARD_FAB2(SCH_1):FM_UARTSW_MSB_N    I75 @BASEBOARD_FAB2_LIB.BASEBOARD_FAB2(SCH_1):PAGE158
     8 P3V3_STBY @BASEBOARD_FAB2_LIB.BASEBOARD_FAB2(SCH_1):P3V3_STBY    I75 @BASEBOARD_FAB2_LIB.BASEBOARD_FAB2(SCH_1):PAGE158

U9F2 FSA3357_SM-IC,C63273-001
     7 UART_MUX_OUT_R @BASEBOARD_FAB2_LIB.BASEBOARD_FAB2(SCH_1):UART_MUX_OUT_R    I74 @BASEBOARD_FAB2_LIB.BASEBOARD_FAB2(SCH_1):PAGE158
     1 SP2_BMC_CM_UART_TX_R @BASEBOARD_FAB2_LIB.BASEBOARD_FAB2(SCH_1):SP2_BMC_CM_UART_TX_R    I74 @BASEBOARD_FAB2_LIB.BASEBOARD_FAB2(SCH_1):PAGE158
     2 UART_BMC_TXD5 @BASEBOARD_FAB2_LIB.BASEBOARD_FAB2(SCH_1):UART_BMC_TXD5    I74 @BASEBOARD_FAB2_LIB.BASEBOARD_FAB2(SCH_1):PAGE158
     3 SP1_BMC_HOST_UART_TX @BASEBOARD_FAB2_LIB.BASEBOARD_FAB2(SCH_1):SP1_BMC_HOST_UART_TX    I74 @BASEBOARD_FAB2_LIB.BASEBOARD_FAB2(SCH_1):PAGE158
     4    GND @BASEBOARD_FAB2_LIB.BASEBOARD_FAB2(SCH_1):GND    I74 @BASEBOARD_FAB2_LIB.BASEBOARD_FAB2(SCH_1):PAGE158
     6 FM_UARTSW_LSB_N @BASEBOARD_FAB2_LIB.BASEBOARD_FAB2(SCH_1):FM_UARTSW_LSB_N    I74 @BASEBOARD_FAB2_LIB.BASEBOARD_FAB2(SCH_1):PAGE158
     5 FM_UARTSW_MSB_N @BASEBOARD_FAB2_LIB.BASEBOARD_FAB2(SCH_1):FM_UARTSW_MSB_N    I74 @BASEBOARD_FAB2_LIB.BASEBOARD_FAB2(SCH_1):PAGE158
     8 P3V3_STBY @BASEBOARD_FAB2_LIB.BASEBOARD_FAB2(SCH_1):P3V3_STBY    I74 @BASEBOARD_FAB2_LIB.BASEBOARD_FAB2(SCH_1):PAGE158

U9F3 TTL1G07_A_SOP-74LVC1G07,IC,C88B
     2 RST_BMC_DDR3_BUF_IN_N @BASEBOARD_FAB2_LIB.BASEBOARD_FAB2(SCH_1):RST_BMC_DDR3_BUF_IN_N    I56 @BASEBOARD_FAB2_LIB.BASEBOARD_FAB2(SCH_1):PAGE151
     4 RST_BMC_DDR3_R_N @BASEBOARD_FAB2_LIB.BASEBOARD_FAB2(SCH_1):RST_BMC_DDR3_R_N    I56 @BASEBOARD_FAB2_LIB.BASEBOARD_FAB2(SCH_1):PAGE151

U9G1 GTL2014_SM-IC,D66151-001
    13 H_CPU1_KLM_MEMHOT_LVT3_R_N @BASEBOARD_FAB2_LIB.BASEBOARD_FAB2(SCH_1):H_CPU1_KLM_MEMHOT_LVT3_R_N     I1 @BASEBOARD_FAB2_LIB.BASEBOARD_FAB2(SCH_1):PAGE152
    12 H_CPU1_GHJ_MEMHOT_LVT3_R_N @BASEBOARD_FAB2_LIB.BASEBOARD_FAB2(SCH_1):H_CPU1_GHJ_MEMHOT_LVT3_R_N     I1 @BASEBOARD_FAB2_LIB.BASEBOARD_FAB2(SCH_1):PAGE152
    10 H_CPU0_DEF_MEMHOT_LVT3_R_N @BASEBOARD_FAB2_LIB.BASEBOARD_FAB2(SCH_1):H_CPU0_DEF_MEMHOT_LVT3_R_N     I1 @BASEBOARD_FAB2_LIB.BASEBOARD_FAB2(SCH_1):PAGE152
     9 H_CPU0_ABC_MEMHOT_LVT3_R_N @BASEBOARD_FAB2_LIB.BASEBOARD_FAB2(SCH_1):H_CPU0_ABC_MEMHOT_LVT3_R_N     I1 @BASEBOARD_FAB2_LIB.BASEBOARD_FAB2(SCH_1):PAGE152
     2 H_CPU1_MEMKLM_MEMHOT_G_R_N @BASEBOARD_FAB2_LIB.BASEBOARD_FAB2(SCH_1):H_CPU1_MEMKLM_MEMHOT_G_R_N     I1 @BASEBOARD_FAB2_LIB.BASEBOARD_FAB2(SCH_1):PAGE152
     3 H_CPU1_MEMGHJ_MEMHOT_G_R_N @BASEBOARD_FAB2_LIB.BASEBOARD_FAB2(SCH_1):H_CPU1_MEMGHJ_MEMHOT_G_R_N     I1 @BASEBOARD_FAB2_LIB.BASEBOARD_FAB2(SCH_1):PAGE152
     5 H_CPU0_MEMDEF_MEMHOT_G_R_N @BASEBOARD_FAB2_LIB.BASEBOARD_FAB2(SCH_1):H_CPU0_MEMDEF_MEMHOT_G_R_N     I1 @BASEBOARD_FAB2_LIB.BASEBOARD_FAB2(SCH_1):PAGE152
     6 H_CPU0_MEMABC_MEMHOT_G_R_N @BASEBOARD_FAB2_LIB.BASEBOARD_FAB2(SCH_1):H_CPU0_MEMABC_MEMHOT_G_R_N     I1 @BASEBOARD_FAB2_LIB.BASEBOARD_FAB2(SCH_1):PAGE152
     1 PD_DIR_2 @BASEBOARD_FAB2_LIB.BASEBOARD_FAB2(SCH_1):PD_DIR_2     I1 @BASEBOARD_FAB2_LIB.BASEBOARD_FAB2(SCH_1):PAGE152
    11    GND @BASEBOARD_FAB2_LIB.BASEBOARD_FAB2(SCH_1):GND     I1 @BASEBOARD_FAB2_LIB.BASEBOARD_FAB2(SCH_1):PAGE152
     8    GND @BASEBOARD_FAB2_LIB.BASEBOARD_FAB2(SCH_1):GND     I1 @BASEBOARD_FAB2_LIB.BASEBOARD_FAB2(SCH_1):PAGE152
     7    GND @BASEBOARD_FAB2_LIB.BASEBOARD_FAB2(SCH_1):GND     I1 @BASEBOARD_FAB2_LIB.BASEBOARD_FAB2(SCH_1):PAGE152
    14   P3V3 @BASEBOARD_FAB2_LIB.BASEBOARD_FAB2(SCH_1):P3V3     I1 @BASEBOARD_FAB2_LIB.BASEBOARD_FAB2(SCH_1):PAGE152
     4 P0V7_GTL2014_2 @BASEBOARD_FAB2_LIB.BASEBOARD_FAB2(SCH_1):P0V7_GTL2014_2     I1 @BASEBOARD_FAB2_LIB.BASEBOARD_FAB2(SCH_1):PAGE152

U9P1 TPS3700_SM-IC,H69492-001
     5    GND @BASEBOARD_FAB2_LIB.BASEBOARD_FAB2(SCH_1):GND   I163 @BASEBOARD_FAB2_LIB.BASEBOARD_FAB2(SCH_1):PAGE200
     4 A_P12V_STBY_ADR_TRIGGER @BASEBOARD_FAB2_LIB.BASEBOARD_FAB2(SCH_1):A_P12V_STBY_ADR_TRIGGER   I163 @BASEBOARD_FAB2_LIB.BASEBOARD_FAB2(SCH_1):PAGE200
     3 A_P12V_STBY_FP_TRIGGER @BASEBOARD_FAB2_LIB.BASEBOARD_FAB2(SCH_1):A_P12V_STBY_FP_TRIGGER   I163 @BASEBOARD_FAB2_LIB.BASEBOARD_FAB2(SCH_1):PAGE200
     6 FM_UV_ADR_TRIGGER_N @BASEBOARD_FAB2_LIB.BASEBOARD_FAB2(SCH_1):FM_UV_ADR_TRIGGER_N   I163 @BASEBOARD_FAB2_LIB.BASEBOARD_FAB2(SCH_1):PAGE200
     1 A_P12V_STBY_FPH_GATE @BASEBOARD_FAB2_LIB.BASEBOARD_FAB2(SCH_1):A_P12V_STBY_FPH_GATE   I163 @BASEBOARD_FAB2_LIB.BASEBOARD_FAB2(SCH_1):PAGE200
     2 P12V_STBY @BASEBOARD_FAB2_LIB.BASEBOARD_FAB2(SCH_1):P12V_STBY   I163 @BASEBOARD_FAB2_LIB.BASEBOARD_FAB2(SCH_1):PAGE200

U9P2 TPS3700_SM-IC,H69492-001
     5    GND @BASEBOARD_FAB2_LIB.BASEBOARD_FAB2(SCH_1):GND   I200 @BASEBOARD_FAB2_LIB.BASEBOARD_FAB2(SCH_1):PAGE200
     4 A_HSC_INAP @BASEBOARD_FAB2_LIB.BASEBOARD_FAB2(SCH_1):A_HSC_INAP   I200 @BASEBOARD_FAB2_LIB.BASEBOARD_FAB2(SCH_1):PAGE200
     3 A_HSC_TIMER_R @BASEBOARD_FAB2_LIB.BASEBOARD_FAB2(SCH_1):A_HSC_TIMER_R   I200 @BASEBOARD_FAB2_LIB.BASEBOARD_FAB2(SCH_1):PAGE200
     6 PWRGD_DSW_PWROK @BASEBOARD_FAB2_LIB.BASEBOARD_FAB2(SCH_1):PWRGD_DSW_PWROK   I200 @BASEBOARD_FAB2_LIB.BASEBOARD_FAB2(SCH_1):PAGE200
     1 FM_HSC_TIMER_EXP_N @BASEBOARD_FAB2_LIB.BASEBOARD_FAB2(SCH_1):FM_HSC_TIMER_EXP_N   I200 @BASEBOARD_FAB2_LIB.BASEBOARD_FAB2(SCH_1):PAGE200
     2 P3V3_STBY @BASEBOARD_FAB2_LIB.BASEBOARD_FAB2(SCH_1):P3V3_STBY   I200 @BASEBOARD_FAB2_LIB.BASEBOARD_FAB2(SCH_1):PAGE200

U10W1 TTL1G07_A_SOP-74LVC1G07,IC,C88B
     2 PUMP_PWM_OUT @BASEBOARD_FAB2_LIB.BASEBOARD_FAB2(SCH_1):PUMP_PWM_OUT    I19 @BASEBOARD_FAB2_LIB.BASEBOARD_FAB2(SCH_1):PAGE251
     4 PUMP_PWM_OUT_BUF @BASEBOARD_FAB2_LIB.BASEBOARD_FAB2(SCH_1):PUMP_PWM_OUT_BUF    I19 @BASEBOARD_FAB2_LIB.BASEBOARD_FAB2(SCH_1):PAGE251

U14E2 TTL1G08_SOTLF-NC7SZ08,IC,D1032C
     4 RST_PCIE_M2_DEV_IC_N @BASEBOARD_FAB2_LIB.BASEBOARD_FAB2(SCH_1):RST_PCIE_M2_DEV_IC_N    I11 @BASEBOARD_FAB2_LIB.BASEBOARD_FAB2(SCH_1):PAGE248
     1 RST_PCIE_M2_DEV_N @BASEBOARD_FAB2_LIB.BASEBOARD_FAB2(SCH_1):RST_PCIE_M2_DEV_N    I11 @BASEBOARD_FAB2_LIB.BASEBOARD_FAB2(SCH_1):PAGE248
     2 RST_PCIE_M2_DEV_AND @BASEBOARD_FAB2_LIB.BASEBOARD_FAB2(SCH_1):RST_PCIE_M2_DEV_AND    I11 @BASEBOARD_FAB2_LIB.BASEBOARD_FAB2(SCH_1):PAGE248

U14E3 TTL1G08_SOTLF-NC7SZ08,IC,D1032C
     4 RST_PCIE_M2_DEV_AND @BASEBOARD_FAB2_LIB.BASEBOARD_FAB2(SCH_1):RST_PCIE_M2_DEV_AND    I19 @BASEBOARD_FAB2_LIB.BASEBOARD_FAB2(SCH_1):PAGE248
     1 PWRGD_P12V_HSC_DLY @BASEBOARD_FAB2_LIB.BASEBOARD_FAB2(SCH_1):PWRGD_P12V_HSC_DLY    I19 @BASEBOARD_FAB2_LIB.BASEBOARD_FAB2(SCH_1):PAGE248
     2 PWRGD_P3V3 @BASEBOARD_FAB2_LIB.BASEBOARD_FAB2(SCH_1):PWRGD_P3V3    I19 @BASEBOARD_FAB2_LIB.BASEBOARD_FAB2(SCH_1):PAGE248

U25W4 AST2520A1-GP-GP_ASIC2-GB1-AST2A
    U9 BMC_M_DQ4 @BASEBOARD_FAB2_LIB.BASEBOARD_FAB2(SCH_1):BMC_M_DQ4    I63 @BASEBOARD_FAB2_LIB.BASEBOARD_FAB2(SCH_1):PAGE143
  AA10 BMC_M_DQ3 @BASEBOARD_FAB2_LIB.BASEBOARD_FAB2(SCH_1):BMC_M_DQ3    I63 @BASEBOARD_FAB2_LIB.BASEBOARD_FAB2(SCH_1):PAGE143
   Y10 BMC_M_DQ2 @BASEBOARD_FAB2_LIB.BASEBOARD_FAB2(SCH_1):BMC_M_DQ2    I63 @BASEBOARD_FAB2_LIB.BASEBOARD_FAB2(SCH_1):PAGE143
   W10 BMC_M_DQ1 @BASEBOARD_FAB2_LIB.BASEBOARD_FAB2(SCH_1):BMC_M_DQ1    I63 @BASEBOARD_FAB2_LIB.BASEBOARD_FAB2(SCH_1):PAGE143
   U10 BMC_M_DQ0 @BASEBOARD_FAB2_LIB.BASEBOARD_FAB2(SCH_1):BMC_M_DQ0    I63 @BASEBOARD_FAB2_LIB.BASEBOARD_FAB2(SCH_1):PAGE143
   U15 TP_BMC_M_A15 @BASEBOARD_FAB2_LIB.BASEBOARD_FAB2(SCH_1):TP_BMC_M_A15    I63 @BASEBOARD_FAB2_LIB.BASEBOARD_FAB2(SCH_1):PAGE143
    U7 BMC_M_DQ15 @BASEBOARD_FAB2_LIB.BASEBOARD_FAB2(SCH_1):BMC_M_DQ15    I63 @BASEBOARD_FAB2_LIB.BASEBOARD_FAB2(SCH_1):PAGE143
    V7 BMC_M_DQ14 @BASEBOARD_FAB2_LIB.BASEBOARD_FAB2(SCH_1):BMC_M_DQ14    I63 @BASEBOARD_FAB2_LIB.BASEBOARD_FAB2(SCH_1):PAGE143
   AB8 BMC_M_DM1 @BASEBOARD_FAB2_LIB.BASEBOARD_FAB2(SCH_1):BMC_M_DM1    I63 @BASEBOARD_FAB2_LIB.BASEBOARD_FAB2(SCH_1):PAGE143
   W11 BMC_MIOZ @BASEBOARD_FAB2_LIB.BASEBOARD_FAB2(SCH_1):BMC_MIOZ    I63 @BASEBOARD_FAB2_LIB.BASEBOARD_FAB2(SCH_1):PAGE143
  AB13 BMC_M_CAS_N @BASEBOARD_FAB2_LIB.BASEBOARD_FAB2(SCH_1):BMC_M_CAS_N    I63 @BASEBOARD_FAB2_LIB.BASEBOARD_FAB2(SCH_1):PAGE143
   U13 BMC_M_A10 @BASEBOARD_FAB2_LIB.BASEBOARD_FAB2(SCH_1):BMC_M_A10    I63 @BASEBOARD_FAB2_LIB.BASEBOARD_FAB2(SCH_1):PAGE143
  AA14 BMC_M_A11 @BASEBOARD_FAB2_LIB.BASEBOARD_FAB2(SCH_1):BMC_M_A11    I63 @BASEBOARD_FAB2_LIB.BASEBOARD_FAB2(SCH_1):PAGE143
    T9 BMC_M_VREFCA @BASEBOARD_FAB2_LIB.BASEBOARD_FAB2(SCH_1):BMC_M_VREFCA    I63 @BASEBOARD_FAB2_LIB.BASEBOARD_FAB2(SCH_1):PAGE143
    Y8 BMC_M_DQ9 @BASEBOARD_FAB2_LIB.BASEBOARD_FAB2(SCH_1):BMC_M_DQ9    I63 @BASEBOARD_FAB2_LIB.BASEBOARD_FAB2(SCH_1):PAGE143
   V11 BMC_M_ODT @BASEBOARD_FAB2_LIB.BASEBOARD_FAB2(SCH_1):BMC_M_ODT    I63 @BASEBOARD_FAB2_LIB.BASEBOARD_FAB2(SCH_1):PAGE143
   Y11 BMC_M_CKE @BASEBOARD_FAB2_LIB.BASEBOARD_FAB2(SCH_1):BMC_M_CKE    I63 @BASEBOARD_FAB2_LIB.BASEBOARD_FAB2(SCH_1):PAGE143
  AB12 BMC_M_CLK_DN @BASEBOARD_FAB2_LIB.BASEBOARD_FAB2(SCH_1):BMC_M_CLK_DN    I63 @BASEBOARD_FAB2_LIB.BASEBOARD_FAB2(SCH_1):PAGE143
   W13 BMC_M_BG0 @BASEBOARD_FAB2_LIB.BASEBOARD_FAB2(SCH_1):BMC_M_BG0    I63 @BASEBOARD_FAB2_LIB.BASEBOARD_FAB2(SCH_1):PAGE143
   Y13 BMC_M_BA1 @BASEBOARD_FAB2_LIB.BASEBOARD_FAB2(SCH_1):BMC_M_BA1    I63 @BASEBOARD_FAB2_LIB.BASEBOARD_FAB2(SCH_1):PAGE143
   U12 BMC_M_BA0 @BASEBOARD_FAB2_LIB.BASEBOARD_FAB2(SCH_1):BMC_M_BA0    I63 @BASEBOARD_FAB2_LIB.BASEBOARD_FAB2(SCH_1):PAGE143
   Y16 BMC_M_A9 @BASEBOARD_FAB2_LIB.BASEBOARD_FAB2(SCH_1):BMC_M_A9    I63 @BASEBOARD_FAB2_LIB.BASEBOARD_FAB2(SCH_1):PAGE143
   W16 BMC_M_A8 @BASEBOARD_FAB2_LIB.BASEBOARD_FAB2(SCH_1):BMC_M_A8    I63 @BASEBOARD_FAB2_LIB.BASEBOARD_FAB2(SCH_1):PAGE143
  AA16 BMC_M_A7 @BASEBOARD_FAB2_LIB.BASEBOARD_FAB2(SCH_1):BMC_M_A7    I63 @BASEBOARD_FAB2_LIB.BASEBOARD_FAB2(SCH_1):PAGE143
  AB16 BMC_M_A6 @BASEBOARD_FAB2_LIB.BASEBOARD_FAB2(SCH_1):BMC_M_A6    I63 @BASEBOARD_FAB2_LIB.BASEBOARD_FAB2(SCH_1):PAGE143
   V15 BMC_M_A5 @BASEBOARD_FAB2_LIB.BASEBOARD_FAB2(SCH_1):BMC_M_A5    I63 @BASEBOARD_FAB2_LIB.BASEBOARD_FAB2(SCH_1):PAGE143
   W15 BMC_M_A4 @BASEBOARD_FAB2_LIB.BASEBOARD_FAB2(SCH_1):BMC_M_A4    I63 @BASEBOARD_FAB2_LIB.BASEBOARD_FAB2(SCH_1):PAGE143
   U14 BMC_M_A3 @BASEBOARD_FAB2_LIB.BASEBOARD_FAB2(SCH_1):BMC_M_A3    I63 @BASEBOARD_FAB2_LIB.BASEBOARD_FAB2(SCH_1):PAGE143
   W14 BMC_M_A2 @BASEBOARD_FAB2_LIB.BASEBOARD_FAB2(SCH_1):BMC_M_A2    I63 @BASEBOARD_FAB2_LIB.BASEBOARD_FAB2(SCH_1):PAGE143
   Y14 BMC_M_A12 @BASEBOARD_FAB2_LIB.BASEBOARD_FAB2(SCH_1):BMC_M_A12    I63 @BASEBOARD_FAB2_LIB.BASEBOARD_FAB2(SCH_1):PAGE143
  AB14 BMC_M_A1 @BASEBOARD_FAB2_LIB.BASEBOARD_FAB2(SCH_1):BMC_M_A1    I63 @BASEBOARD_FAB2_LIB.BASEBOARD_FAB2(SCH_1):PAGE143
   V13 BMC_M_A0 @BASEBOARD_FAB2_LIB.BASEBOARD_FAB2(SCH_1):BMC_M_A0    I63 @BASEBOARD_FAB2_LIB.BASEBOARD_FAB2(SCH_1):PAGE143
   AB7 BMC_M_DQS1_DP @BASEBOARD_FAB2_LIB.BASEBOARD_FAB2(SCH_1):BMC_M_DQS1_DP    I63 @BASEBOARD_FAB2_LIB.BASEBOARD_FAB2(SCH_1):PAGE143
   AB6 BMC_M_DQS1_DN @BASEBOARD_FAB2_LIB.BASEBOARD_FAB2(SCH_1):BMC_M_DQS1_DN    I63 @BASEBOARD_FAB2_LIB.BASEBOARD_FAB2(SCH_1):PAGE143
   AB9 BMC_M_DQS0_DP @BASEBOARD_FAB2_LIB.BASEBOARD_FAB2(SCH_1):BMC_M_DQS0_DP    I63 @BASEBOARD_FAB2_LIB.BASEBOARD_FAB2(SCH_1):PAGE143
  AB10 BMC_M_DQS0_DN @BASEBOARD_FAB2_LIB.BASEBOARD_FAB2(SCH_1):BMC_M_DQS0_DN    I63 @BASEBOARD_FAB2_LIB.BASEBOARD_FAB2(SCH_1):PAGE143
    W9 BMC_M_DQ6 @BASEBOARD_FAB2_LIB.BASEBOARD_FAB2(SCH_1):BMC_M_DQ6    I63 @BASEBOARD_FAB2_LIB.BASEBOARD_FAB2(SCH_1):PAGE143
    Y9 BMC_M_DQ5 @BASEBOARD_FAB2_LIB.BASEBOARD_FAB2(SCH_1):BMC_M_DQ5    I63 @BASEBOARD_FAB2_LIB.BASEBOARD_FAB2(SCH_1):PAGE143
    W7 BMC_M_DQ13 @BASEBOARD_FAB2_LIB.BASEBOARD_FAB2(SCH_1):BMC_M_DQ13    I63 @BASEBOARD_FAB2_LIB.BASEBOARD_FAB2(SCH_1):PAGE143
   AA6 BMC_M_DQ12 @BASEBOARD_FAB2_LIB.BASEBOARD_FAB2(SCH_1):BMC_M_DQ12    I63 @BASEBOARD_FAB2_LIB.BASEBOARD_FAB2(SCH_1):PAGE143
    U8 BMC_M_DM0 @BASEBOARD_FAB2_LIB.BASEBOARD_FAB2(SCH_1):BMC_M_DM0    I63 @BASEBOARD_FAB2_LIB.BASEBOARD_FAB2(SCH_1):PAGE143
  AB15 BMC_M_A13 @BASEBOARD_FAB2_LIB.BASEBOARD_FAB2(SCH_1):BMC_M_A13    I63 @BASEBOARD_FAB2_LIB.BASEBOARD_FAB2(SCH_1):PAGE143
   Y15 BMC_M_MACT_N @BASEBOARD_FAB2_LIB.BASEBOARD_FAB2(SCH_1):BMC_M_MACT_N    I63 @BASEBOARD_FAB2_LIB.BASEBOARD_FAB2(SCH_1):PAGE143
    W8 BMC_M_DQ11 @BASEBOARD_FAB2_LIB.BASEBOARD_FAB2(SCH_1):BMC_M_DQ11    I63 @BASEBOARD_FAB2_LIB.BASEBOARD_FAB2(SCH_1):PAGE143
    Y7 BMC_M_DQ10 @BASEBOARD_FAB2_LIB.BASEBOARD_FAB2(SCH_1):BMC_M_DQ10    I63 @BASEBOARD_FAB2_LIB.BASEBOARD_FAB2(SCH_1):PAGE143
   Y12 BMC_M_WE_N @BASEBOARD_FAB2_LIB.BASEBOARD_FAB2(SCH_1):BMC_M_WE_N    I63 @BASEBOARD_FAB2_LIB.BASEBOARD_FAB2(SCH_1):PAGE143
   W12 BMC_M_RAS_N @BASEBOARD_FAB2_LIB.BASEBOARD_FAB2(SCH_1):BMC_M_RAS_N    I63 @BASEBOARD_FAB2_LIB.BASEBOARD_FAB2(SCH_1):PAGE143
    V9 BMC_M_DQ7 @BASEBOARD_FAB2_LIB.BASEBOARD_FAB2(SCH_1):BMC_M_DQ7    I63 @BASEBOARD_FAB2_LIB.BASEBOARD_FAB2(SCH_1):PAGE143
   AA8 BMC_M_DQ8 @BASEBOARD_FAB2_LIB.BASEBOARD_FAB2(SCH_1):BMC_M_DQ8    I63 @BASEBOARD_FAB2_LIB.BASEBOARD_FAB2(SCH_1):PAGE143
  AB11 BMC_M_CLK_DP @BASEBOARD_FAB2_LIB.BASEBOARD_FAB2(SCH_1):BMC_M_CLK_DP    I63 @BASEBOARD_FAB2_LIB.BASEBOARD_FAB2(SCH_1):PAGE143
  AA12 BMC_M_CS_N @BASEBOARD_FAB2_LIB.BASEBOARD_FAB2(SCH_1):BMC_M_CS_N    I63 @BASEBOARD_FAB2_LIB.BASEBOARD_FAB2(SCH_1):PAGE143
   H22 PWRGD_SYS_PWROK @BASEBOARD_FAB2_LIB.BASEBOARD_FAB2(SCH_1):PWRGD_SYS_PWROK    I95 @BASEBOARD_FAB2_LIB.BASEBOARD_FAB2(SCH_1):PAGE144
   J20 CLK_48M_USB_BMC_R @BASEBOARD_FAB2_LIB.BASEBOARD_FAB2(SCH_1):CLK_48M_USB_BMC_R    I95 @BASEBOARD_FAB2_LIB.BASEBOARD_FAB2(SCH_1):PAGE144
   M18 SMB_LAN_STBY_LVC3_SCL_R @BASEBOARD_FAB2_LIB.BASEBOARD_FAB2(SCH_1):SMB_LAN_STBY_LVC3_SCL_R    I95 @BASEBOARD_FAB2_LIB.BASEBOARD_FAB2(SCH_1):PAGE144
   A15 SPI_BMC_DI @BASEBOARD_FAB2_LIB.BASEBOARD_FAB2(SCH_1):SPI_BMC_DI    I95 @BASEBOARD_FAB2_LIB.BASEBOARD_FAB2(SCH_1):PAGE144
    K4 A_DACRSET @BASEBOARD_FAB2_LIB.BASEBOARD_FAB2(SCH_1):A_DACRSET    I95 @BASEBOARD_FAB2_LIB.BASEBOARD_FAB2(SCH_1):PAGE144
    J4 BMC_VGA_RED @BASEBOARD_FAB2_LIB.BASEBOARD_FAB2(SCH_1):BMC_VGA_RED    I95 @BASEBOARD_FAB2_LIB.BASEBOARD_FAB2(SCH_1):PAGE144
    J3 BMC_VGA_GREEN @BASEBOARD_FAB2_LIB.BASEBOARD_FAB2(SCH_1):BMC_VGA_GREEN    I95 @BASEBOARD_FAB2_LIB.BASEBOARD_FAB2(SCH_1):PAGE144
    C8 JTAG_BMC_TMS @BASEBOARD_FAB2_LIB.BASEBOARD_FAB2(SCH_1):JTAG_BMC_TMS    I95 @BASEBOARD_FAB2_LIB.BASEBOARD_FAB2(SCH_1):PAGE144
   D12 JTAG_BMC_TDI @BASEBOARD_FAB2_LIB.BASEBOARD_FAB2(SCH_1):JTAG_BMC_TDI    I95 @BASEBOARD_FAB2_LIB.BASEBOARD_FAB2(SCH_1):PAGE144
   C10 JTAG_BMC_TCK @BASEBOARD_FAB2_LIB.BASEBOARD_FAB2(SCH_1):JTAG_BMC_TCK    I95 @BASEBOARD_FAB2_LIB.BASEBOARD_FAB2(SCH_1):PAGE144
    C9 PU_JTAG_BMC_RTCK @BASEBOARD_FAB2_LIB.BASEBOARD_FAB2(SCH_1):PU_JTAG_BMC_RTCK    I95 @BASEBOARD_FAB2_LIB.BASEBOARD_FAB2(SCH_1):PAGE144
   E11 JTAG_BMC_TRST_N @BASEBOARD_FAB2_LIB.BASEBOARD_FAB2(SCH_1):JTAG_BMC_TRST_N    I95 @BASEBOARD_FAB2_LIB.BASEBOARD_FAB2(SCH_1):PAGE144
   E15 FM_CPU1_FIVR_FAULT_LVT3_R_N @BASEBOARD_FAB2_LIB.BASEBOARD_FAB2(SCH_1):FM_CPU1_FIVR_FAULT_LVT3_R_N    I95 @BASEBOARD_FAB2_LIB.BASEBOARD_FAB2(SCH_1):PAGE144
   C18 FM_CPU0_FIVR_FAULT_LVT3_R_N @BASEBOARD_FAB2_LIB.BASEBOARD_FAB2(SCH_1):FM_CPU0_FIVR_FAULT_LVT3_R_N    I95 @BASEBOARD_FAB2_LIB.BASEBOARD_FAB2(SCH_1):PAGE144
   C15 SPI_BMC_CLK @BASEBOARD_FAB2_LIB.BASEBOARD_FAB2(SCH_1):SPI_BMC_CLK    I95 @BASEBOARD_FAB2_LIB.BASEBOARD_FAB2(SCH_1):PAGE144
   B15 SPI_BMC_CS0_N @BASEBOARD_FAB2_LIB.BASEBOARD_FAB2(SCH_1):SPI_BMC_CS0_N    I95 @BASEBOARD_FAB2_LIB.BASEBOARD_FAB2(SCH_1):PAGE144
   A14 SPI_BMC_DO @BASEBOARD_FAB2_LIB.BASEBOARD_FAB2(SCH_1):SPI_BMC_DO    I95 @BASEBOARD_FAB2_LIB.BASEBOARD_FAB2(SCH_1):PAGE144
    L2 SGPIO_BMC_LD_R_N @BASEBOARD_FAB2_LIB.BASEBOARD_FAB2(SCH_1):SGPIO_BMC_LD_R_N    I95 @BASEBOARD_FAB2_LIB.BASEBOARD_FAB2(SCH_1):PAGE144
    R2 SGPIO_BMC_CLK_R @BASEBOARD_FAB2_LIB.BASEBOARD_FAB2(SCH_1):SGPIO_BMC_CLK_R    I95 @BASEBOARD_FAB2_LIB.BASEBOARD_FAB2(SCH_1):PAGE144
    N3 SGPIO_BMC_DOUT_R @BASEBOARD_FAB2_LIB.BASEBOARD_FAB2(SCH_1):SGPIO_BMC_DOUT_R    I95 @BASEBOARD_FAB2_LIB.BASEBOARD_FAB2(SCH_1):PAGE144
   E16 FM_CPU0_SKTOCC_LVT3_N @BASEBOARD_FAB2_LIB.BASEBOARD_FAB2(SCH_1):FM_CPU0_SKTOCC_LVT3_N    I95 @BASEBOARD_FAB2_LIB.BASEBOARD_FAB2(SCH_1):PAGE144
   C19 FM_PCH_BMC_THERMTRIP_N @BASEBOARD_FAB2_LIB.BASEBOARD_FAB2(SCH_1):FM_PCH_BMC_THERMTRIP_N    I95 @BASEBOARD_FAB2_LIB.BASEBOARD_FAB2(SCH_1):PAGE144
    J2 BMC_VGA_BLUE @BASEBOARD_FAB2_LIB.BASEBOARD_FAB2(SCH_1):BMC_VGA_BLUE    I95 @BASEBOARD_FAB2_LIB.BASEBOARD_FAB2(SCH_1):PAGE144
   M19 SMB_LAN_STBY_LVC3_SDA_R @BASEBOARD_FAB2_LIB.BASEBOARD_FAB2(SCH_1):SMB_LAN_STBY_LVC3_SDA_R    I95 @BASEBOARD_FAB2_LIB.BASEBOARD_FAB2(SCH_1):PAGE144
   D11 JTAG_BMC_TDO @BASEBOARD_FAB2_LIB.BASEBOARD_FAB2(SCH_1):JTAG_BMC_TDO    I95 @BASEBOARD_FAB2_LIB.BASEBOARD_FAB2(SCH_1):PAGE144
   K19 PWRGD_PCH_PWROK @BASEBOARD_FAB2_LIB.BASEBOARD_FAB2(SCH_1):PWRGD_PCH_PWROK    I95 @BASEBOARD_FAB2_LIB.BASEBOARD_FAB2(SCH_1):PAGE144
   L19 BMC_DEBUG_EN_N @BASEBOARD_FAB2_LIB.BASEBOARD_FAB2(SCH_1):BMC_DEBUG_EN_N    I95 @BASEBOARD_FAB2_LIB.BASEBOARD_FAB2(SCH_1):PAGE144
   L18 FM_MP_PS_FAIL_N @BASEBOARD_FAB2_LIB.BASEBOARD_FAB2(SCH_1):FM_MP_PS_FAIL_N    I95 @BASEBOARD_FAB2_LIB.BASEBOARD_FAB2(SCH_1):PAGE144
   K18 H_CPU0_FAST_WAKE_LVT3_N @BASEBOARD_FAB2_LIB.BASEBOARD_FAB2(SCH_1):H_CPU0_FAST_WAKE_LVT3_N    I95 @BASEBOARD_FAB2_LIB.BASEBOARD_FAB2(SCH_1):PAGE144
   H20 IRQ_PVDDQ_GHJ_VRHOT_LVT3_N @BASEBOARD_FAB2_LIB.BASEBOARD_FAB2(SCH_1):IRQ_PVDDQ_GHJ_VRHOT_LVT3_N    I95 @BASEBOARD_FAB2_LIB.BASEBOARD_FAB2(SCH_1):PAGE144
   M20 SMB_SLOTX24_STBY_LVC3_SCL_R @BASEBOARD_FAB2_LIB.BASEBOARD_FAB2(SCH_1):SMB_SLOTX24_STBY_LVC3_SCL_R    I95 @BASEBOARD_FAB2_LIB.BASEBOARD_FAB2(SCH_1):PAGE144
   P20 SMB_SLOTX24_STBY_LVC3_SDA_R @BASEBOARD_FAB2_LIB.BASEBOARD_FAB2(SCH_1):SMB_SLOTX24_STBY_LVC3_SDA_R    I95 @BASEBOARD_FAB2_LIB.BASEBOARD_FAB2(SCH_1):PAGE144
   A11 SMB_OCP_LAN_STBY_LVC3_SCL_R @BASEBOARD_FAB2_LIB.BASEBOARD_FAB2(SCH_1):SMB_OCP_LAN_STBY_LVC3_SCL_R    I95 @BASEBOARD_FAB2_LIB.BASEBOARD_FAB2(SCH_1):PAGE144
   A10 SMB_OCP_LAN_STBY_LVC3_SDA_R @BASEBOARD_FAB2_LIB.BASEBOARD_FAB2(SCH_1):SMB_OCP_LAN_STBY_LVC3_SDA_R    I95 @BASEBOARD_FAB2_LIB.BASEBOARD_FAB2(SCH_1):PAGE144
    A9 SMB_HOST_STBY_LVC3_SCL_R @BASEBOARD_FAB2_LIB.BASEBOARD_FAB2(SCH_1):SMB_HOST_STBY_LVC3_SCL_R    I95 @BASEBOARD_FAB2_LIB.BASEBOARD_FAB2(SCH_1):PAGE144
    B9 SMB_HOST_STBY_LVC3_SDA_R @BASEBOARD_FAB2_LIB.BASEBOARD_FAB2(SCH_1):SMB_HOST_STBY_LVC3_SDA_R    I95 @BASEBOARD_FAB2_LIB.BASEBOARD_FAB2(SCH_1):PAGE144
    L3 SMB_SMLINK0_STBY_LVC3_SCL_R @BASEBOARD_FAB2_LIB.BASEBOARD_FAB2(SCH_1):SMB_SMLINK0_STBY_LVC3_SCL_R    I95 @BASEBOARD_FAB2_LIB.BASEBOARD_FAB2(SCH_1):PAGE144
    L4 SMB_SMLINK0_STBY_LVC3_SDA_R @BASEBOARD_FAB2_LIB.BASEBOARD_FAB2(SCH_1):SMB_SMLINK0_STBY_LVC3_SDA_R    I95 @BASEBOARD_FAB2_LIB.BASEBOARD_FAB2(SCH_1):PAGE144
    L1 SMB_VR_STBY_LVC3_SCL_R @BASEBOARD_FAB2_LIB.BASEBOARD_FAB2(SCH_1):SMB_VR_STBY_LVC3_SCL_R    I95 @BASEBOARD_FAB2_LIB.BASEBOARD_FAB2(SCH_1):PAGE144
    N2 SMB_VR_STBY_LVC3_SDA_R @BASEBOARD_FAB2_LIB.BASEBOARD_FAB2(SCH_1):SMB_VR_STBY_LVC3_SDA_R    I95 @BASEBOARD_FAB2_LIB.BASEBOARD_FAB2(SCH_1):PAGE144
   E19 FM_CPU_CATERR_LVT3_N @BASEBOARD_FAB2_LIB.BASEBOARD_FAB2(SCH_1):FM_CPU_CATERR_LVT3_N    I95 @BASEBOARD_FAB2_LIB.BASEBOARD_FAB2(SCH_1):PAGE144
   A19 FM_CPU_ERR2_LVT3_N @BASEBOARD_FAB2_LIB.BASEBOARD_FAB2(SCH_1):FM_CPU_ERR2_LVT3_N    I95 @BASEBOARD_FAB2_LIB.BASEBOARD_FAB2(SCH_1):PAGE144
    N4 SGPIO_BMC_DIN @BASEBOARD_FAB2_LIB.BASEBOARD_FAB2(SCH_1):SGPIO_BMC_DIN    I95 @BASEBOARD_FAB2_LIB.BASEBOARD_FAB2(SCH_1):PAGE144
   B16 FM_FORCE_ADR_N @BASEBOARD_FAB2_LIB.BASEBOARD_FAB2(SCH_1):FM_FORCE_ADR_N    I95 @BASEBOARD_FAB2_LIB.BASEBOARD_FAB2(SCH_1):PAGE144
   C16 FM_UV_ADR_TRIGGER_EN @BASEBOARD_FAB2_LIB.BASEBOARD_FAB2(SCH_1):FM_UV_ADR_TRIGGER_EN    I95 @BASEBOARD_FAB2_LIB.BASEBOARD_FAB2(SCH_1):PAGE144
   A13 SMB_OCP_FRU_STBY_LVC3_SDA_R @BASEBOARD_FAB2_LIB.BASEBOARD_FAB2(SCH_1):SMB_OCP_FRU_STBY_LVC3_SDA_R    I95 @BASEBOARD_FAB2_LIB.BASEBOARD_FAB2(SCH_1):PAGE144
   C14 SMB_OCP_FRU_STBY_LVC3_SCL_R @BASEBOARD_FAB2_LIB.BASEBOARD_FAB2(SCH_1):SMB_OCP_FRU_STBY_LVC3_SCL_R    I95 @BASEBOARD_FAB2_LIB.BASEBOARD_FAB2(SCH_1):PAGE144
    R1 SMB_BMC_PMBUS_STBY_LVC3_SDA_R @BASEBOARD_FAB2_LIB.BASEBOARD_FAB2(SCH_1):SMB_BMC_PMBUS_STBY_LVC3_SDA_R    I95 @BASEBOARD_FAB2_LIB.BASEBOARD_FAB2(SCH_1):PAGE144
    P2 SMB_BMC_PMBUS_STBY_LVC3_SCL_R @BASEBOARD_FAB2_LIB.BASEBOARD_FAB2(SCH_1):SMB_BMC_PMBUS_STBY_LVC3_SCL_R    I95 @BASEBOARD_FAB2_LIB.BASEBOARD_FAB2(SCH_1):PAGE144
    P1 SMB_SENSOR_BMC_STBY_LVC3_SDA @BASEBOARD_FAB2_LIB.BASEBOARD_FAB2(SCH_1):SMB_SENSOR_BMC_STBY_LVC3_SDA    I95 @BASEBOARD_FAB2_LIB.BASEBOARD_FAB2(SCH_1):PAGE144
    N1 SMB_SENSOR_BMC_STBY_LVC3_SCL @BASEBOARD_FAB2_LIB.BASEBOARD_FAB2(SCH_1):SMB_SENSOR_BMC_STBY_LVC3_SCL    I95 @BASEBOARD_FAB2_LIB.BASEBOARD_FAB2(SCH_1):PAGE144
   H21 IRQ_BMC_PCH_SMI_LPC_N @BASEBOARD_FAB2_LIB.BASEBOARD_FAB2(SCH_1):IRQ_BMC_PCH_SMI_LPC_N    I95 @BASEBOARD_FAB2_LIB.BASEBOARD_FAB2(SCH_1):PAGE144
   N21 FM_UARTSW_LSB_N @BASEBOARD_FAB2_LIB.BASEBOARD_FAB2(SCH_1):FM_UARTSW_LSB_N    I95 @BASEBOARD_FAB2_LIB.BASEBOARD_FAB2(SCH_1):PAGE144
   N22 FM_UARTSW_MSB_N @BASEBOARD_FAB2_LIB.BASEBOARD_FAB2(SCH_1):FM_UARTSW_MSB_N    I95 @BASEBOARD_FAB2_LIB.BASEBOARD_FAB2(SCH_1):PAGE144
   B12 SMB_PEHPCPU0_STBY_LVC3_SCL @BASEBOARD_FAB2_LIB.BASEBOARD_FAB2(SCH_1):SMB_PEHPCPU0_STBY_LVC3_SCL   I117 @BASEBOARD_FAB2_LIB.BASEBOARD_FAB2(SCH_1):PAGE145
    D9 SMB_PEHPCPU0_STBY_LVC3_SDA @BASEBOARD_FAB2_LIB.BASEBOARD_FAB2(SCH_1):SMB_PEHPCPU0_STBY_LVC3_SDA   I117 @BASEBOARD_FAB2_LIB.BASEBOARD_FAB2(SCH_1):PAGE145
   A12 SMB_DEBUG_STBY_LVC3_SDA_R @BASEBOARD_FAB2_LIB.BASEBOARD_FAB2(SCH_1):SMB_DEBUG_STBY_LVC3_SDA_R   I117 @BASEBOARD_FAB2_LIB.BASEBOARD_FAB2(SCH_1):PAGE145
   C12 SMB_DEBUG_STBY_LVC3_SCL_R @BASEBOARD_FAB2_LIB.BASEBOARD_FAB2(SCH_1):SMB_DEBUG_STBY_LVC3_SCL_R   I117 @BASEBOARD_FAB2_LIB.BASEBOARD_FAB2(SCH_1):PAGE145
   B14 JTAG_RISER_N @BASEBOARD_FAB2_LIB.BASEBOARD_FAB2(SCH_1):JTAG_RISER_N   I117 @BASEBOARD_FAB2_LIB.BASEBOARD_FAB2(SCH_1):PAGE145
   D14 FM_CPLD_BMC_PWRDN_N @BASEBOARD_FAB2_LIB.BASEBOARD_FAB2(SCH_1):FM_CPLD_BMC_PWRDN_N   I117 @BASEBOARD_FAB2_LIB.BASEBOARD_FAB2(SCH_1):PAGE145
   P21 FM_BMC_ONCTL_R_N @BASEBOARD_FAB2_LIB.BASEBOARD_FAB2(SCH_1):FM_BMC_ONCTL_R_N   I117 @BASEBOARD_FAB2_LIB.BASEBOARD_FAB2(SCH_1):PAGE145
   D15 IRQ_MEZZ_LAN_ALERT_N @BASEBOARD_FAB2_LIB.BASEBOARD_FAB2(SCH_1):IRQ_MEZZ_LAN_ALERT_N   I117 @BASEBOARD_FAB2_LIB.BASEBOARD_FAB2(SCH_1):PAGE145
   C11 SMB_PEHPCPU0_STBY_LVC3_R2_SCL @BASEBOARD_FAB2_LIB.BASEBOARD_FAB2(SCH_1):SMB_PEHPCPU0_STBY_LVC3_R2_SCL   I117 @BASEBOARD_FAB2_LIB.BASEBOARD_FAB2(SCH_1):PAGE145
   D10 SMB_PEHPCPU1_STBY_LVC3_SCL @BASEBOARD_FAB2_LIB.BASEBOARD_FAB2(SCH_1):SMB_PEHPCPU1_STBY_LVC3_SCL   I117 @BASEBOARD_FAB2_LIB.BASEBOARD_FAB2(SCH_1):PAGE145
   E14 FM_BIOS_SMI_ACTIVE_N @BASEBOARD_FAB2_LIB.BASEBOARD_FAB2(SCH_1):FM_BIOS_SMI_ACTIVE_N   I117 @BASEBOARD_FAB2_LIB.BASEBOARD_FAB2(SCH_1):PAGE145
   D13 TP_BMC_GPIOA2 @BASEBOARD_FAB2_LIB.BASEBOARD_FAB2(SCH_1):TP_BMC_GPIOA2   I117 @BASEBOARD_FAB2_LIB.BASEBOARD_FAB2(SCH_1):PAGE145
   D16 IRQ_OOB_MGMT_RISER_ALERT_N @BASEBOARD_FAB2_LIB.BASEBOARD_FAB2(SCH_1):IRQ_OOB_MGMT_RISER_ALERT_N   I117 @BASEBOARD_FAB2_LIB.BASEBOARD_FAB2(SCH_1):PAGE145
   E17 IRQ_PCH_NIC_ALERT_N @BASEBOARD_FAB2_LIB.BASEBOARD_FAB2(SCH_1):IRQ_PCH_NIC_ALERT_N   I117 @BASEBOARD_FAB2_LIB.BASEBOARD_FAB2(SCH_1):PAGE145
   H19 FM_OCP_MEZZB_PRES_LVT3_BMC @BASEBOARD_FAB2_LIB.BASEBOARD_FAB2(SCH_1):FM_OCP_MEZZB_PRES_LVT3_BMC   I117 @BASEBOARD_FAB2_LIB.BASEBOARD_FAB2(SCH_1):PAGE145
   H18 FM_OCP_MEZZC_PRES_LVT3_BMC @BASEBOARD_FAB2_LIB.BASEBOARD_FAB2(SCH_1):FM_OCP_MEZZC_PRES_LVT3_BMC   I117 @BASEBOARD_FAB2_LIB.BASEBOARD_FAB2(SCH_1):PAGE145
    U1 FM_HSC_TIMER_EXP_N @BASEBOARD_FAB2_LIB.BASEBOARD_FAB2(SCH_1):FM_HSC_TIMER_EXP_N   I117 @BASEBOARD_FAB2_LIB.BASEBOARD_FAB2(SCH_1):PAGE145
    U2 FM_BIOS_TOP_SWAP @BASEBOARD_FAB2_LIB.BASEBOARD_FAB2(SCH_1):FM_BIOS_TOP_SWAP   I117 @BASEBOARD_FAB2_LIB.BASEBOARD_FAB2(SCH_1):PAGE145
    P4 FM_MEM_THERM_EVENT_PCH_N @BASEBOARD_FAB2_LIB.BASEBOARD_FAB2(SCH_1):FM_MEM_THERM_EVENT_PCH_N   I117 @BASEBOARD_FAB2_LIB.BASEBOARD_FAB2(SCH_1):PAGE145
   K22 CLK_100M_BMC_PE_R_DN @BASEBOARD_FAB2_LIB.BASEBOARD_FAB2(SCH_1):CLK_100M_BMC_PE_R_DN   I117 @BASEBOARD_FAB2_LIB.BASEBOARD_FAB2(SCH_1):PAGE145
   K21 CLK_100M_BMC_PE_R_DP @BASEBOARD_FAB2_LIB.BASEBOARD_FAB2(SCH_1):CLK_100M_BMC_PE_R_DP   I117 @BASEBOARD_FAB2_LIB.BASEBOARD_FAB2(SCH_1):PAGE145
    K2 UART_BMC_RXD5 @BASEBOARD_FAB2_LIB.BASEBOARD_FAB2(SCH_1):UART_BMC_RXD5   I117 @BASEBOARD_FAB2_LIB.BASEBOARD_FAB2(SCH_1):PAGE145
  AB18 PECI_BMC_R @BASEBOARD_FAB2_LIB.BASEBOARD_FAB2(SCH_1):PECI_BMC_R   I117 @BASEBOARD_FAB2_LIB.BASEBOARD_FAB2(SCH_1):PAGE145
   D20 FM_BOARD_REV_ID1 @BASEBOARD_FAB2_LIB.BASEBOARD_FAB2(SCH_1):FM_BOARD_REV_ID1   I117 @BASEBOARD_FAB2_LIB.BASEBOARD_FAB2(SCH_1):PAGE145
   D21 IRQ_DIMM_SAVE_LVT3_N @BASEBOARD_FAB2_LIB.BASEBOARD_FAB2(SCH_1):IRQ_DIMM_SAVE_LVT3_N   I117 @BASEBOARD_FAB2_LIB.BASEBOARD_FAB2(SCH_1):PAGE145
   E21 FM_BOARD_REV_ID0 @BASEBOARD_FAB2_LIB.BASEBOARD_FAB2(SCH_1):FM_BOARD_REV_ID0   I117 @BASEBOARD_FAB2_LIB.BASEBOARD_FAB2(SCH_1):PAGE145
   W18 CLK_24M_25M_BMC_CLKIN @BASEBOARD_FAB2_LIB.BASEBOARD_FAB2(SCH_1):CLK_24M_25M_BMC_CLKIN   I117 @BASEBOARD_FAB2_LIB.BASEBOARD_FAB2(SCH_1):PAGE145
   U18 RST_BMC_SRST_N @BASEBOARD_FAB2_LIB.BASEBOARD_FAB2(SCH_1):RST_BMC_SRST_N   I117 @BASEBOARD_FAB2_LIB.BASEBOARD_FAB2(SCH_1):PAGE145
   E13 FM_BMC_SYS_THROTTLE_R_N @BASEBOARD_FAB2_LIB.BASEBOARD_FAB2(SCH_1):FM_BMC_SYS_THROTTLE_R_N   I117 @BASEBOARD_FAB2_LIB.BASEBOARD_FAB2(SCH_1):PAGE145
   L20 RST_PLTRST_BUF_N_R @BASEBOARD_FAB2_LIB.BASEBOARD_FAB2(SCH_1):RST_PLTRST_BUF_N_R   I117 @BASEBOARD_FAB2_LIB.BASEBOARD_FAB2(SCH_1):PAGE145
   M22 P2E_SSB_BMC_TX_C_DN @BASEBOARD_FAB2_LIB.BASEBOARD_FAB2(SCH_1):P2E_SSB_BMC_TX_C_DN   I117 @BASEBOARD_FAB2_LIB.BASEBOARD_FAB2(SCH_1):PAGE145
   M21 P2E_SSB_BMC_TX_C_DP @BASEBOARD_FAB2_LIB.BASEBOARD_FAB2(SCH_1):P2E_SSB_BMC_TX_C_DP   I117 @BASEBOARD_FAB2_LIB.BASEBOARD_FAB2(SCH_1):PAGE145
    Y1 FM_CPU0_RC_ERROR_N @BASEBOARD_FAB2_LIB.BASEBOARD_FAB2(SCH_1):FM_CPU0_RC_ERROR_N   I117 @BASEBOARD_FAB2_LIB.BASEBOARD_FAB2(SCH_1):PAGE145
   AB2 FM_CPU1_RC_ERROR_N @BASEBOARD_FAB2_LIB.BASEBOARD_FAB2(SCH_1):FM_CPU1_RC_ERROR_N   I117 @BASEBOARD_FAB2_LIB.BASEBOARD_FAB2(SCH_1):PAGE145
   AA1 IRQ_BOARD_BMC_ALERT_N @BASEBOARD_FAB2_LIB.BASEBOARD_FAB2(SCH_1):IRQ_BOARD_BMC_ALERT_N   I117 @BASEBOARD_FAB2_LIB.BASEBOARD_FAB2(SCH_1):PAGE145
    Y2 FM_OC_DETECT_EN_N @BASEBOARD_FAB2_LIB.BASEBOARD_FAB2(SCH_1):FM_OC_DETECT_EN_N   I117 @BASEBOARD_FAB2_LIB.BASEBOARD_FAB2(SCH_1):PAGE145
   AA2 FM_CPU0_THERMTRIP_LATCH_LVT3_N @BASEBOARD_FAB2_LIB.BASEBOARD_FAB2(SCH_1):FM_CPU0_THERMTRIP_LATCH_LVT3_N   I117 @BASEBOARD_FAB2_LIB.BASEBOARD_FAB2(SCH_1):PAGE145
    P5 FM_CPU1_THERMTRIP_LATCH_LVT3_N @BASEBOARD_FAB2_LIB.BASEBOARD_FAB2(SCH_1):FM_CPU1_THERMTRIP_LATCH_LVT3_N   I117 @BASEBOARD_FAB2_LIB.BASEBOARD_FAB2(SCH_1):PAGE145
    R5 SP2_BMC_CM_UART_TX @BASEBOARD_FAB2_LIB.BASEBOARD_FAB2(SCH_1):SP2_BMC_CM_UART_TX   I117 @BASEBOARD_FAB2_LIB.BASEBOARD_FAB2(SCH_1):PAGE145
    T5 SP2_BMC_CM_UART_RX @BASEBOARD_FAB2_LIB.BASEBOARD_FAB2(SCH_1):SP2_BMC_CM_UART_RX   I117 @BASEBOARD_FAB2_LIB.BASEBOARD_FAB2(SCH_1):PAGE145
    T1 IRQ_OC_DETECT_N @BASEBOARD_FAB2_LIB.BASEBOARD_FAB2(SCH_1):IRQ_OC_DETECT_N   I117 @BASEBOARD_FAB2_LIB.BASEBOARD_FAB2(SCH_1):PAGE145
    P3 FM_PMBUS_ALERT_BUF_EN_R3_N @BASEBOARD_FAB2_LIB.BASEBOARD_FAB2(SCH_1):FM_PMBUS_ALERT_BUF_EN_R3_N   I117 @BASEBOARD_FAB2_LIB.BASEBOARD_FAB2(SCH_1):PAGE145
    W1 SP1_BMC_HOST_UART_RX @BASEBOARD_FAB2_LIB.BASEBOARD_FAB2(SCH_1):SP1_BMC_HOST_UART_RX   I117 @BASEBOARD_FAB2_LIB.BASEBOARD_FAB2(SCH_1):PAGE145
   J19 IRQ_PVDDQ_ABC_VRHOT_LVT3_N @BASEBOARD_FAB2_LIB.BASEBOARD_FAB2(SCH_1):IRQ_PVDDQ_ABC_VRHOT_LVT3_N   I117 @BASEBOARD_FAB2_LIB.BASEBOARD_FAB2(SCH_1):PAGE145
   J18 SPI_BMC_BT_WP0_N @BASEBOARD_FAB2_LIB.BASEBOARD_FAB2(SCH_1):SPI_BMC_BT_WP0_N   I117 @BASEBOARD_FAB2_LIB.BASEBOARD_FAB2(SCH_1):PAGE145
   B22 IRQ_PVCCIN_CPU0_VRHOT_LVC3_N @BASEBOARD_FAB2_LIB.BASEBOARD_FAB2(SCH_1):IRQ_PVCCIN_CPU0_VRHOT_LVC3_N   I117 @BASEBOARD_FAB2_LIB.BASEBOARD_FAB2(SCH_1):PAGE145
   F18 FM_PWR_BTN_R1_N @BASEBOARD_FAB2_LIB.BASEBOARD_FAB2(SCH_1):FM_PWR_BTN_R1_N   I117 @BASEBOARD_FAB2_LIB.BASEBOARD_FAB2(SCH_1):PAGE145
   F17 FM_BMC_PWRBTN_OUT_N @BASEBOARD_FAB2_LIB.BASEBOARD_FAB2(SCH_1):FM_BMC_PWRBTN_OUT_N   I117 @BASEBOARD_FAB2_LIB.BASEBOARD_FAB2(SCH_1):PAGE145
   E18 FP_NMI_BTN_N @BASEBOARD_FAB2_LIB.BASEBOARD_FAB2(SCH_1):FP_NMI_BTN_N   I117 @BASEBOARD_FAB2_LIB.BASEBOARD_FAB2(SCH_1):PAGE145
   A20 FM_CPU0_PROCHOT_LVT3_BMC_N @BASEBOARD_FAB2_LIB.BASEBOARD_FAB2(SCH_1):FM_CPU0_PROCHOT_LVT3_BMC_N   I117 @BASEBOARD_FAB2_LIB.BASEBOARD_FAB2(SCH_1):PAGE145
   B19 FM_CPU1_PROCHOT_LVT3_BMC_N @BASEBOARD_FAB2_LIB.BASEBOARD_FAB2(SCH_1):FM_CPU1_PROCHOT_LVT3_BMC_N   I117 @BASEBOARD_FAB2_LIB.BASEBOARD_FAB2(SCH_1):PAGE145
    K1 UART_BMC_TXD5 @BASEBOARD_FAB2_LIB.BASEBOARD_FAB2(SCH_1):UART_BMC_TXD5   I117 @BASEBOARD_FAB2_LIB.BASEBOARD_FAB2(SCH_1):PAGE145
   K20 PD_PEREXT @BASEBOARD_FAB2_LIB.BASEBOARD_FAB2(SCH_1):PD_PEREXT   I117 @BASEBOARD_FAB2_LIB.BASEBOARD_FAB2(SCH_1):PAGE145
   L22 P2E_SSB_BMC_RX_DN @BASEBOARD_FAB2_LIB.BASEBOARD_FAB2(SCH_1):P2E_SSB_BMC_RX_DN   I117 @BASEBOARD_FAB2_LIB.BASEBOARD_FAB2(SCH_1):PAGE145
   L21 P2E_SSB_BMC_RX_DP @BASEBOARD_FAB2_LIB.BASEBOARD_FAB2(SCH_1):P2E_SSB_BMC_RX_DP   I117 @BASEBOARD_FAB2_LIB.BASEBOARD_FAB2(SCH_1):PAGE145
   D19 IRQ_BMC_PCH_NMI_STBY_N @BASEBOARD_FAB2_LIB.BASEBOARD_FAB2(SCH_1):IRQ_BMC_PCH_NMI_STBY_N   I117 @BASEBOARD_FAB2_LIB.BASEBOARD_FAB2(SCH_1):PAGE145
   C20 RST_BMC_SYSRST_BTN_OUT_N @BASEBOARD_FAB2_LIB.BASEBOARD_FAB2(SCH_1):RST_BMC_SYSRST_BTN_OUT_N   I117 @BASEBOARD_FAB2_LIB.BASEBOARD_FAB2(SCH_1):PAGE145
   B20 RST_SYSTEM_BTN_R_N @BASEBOARD_FAB2_LIB.BASEBOARD_FAB2(SCH_1):RST_SYSTEM_BTN_R_N   I117 @BASEBOARD_FAB2_LIB.BASEBOARD_FAB2(SCH_1):PAGE145
   F19 FM_BIOS_MRC_DEBUG_MSG_DIS_N @BASEBOARD_FAB2_LIB.BASEBOARD_FAB2(SCH_1):FM_BIOS_MRC_DEBUG_MSG_DIS_N   I117 @BASEBOARD_FAB2_LIB.BASEBOARD_FAB2(SCH_1):PAGE145
   F20 FM_SOL_UART_CH_SEL @BASEBOARD_FAB2_LIB.BASEBOARD_FAB2(SCH_1):FM_SOL_UART_CH_SEL   I117 @BASEBOARD_FAB2_LIB.BASEBOARD_FAB2(SCH_1):PAGE145
   C21 FM_CPU_ERR1_LVT3_BMC_N @BASEBOARD_FAB2_LIB.BASEBOARD_FAB2(SCH_1):FM_CPU_ERR1_LVT3_BMC_N   I117 @BASEBOARD_FAB2_LIB.BASEBOARD_FAB2(SCH_1):PAGE145
   B11 SMB_PEHPCPU0_STBY_LVC3_R2_SDA @BASEBOARD_FAB2_LIB.BASEBOARD_FAB2(SCH_1):SMB_PEHPCPU0_STBY_LVC3_R2_SDA   I117 @BASEBOARD_FAB2_LIB.BASEBOARD_FAB2(SCH_1):PAGE145
   E12 SMB_PEHPCPU1_STBY_LVC3_SDA @BASEBOARD_FAB2_LIB.BASEBOARD_FAB2(SCH_1):SMB_PEHPCPU1_STBY_LVC3_SDA   I117 @BASEBOARD_FAB2_LIB.BASEBOARD_FAB2(SCH_1):PAGE145
    T2 IRQ_UV_DETECT_N @BASEBOARD_FAB2_LIB.BASEBOARD_FAB2(SCH_1):IRQ_UV_DETECT_N   I117 @BASEBOARD_FAB2_LIB.BASEBOARD_FAB2(SCH_1):PAGE145
   B21 IRQ_PVCCIN_CPU1_VRHOT_LVC3_N @BASEBOARD_FAB2_LIB.BASEBOARD_FAB2(SCH_1):IRQ_PVCCIN_CPU1_VRHOT_LVC3_N   I117 @BASEBOARD_FAB2_LIB.BASEBOARD_FAB2(SCH_1):PAGE145
   A21 IRQ_PVDDQ_KLM_VRHOT_LVT3_N @BASEBOARD_FAB2_LIB.BASEBOARD_FAB2(SCH_1):IRQ_PVDDQ_KLM_VRHOT_LVT3_N   I117 @BASEBOARD_FAB2_LIB.BASEBOARD_FAB2(SCH_1):PAGE145
   G17 FM_BATTERY_SENSE_EN_N @BASEBOARD_FAB2_LIB.BASEBOARD_FAB2(SCH_1):FM_BATTERY_SENSE_EN_N   I117 @BASEBOARD_FAB2_LIB.BASEBOARD_FAB2(SCH_1):PAGE145
    V1 SP1_BMC_HOST_UART_TX @BASEBOARD_FAB2_LIB.BASEBOARD_FAB2(SCH_1):SP1_BMC_HOST_UART_TX   I117 @BASEBOARD_FAB2_LIB.BASEBOARD_FAB2(SCH_1):PAGE145
   G18 FM_CPU_ERR0_LVT3_BMC_N @BASEBOARD_FAB2_LIB.BASEBOARD_FAB2(SCH_1):FM_CPU_ERR0_LVT3_BMC_N   I117 @BASEBOARD_FAB2_LIB.BASEBOARD_FAB2(SCH_1):PAGE145
   E20 FM_BOARD_REV_ID2 @BASEBOARD_FAB2_LIB.BASEBOARD_FAB2(SCH_1):FM_BOARD_REV_ID2   I117 @BASEBOARD_FAB2_LIB.BASEBOARD_FAB2(SCH_1):PAGE145
    B7 A_USB2BVRES @BASEBOARD_FAB2_LIB.BASEBOARD_FAB2(SCH_1):A_USB2BVRES   I104 @BASEBOARD_FAB2_LIB.BASEBOARD_FAB2(SCH_1):PAGE146
    B8 A_USB2AVRES @BASEBOARD_FAB2_LIB.BASEBOARD_FAB2(SCH_1):A_USB2AVRES   I104 @BASEBOARD_FAB2_LIB.BASEBOARD_FAB2(SCH_1):PAGE146
   A18 LED_POSTCODE_0 @BASEBOARD_FAB2_LIB.BASEBOARD_FAB2(SCH_1):LED_POSTCODE_0   I104 @BASEBOARD_FAB2_LIB.BASEBOARD_FAB2(SCH_1):PAGE146
   D17 LED_POSTCODE_2 @BASEBOARD_FAB2_LIB.BASEBOARD_FAB2(SCH_1):LED_POSTCODE_2   I104 @BASEBOARD_FAB2_LIB.BASEBOARD_FAB2(SCH_1):PAGE146
   B18 LED_POSTCODE_1 @BASEBOARD_FAB2_LIB.BASEBOARD_FAB2(SCH_1):LED_POSTCODE_1   I104 @BASEBOARD_FAB2_LIB.BASEBOARD_FAB2(SCH_1):PAGE146
   A17 LED_POSTCODE_4 @BASEBOARD_FAB2_LIB.BASEBOARD_FAB2(SCH_1):LED_POSTCODE_4   I104 @BASEBOARD_FAB2_LIB.BASEBOARD_FAB2(SCH_1):PAGE146
   C17 LED_POSTCODE_3 @BASEBOARD_FAB2_LIB.BASEBOARD_FAB2(SCH_1):LED_POSTCODE_3   I104 @BASEBOARD_FAB2_LIB.BASEBOARD_FAB2(SCH_1):PAGE146
   B17 LED_POSTCODE_5 @BASEBOARD_FAB2_LIB.BASEBOARD_FAB2(SCH_1):LED_POSTCODE_5   I104 @BASEBOARD_FAB2_LIB.BASEBOARD_FAB2(SCH_1):PAGE146
   D18 LED_POSTCODE_7 @BASEBOARD_FAB2_LIB.BASEBOARD_FAB2(SCH_1):LED_POSTCODE_7   I104 @BASEBOARD_FAB2_LIB.BASEBOARD_FAB2(SCH_1):PAGE146
   A16 LED_POSTCODE_6 @BASEBOARD_FAB2_LIB.BASEBOARD_FAB2(SCH_1):LED_POSTCODE_6   I104 @BASEBOARD_FAB2_LIB.BASEBOARD_FAB2(SCH_1):PAGE146
   V20 FM_THROTTLE_N @BASEBOARD_FAB2_LIB.BASEBOARD_FAB2(SCH_1):FM_THROTTLE_N   I104 @BASEBOARD_FAB2_LIB.BASEBOARD_FAB2(SCH_1):PAGE146
   R18 IRQ_SML0_ALERT_N @BASEBOARD_FAB2_LIB.BASEBOARD_FAB2(SCH_1):IRQ_SML0_ALERT_N   I104 @BASEBOARD_FAB2_LIB.BASEBOARD_FAB2(SCH_1):PAGE146
  AB20 FM_BMC_NMI_N_R @BASEBOARD_FAB2_LIB.BASEBOARD_FAB2(SCH_1):FM_BMC_NMI_N_R   I104 @BASEBOARD_FAB2_LIB.BASEBOARD_FAB2(SCH_1):PAGE146
  AB21 IRQ_PVDDQ_DEF_VRHOT_LVT3_N @BASEBOARD_FAB2_LIB.BASEBOARD_FAB2(SCH_1):IRQ_PVDDQ_DEF_VRHOT_LVT3_N   I104 @BASEBOARD_FAB2_LIB.BASEBOARD_FAB2(SCH_1):PAGE146
  AA21 IRQ_BMC_PCH_SCI_LPC_N @BASEBOARD_FAB2_LIB.BASEBOARD_FAB2(SCH_1):IRQ_BMC_PCH_SCI_LPC_N   I104 @BASEBOARD_FAB2_LIB.BASEBOARD_FAB2(SCH_1):PAGE146
   U21 BMC_STRAP_BIT17 @BASEBOARD_FAB2_LIB.BASEBOARD_FAB2(SCH_1):BMC_STRAP_BIT17   I104 @BASEBOARD_FAB2_LIB.BASEBOARD_FAB2(SCH_1):PAGE146
   W22 BMC_STRAP_BIT18 @BASEBOARD_FAB2_LIB.BASEBOARD_FAB2(SCH_1):BMC_STRAP_BIT18   I104 @BASEBOARD_FAB2_LIB.BASEBOARD_FAB2(SCH_1):PAGE146
   V22 BMC_STRAP_BIT20 @BASEBOARD_FAB2_LIB.BASEBOARD_FAB2(SCH_1):BMC_STRAP_BIT20   I104 @BASEBOARD_FAB2_LIB.BASEBOARD_FAB2(SCH_1):PAGE146
   W21 BMC_STRAP_BIT27 @BASEBOARD_FAB2_LIB.BASEBOARD_FAB2(SCH_1):BMC_STRAP_BIT27   I104 @BASEBOARD_FAB2_LIB.BASEBOARD_FAB2(SCH_1):PAGE146
   Y21 FM_CPU1_SKTOCC_LVT3_N @BASEBOARD_FAB2_LIB.BASEBOARD_FAB2(SCH_1):FM_CPU1_SKTOCC_LVT3_N   I104 @BASEBOARD_FAB2_LIB.BASEBOARD_FAB2(SCH_1):PAGE146
   P18 HSC_SMBUS_SWITCH_EN @BASEBOARD_FAB2_LIB.BASEBOARD_FAB2(SCH_1):HSC_SMBUS_SWITCH_EN   I104 @BASEBOARD_FAB2_LIB.BASEBOARD_FAB2(SCH_1):PAGE146
  AA20 GPIOS7 @BASEBOARD_FAB2_LIB.BASEBOARD_FAB2(SCH_1):GPIOS7   I104 @BASEBOARD_FAB2_LIB.BASEBOARD_FAB2(SCH_1):PAGE146
   Y20 FM_BMC_CPLD_GPO @BASEBOARD_FAB2_LIB.BASEBOARD_FAB2(SCH_1):FM_BMC_CPLD_GPO   I104 @BASEBOARD_FAB2_LIB.BASEBOARD_FAB2(SCH_1):PAGE146
   Y22 FP_PWR_ID_LED_N @BASEBOARD_FAB2_LIB.BASEBOARD_FAB2(SCH_1):FP_PWR_ID_LED_N   I104 @BASEBOARD_FAB2_LIB.BASEBOARD_FAB2(SCH_1):PAGE146
    A7 USB_PCH_BMC_P4_DP @BASEBOARD_FAB2_LIB.BASEBOARD_FAB2(SCH_1):USB_PCH_BMC_P4_DP   I104 @BASEBOARD_FAB2_LIB.BASEBOARD_FAB2(SCH_1):PAGE146
    A8 USB_PCH_BMC_P4_DN @BASEBOARD_FAB2_LIB.BASEBOARD_FAB2(SCH_1):USB_PCH_BMC_P4_DN   I104 @BASEBOARD_FAB2_LIB.BASEBOARD_FAB2(SCH_1):PAGE146
    B6 USB2_PCH_BMC_P5_DP @BASEBOARD_FAB2_LIB.BASEBOARD_FAB2(SCH_1):USB2_PCH_BMC_P5_DP   I104 @BASEBOARD_FAB2_LIB.BASEBOARD_FAB2(SCH_1):PAGE146
    A6 USB2_PCH_BMC_P5_DN @BASEBOARD_FAB2_LIB.BASEBOARD_FAB2(SCH_1):USB2_PCH_BMC_P5_DN   I104 @BASEBOARD_FAB2_LIB.BASEBOARD_FAB2(SCH_1):PAGE146
   U20 BMC_STRAP_BIT5 @BASEBOARD_FAB2_LIB.BASEBOARD_FAB2(SCH_1):BMC_STRAP_BIT5   I104 @BASEBOARD_FAB2_LIB.BASEBOARD_FAB2(SCH_1):PAGE146
   W20     NC     NC   I104 @BASEBOARD_FAB2_LIB.BASEBOARD_FAB2(SCH_1):PAGE146
   R19 BMC_STRAP_BIT3 @BASEBOARD_FAB2_LIB.BASEBOARD_FAB2(SCH_1):BMC_STRAP_BIT3   I104 @BASEBOARD_FAB2_LIB.BASEBOARD_FAB2(SCH_1):PAGE146
   U19 FM_BMC_READY_N @BASEBOARD_FAB2_LIB.BASEBOARD_FAB2(SCH_1):FM_BMC_READY_N   I104 @BASEBOARD_FAB2_LIB.BASEBOARD_FAB2(SCH_1):PAGE146
   V21 IRQ_SML1_PMBUS_ALERT_N @BASEBOARD_FAB2_LIB.BASEBOARD_FAB2(SCH_1):IRQ_SML1_PMBUS_ALERT_N   I104 @BASEBOARD_FAB2_LIB.BASEBOARD_FAB2(SCH_1):PAGE146
   P19 FM_BIOS_POST_CMPLT_N @BASEBOARD_FAB2_LIB.BASEBOARD_FAB2(SCH_1):FM_BIOS_POST_CMPLT_N   I104 @BASEBOARD_FAB2_LIB.BASEBOARD_FAB2(SCH_1):PAGE146
   N18 IRQ_LOM_ALERT_N @BASEBOARD_FAB2_LIB.BASEBOARD_FAB2(SCH_1):IRQ_LOM_ALERT_N   I104 @BASEBOARD_FAB2_LIB.BASEBOARD_FAB2(SCH_1):PAGE146
   T20 UV_HIGH_SET @BASEBOARD_FAB2_LIB.BASEBOARD_FAB2(SCH_1):UV_HIGH_SET   I104 @BASEBOARD_FAB2_LIB.BASEBOARD_FAB2(SCH_1):PAGE146
   U22 PECI_SEL @BASEBOARD_FAB2_LIB.BASEBOARD_FAB2(SCH_1):PECI_SEL   I104 @BASEBOARD_FAB2_LIB.BASEBOARD_FAB2(SCH_1):PAGE146
  AA22 FM_TPM_PRES_N @BASEBOARD_FAB2_LIB.BASEBOARD_FAB2(SCH_1):FM_TPM_PRES_N   I104 @BASEBOARD_FAB2_LIB.BASEBOARD_FAB2(SCH_1):PAGE146
   G22 RST_BMC_LVC3_N @BASEBOARD_FAB2_LIB.BASEBOARD_FAB2(SCH_1):RST_BMC_LVC3_N   I105 @BASEBOARD_FAB2_LIB.BASEBOARD_FAB2(SCH_1):PAGE146
    K3 PD_SP_ENTEST @BASEBOARD_FAB2_LIB.BASEBOARD_FAB2(SCH_1):PD_SP_ENTEST   I105 @BASEBOARD_FAB2_LIB.BASEBOARD_FAB2(SCH_1):PAGE146
   V18 RST_BMC_EXTRST_N @BASEBOARD_FAB2_LIB.BASEBOARD_FAB2(SCH_1):RST_BMC_EXTRST_N   I105 @BASEBOARD_FAB2_LIB.BASEBOARD_FAB2(SCH_1):PAGE146
   B10 FM_POST_CARD_PRES_BMC_N @BASEBOARD_FAB2_LIB.BASEBOARD_FAB2(SCH_1):FM_POST_CARD_PRES_BMC_N   I105 @BASEBOARD_FAB2_LIB.BASEBOARD_FAB2(SCH_1):PAGE146
   N20 FM_PE_BMC_WAKE_N @BASEBOARD_FAB2_LIB.BASEBOARD_FAB2(SCH_1):FM_PE_BMC_WAKE_N   I105 @BASEBOARD_FAB2_LIB.BASEBOARD_FAB2(SCH_1):PAGE146
   V19 RST_BMC_PLTRST_BUF_N @BASEBOARD_FAB2_LIB.BASEBOARD_FAB2(SCH_1):RST_BMC_PLTRST_BUF_N   I105 @BASEBOARD_FAB2_LIB.BASEBOARD_FAB2(SCH_1):PAGE146
   T17 BMC_TCK_MUX_SEL @BASEBOARD_FAB2_LIB.BASEBOARD_FAB2(SCH_1):BMC_TCK_MUX_SEL   I105 @BASEBOARD_FAB2_LIB.BASEBOARD_FAB2(SCH_1):PAGE146
   T19 FM_MP_PS_REDUNDANT_LOST_N @BASEBOARD_FAB2_LIB.BASEBOARD_FAB2(SCH_1):FM_MP_PS_REDUNDANT_LOST_N   I105 @BASEBOARD_FAB2_LIB.BASEBOARD_FAB2(SCH_1):PAGE146
  AA19 SPI_BMC_BT_CS_R_N @BASEBOARD_FAB2_LIB.BASEBOARD_FAB2(SCH_1):SPI_BMC_BT_CS_R_N   I105 @BASEBOARD_FAB2_LIB.BASEBOARD_FAB2(SCH_1):PAGE146
  AB17 BMC_M_RST_N @BASEBOARD_FAB2_LIB.BASEBOARD_FAB2(SCH_1):BMC_M_RST_N   I105 @BASEBOARD_FAB2_LIB.BASEBOARD_FAB2(SCH_1):PAGE146
   U16 BMC_M_MALERT_N @BASEBOARD_FAB2_LIB.BASEBOARD_FAB2(SCH_1):BMC_M_MALERT_N   I105 @BASEBOARD_FAB2_LIB.BASEBOARD_FAB2(SCH_1):PAGE146
   Y18 FM_BMC_HEARTBEAT_N @BASEBOARD_FAB2_LIB.BASEBOARD_FAB2(SCH_1):FM_BMC_HEARTBEAT_N   I105 @BASEBOARD_FAB2_LIB.BASEBOARD_FAB2(SCH_1):PAGE146
    N5 BMC_VGA_HSYNC @BASEBOARD_FAB2_LIB.BASEBOARD_FAB2(SCH_1):BMC_VGA_HSYNC   I105 @BASEBOARD_FAB2_LIB.BASEBOARD_FAB2(SCH_1):PAGE146
   U17 SPI_BMC_BT_DO_R @BASEBOARD_FAB2_LIB.BASEBOARD_FAB2(SCH_1):SPI_BMC_BT_DO_R   I105 @BASEBOARD_FAB2_LIB.BASEBOARD_FAB2(SCH_1):PAGE146
  AA18 SPI_BMC_BT_CLK_R @BASEBOARD_FAB2_LIB.BASEBOARD_FAB2(SCH_1):SPI_BMC_BT_CLK_R   I105 @BASEBOARD_FAB2_LIB.BASEBOARD_FAB2(SCH_1):PAGE146
    T3 I2C_BMC_VGA_DDC_SDA @BASEBOARD_FAB2_LIB.BASEBOARD_FAB2(SCH_1):I2C_BMC_VGA_DDC_SDA   I105 @BASEBOARD_FAB2_LIB.BASEBOARD_FAB2(SCH_1):PAGE146
    R3 I2C_BMC_VGA_DDC_SCL @BASEBOARD_FAB2_LIB.BASEBOARD_FAB2(SCH_1):I2C_BMC_VGA_DDC_SCL   I105 @BASEBOARD_FAB2_LIB.BASEBOARD_FAB2(SCH_1):PAGE146
    R4 BMC_VGA_VSYNC @BASEBOARD_FAB2_LIB.BASEBOARD_FAB2(SCH_1):BMC_VGA_VSYNC   I105 @BASEBOARD_FAB2_LIB.BASEBOARD_FAB2(SCH_1):PAGE146
   R20     NC     NC   I105 @BASEBOARD_FAB2_LIB.BASEBOARD_FAB2(SCH_1):PAGE146
   T22 BMC_SELF_HW_RST @BASEBOARD_FAB2_LIB.BASEBOARD_FAB2(SCH_1):BMC_SELF_HW_RST   I105 @BASEBOARD_FAB2_LIB.BASEBOARD_FAB2(SCH_1):PAGE146
   T21 FM_OCP_MEZZA_PRES @BASEBOARD_FAB2_LIB.BASEBOARD_FAB2(SCH_1):FM_OCP_MEZZA_PRES   I105 @BASEBOARD_FAB2_LIB.BASEBOARD_FAB2(SCH_1):PAGE146
   N19 IRQ_HSC_FAULT_N @BASEBOARD_FAB2_LIB.BASEBOARD_FAB2(SCH_1):IRQ_HSC_FAULT_N   I105 @BASEBOARD_FAB2_LIB.BASEBOARD_FAB2(SCH_1):PAGE146
   C22 CLK_24M_BMC_LPC @BASEBOARD_FAB2_LIB.BASEBOARD_FAB2(SCH_1):CLK_24M_BMC_LPC   I105 @BASEBOARD_FAB2_LIB.BASEBOARD_FAB2(SCH_1):PAGE146
   E22 LPC_LAD3_IO3_R @BASEBOARD_FAB2_LIB.BASEBOARD_FAB2(SCH_1):LPC_LAD3_IO3_R   I105 @BASEBOARD_FAB2_LIB.BASEBOARD_FAB2(SCH_1):PAGE146
   D22 LPC_LAD2_IO2_R @BASEBOARD_FAB2_LIB.BASEBOARD_FAB2(SCH_1):LPC_LAD2_IO2_R   I105 @BASEBOARD_FAB2_LIB.BASEBOARD_FAB2(SCH_1):PAGE146
   G20 LPC_LAD1_IO1_R @BASEBOARD_FAB2_LIB.BASEBOARD_FAB2(SCH_1):LPC_LAD1_IO1_R   I105 @BASEBOARD_FAB2_LIB.BASEBOARD_FAB2(SCH_1):PAGE146
   G21 LPC_LAD0_IO0_R @BASEBOARD_FAB2_LIB.BASEBOARD_FAB2(SCH_1):LPC_LAD0_IO0_R   I105 @BASEBOARD_FAB2_LIB.BASEBOARD_FAB2(SCH_1):PAGE146
   T18 SPI_BMC_BT_DI @BASEBOARD_FAB2_LIB.BASEBOARD_FAB2(SCH_1):SPI_BMC_BT_DI   I105 @BASEBOARD_FAB2_LIB.BASEBOARD_FAB2(SCH_1):PAGE146
  AB19 SPI_BMC_BT_CS0_N @BASEBOARD_FAB2_LIB.BASEBOARD_FAB2(SCH_1):SPI_BMC_BT_CS0_N   I105 @BASEBOARD_FAB2_LIB.BASEBOARD_FAB2(SCH_1):PAGE146
   F22 IRQ_LPC_SERIRQ_R @BASEBOARD_FAB2_LIB.BASEBOARD_FAB2(SCH_1):IRQ_LPC_SERIRQ_R   I105 @BASEBOARD_FAB2_LIB.BASEBOARD_FAB2(SCH_1):PAGE146
   F21 LPC_LFRAME_N_CS0_R_N @BASEBOARD_FAB2_LIB.BASEBOARD_FAB2(SCH_1):LPC_LFRAME_N_CS0_R_N   I105 @BASEBOARD_FAB2_LIB.BASEBOARD_FAB2(SCH_1):PAGE146
   Y19 BMC_PRDY_N @BASEBOARD_FAB2_LIB.BASEBOARD_FAB2(SCH_1):BMC_PRDY_N   I105 @BASEBOARD_FAB2_LIB.BASEBOARD_FAB2(SCH_1):PAGE146
   W19 XDP_PRESENT_N @BASEBOARD_FAB2_LIB.BASEBOARD_FAB2(SCH_1):XDP_PRESENT_N   I105 @BASEBOARD_FAB2_LIB.BASEBOARD_FAB2(SCH_1):PAGE146
    F2    GND @BASEBOARD_FAB2_LIB.BASEBOARD_FAB2(SCH_1):GND   I106 @BASEBOARD_FAB2_LIB.BASEBOARD_FAB2(SCH_1):PAGE147
    G4 A_P3V_BAT_SCALED @BASEBOARD_FAB2_LIB.BASEBOARD_FAB2(SCH_1):A_P3V_BAT_SCALED   I106 @BASEBOARD_FAB2_LIB.BASEBOARD_FAB2(SCH_1):PAGE147
   C13 FM_BB_BMC_MP_GPIO @BASEBOARD_FAB2_LIB.BASEBOARD_FAB2(SCH_1):FM_BB_BMC_MP_GPIO   I106 @BASEBOARD_FAB2_LIB.BASEBOARD_FAB2(SCH_1):PAGE147
   B13 FM_BMC_CPLD_MP_RST_N @BASEBOARD_FAB2_LIB.BASEBOARD_FAB2(SCH_1):FM_BMC_CPLD_MP_RST_N   I106 @BASEBOARD_FAB2_LIB.BASEBOARD_FAB2(SCH_1):PAGE147
    D3     NC     NC   I106 @BASEBOARD_FAB2_LIB.BASEBOARD_FAB2(SCH_1):PAGE147
    Y3 PUMP_PWM_OUT @BASEBOARD_FAB2_LIB.BASEBOARD_FAB2(SCH_1):PUMP_PWM_OUT   I106 @BASEBOARD_FAB2_LIB.BASEBOARD_FAB2(SCH_1):PAGE147
    T4 FM_PWRBRK_N @BASEBOARD_FAB2_LIB.BASEBOARD_FAB2(SCH_1):FM_PWRBRK_N   I106 @BASEBOARD_FAB2_LIB.BASEBOARD_FAB2(SCH_1):PAGE147
    W3 FM_BACKUP_BIOS_SEL_N @BASEBOARD_FAB2_LIB.BASEBOARD_FAB2(SCH_1):FM_BACKUP_BIOS_SEL_N   I106 @BASEBOARD_FAB2_LIB.BASEBOARD_FAB2(SCH_1):PAGE147
   AA3 FM_BIOS_SPI_BMC_CTRL @BASEBOARD_FAB2_LIB.BASEBOARD_FAB2(SCH_1):FM_BIOS_SPI_BMC_CTRL   I106 @BASEBOARD_FAB2_LIB.BASEBOARD_FAB2(SCH_1):PAGE147
    U3 FM_CPU_MSMI_LVT3_N @BASEBOARD_FAB2_LIB.BASEBOARD_FAB2(SCH_1):FM_CPU_MSMI_LVT3_N   I106 @BASEBOARD_FAB2_LIB.BASEBOARD_FAB2(SCH_1):PAGE147
    W2 FAN_PWM_OUT_SYS1 @BASEBOARD_FAB2_LIB.BASEBOARD_FAB2(SCH_1):FAN_PWM_OUT_SYS1   I106 @BASEBOARD_FAB2_LIB.BASEBOARD_FAB2(SCH_1):PAGE147
    V3 FM_BIOS_PREFRB2_GOOD @BASEBOARD_FAB2_LIB.BASEBOARD_FAB2(SCH_1):FM_BIOS_PREFRB2_GOOD   I106 @BASEBOARD_FAB2_LIB.BASEBOARD_FAB2(SCH_1):PAGE147
    V2 FAN_PWM_OUT_SYS0 @BASEBOARD_FAB2_LIB.BASEBOARD_FAB2(SCH_1):FAN_PWM_OUT_SYS0   I106 @BASEBOARD_FAB2_LIB.BASEBOARD_FAB2(SCH_1):PAGE147
    H2 P3V3_STBY_BMC_ADCVREFP @BASEBOARD_FAB2_LIB.BASEBOARD_FAB2(SCH_1):P3V3_STBY_BMC_ADCVREFP   I106 @BASEBOARD_FAB2_LIB.BASEBOARD_FAB2(SCH_1):PAGE147
    J1 PD_ADCREXT @BASEBOARD_FAB2_LIB.BASEBOARD_FAB2(SCH_1):PD_ADCREXT   I106 @BASEBOARD_FAB2_LIB.BASEBOARD_FAB2(SCH_1):PAGE147
    H1 P3V3_STBY_BMC_ADCVREFN @BASEBOARD_FAB2_LIB.BASEBOARD_FAB2(SCH_1):P3V3_STBY_BMC_ADCVREFN   I106 @BASEBOARD_FAB2_LIB.BASEBOARD_FAB2(SCH_1):PAGE147
    H3 H_CPU1_MEMGHJ_MEMHOT_LVT3_BMC_N @BASEBOARD_FAB2_LIB.BASEBOARD_FAB2(SCH_1):H_CPU1_MEMGHJ_MEMHOT_LVT3_BMC_N   I106 @BASEBOARD_FAB2_LIB.BASEBOARD_FAB2(SCH_1):PAGE147
    H4 H_CPU1_MEMKLM_MEMHOT_LVT3_BMC_N @BASEBOARD_FAB2_LIB.BASEBOARD_FAB2(SCH_1):H_CPU1_MEMKLM_MEMHOT_LVT3_BMC_N   I106 @BASEBOARD_FAB2_LIB.BASEBOARD_FAB2(SCH_1):PAGE147
    G1 H_CPU0_MEMDEF_MEMHOT_LVT3_BMC_N @BASEBOARD_FAB2_LIB.BASEBOARD_FAB2(SCH_1):H_CPU0_MEMDEF_MEMHOT_LVT3_BMC_N   I106 @BASEBOARD_FAB2_LIB.BASEBOARD_FAB2(SCH_1):PAGE147
    H5 H_CPU0_MEMABC_MEMHOT_LVT3_BMC_N @BASEBOARD_FAB2_LIB.BASEBOARD_FAB2(SCH_1):H_CPU0_MEMABC_MEMHOT_LVT3_BMC_N   I106 @BASEBOARD_FAB2_LIB.BASEBOARD_FAB2(SCH_1):PAGE147
    F1 FM_GLOBAL_RST_WARN_N_R @BASEBOARD_FAB2_LIB.BASEBOARD_FAB2(SCH_1):FM_GLOBAL_RST_WARN_N_R   I106 @BASEBOARD_FAB2_LIB.BASEBOARD_FAB2(SCH_1):PAGE147
    G3    GND @BASEBOARD_FAB2_LIB.BASEBOARD_FAB2(SCH_1):GND   I106 @BASEBOARD_FAB2_LIB.BASEBOARD_FAB2(SCH_1):PAGE147
    G2    GND @BASEBOARD_FAB2_LIB.BASEBOARD_FAB2(SCH_1):GND   I106 @BASEBOARD_FAB2_LIB.BASEBOARD_FAB2(SCH_1):PAGE147
    G5 A_P5V_STBY_SCALED @BASEBOARD_FAB2_LIB.BASEBOARD_FAB2(SCH_1):A_P5V_STBY_SCALED   I106 @BASEBOARD_FAB2_LIB.BASEBOARD_FAB2(SCH_1):PAGE147
    F3 A_PVNN_STBY_PCH_SENSOR @BASEBOARD_FAB2_LIB.BASEBOARD_FAB2(SCH_1):A_PVNN_STBY_PCH_SENSOR   I106 @BASEBOARD_FAB2_LIB.BASEBOARD_FAB2(SCH_1):PAGE147
    E3 A_P3V3_STBY_SCALED @BASEBOARD_FAB2_LIB.BASEBOARD_FAB2(SCH_1):A_P3V3_STBY_SCALED   I106 @BASEBOARD_FAB2_LIB.BASEBOARD_FAB2(SCH_1):PAGE147
    E1 A_P1V05_STBY_PCH_SENSOR @BASEBOARD_FAB2_LIB.BASEBOARD_FAB2(SCH_1):A_P1V05_STBY_PCH_SENSOR   I106 @BASEBOARD_FAB2_LIB.BASEBOARD_FAB2(SCH_1):PAGE147
    E2 A_P12V_STBY_SCALED @BASEBOARD_FAB2_LIB.BASEBOARD_FAB2(SCH_1):A_P12V_STBY_SCALED   I106 @BASEBOARD_FAB2_LIB.BASEBOARD_FAB2(SCH_1):PAGE147
    F5 A_P5V_SCALED @BASEBOARD_FAB2_LIB.BASEBOARD_FAB2(SCH_1):A_P5V_SCALED   I106 @BASEBOARD_FAB2_LIB.BASEBOARD_FAB2(SCH_1):PAGE147
    F4 A_P3V3_SCALED @BASEBOARD_FAB2_LIB.BASEBOARD_FAB2(SCH_1):A_P3V3_SCALED   I106 @BASEBOARD_FAB2_LIB.BASEBOARD_FAB2(SCH_1):PAGE147
    V6 BMC_RSMRST_B_N @BASEBOARD_FAB2_LIB.BASEBOARD_FAB2(SCH_1):BMC_RSMRST_B_N   I106 @BASEBOARD_FAB2_LIB.BASEBOARD_FAB2(SCH_1):PAGE147
    W6 BMC_PWR_DEBUG_N @BASEBOARD_FAB2_LIB.BASEBOARD_FAB2(SCH_1):BMC_PWR_DEBUG_N   I106 @BASEBOARD_FAB2_LIB.BASEBOARD_FAB2(SCH_1):PAGE147
   AB5 FM_BOARD_SKU_ID3 @BASEBOARD_FAB2_LIB.BASEBOARD_FAB2(SCH_1):FM_BOARD_SKU_ID3   I106 @BASEBOARD_FAB2_LIB.BASEBOARD_FAB2(SCH_1):PAGE147
    Y6 FM_BOARD_SKU_ID4 @BASEBOARD_FAB2_LIB.BASEBOARD_FAB2(SCH_1):FM_BOARD_SKU_ID4   I106 @BASEBOARD_FAB2_LIB.BASEBOARD_FAB2(SCH_1):PAGE147
    Y5 BMC_PREQ_N @BASEBOARD_FAB2_LIB.BASEBOARD_FAB2(SCH_1):BMC_PREQ_N   I106 @BASEBOARD_FAB2_LIB.BASEBOARD_FAB2(SCH_1):PAGE147
   AA5 FM_BOARD_SKU_ID2 @BASEBOARD_FAB2_LIB.BASEBOARD_FAB2(SCH_1):FM_BOARD_SKU_ID2   I106 @BASEBOARD_FAB2_LIB.BASEBOARD_FAB2(SCH_1):PAGE147
    W5 FM_BOARD_SKU_ID1 @BASEBOARD_FAB2_LIB.BASEBOARD_FAB2(SCH_1):FM_BOARD_SKU_ID1   I106 @BASEBOARD_FAB2_LIB.BASEBOARD_FAB2(SCH_1):PAGE147
   AA4 FM_XRC_PRESENT_N @BASEBOARD_FAB2_LIB.BASEBOARD_FAB2(SCH_1):FM_XRC_PRESENT_N   I106 @BASEBOARD_FAB2_LIB.BASEBOARD_FAB2(SCH_1):PAGE147
    W4 FM_XRC_READY_N @BASEBOARD_FAB2_LIB.BASEBOARD_FAB2(SCH_1):FM_XRC_READY_N   I106 @BASEBOARD_FAB2_LIB.BASEBOARD_FAB2(SCH_1):PAGE147
    V4 FM_BOARD_SKU_ID0 @BASEBOARD_FAB2_LIB.BASEBOARD_FAB2(SCH_1):FM_BOARD_SKU_ID0   I106 @BASEBOARD_FAB2_LIB.BASEBOARD_FAB2(SCH_1):PAGE147
   AB3 PUMP_TACH0 @BASEBOARD_FAB2_LIB.BASEBOARD_FAB2(SCH_1):PUMP_TACH0   I106 @BASEBOARD_FAB2_LIB.BASEBOARD_FAB2(SCH_1):PAGE147
    Y4 PUMP_TACH1 @BASEBOARD_FAB2_LIB.BASEBOARD_FAB2(SCH_1):PUMP_TACH1   I106 @BASEBOARD_FAB2_LIB.BASEBOARD_FAB2(SCH_1):PAGE147
   AB4 FAN_TACH3 @BASEBOARD_FAB2_LIB.BASEBOARD_FAB2(SCH_1):FAN_TACH3   I106 @BASEBOARD_FAB2_LIB.BASEBOARD_FAB2(SCH_1):PAGE147
    U4 FAN_TACH1 @BASEBOARD_FAB2_LIB.BASEBOARD_FAB2(SCH_1):FAN_TACH1   I106 @BASEBOARD_FAB2_LIB.BASEBOARD_FAB2(SCH_1):PAGE147
    V5 FAN_TACH2 @BASEBOARD_FAB2_LIB.BASEBOARD_FAB2(SCH_1):FAN_TACH2   I106 @BASEBOARD_FAB2_LIB.BASEBOARD_FAB2(SCH_1):PAGE147
    U5 FAN_TACH0 @BASEBOARD_FAB2_LIB.BASEBOARD_FAB2(SCH_1):FAN_TACH0   I106 @BASEBOARD_FAB2_LIB.BASEBOARD_FAB2(SCH_1):PAGE147
    B1 RMII_BMC_SPRNGVLLE_TXEN_R @BASEBOARD_FAB2_LIB.BASEBOARD_FAB2(SCH_1):RMII_BMC_SPRNGVLLE_TXEN_R   I106 @BASEBOARD_FAB2_LIB.BASEBOARD_FAB2(SCH_1):PAGE147
    B2     NC     NC   I106 @BASEBOARD_FAB2_LIB.BASEBOARD_FAB2(SCH_1):PAGE147
    D5 TP_RGMII2TXD2_GPIOU2 @BASEBOARD_FAB2_LIB.BASEBOARD_FAB2(SCH_1):TP_RGMII2TXD2_GPIOU2   I106 @BASEBOARD_FAB2_LIB.BASEBOARD_FAB2(SCH_1):PAGE147
    D4 TP_RGMII2TXD3_GPIOU3 @BASEBOARD_FAB2_LIB.BASEBOARD_FAB2(SCH_1):TP_RGMII2TXD3_GPIOU3   I106 @BASEBOARD_FAB2_LIB.BASEBOARD_FAB2(SCH_1):PAGE147
    B3 RMII_BMC_PCH_SPRNGVLLE_TXD1_R @BASEBOARD_FAB2_LIB.BASEBOARD_FAB2(SCH_1):RMII_BMC_PCH_SPRNGVLLE_TXD1_R   I106 @BASEBOARD_FAB2_LIB.BASEBOARD_FAB2(SCH_1):PAGE147
    A2 RMII_BMC_PCH_SPRNGVLLE_TXD0_R @BASEBOARD_FAB2_LIB.BASEBOARD_FAB2(SCH_1):RMII_BMC_PCH_SPRNGVLLE_TXD0_R   I106 @BASEBOARD_FAB2_LIB.BASEBOARD_FAB2(SCH_1):PAGE147
    B5     NC     NC   I106 @BASEBOARD_FAB2_LIB.BASEBOARD_FAB2(SCH_1):PAGE147
    E9 RMII_BMC_OCP_TXEN_R @BASEBOARD_FAB2_LIB.BASEBOARD_FAB2(SCH_1):RMII_BMC_OCP_TXEN_R   I106 @BASEBOARD_FAB2_LIB.BASEBOARD_FAB2(SCH_1):PAGE147
    E7 TP_RGMII1TXD2_GPIOT4 @BASEBOARD_FAB2_LIB.BASEBOARD_FAB2(SCH_1):TP_RGMII1TXD2_GPIOT4   I106 @BASEBOARD_FAB2_LIB.BASEBOARD_FAB2(SCH_1):PAGE147
    D7 TP_RGMII1TXD3_GPIOT5 @BASEBOARD_FAB2_LIB.BASEBOARD_FAB2(SCH_1):TP_RGMII1TXD3_GPIOT5   I106 @BASEBOARD_FAB2_LIB.BASEBOARD_FAB2(SCH_1):PAGE147
    F9 RMII_BMC_OCP_TXD0_R @BASEBOARD_FAB2_LIB.BASEBOARD_FAB2(SCH_1):RMII_BMC_OCP_TXD0_R   I106 @BASEBOARD_FAB2_LIB.BASEBOARD_FAB2(SCH_1):PAGE147
    A5 RMII_BMC_OCP_TXD1_R @BASEBOARD_FAB2_LIB.BASEBOARD_FAB2(SCH_1):RMII_BMC_OCP_TXD1_R   I106 @BASEBOARD_FAB2_LIB.BASEBOARD_FAB2(SCH_1):PAGE147
    C1 FM_FAST_PROCHOT_EN_N @BASEBOARD_FAB2_LIB.BASEBOARD_FAB2(SCH_1):FM_FAST_PROCHOT_EN_N   I106 @BASEBOARD_FAB2_LIB.BASEBOARD_FAB2(SCH_1):PAGE147
    D8 FM_SLT_CFG0 @BASEBOARD_FAB2_LIB.BASEBOARD_FAB2(SCH_1):FM_SLT_CFG0   I106 @BASEBOARD_FAB2_LIB.BASEBOARD_FAB2(SCH_1):PAGE147
   E10 FM_SLT_CFG1 @BASEBOARD_FAB2_LIB.BASEBOARD_FAB2(SCH_1):FM_SLT_CFG1   I106 @BASEBOARD_FAB2_LIB.BASEBOARD_FAB2(SCH_1):PAGE147
    A3 RMII_BMC_OCP_RXD0 @BASEBOARD_FAB2_LIB.BASEBOARD_FAB2(SCH_1):RMII_BMC_OCP_RXD0   I106 @BASEBOARD_FAB2_LIB.BASEBOARD_FAB2(SCH_1):PAGE147
    D6 RMII_BMC_OCP_RXD1 @BASEBOARD_FAB2_LIB.BASEBOARD_FAB2(SCH_1):RMII_BMC_OCP_RXD1   I106 @BASEBOARD_FAB2_LIB.BASEBOARD_FAB2(SCH_1):PAGE147
    C5 RMII_BMC_OCP_CRSDV @BASEBOARD_FAB2_LIB.BASEBOARD_FAB2(SCH_1):RMII_BMC_OCP_CRSDV   I106 @BASEBOARD_FAB2_LIB.BASEBOARD_FAB2(SCH_1):PAGE147
    C4 RMII_BMC_OCP_RXER @BASEBOARD_FAB2_LIB.BASEBOARD_FAB2(SCH_1):RMII_BMC_OCP_RXER   I106 @BASEBOARD_FAB2_LIB.BASEBOARD_FAB2(SCH_1):PAGE147
    A4 FM_BMC_FAULT_LED_N @BASEBOARD_FAB2_LIB.BASEBOARD_FAB2(SCH_1):FM_BMC_FAULT_LED_N   I106 @BASEBOARD_FAB2_LIB.BASEBOARD_FAB2(SCH_1):PAGE147
    B4 CLK_50M_CKMNG_BMC_1 @BASEBOARD_FAB2_LIB.BASEBOARD_FAB2(SCH_1):CLK_50M_CKMNG_BMC_1   I106 @BASEBOARD_FAB2_LIB.BASEBOARD_FAB2(SCH_1):PAGE147
    C3 RMII_SPRNGVLLE_BMC_PCH_RXD0 @BASEBOARD_FAB2_LIB.BASEBOARD_FAB2(SCH_1):RMII_SPRNGVLLE_BMC_PCH_RXD0   I106 @BASEBOARD_FAB2_LIB.BASEBOARD_FAB2(SCH_1):PAGE147
    D1 RMII_SPRNGVLLE_BMC_PCH_RXD1 @BASEBOARD_FAB2_LIB.BASEBOARD_FAB2(SCH_1):RMII_SPRNGVLLE_BMC_PCH_RXD1   I106 @BASEBOARD_FAB2_LIB.BASEBOARD_FAB2(SCH_1):PAGE147
    D2 RMII_BMC_PCH_SPRNGVLLE_CRSDV @BASEBOARD_FAB2_LIB.BASEBOARD_FAB2(SCH_1):RMII_BMC_PCH_SPRNGVLLE_CRSDV   I106 @BASEBOARD_FAB2_LIB.BASEBOARD_FAB2(SCH_1):PAGE147
    E6 RMII_BMC_PCH_SPRNGVLLE_RXER @BASEBOARD_FAB2_LIB.BASEBOARD_FAB2(SCH_1):RMII_BMC_PCH_SPRNGVLLE_RXER   I106 @BASEBOARD_FAB2_LIB.BASEBOARD_FAB2(SCH_1):PAGE147
    C2 CLK_50M_CKMNG_BMC_2 @BASEBOARD_FAB2_LIB.BASEBOARD_FAB2(SCH_1):CLK_50M_CKMNG_BMC_2   I106 @BASEBOARD_FAB2_LIB.BASEBOARD_FAB2(SCH_1):PAGE147
   K17 P3V3_STBY @BASEBOARD_FAB2_LIB.BASEBOARD_FAB2(SCH_1):P3V3_STBY    I28 @BASEBOARD_FAB2_LIB.BASEBOARD_FAB2(SCH_1):PAGE148
   J17 P3V3_STBY @BASEBOARD_FAB2_LIB.BASEBOARD_FAB2(SCH_1):P3V3_STBY    I28 @BASEBOARD_FAB2_LIB.BASEBOARD_FAB2(SCH_1):PAGE148
    E5    GND @BASEBOARD_FAB2_LIB.BASEBOARD_FAB2(SCH_1):GND    I28 @BASEBOARD_FAB2_LIB.BASEBOARD_FAB2(SCH_1):PAGE148
    K6 VCC_DACAV3V3 @BASEBOARD_FAB2_LIB.BASEBOARD_FAB2(SCH_1):VCC_DACAV3V3    I28 @BASEBOARD_FAB2_LIB.BASEBOARD_FAB2(SCH_1):PAGE148
   F12 VCC_D_3V3 @BASEBOARD_FAB2_LIB.BASEBOARD_FAB2(SCH_1):VCC_D_3V3    I28 @BASEBOARD_FAB2_LIB.BASEBOARD_FAB2(SCH_1):PAGE148
    T8 P1V2_AUX_BMC @BASEBOARD_FAB2_LIB.BASEBOARD_FAB2(SCH_1):P1V2_AUX_BMC    I28 @BASEBOARD_FAB2_LIB.BASEBOARD_FAB2(SCH_1):PAGE148
   P22 BMC_JTAG_SEL_N @BASEBOARD_FAB2_LIB.BASEBOARD_FAB2(SCH_1):BMC_JTAG_SEL_N    I28 @BASEBOARD_FAB2_LIB.BASEBOARD_FAB2(SCH_1):PAGE148
   R21 FM_SLPS4_N @BASEBOARD_FAB2_LIB.BASEBOARD_FAB2(SCH_1):FM_SLPS4_N    I28 @BASEBOARD_FAB2_LIB.BASEBOARD_FAB2(SCH_1):PAGE148
   R22 FM_SLPS3_N @BASEBOARD_FAB2_LIB.BASEBOARD_FAB2(SCH_1):FM_SLPS3_N    I28 @BASEBOARD_FAB2_LIB.BASEBOARD_FAB2(SCH_1):PAGE148
    F6 P1V15_AUX_BMC @BASEBOARD_FAB2_LIB.BASEBOARD_FAB2(SCH_1):P1V15_AUX_BMC    I28 @BASEBOARD_FAB2_LIB.BASEBOARD_FAB2(SCH_1):PAGE148
   G10 P1V15_AUX_BMC @BASEBOARD_FAB2_LIB.BASEBOARD_FAB2(SCH_1):P1V15_AUX_BMC    I28 @BASEBOARD_FAB2_LIB.BASEBOARD_FAB2(SCH_1):PAGE148
   G11 P1V15_AUX_BMC @BASEBOARD_FAB2_LIB.BASEBOARD_FAB2(SCH_1):P1V15_AUX_BMC    I28 @BASEBOARD_FAB2_LIB.BASEBOARD_FAB2(SCH_1):PAGE148
   G12 P1V15_AUX_BMC @BASEBOARD_FAB2_LIB.BASEBOARD_FAB2(SCH_1):P1V15_AUX_BMC    I28 @BASEBOARD_FAB2_LIB.BASEBOARD_FAB2(SCH_1):PAGE148
   G13 P1V15_AUX_BMC @BASEBOARD_FAB2_LIB.BASEBOARD_FAB2(SCH_1):P1V15_AUX_BMC    I28 @BASEBOARD_FAB2_LIB.BASEBOARD_FAB2(SCH_1):PAGE148
   G14 P1V15_AUX_BMC @BASEBOARD_FAB2_LIB.BASEBOARD_FAB2(SCH_1):P1V15_AUX_BMC    I28 @BASEBOARD_FAB2_LIB.BASEBOARD_FAB2(SCH_1):PAGE148
   G15 P1V15_AUX_BMC @BASEBOARD_FAB2_LIB.BASEBOARD_FAB2(SCH_1):P1V15_AUX_BMC    I28 @BASEBOARD_FAB2_LIB.BASEBOARD_FAB2(SCH_1):PAGE148
    G7 P1V15_AUX_BMC @BASEBOARD_FAB2_LIB.BASEBOARD_FAB2(SCH_1):P1V15_AUX_BMC    I28 @BASEBOARD_FAB2_LIB.BASEBOARD_FAB2(SCH_1):PAGE148
    G8 P1V15_AUX_BMC @BASEBOARD_FAB2_LIB.BASEBOARD_FAB2(SCH_1):P1V15_AUX_BMC    I28 @BASEBOARD_FAB2_LIB.BASEBOARD_FAB2(SCH_1):PAGE148
    G9 P1V15_AUX_BMC @BASEBOARD_FAB2_LIB.BASEBOARD_FAB2(SCH_1):P1V15_AUX_BMC    I28 @BASEBOARD_FAB2_LIB.BASEBOARD_FAB2(SCH_1):PAGE148
   H16 P1V15_AUX_BMC @BASEBOARD_FAB2_LIB.BASEBOARD_FAB2(SCH_1):P1V15_AUX_BMC    I28 @BASEBOARD_FAB2_LIB.BASEBOARD_FAB2(SCH_1):PAGE148
   J16 P1V15_AUX_BMC @BASEBOARD_FAB2_LIB.BASEBOARD_FAB2(SCH_1):P1V15_AUX_BMC    I28 @BASEBOARD_FAB2_LIB.BASEBOARD_FAB2(SCH_1):PAGE148
    L7 P1V15_AUX_BMC @BASEBOARD_FAB2_LIB.BASEBOARD_FAB2(SCH_1):P1V15_AUX_BMC    I28 @BASEBOARD_FAB2_LIB.BASEBOARD_FAB2(SCH_1):PAGE148
   N16 P1V15_AUX_BMC @BASEBOARD_FAB2_LIB.BASEBOARD_FAB2(SCH_1):P1V15_AUX_BMC    I28 @BASEBOARD_FAB2_LIB.BASEBOARD_FAB2(SCH_1):PAGE148
    N7 P1V15_AUX_BMC @BASEBOARD_FAB2_LIB.BASEBOARD_FAB2(SCH_1):P1V15_AUX_BMC    I28 @BASEBOARD_FAB2_LIB.BASEBOARD_FAB2(SCH_1):PAGE148
   P10 P1V15_AUX_BMC @BASEBOARD_FAB2_LIB.BASEBOARD_FAB2(SCH_1):P1V15_AUX_BMC    I28 @BASEBOARD_FAB2_LIB.BASEBOARD_FAB2(SCH_1):PAGE148
   P11 P1V15_AUX_BMC @BASEBOARD_FAB2_LIB.BASEBOARD_FAB2(SCH_1):P1V15_AUX_BMC    I28 @BASEBOARD_FAB2_LIB.BASEBOARD_FAB2(SCH_1):PAGE148
   P12 P1V15_AUX_BMC @BASEBOARD_FAB2_LIB.BASEBOARD_FAB2(SCH_1):P1V15_AUX_BMC    I28 @BASEBOARD_FAB2_LIB.BASEBOARD_FAB2(SCH_1):PAGE148
   P13 P1V15_AUX_BMC @BASEBOARD_FAB2_LIB.BASEBOARD_FAB2(SCH_1):P1V15_AUX_BMC    I28 @BASEBOARD_FAB2_LIB.BASEBOARD_FAB2(SCH_1):PAGE148
   P14 P1V15_AUX_BMC @BASEBOARD_FAB2_LIB.BASEBOARD_FAB2(SCH_1):P1V15_AUX_BMC    I28 @BASEBOARD_FAB2_LIB.BASEBOARD_FAB2(SCH_1):PAGE148
   P16 P1V15_AUX_BMC @BASEBOARD_FAB2_LIB.BASEBOARD_FAB2(SCH_1):P1V15_AUX_BMC    I28 @BASEBOARD_FAB2_LIB.BASEBOARD_FAB2(SCH_1):PAGE148
    P7 P1V15_AUX_BMC @BASEBOARD_FAB2_LIB.BASEBOARD_FAB2(SCH_1):P1V15_AUX_BMC    I28 @BASEBOARD_FAB2_LIB.BASEBOARD_FAB2(SCH_1):PAGE148
    P9 P1V15_AUX_BMC @BASEBOARD_FAB2_LIB.BASEBOARD_FAB2(SCH_1):P1V15_AUX_BMC    I28 @BASEBOARD_FAB2_LIB.BASEBOARD_FAB2(SCH_1):PAGE148
   R16 P1V15_AUX_BMC @BASEBOARD_FAB2_LIB.BASEBOARD_FAB2(SCH_1):P1V15_AUX_BMC    I28 @BASEBOARD_FAB2_LIB.BASEBOARD_FAB2(SCH_1):PAGE148
    R7 P1V15_AUX_BMC @BASEBOARD_FAB2_LIB.BASEBOARD_FAB2(SCH_1):P1V15_AUX_BMC    I28 @BASEBOARD_FAB2_LIB.BASEBOARD_FAB2(SCH_1):PAGE148
    L5 VCC_A_1V1 @BASEBOARD_FAB2_LIB.BASEBOARD_FAB2(SCH_1):VCC_A_1V1    I28 @BASEBOARD_FAB2_LIB.BASEBOARD_FAB2(SCH_1):PAGE148
    L6 VCC_A_1V1 @BASEBOARD_FAB2_LIB.BASEBOARD_FAB2(SCH_1):VCC_A_1V1    I28 @BASEBOARD_FAB2_LIB.BASEBOARD_FAB2(SCH_1):PAGE148
   L17 P1V15_AUX_BMC @BASEBOARD_FAB2_LIB.BASEBOARD_FAB2(SCH_1):P1V15_AUX_BMC    I28 @BASEBOARD_FAB2_LIB.BASEBOARD_FAB2(SCH_1):PAGE148
   V17 P1V15_AUX_BMC @BASEBOARD_FAB2_LIB.BASEBOARD_FAB2(SCH_1):P1V15_AUX_BMC    I28 @BASEBOARD_FAB2_LIB.BASEBOARD_FAB2(SCH_1):PAGE148
  AA17 PVCCIO_CPU0_R @BASEBOARD_FAB2_LIB.BASEBOARD_FAB2(SCH_1):PVCCIO_CPU0_R    I28 @BASEBOARD_FAB2_LIB.BASEBOARD_FAB2(SCH_1):PAGE148
   T10 P1V2_AUX_BMC @BASEBOARD_FAB2_LIB.BASEBOARD_FAB2(SCH_1):P1V2_AUX_BMC    I28 @BASEBOARD_FAB2_LIB.BASEBOARD_FAB2(SCH_1):PAGE148
   T12 P1V2_AUX_BMC @BASEBOARD_FAB2_LIB.BASEBOARD_FAB2(SCH_1):P1V2_AUX_BMC    I28 @BASEBOARD_FAB2_LIB.BASEBOARD_FAB2(SCH_1):PAGE148
   T13 P1V2_AUX_BMC @BASEBOARD_FAB2_LIB.BASEBOARD_FAB2(SCH_1):P1V2_AUX_BMC    I28 @BASEBOARD_FAB2_LIB.BASEBOARD_FAB2(SCH_1):PAGE148
   T14 P1V2_AUX_BMC @BASEBOARD_FAB2_LIB.BASEBOARD_FAB2(SCH_1):P1V2_AUX_BMC    I28 @BASEBOARD_FAB2_LIB.BASEBOARD_FAB2(SCH_1):PAGE148
   F13 VCC_D_3V3 @BASEBOARD_FAB2_LIB.BASEBOARD_FAB2(SCH_1):VCC_D_3V3    I28 @BASEBOARD_FAB2_LIB.BASEBOARD_FAB2(SCH_1):PAGE148
   F14 VCC_D_3V3 @BASEBOARD_FAB2_LIB.BASEBOARD_FAB2(SCH_1):VCC_D_3V3    I28 @BASEBOARD_FAB2_LIB.BASEBOARD_FAB2(SCH_1):PAGE148
   F15 VCC_D_3V3 @BASEBOARD_FAB2_LIB.BASEBOARD_FAB2(SCH_1):VCC_D_3V3    I28 @BASEBOARD_FAB2_LIB.BASEBOARD_FAB2(SCH_1):PAGE148
   G16 VCC_D_3V3 @BASEBOARD_FAB2_LIB.BASEBOARD_FAB2(SCH_1):VCC_D_3V3    I28 @BASEBOARD_FAB2_LIB.BASEBOARD_FAB2(SCH_1):PAGE148
   H17 VCC_D_3V3 @BASEBOARD_FAB2_LIB.BASEBOARD_FAB2(SCH_1):VCC_D_3V3    I28 @BASEBOARD_FAB2_LIB.BASEBOARD_FAB2(SCH_1):PAGE148
    K7 VCC_D_3V3 @BASEBOARD_FAB2_LIB.BASEBOARD_FAB2(SCH_1):VCC_D_3V3    I28 @BASEBOARD_FAB2_LIB.BASEBOARD_FAB2(SCH_1):PAGE148
   N17 VCC_D_3V3 @BASEBOARD_FAB2_LIB.BASEBOARD_FAB2(SCH_1):VCC_D_3V3    I28 @BASEBOARD_FAB2_LIB.BASEBOARD_FAB2(SCH_1):PAGE148
    N6 VCC_D_3V3 @BASEBOARD_FAB2_LIB.BASEBOARD_FAB2(SCH_1):VCC_D_3V3    I28 @BASEBOARD_FAB2_LIB.BASEBOARD_FAB2(SCH_1):PAGE148
   P17 VCC_D_3V3 @BASEBOARD_FAB2_LIB.BASEBOARD_FAB2(SCH_1):VCC_D_3V3    I28 @BASEBOARD_FAB2_LIB.BASEBOARD_FAB2(SCH_1):PAGE148
    P6 VCC_D_3V3 @BASEBOARD_FAB2_LIB.BASEBOARD_FAB2(SCH_1):VCC_D_3V3    I28 @BASEBOARD_FAB2_LIB.BASEBOARD_FAB2(SCH_1):PAGE148
   R17 VCC_D_3V3 @BASEBOARD_FAB2_LIB.BASEBOARD_FAB2(SCH_1):VCC_D_3V3    I28 @BASEBOARD_FAB2_LIB.BASEBOARD_FAB2(SCH_1):PAGE148
    R6 VCC_D_3V3 @BASEBOARD_FAB2_LIB.BASEBOARD_FAB2(SCH_1):VCC_D_3V3    I28 @BASEBOARD_FAB2_LIB.BASEBOARD_FAB2(SCH_1):PAGE148
   T11 VCC_PA_3V3 @BASEBOARD_FAB2_LIB.BASEBOARD_FAB2(SCH_1):VCC_PA_3V3    I28 @BASEBOARD_FAB2_LIB.BASEBOARD_FAB2(SCH_1):PAGE148
   T15 VCC_D_3V3 @BASEBOARD_FAB2_LIB.BASEBOARD_FAB2(SCH_1):VCC_D_3V3    I28 @BASEBOARD_FAB2_LIB.BASEBOARD_FAB2(SCH_1):PAGE148
   Y17 VCC_PA_3V3 @BASEBOARD_FAB2_LIB.BASEBOARD_FAB2(SCH_1):VCC_PA_3V3    I28 @BASEBOARD_FAB2_LIB.BASEBOARD_FAB2(SCH_1):PAGE148
   W17 VCC_PA_3V3 @BASEBOARD_FAB2_LIB.BASEBOARD_FAB2(SCH_1):VCC_PA_3V3    I28 @BASEBOARD_FAB2_LIB.BASEBOARD_FAB2(SCH_1):PAGE148
    J7 VCC_VA_3V3 @BASEBOARD_FAB2_LIB.BASEBOARD_FAB2(SCH_1):VCC_VA_3V3    I28 @BASEBOARD_FAB2_LIB.BASEBOARD_FAB2(SCH_1):PAGE148
    H7 VCC_VA_3V3 @BASEBOARD_FAB2_LIB.BASEBOARD_FAB2(SCH_1):VCC_VA_3V3    I28 @BASEBOARD_FAB2_LIB.BASEBOARD_FAB2(SCH_1):PAGE148
   L16 VCC_D_3V3 @BASEBOARD_FAB2_LIB.BASEBOARD_FAB2(SCH_1):VCC_D_3V3    I28 @BASEBOARD_FAB2_LIB.BASEBOARD_FAB2(SCH_1):PAGE148
    E4 VCCBAT_TW12 @BASEBOARD_FAB2_LIB.BASEBOARD_FAB2(SCH_1):VCCBAT_TW12    I28 @BASEBOARD_FAB2_LIB.BASEBOARD_FAB2(SCH_1):PAGE148
    C7 P3V3_USB2A_ALG @BASEBOARD_FAB2_LIB.BASEBOARD_FAB2(SCH_1):P3V3_USB2A_ALG    I28 @BASEBOARD_FAB2_LIB.BASEBOARD_FAB2(SCH_1):PAGE148
    K5 VCC_DACAV3V3 @BASEBOARD_FAB2_LIB.BASEBOARD_FAB2(SCH_1):VCC_DACAV3V3    I28 @BASEBOARD_FAB2_LIB.BASEBOARD_FAB2(SCH_1):PAGE148
    J6 VCC_ADCAV3V3 @BASEBOARD_FAB2_LIB.BASEBOARD_FAB2(SCH_1):VCC_ADCAV3V3    I28 @BASEBOARD_FAB2_LIB.BASEBOARD_FAB2(SCH_1):PAGE148
    F7 P3V3_STBY @BASEBOARD_FAB2_LIB.BASEBOARD_FAB2(SCH_1):P3V3_STBY    I28 @BASEBOARD_FAB2_LIB.BASEBOARD_FAB2(SCH_1):PAGE148
    F8 P3V3_STBY @BASEBOARD_FAB2_LIB.BASEBOARD_FAB2(SCH_1):P3V3_STBY    I28 @BASEBOARD_FAB2_LIB.BASEBOARD_FAB2(SCH_1):PAGE148
   F10 P3V3_STBY @BASEBOARD_FAB2_LIB.BASEBOARD_FAB2(SCH_1):P3V3_STBY    I28 @BASEBOARD_FAB2_LIB.BASEBOARD_FAB2(SCH_1):PAGE148
   F11 P3V3_STBY @BASEBOARD_FAB2_LIB.BASEBOARD_FAB2(SCH_1):P3V3_STBY    I28 @BASEBOARD_FAB2_LIB.BASEBOARD_FAB2(SCH_1):PAGE148
    V8    GND @BASEBOARD_FAB2_LIB.BASEBOARD_FAB2(SCH_1):GND    I28 @BASEBOARD_FAB2_LIB.BASEBOARD_FAB2(SCH_1):PAGE148
   V16    GND @BASEBOARD_FAB2_LIB.BASEBOARD_FAB2(SCH_1):GND    I28 @BASEBOARD_FAB2_LIB.BASEBOARD_FAB2(SCH_1):PAGE148
   V14    GND @BASEBOARD_FAB2_LIB.BASEBOARD_FAB2(SCH_1):GND    I28 @BASEBOARD_FAB2_LIB.BASEBOARD_FAB2(SCH_1):PAGE148
    T7    GND @BASEBOARD_FAB2_LIB.BASEBOARD_FAB2(SCH_1):GND    I28 @BASEBOARD_FAB2_LIB.BASEBOARD_FAB2(SCH_1):PAGE148
   U11    GND @BASEBOARD_FAB2_LIB.BASEBOARD_FAB2(SCH_1):GND    I28 @BASEBOARD_FAB2_LIB.BASEBOARD_FAB2(SCH_1):PAGE148
   V12    GND @BASEBOARD_FAB2_LIB.BASEBOARD_FAB2(SCH_1):GND    I28 @BASEBOARD_FAB2_LIB.BASEBOARD_FAB2(SCH_1):PAGE148
   V10    GND @BASEBOARD_FAB2_LIB.BASEBOARD_FAB2(SCH_1):GND    I28 @BASEBOARD_FAB2_LIB.BASEBOARD_FAB2(SCH_1):PAGE148
    U6    GND @BASEBOARD_FAB2_LIB.BASEBOARD_FAB2(SCH_1):GND    I28 @BASEBOARD_FAB2_LIB.BASEBOARD_FAB2(SCH_1):PAGE148
   N13    GND @BASEBOARD_FAB2_LIB.BASEBOARD_FAB2(SCH_1):GND    I28 @BASEBOARD_FAB2_LIB.BASEBOARD_FAB2(SCH_1):PAGE148
   N14    GND @BASEBOARD_FAB2_LIB.BASEBOARD_FAB2(SCH_1):GND    I28 @BASEBOARD_FAB2_LIB.BASEBOARD_FAB2(SCH_1):PAGE148
    T6    GND @BASEBOARD_FAB2_LIB.BASEBOARD_FAB2(SCH_1):GND    I28 @BASEBOARD_FAB2_LIB.BASEBOARD_FAB2(SCH_1):PAGE148
   T16    GND @BASEBOARD_FAB2_LIB.BASEBOARD_FAB2(SCH_1):GND    I28 @BASEBOARD_FAB2_LIB.BASEBOARD_FAB2(SCH_1):PAGE148
    N9    GND @BASEBOARD_FAB2_LIB.BASEBOARD_FAB2(SCH_1):GND    I28 @BASEBOARD_FAB2_LIB.BASEBOARD_FAB2(SCH_1):PAGE148
    M7    GND @BASEBOARD_FAB2_LIB.BASEBOARD_FAB2(SCH_1):GND    I28 @BASEBOARD_FAB2_LIB.BASEBOARD_FAB2(SCH_1):PAGE148
    M9    GND @BASEBOARD_FAB2_LIB.BASEBOARD_FAB2(SCH_1):GND    I28 @BASEBOARD_FAB2_LIB.BASEBOARD_FAB2(SCH_1):PAGE148
   N12    GND @BASEBOARD_FAB2_LIB.BASEBOARD_FAB2(SCH_1):GND    I28 @BASEBOARD_FAB2_LIB.BASEBOARD_FAB2(SCH_1):PAGE148
   N11    GND @BASEBOARD_FAB2_LIB.BASEBOARD_FAB2(SCH_1):GND    I28 @BASEBOARD_FAB2_LIB.BASEBOARD_FAB2(SCH_1):PAGE148
   N10    GND @BASEBOARD_FAB2_LIB.BASEBOARD_FAB2(SCH_1):GND    I28 @BASEBOARD_FAB2_LIB.BASEBOARD_FAB2(SCH_1):PAGE148
    M2    GND @BASEBOARD_FAB2_LIB.BASEBOARD_FAB2(SCH_1):GND    I28 @BASEBOARD_FAB2_LIB.BASEBOARD_FAB2(SCH_1):PAGE148
    M3    GND @BASEBOARD_FAB2_LIB.BASEBOARD_FAB2(SCH_1):GND    I28 @BASEBOARD_FAB2_LIB.BASEBOARD_FAB2(SCH_1):PAGE148
    M6    GND @BASEBOARD_FAB2_LIB.BASEBOARD_FAB2(SCH_1):GND    I28 @BASEBOARD_FAB2_LIB.BASEBOARD_FAB2(SCH_1):PAGE148
    M5    GND @BASEBOARD_FAB2_LIB.BASEBOARD_FAB2(SCH_1):GND    I28 @BASEBOARD_FAB2_LIB.BASEBOARD_FAB2(SCH_1):PAGE148
    M4    GND @BASEBOARD_FAB2_LIB.BASEBOARD_FAB2(SCH_1):GND    I28 @BASEBOARD_FAB2_LIB.BASEBOARD_FAB2(SCH_1):PAGE148
   M12    GND @BASEBOARD_FAB2_LIB.BASEBOARD_FAB2(SCH_1):GND    I28 @BASEBOARD_FAB2_LIB.BASEBOARD_FAB2(SCH_1):PAGE148
   M13    GND @BASEBOARD_FAB2_LIB.BASEBOARD_FAB2(SCH_1):GND    I28 @BASEBOARD_FAB2_LIB.BASEBOARD_FAB2(SCH_1):PAGE148
   M17    GND @BASEBOARD_FAB2_LIB.BASEBOARD_FAB2(SCH_1):GND    I28 @BASEBOARD_FAB2_LIB.BASEBOARD_FAB2(SCH_1):PAGE148
   M16    GND @BASEBOARD_FAB2_LIB.BASEBOARD_FAB2(SCH_1):GND    I28 @BASEBOARD_FAB2_LIB.BASEBOARD_FAB2(SCH_1):PAGE148
   M14    GND @BASEBOARD_FAB2_LIB.BASEBOARD_FAB2(SCH_1):GND    I28 @BASEBOARD_FAB2_LIB.BASEBOARD_FAB2(SCH_1):PAGE148
   L14    GND @BASEBOARD_FAB2_LIB.BASEBOARD_FAB2(SCH_1):GND    I28 @BASEBOARD_FAB2_LIB.BASEBOARD_FAB2(SCH_1):PAGE148
   M11    GND @BASEBOARD_FAB2_LIB.BASEBOARD_FAB2(SCH_1):GND    I28 @BASEBOARD_FAB2_LIB.BASEBOARD_FAB2(SCH_1):PAGE148
   M10    GND @BASEBOARD_FAB2_LIB.BASEBOARD_FAB2(SCH_1):GND    I28 @BASEBOARD_FAB2_LIB.BASEBOARD_FAB2(SCH_1):PAGE148
    M1    GND @BASEBOARD_FAB2_LIB.BASEBOARD_FAB2(SCH_1):GND    I28 @BASEBOARD_FAB2_LIB.BASEBOARD_FAB2(SCH_1):PAGE148
    L9    GND @BASEBOARD_FAB2_LIB.BASEBOARD_FAB2(SCH_1):GND    I28 @BASEBOARD_FAB2_LIB.BASEBOARD_FAB2(SCH_1):PAGE148
    K9    GND @BASEBOARD_FAB2_LIB.BASEBOARD_FAB2(SCH_1):GND    I28 @BASEBOARD_FAB2_LIB.BASEBOARD_FAB2(SCH_1):PAGE148
   L13    GND @BASEBOARD_FAB2_LIB.BASEBOARD_FAB2(SCH_1):GND    I28 @BASEBOARD_FAB2_LIB.BASEBOARD_FAB2(SCH_1):PAGE148
   L12    GND @BASEBOARD_FAB2_LIB.BASEBOARD_FAB2(SCH_1):GND    I28 @BASEBOARD_FAB2_LIB.BASEBOARD_FAB2(SCH_1):PAGE148
   L11    GND @BASEBOARD_FAB2_LIB.BASEBOARD_FAB2(SCH_1):GND    I28 @BASEBOARD_FAB2_LIB.BASEBOARD_FAB2(SCH_1):PAGE148
   L10    GND @BASEBOARD_FAB2_LIB.BASEBOARD_FAB2(SCH_1):GND    I28 @BASEBOARD_FAB2_LIB.BASEBOARD_FAB2(SCH_1):PAGE148
   K16    GND @BASEBOARD_FAB2_LIB.BASEBOARD_FAB2(SCH_1):GND    I28 @BASEBOARD_FAB2_LIB.BASEBOARD_FAB2(SCH_1):PAGE148
   K11    GND @BASEBOARD_FAB2_LIB.BASEBOARD_FAB2(SCH_1):GND    I28 @BASEBOARD_FAB2_LIB.BASEBOARD_FAB2(SCH_1):PAGE148
   K13    GND @BASEBOARD_FAB2_LIB.BASEBOARD_FAB2(SCH_1):GND    I28 @BASEBOARD_FAB2_LIB.BASEBOARD_FAB2(SCH_1):PAGE148
   K14    GND @BASEBOARD_FAB2_LIB.BASEBOARD_FAB2(SCH_1):GND    I28 @BASEBOARD_FAB2_LIB.BASEBOARD_FAB2(SCH_1):PAGE148
   K12    GND @BASEBOARD_FAB2_LIB.BASEBOARD_FAB2(SCH_1):GND    I28 @BASEBOARD_FAB2_LIB.BASEBOARD_FAB2(SCH_1):PAGE148
   K10    GND @BASEBOARD_FAB2_LIB.BASEBOARD_FAB2(SCH_1):GND    I28 @BASEBOARD_FAB2_LIB.BASEBOARD_FAB2(SCH_1):PAGE148
   J21    GND @BASEBOARD_FAB2_LIB.BASEBOARD_FAB2(SCH_1):GND    I28 @BASEBOARD_FAB2_LIB.BASEBOARD_FAB2(SCH_1):PAGE148
    J9    GND @BASEBOARD_FAB2_LIB.BASEBOARD_FAB2(SCH_1):GND    I28 @BASEBOARD_FAB2_LIB.BASEBOARD_FAB2(SCH_1):PAGE148
    J5    GND @BASEBOARD_FAB2_LIB.BASEBOARD_FAB2(SCH_1):GND    I28 @BASEBOARD_FAB2_LIB.BASEBOARD_FAB2(SCH_1):PAGE148
   J22    GND @BASEBOARD_FAB2_LIB.BASEBOARD_FAB2(SCH_1):GND    I28 @BASEBOARD_FAB2_LIB.BASEBOARD_FAB2(SCH_1):PAGE148
   J14    GND @BASEBOARD_FAB2_LIB.BASEBOARD_FAB2(SCH_1):GND    I28 @BASEBOARD_FAB2_LIB.BASEBOARD_FAB2(SCH_1):PAGE148
    H6    GND @BASEBOARD_FAB2_LIB.BASEBOARD_FAB2(SCH_1):GND    I28 @BASEBOARD_FAB2_LIB.BASEBOARD_FAB2(SCH_1):PAGE148
   J10    GND @BASEBOARD_FAB2_LIB.BASEBOARD_FAB2(SCH_1):GND    I28 @BASEBOARD_FAB2_LIB.BASEBOARD_FAB2(SCH_1):PAGE148
   J13    GND @BASEBOARD_FAB2_LIB.BASEBOARD_FAB2(SCH_1):GND    I28 @BASEBOARD_FAB2_LIB.BASEBOARD_FAB2(SCH_1):PAGE148
   J12    GND @BASEBOARD_FAB2_LIB.BASEBOARD_FAB2(SCH_1):GND    I28 @BASEBOARD_FAB2_LIB.BASEBOARD_FAB2(SCH_1):PAGE148
   J11    GND @BASEBOARD_FAB2_LIB.BASEBOARD_FAB2(SCH_1):GND    I28 @BASEBOARD_FAB2_LIB.BASEBOARD_FAB2(SCH_1):PAGE148
    C6    GND @BASEBOARD_FAB2_LIB.BASEBOARD_FAB2(SCH_1):GND    I28 @BASEBOARD_FAB2_LIB.BASEBOARD_FAB2(SCH_1):PAGE148
    E8    GND @BASEBOARD_FAB2_LIB.BASEBOARD_FAB2(SCH_1):GND    I28 @BASEBOARD_FAB2_LIB.BASEBOARD_FAB2(SCH_1):PAGE148
    G6    GND @BASEBOARD_FAB2_LIB.BASEBOARD_FAB2(SCH_1):GND    I28 @BASEBOARD_FAB2_LIB.BASEBOARD_FAB2(SCH_1):PAGE148
   G19    GND @BASEBOARD_FAB2_LIB.BASEBOARD_FAB2(SCH_1):GND    I28 @BASEBOARD_FAB2_LIB.BASEBOARD_FAB2(SCH_1):PAGE148
   F16    GND @BASEBOARD_FAB2_LIB.BASEBOARD_FAB2(SCH_1):GND    I28 @BASEBOARD_FAB2_LIB.BASEBOARD_FAB2(SCH_1):PAGE148
  AA15    GND @BASEBOARD_FAB2_LIB.BASEBOARD_FAB2(SCH_1):GND    I28 @BASEBOARD_FAB2_LIB.BASEBOARD_FAB2(SCH_1):PAGE148
   AA7    GND @BASEBOARD_FAB2_LIB.BASEBOARD_FAB2(SCH_1):GND    I28 @BASEBOARD_FAB2_LIB.BASEBOARD_FAB2(SCH_1):PAGE148
   AB1    GND @BASEBOARD_FAB2_LIB.BASEBOARD_FAB2(SCH_1):GND    I28 @BASEBOARD_FAB2_LIB.BASEBOARD_FAB2(SCH_1):PAGE148
  AB22    GND @BASEBOARD_FAB2_LIB.BASEBOARD_FAB2(SCH_1):GND    I28 @BASEBOARD_FAB2_LIB.BASEBOARD_FAB2(SCH_1):PAGE148
   AA9    GND @BASEBOARD_FAB2_LIB.BASEBOARD_FAB2(SCH_1):GND    I28 @BASEBOARD_FAB2_LIB.BASEBOARD_FAB2(SCH_1):PAGE148
  AA13    GND @BASEBOARD_FAB2_LIB.BASEBOARD_FAB2(SCH_1):GND    I28 @BASEBOARD_FAB2_LIB.BASEBOARD_FAB2(SCH_1):PAGE148
  AA11    GND @BASEBOARD_FAB2_LIB.BASEBOARD_FAB2(SCH_1):GND    I28 @BASEBOARD_FAB2_LIB.BASEBOARD_FAB2(SCH_1):PAGE148
   A22    GND @BASEBOARD_FAB2_LIB.BASEBOARD_FAB2(SCH_1):GND    I28 @BASEBOARD_FAB2_LIB.BASEBOARD_FAB2(SCH_1):PAGE148
    A1    GND @BASEBOARD_FAB2_LIB.BASEBOARD_FAB2(SCH_1):GND    I28 @BASEBOARD_FAB2_LIB.BASEBOARD_FAB2(SCH_1):PAGE148

U25W5 H5AN4G6NAFR-TFC-GP_MEMORY-G2-HA
    B1 P2V5_AUX_BMC @BASEBOARD_FAB2_LIB.BASEBOARD_FAB2(SCH_1):P2V5_AUX_BMC    I49 @BASEBOARD_FAB2_LIB.BASEBOARD_FAB2(SCH_1):PAGE151
    B3 P1V2_AUX_BMC @BASEBOARD_FAB2_LIB.BASEBOARD_FAB2(SCH_1):P1V2_AUX_BMC    I49 @BASEBOARD_FAB2_LIB.BASEBOARD_FAB2(SCH_1):PAGE151
    B9 P1V2_AUX_BMC @BASEBOARD_FAB2_LIB.BASEBOARD_FAB2(SCH_1):P1V2_AUX_BMC    I49 @BASEBOARD_FAB2_LIB.BASEBOARD_FAB2(SCH_1):PAGE151
    D1 P1V2_AUX_BMC @BASEBOARD_FAB2_LIB.BASEBOARD_FAB2(SCH_1):P1V2_AUX_BMC    I49 @BASEBOARD_FAB2_LIB.BASEBOARD_FAB2(SCH_1):PAGE151
    G7 P1V2_AUX_BMC @BASEBOARD_FAB2_LIB.BASEBOARD_FAB2(SCH_1):P1V2_AUX_BMC    I49 @BASEBOARD_FAB2_LIB.BASEBOARD_FAB2(SCH_1):PAGE151
    J1 P1V2_AUX_BMC @BASEBOARD_FAB2_LIB.BASEBOARD_FAB2(SCH_1):P1V2_AUX_BMC    I49 @BASEBOARD_FAB2_LIB.BASEBOARD_FAB2(SCH_1):PAGE151
    J9 P1V2_AUX_BMC @BASEBOARD_FAB2_LIB.BASEBOARD_FAB2(SCH_1):P1V2_AUX_BMC    I49 @BASEBOARD_FAB2_LIB.BASEBOARD_FAB2(SCH_1):PAGE151
    L1 P1V2_AUX_BMC @BASEBOARD_FAB2_LIB.BASEBOARD_FAB2(SCH_1):P1V2_AUX_BMC    I49 @BASEBOARD_FAB2_LIB.BASEBOARD_FAB2(SCH_1):PAGE151
    L9 P1V2_AUX_BMC @BASEBOARD_FAB2_LIB.BASEBOARD_FAB2(SCH_1):P1V2_AUX_BMC    I49 @BASEBOARD_FAB2_LIB.BASEBOARD_FAB2(SCH_1):PAGE151
    R1 P1V2_AUX_BMC @BASEBOARD_FAB2_LIB.BASEBOARD_FAB2(SCH_1):P1V2_AUX_BMC    I49 @BASEBOARD_FAB2_LIB.BASEBOARD_FAB2(SCH_1):PAGE151
    T9 P1V2_AUX_BMC @BASEBOARD_FAB2_LIB.BASEBOARD_FAB2(SCH_1):P1V2_AUX_BMC    I49 @BASEBOARD_FAB2_LIB.BASEBOARD_FAB2(SCH_1):PAGE151
    A1 P1V2_AUX_BMC @BASEBOARD_FAB2_LIB.BASEBOARD_FAB2(SCH_1):P1V2_AUX_BMC    I49 @BASEBOARD_FAB2_LIB.BASEBOARD_FAB2(SCH_1):PAGE151
    A9 P1V2_AUX_BMC @BASEBOARD_FAB2_LIB.BASEBOARD_FAB2(SCH_1):P1V2_AUX_BMC    I49 @BASEBOARD_FAB2_LIB.BASEBOARD_FAB2(SCH_1):PAGE151
    C1 P1V2_AUX_BMC @BASEBOARD_FAB2_LIB.BASEBOARD_FAB2(SCH_1):P1V2_AUX_BMC    I49 @BASEBOARD_FAB2_LIB.BASEBOARD_FAB2(SCH_1):PAGE151
    D9 P1V2_AUX_BMC @BASEBOARD_FAB2_LIB.BASEBOARD_FAB2(SCH_1):P1V2_AUX_BMC    I49 @BASEBOARD_FAB2_LIB.BASEBOARD_FAB2(SCH_1):PAGE151
    F2 P1V2_AUX_BMC @BASEBOARD_FAB2_LIB.BASEBOARD_FAB2(SCH_1):P1V2_AUX_BMC    I49 @BASEBOARD_FAB2_LIB.BASEBOARD_FAB2(SCH_1):PAGE151
    F8 P1V2_AUX_BMC @BASEBOARD_FAB2_LIB.BASEBOARD_FAB2(SCH_1):P1V2_AUX_BMC    I49 @BASEBOARD_FAB2_LIB.BASEBOARD_FAB2(SCH_1):PAGE151
    G1 P1V2_AUX_BMC @BASEBOARD_FAB2_LIB.BASEBOARD_FAB2(SCH_1):P1V2_AUX_BMC    I49 @BASEBOARD_FAB2_LIB.BASEBOARD_FAB2(SCH_1):PAGE151
    G9 P1V2_AUX_BMC @BASEBOARD_FAB2_LIB.BASEBOARD_FAB2(SCH_1):P1V2_AUX_BMC    I49 @BASEBOARD_FAB2_LIB.BASEBOARD_FAB2(SCH_1):PAGE151
    J2 P1V2_AUX_BMC @BASEBOARD_FAB2_LIB.BASEBOARD_FAB2(SCH_1):P1V2_AUX_BMC    I49 @BASEBOARD_FAB2_LIB.BASEBOARD_FAB2(SCH_1):PAGE151
    J8 P1V2_AUX_BMC @BASEBOARD_FAB2_LIB.BASEBOARD_FAB2(SCH_1):P1V2_AUX_BMC    I49 @BASEBOARD_FAB2_LIB.BASEBOARD_FAB2(SCH_1):PAGE151
    C2 BMC_M_DQ12 @BASEBOARD_FAB2_LIB.BASEBOARD_FAB2(SCH_1):BMC_M_DQ12    I49 @BASEBOARD_FAB2_LIB.BASEBOARD_FAB2(SCH_1):PAGE151
    C8 BMC_M_DQ13 @BASEBOARD_FAB2_LIB.BASEBOARD_FAB2(SCH_1):BMC_M_DQ13    I49 @BASEBOARD_FAB2_LIB.BASEBOARD_FAB2(SCH_1):PAGE151
    D3 BMC_M_DQ14 @BASEBOARD_FAB2_LIB.BASEBOARD_FAB2(SCH_1):BMC_M_DQ14    I49 @BASEBOARD_FAB2_LIB.BASEBOARD_FAB2(SCH_1):PAGE151
    D7 BMC_M_DQ15 @BASEBOARD_FAB2_LIB.BASEBOARD_FAB2(SCH_1):BMC_M_DQ15    I49 @BASEBOARD_FAB2_LIB.BASEBOARD_FAB2(SCH_1):PAGE151
    A3 BMC_M_DQ8 @BASEBOARD_FAB2_LIB.BASEBOARD_FAB2(SCH_1):BMC_M_DQ8    I49 @BASEBOARD_FAB2_LIB.BASEBOARD_FAB2(SCH_1):PAGE151
    B8 BMC_M_DQ9 @BASEBOARD_FAB2_LIB.BASEBOARD_FAB2(SCH_1):BMC_M_DQ9    I49 @BASEBOARD_FAB2_LIB.BASEBOARD_FAB2(SCH_1):PAGE151
    C3 BMC_M_DQ10 @BASEBOARD_FAB2_LIB.BASEBOARD_FAB2(SCH_1):BMC_M_DQ10    I49 @BASEBOARD_FAB2_LIB.BASEBOARD_FAB2(SCH_1):PAGE151
    C7 BMC_M_DQ11 @BASEBOARD_FAB2_LIB.BASEBOARD_FAB2(SCH_1):BMC_M_DQ11    I49 @BASEBOARD_FAB2_LIB.BASEBOARD_FAB2(SCH_1):PAGE151
    F7 BMC_M_DQ1 @BASEBOARD_FAB2_LIB.BASEBOARD_FAB2(SCH_1):BMC_M_DQ1    I49 @BASEBOARD_FAB2_LIB.BASEBOARD_FAB2(SCH_1):PAGE151
    G2 BMC_M_DQ0 @BASEBOARD_FAB2_LIB.BASEBOARD_FAB2(SCH_1):BMC_M_DQ0    I49 @BASEBOARD_FAB2_LIB.BASEBOARD_FAB2(SCH_1):PAGE151
    H2 BMC_M_DQ4 @BASEBOARD_FAB2_LIB.BASEBOARD_FAB2(SCH_1):BMC_M_DQ4    I49 @BASEBOARD_FAB2_LIB.BASEBOARD_FAB2(SCH_1):PAGE151
    H3 BMC_M_DQ2 @BASEBOARD_FAB2_LIB.BASEBOARD_FAB2(SCH_1):BMC_M_DQ2    I49 @BASEBOARD_FAB2_LIB.BASEBOARD_FAB2(SCH_1):PAGE151
    H7 BMC_M_DQ3 @BASEBOARD_FAB2_LIB.BASEBOARD_FAB2(SCH_1):BMC_M_DQ3    I49 @BASEBOARD_FAB2_LIB.BASEBOARD_FAB2(SCH_1):PAGE151
    H8 BMC_M_DQ5 @BASEBOARD_FAB2_LIB.BASEBOARD_FAB2(SCH_1):BMC_M_DQ5    I49 @BASEBOARD_FAB2_LIB.BASEBOARD_FAB2(SCH_1):PAGE151
    J3 BMC_M_DQ6 @BASEBOARD_FAB2_LIB.BASEBOARD_FAB2(SCH_1):BMC_M_DQ6    I49 @BASEBOARD_FAB2_LIB.BASEBOARD_FAB2(SCH_1):PAGE151
    J7 BMC_M_DQ7 @BASEBOARD_FAB2_LIB.BASEBOARD_FAB2(SCH_1):BMC_M_DQ7    I49 @BASEBOARD_FAB2_LIB.BASEBOARD_FAB2(SCH_1):PAGE151
    P3 BMC_M_A0 @BASEBOARD_FAB2_LIB.BASEBOARD_FAB2(SCH_1):BMC_M_A0    I49 @BASEBOARD_FAB2_LIB.BASEBOARD_FAB2(SCH_1):PAGE151
    P7 BMC_M_A1 @BASEBOARD_FAB2_LIB.BASEBOARD_FAB2(SCH_1):BMC_M_A1    I49 @BASEBOARD_FAB2_LIB.BASEBOARD_FAB2(SCH_1):PAGE151
    R3 BMC_M_A2 @BASEBOARD_FAB2_LIB.BASEBOARD_FAB2(SCH_1):BMC_M_A2    I49 @BASEBOARD_FAB2_LIB.BASEBOARD_FAB2(SCH_1):PAGE151
    N7 BMC_M_A3 @BASEBOARD_FAB2_LIB.BASEBOARD_FAB2(SCH_1):BMC_M_A3    I49 @BASEBOARD_FAB2_LIB.BASEBOARD_FAB2(SCH_1):PAGE151
    N3 BMC_M_A4 @BASEBOARD_FAB2_LIB.BASEBOARD_FAB2(SCH_1):BMC_M_A4    I49 @BASEBOARD_FAB2_LIB.BASEBOARD_FAB2(SCH_1):PAGE151
    P8 BMC_M_A5 @BASEBOARD_FAB2_LIB.BASEBOARD_FAB2(SCH_1):BMC_M_A5    I49 @BASEBOARD_FAB2_LIB.BASEBOARD_FAB2(SCH_1):PAGE151
    P2 BMC_M_A6 @BASEBOARD_FAB2_LIB.BASEBOARD_FAB2(SCH_1):BMC_M_A6    I49 @BASEBOARD_FAB2_LIB.BASEBOARD_FAB2(SCH_1):PAGE151
    R8 BMC_M_A7 @BASEBOARD_FAB2_LIB.BASEBOARD_FAB2(SCH_1):BMC_M_A7    I49 @BASEBOARD_FAB2_LIB.BASEBOARD_FAB2(SCH_1):PAGE151
    R2 BMC_M_A8 @BASEBOARD_FAB2_LIB.BASEBOARD_FAB2(SCH_1):BMC_M_A8    I49 @BASEBOARD_FAB2_LIB.BASEBOARD_FAB2(SCH_1):PAGE151
    R7 BMC_M_A9 @BASEBOARD_FAB2_LIB.BASEBOARD_FAB2(SCH_1):BMC_M_A9    I49 @BASEBOARD_FAB2_LIB.BASEBOARD_FAB2(SCH_1):PAGE151
    M3 BMC_M_A10 @BASEBOARD_FAB2_LIB.BASEBOARD_FAB2(SCH_1):BMC_M_A10    I49 @BASEBOARD_FAB2_LIB.BASEBOARD_FAB2(SCH_1):PAGE151
    T2 BMC_M_A11 @BASEBOARD_FAB2_LIB.BASEBOARD_FAB2(SCH_1):BMC_M_A11    I49 @BASEBOARD_FAB2_LIB.BASEBOARD_FAB2(SCH_1):PAGE151
    M7 BMC_M_A12 @BASEBOARD_FAB2_LIB.BASEBOARD_FAB2(SCH_1):BMC_M_A12    I49 @BASEBOARD_FAB2_LIB.BASEBOARD_FAB2(SCH_1):PAGE151
    T8 BMC_M_A13 @BASEBOARD_FAB2_LIB.BASEBOARD_FAB2(SCH_1):BMC_M_A13    I49 @BASEBOARD_FAB2_LIB.BASEBOARD_FAB2(SCH_1):PAGE151
    L2 BMC_M_WE_N @BASEBOARD_FAB2_LIB.BASEBOARD_FAB2(SCH_1):BMC_M_WE_N    I49 @BASEBOARD_FAB2_LIB.BASEBOARD_FAB2(SCH_1):PAGE151
    M8 BMC_M_CAS_N @BASEBOARD_FAB2_LIB.BASEBOARD_FAB2(SCH_1):BMC_M_CAS_N    I49 @BASEBOARD_FAB2_LIB.BASEBOARD_FAB2(SCH_1):PAGE151
    L8 BMC_M_RAS_N @BASEBOARD_FAB2_LIB.BASEBOARD_FAB2(SCH_1):BMC_M_RAS_N    I49 @BASEBOARD_FAB2_LIB.BASEBOARD_FAB2(SCH_1):PAGE151
    M1 BMC_M_VREFCA @BASEBOARD_FAB2_LIB.BASEBOARD_FAB2(SCH_1):BMC_M_VREFCA    I49 @BASEBOARD_FAB2_LIB.BASEBOARD_FAB2(SCH_1):PAGE151
    F9 BMC_ZQ @BASEBOARD_FAB2_LIB.BASEBOARD_FAB2(SCH_1):BMC_ZQ    I49 @BASEBOARD_FAB2_LIB.BASEBOARD_FAB2(SCH_1):PAGE151
    K2 BMC_M_CKE @BASEBOARD_FAB2_LIB.BASEBOARD_FAB2(SCH_1):BMC_M_CKE    I49 @BASEBOARD_FAB2_LIB.BASEBOARD_FAB2(SCH_1):PAGE151
    K3 BMC_M_ODT @BASEBOARD_FAB2_LIB.BASEBOARD_FAB2(SCH_1):BMC_M_ODT    I49 @BASEBOARD_FAB2_LIB.BASEBOARD_FAB2(SCH_1):PAGE151
    M2 BMC_M_BG0 @BASEBOARD_FAB2_LIB.BASEBOARD_FAB2(SCH_1):BMC_M_BG0    I49 @BASEBOARD_FAB2_LIB.BASEBOARD_FAB2(SCH_1):PAGE151
    N9    GND @BASEBOARD_FAB2_LIB.BASEBOARD_FAB2(SCH_1):GND    I49 @BASEBOARD_FAB2_LIB.BASEBOARD_FAB2(SCH_1):PAGE151
    T3 BMC_M_PAR @BASEBOARD_FAB2_LIB.BASEBOARD_FAB2(SCH_1):BMC_M_PAR    I49 @BASEBOARD_FAB2_LIB.BASEBOARD_FAB2(SCH_1):PAGE151
    T7     NC     NC    I49 @BASEBOARD_FAB2_LIB.BASEBOARD_FAB2(SCH_1):PAGE151
    K7 BMC_M_CLK_DP @BASEBOARD_FAB2_LIB.BASEBOARD_FAB2(SCH_1):BMC_M_CLK_DP    I49 @BASEBOARD_FAB2_LIB.BASEBOARD_FAB2(SCH_1):PAGE151
    K8 BMC_M_CLK_DN @BASEBOARD_FAB2_LIB.BASEBOARD_FAB2(SCH_1):BMC_M_CLK_DN    I49 @BASEBOARD_FAB2_LIB.BASEBOARD_FAB2(SCH_1):PAGE151
    R9 P2V5_AUX_BMC @BASEBOARD_FAB2_LIB.BASEBOARD_FAB2(SCH_1):P2V5_AUX_BMC    I49 @BASEBOARD_FAB2_LIB.BASEBOARD_FAB2(SCH_1):PAGE151
    L3 BMC_M_MACT_N @BASEBOARD_FAB2_LIB.BASEBOARD_FAB2(SCH_1):BMC_M_MACT_N    I49 @BASEBOARD_FAB2_LIB.BASEBOARD_FAB2(SCH_1):PAGE151
    L7 BMC_M_CS_N @BASEBOARD_FAB2_LIB.BASEBOARD_FAB2(SCH_1):BMC_M_CS_N    I49 @BASEBOARD_FAB2_LIB.BASEBOARD_FAB2(SCH_1):PAGE151
    P1 BMC_M_RST_N @BASEBOARD_FAB2_LIB.BASEBOARD_FAB2(SCH_1):BMC_M_RST_N    I49 @BASEBOARD_FAB2_LIB.BASEBOARD_FAB2(SCH_1):PAGE151
    P9 BMC_M_MALERT_N @BASEBOARD_FAB2_LIB.BASEBOARD_FAB2(SCH_1):BMC_M_MALERT_N    I49 @BASEBOARD_FAB2_LIB.BASEBOARD_FAB2(SCH_1):PAGE151
    B2    GND @BASEBOARD_FAB2_LIB.BASEBOARD_FAB2(SCH_1):GND    I49 @BASEBOARD_FAB2_LIB.BASEBOARD_FAB2(SCH_1):PAGE151
    E1    GND @BASEBOARD_FAB2_LIB.BASEBOARD_FAB2(SCH_1):GND    I49 @BASEBOARD_FAB2_LIB.BASEBOARD_FAB2(SCH_1):PAGE151
    E9    GND @BASEBOARD_FAB2_LIB.BASEBOARD_FAB2(SCH_1):GND    I49 @BASEBOARD_FAB2_LIB.BASEBOARD_FAB2(SCH_1):PAGE151
    G8    GND @BASEBOARD_FAB2_LIB.BASEBOARD_FAB2(SCH_1):GND    I49 @BASEBOARD_FAB2_LIB.BASEBOARD_FAB2(SCH_1):PAGE151
    K1    GND @BASEBOARD_FAB2_LIB.BASEBOARD_FAB2(SCH_1):GND    I49 @BASEBOARD_FAB2_LIB.BASEBOARD_FAB2(SCH_1):PAGE151
    K9    GND @BASEBOARD_FAB2_LIB.BASEBOARD_FAB2(SCH_1):GND    I49 @BASEBOARD_FAB2_LIB.BASEBOARD_FAB2(SCH_1):PAGE151
    M9    GND @BASEBOARD_FAB2_LIB.BASEBOARD_FAB2(SCH_1):GND    I49 @BASEBOARD_FAB2_LIB.BASEBOARD_FAB2(SCH_1):PAGE151
    N1    GND @BASEBOARD_FAB2_LIB.BASEBOARD_FAB2(SCH_1):GND    I49 @BASEBOARD_FAB2_LIB.BASEBOARD_FAB2(SCH_1):PAGE151
    T1    GND @BASEBOARD_FAB2_LIB.BASEBOARD_FAB2(SCH_1):GND    I49 @BASEBOARD_FAB2_LIB.BASEBOARD_FAB2(SCH_1):PAGE151
    A2    GND @BASEBOARD_FAB2_LIB.BASEBOARD_FAB2(SCH_1):GND    I49 @BASEBOARD_FAB2_LIB.BASEBOARD_FAB2(SCH_1):PAGE151
    A8    GND @BASEBOARD_FAB2_LIB.BASEBOARD_FAB2(SCH_1):GND    I49 @BASEBOARD_FAB2_LIB.BASEBOARD_FAB2(SCH_1):PAGE151
    C9    GND @BASEBOARD_FAB2_LIB.BASEBOARD_FAB2(SCH_1):GND    I49 @BASEBOARD_FAB2_LIB.BASEBOARD_FAB2(SCH_1):PAGE151
    D2    GND @BASEBOARD_FAB2_LIB.BASEBOARD_FAB2(SCH_1):GND    I49 @BASEBOARD_FAB2_LIB.BASEBOARD_FAB2(SCH_1):PAGE151
    D8    GND @BASEBOARD_FAB2_LIB.BASEBOARD_FAB2(SCH_1):GND    I49 @BASEBOARD_FAB2_LIB.BASEBOARD_FAB2(SCH_1):PAGE151
    E3    GND @BASEBOARD_FAB2_LIB.BASEBOARD_FAB2(SCH_1):GND    I49 @BASEBOARD_FAB2_LIB.BASEBOARD_FAB2(SCH_1):PAGE151
    E8    GND @BASEBOARD_FAB2_LIB.BASEBOARD_FAB2(SCH_1):GND    I49 @BASEBOARD_FAB2_LIB.BASEBOARD_FAB2(SCH_1):PAGE151
    F1    GND @BASEBOARD_FAB2_LIB.BASEBOARD_FAB2(SCH_1):GND    I49 @BASEBOARD_FAB2_LIB.BASEBOARD_FAB2(SCH_1):PAGE151
    H1    GND @BASEBOARD_FAB2_LIB.BASEBOARD_FAB2(SCH_1):GND    I49 @BASEBOARD_FAB2_LIB.BASEBOARD_FAB2(SCH_1):PAGE151
    H9    GND @BASEBOARD_FAB2_LIB.BASEBOARD_FAB2(SCH_1):GND    I49 @BASEBOARD_FAB2_LIB.BASEBOARD_FAB2(SCH_1):PAGE151
    A7 BMC_M_DQS1_DN @BASEBOARD_FAB2_LIB.BASEBOARD_FAB2(SCH_1):BMC_M_DQS1_DN    I49 @BASEBOARD_FAB2_LIB.BASEBOARD_FAB2(SCH_1):PAGE151
    B7 BMC_M_DQS1_DP @BASEBOARD_FAB2_LIB.BASEBOARD_FAB2(SCH_1):BMC_M_DQS1_DP    I49 @BASEBOARD_FAB2_LIB.BASEBOARD_FAB2(SCH_1):PAGE151
    F3 BMC_M_DQS0_DN @BASEBOARD_FAB2_LIB.BASEBOARD_FAB2(SCH_1):BMC_M_DQS0_DN    I49 @BASEBOARD_FAB2_LIB.BASEBOARD_FAB2(SCH_1):PAGE151
    G3 BMC_M_DQS0_DP @BASEBOARD_FAB2_LIB.BASEBOARD_FAB2(SCH_1):BMC_M_DQS0_DP    I49 @BASEBOARD_FAB2_LIB.BASEBOARD_FAB2(SCH_1):PAGE151
    E2 BMC_M_DM1 @BASEBOARD_FAB2_LIB.BASEBOARD_FAB2(SCH_1):BMC_M_DM1    I49 @BASEBOARD_FAB2_LIB.BASEBOARD_FAB2(SCH_1):PAGE151
    E7 BMC_M_DM0 @BASEBOARD_FAB2_LIB.BASEBOARD_FAB2(SCH_1):BMC_M_DM0    I49 @BASEBOARD_FAB2_LIB.BASEBOARD_FAB2(SCH_1):PAGE151
    N2 BMC_M_BA0 @BASEBOARD_FAB2_LIB.BASEBOARD_FAB2(SCH_1):BMC_M_BA0    I49 @BASEBOARD_FAB2_LIB.BASEBOARD_FAB2(SCH_1):PAGE151
    N8 BMC_M_BA1 @BASEBOARD_FAB2_LIB.BASEBOARD_FAB2(SCH_1):BMC_M_BA1    I49 @BASEBOARD_FAB2_LIB.BASEBOARD_FAB2(SCH_1):PAGE151

U25W7 U74AHCT1G125G-AL5-R-GP-U_TTL-GA
     1    GND @BASEBOARD_FAB2_LIB.BASEBOARD_FAB2(SCH_1):GND   I111 @BASEBOARD_FAB2_LIB.BASEBOARD_FAB2(SCH_1):PAGE255
     2 BMC_VGA_HSYNC @BASEBOARD_FAB2_LIB.BASEBOARD_FAB2(SCH_1):BMC_VGA_HSYNC   I111 @BASEBOARD_FAB2_LIB.BASEBOARD_FAB2(SCH_1):PAGE255
     3    GND @BASEBOARD_FAB2_LIB.BASEBOARD_FAB2(SCH_1):GND   I111 @BASEBOARD_FAB2_LIB.BASEBOARD_FAB2(SCH_1):PAGE255
     4 VGA_REAR_HSYNC_S @BASEBOARD_FAB2_LIB.BASEBOARD_FAB2(SCH_1):VGA_REAR_HSYNC_S   I111 @BASEBOARD_FAB2_LIB.BASEBOARD_FAB2(SCH_1):PAGE255
     5 P5V_VGA_D @BASEBOARD_FAB2_LIB.BASEBOARD_FAB2(SCH_1):P5V_VGA_D   I111 @BASEBOARD_FAB2_LIB.BASEBOARD_FAB2(SCH_1):PAGE255

U25W8 U74AHCT1G125G-AL5-R-GP-U_TTL-GA
     1    GND @BASEBOARD_FAB2_LIB.BASEBOARD_FAB2(SCH_1):GND   I112 @BASEBOARD_FAB2_LIB.BASEBOARD_FAB2(SCH_1):PAGE255
     2 BMC_VGA_VSYNC @BASEBOARD_FAB2_LIB.BASEBOARD_FAB2(SCH_1):BMC_VGA_VSYNC   I112 @BASEBOARD_FAB2_LIB.BASEBOARD_FAB2(SCH_1):PAGE255
     3    GND @BASEBOARD_FAB2_LIB.BASEBOARD_FAB2(SCH_1):GND   I112 @BASEBOARD_FAB2_LIB.BASEBOARD_FAB2(SCH_1):PAGE255
     4 VGA_REAR_VSYNC_S @BASEBOARD_FAB2_LIB.BASEBOARD_FAB2(SCH_1):VGA_REAR_VSYNC_S   I112 @BASEBOARD_FAB2_LIB.BASEBOARD_FAB2(SCH_1):PAGE255
     5 P5V_VGA_D @BASEBOARD_FAB2_LIB.BASEBOARD_FAB2(SCH_1):P5V_VGA_D   I112 @BASEBOARD_FAB2_LIB.BASEBOARD_FAB2(SCH_1):PAGE255

U25W9 TTL1G07_A_SOP-74LVC1G07,IC,C88B
     2 PWRGD_DSW_PWROK @BASEBOARD_FAB2_LIB.BASEBOARD_FAB2(SCH_1):PWRGD_DSW_PWROK   I394 @BASEBOARD_FAB2_LIB.BASEBOARD_FAB2(SCH_1):PAGE157
     4 RST_BMC_SRST_N @BASEBOARD_FAB2_LIB.BASEBOARD_FAB2(SCH_1):RST_BMC_SRST_N   I394 @BASEBOARD_FAB2_LIB.BASEBOARD_FAB2(SCH_1):PAGE157

U25W10 GTL2014_SM-IC,D66151-001
    13 BMC_PREQ_BUF_N @BASEBOARD_FAB2_LIB.BASEBOARD_FAB2(SCH_1):BMC_PREQ_BUF_N    I49 @BASEBOARD_FAB2_LIB.BASEBOARD_FAB2(SCH_1):PAGE269
    12 BMC_PWR_DEBUG_BUF_N @BASEBOARD_FAB2_LIB.BASEBOARD_FAB2(SCH_1):BMC_PWR_DEBUG_BUF_N    I49 @BASEBOARD_FAB2_LIB.BASEBOARD_FAB2(SCH_1):PAGE269
    10 JTAG_BMC_BUF_TDI @BASEBOARD_FAB2_LIB.BASEBOARD_FAB2(SCH_1):JTAG_BMC_BUF_TDI    I49 @BASEBOARD_FAB2_LIB.BASEBOARD_FAB2(SCH_1):PAGE269
     9 JTAG_BMC_BUF_TMS @BASEBOARD_FAB2_LIB.BASEBOARD_FAB2(SCH_1):JTAG_BMC_BUF_TMS    I49 @BASEBOARD_FAB2_LIB.BASEBOARD_FAB2(SCH_1):PAGE269
     2 XDP_PREQ_N @BASEBOARD_FAB2_LIB.BASEBOARD_FAB2(SCH_1):XDP_PREQ_N    I49 @BASEBOARD_FAB2_LIB.BASEBOARD_FAB2(SCH_1):PAGE269
     3 XDP_CPU_PWR_DEBUG_N @BASEBOARD_FAB2_LIB.BASEBOARD_FAB2(SCH_1):XDP_CPU_PWR_DEBUG_N    I49 @BASEBOARD_FAB2_LIB.BASEBOARD_FAB2(SCH_1):PAGE269
     5 XDP_TDI_R @BASEBOARD_FAB2_LIB.BASEBOARD_FAB2(SCH_1):XDP_TDI_R    I49 @BASEBOARD_FAB2_LIB.BASEBOARD_FAB2(SCH_1):PAGE269
     6 XDP_TMS_R @BASEBOARD_FAB2_LIB.BASEBOARD_FAB2(SCH_1):XDP_TMS_R    I49 @BASEBOARD_FAB2_LIB.BASEBOARD_FAB2(SCH_1):PAGE269
     1 PU_GTL2014_3_DIR @BASEBOARD_FAB2_LIB.BASEBOARD_FAB2(SCH_1):PU_GTL2014_3_DIR    I49 @BASEBOARD_FAB2_LIB.BASEBOARD_FAB2(SCH_1):PAGE269
    11    GND @BASEBOARD_FAB2_LIB.BASEBOARD_FAB2(SCH_1):GND    I49 @BASEBOARD_FAB2_LIB.BASEBOARD_FAB2(SCH_1):PAGE269
     8    GND @BASEBOARD_FAB2_LIB.BASEBOARD_FAB2(SCH_1):GND    I49 @BASEBOARD_FAB2_LIB.BASEBOARD_FAB2(SCH_1):PAGE269
     7    GND @BASEBOARD_FAB2_LIB.BASEBOARD_FAB2(SCH_1):GND    I49 @BASEBOARD_FAB2_LIB.BASEBOARD_FAB2(SCH_1):PAGE269
    14 P3V3_STBY @BASEBOARD_FAB2_LIB.BASEBOARD_FAB2(SCH_1):P3V3_STBY    I49 @BASEBOARD_FAB2_LIB.BASEBOARD_FAB2(SCH_1):PAGE269
     4 PD_GTL2014_3_VREF @BASEBOARD_FAB2_LIB.BASEBOARD_FAB2(SCH_1):PD_GTL2014_3_VREF    I49 @BASEBOARD_FAB2_LIB.BASEBOARD_FAB2(SCH_1):PAGE269

U25W11 GTL2014_SM-IC,D66151-001
    13 TP_GTL2014_6_A0 @BASEBOARD_FAB2_LIB.BASEBOARD_FAB2(SCH_1):TP_GTL2014_6_A0    I33 @BASEBOARD_FAB2_LIB.BASEBOARD_FAB2(SCH_1):PAGE268
    12 BMC_PRDY_N @BASEBOARD_FAB2_LIB.BASEBOARD_FAB2(SCH_1):BMC_PRDY_N    I33 @BASEBOARD_FAB2_LIB.BASEBOARD_FAB2(SCH_1):PAGE268
    10 TP_GTL2014_6_A2 @BASEBOARD_FAB2_LIB.BASEBOARD_FAB2(SCH_1):TP_GTL2014_6_A2    I33 @BASEBOARD_FAB2_LIB.BASEBOARD_FAB2(SCH_1):PAGE268
     9 JTAG_BMC_BUF_TDO_R @BASEBOARD_FAB2_LIB.BASEBOARD_FAB2(SCH_1):JTAG_BMC_BUF_TDO_R    I33 @BASEBOARD_FAB2_LIB.BASEBOARD_FAB2(SCH_1):PAGE268
     2 PD_GTL2014_6_B0 @BASEBOARD_FAB2_LIB.BASEBOARD_FAB2(SCH_1):PD_GTL2014_6_B0    I33 @BASEBOARD_FAB2_LIB.BASEBOARD_FAB2(SCH_1):PAGE268
     3 XDP_PRDY_N @BASEBOARD_FAB2_LIB.BASEBOARD_FAB2(SCH_1):XDP_PRDY_N    I33 @BASEBOARD_FAB2_LIB.BASEBOARD_FAB2(SCH_1):PAGE268
     5 PD_GTL2014_6_B2 @BASEBOARD_FAB2_LIB.BASEBOARD_FAB2(SCH_1):PD_GTL2014_6_B2    I33 @BASEBOARD_FAB2_LIB.BASEBOARD_FAB2(SCH_1):PAGE268
     6 XDP_TDO @BASEBOARD_FAB2_LIB.BASEBOARD_FAB2(SCH_1):XDP_TDO    I33 @BASEBOARD_FAB2_LIB.BASEBOARD_FAB2(SCH_1):PAGE268
     1 PD_GTL2014_DIR_6 @BASEBOARD_FAB2_LIB.BASEBOARD_FAB2(SCH_1):PD_GTL2014_DIR_6    I33 @BASEBOARD_FAB2_LIB.BASEBOARD_FAB2(SCH_1):PAGE268
    11    GND @BASEBOARD_FAB2_LIB.BASEBOARD_FAB2(SCH_1):GND    I33 @BASEBOARD_FAB2_LIB.BASEBOARD_FAB2(SCH_1):PAGE268
     8    GND @BASEBOARD_FAB2_LIB.BASEBOARD_FAB2(SCH_1):GND    I33 @BASEBOARD_FAB2_LIB.BASEBOARD_FAB2(SCH_1):PAGE268
     7    GND @BASEBOARD_FAB2_LIB.BASEBOARD_FAB2(SCH_1):GND    I33 @BASEBOARD_FAB2_LIB.BASEBOARD_FAB2(SCH_1):PAGE268
    14 P3V3_STBY @BASEBOARD_FAB2_LIB.BASEBOARD_FAB2(SCH_1):P3V3_STBY    I33 @BASEBOARD_FAB2_LIB.BASEBOARD_FAB2(SCH_1):PAGE268
     4 P0V7_GTL2014_VREF_6 @BASEBOARD_FAB2_LIB.BASEBOARD_FAB2(SCH_1):P0V7_GTL2014_VREF_6    I33 @BASEBOARD_FAB2_LIB.BASEBOARD_FAB2(SCH_1):PAGE268

U25W12 TTL3126_QFNLF-74CBTLV3126,IC,DB
     1 BMC_JTAG_SEL_BUF @BASEBOARD_FAB2_LIB.BASEBOARD_FAB2(SCH_1):BMC_JTAG_SEL_BUF    I33 @BASEBOARD_FAB2_LIB.BASEBOARD_FAB2(SCH_1):PAGE269
     2 BMC_PREQ_N @BASEBOARD_FAB2_LIB.BASEBOARD_FAB2(SCH_1):BMC_PREQ_N    I33 @BASEBOARD_FAB2_LIB.BASEBOARD_FAB2(SCH_1):PAGE269
     3 BMC_PREQ_BUF_N @BASEBOARD_FAB2_LIB.BASEBOARD_FAB2(SCH_1):BMC_PREQ_BUF_N    I33 @BASEBOARD_FAB2_LIB.BASEBOARD_FAB2(SCH_1):PAGE269
     4 JTAG_BMC_TCK0 @BASEBOARD_FAB2_LIB.BASEBOARD_FAB2(SCH_1):JTAG_BMC_TCK0    I33 @BASEBOARD_FAB2_LIB.BASEBOARD_FAB2(SCH_1):PAGE269
     5 P1V05_PCH_STBY @BASEBOARD_FAB2_LIB.BASEBOARD_FAB2(SCH_1):P1V05_PCH_STBY    I33 @BASEBOARD_FAB2_LIB.BASEBOARD_FAB2(SCH_1):PAGE269
     6 XDP_CPU_TCK0_R @BASEBOARD_FAB2_LIB.BASEBOARD_FAB2(SCH_1):XDP_CPU_TCK0_R    I33 @BASEBOARD_FAB2_LIB.BASEBOARD_FAB2(SCH_1):PAGE269
    10 JTAG_BMC_TCK1 @BASEBOARD_FAB2_LIB.BASEBOARD_FAB2(SCH_1):JTAG_BMC_TCK1    I33 @BASEBOARD_FAB2_LIB.BASEBOARD_FAB2(SCH_1):PAGE269
     9 P1V05_PCH_STBY @BASEBOARD_FAB2_LIB.BASEBOARD_FAB2(SCH_1):P1V05_PCH_STBY    I33 @BASEBOARD_FAB2_LIB.BASEBOARD_FAB2(SCH_1):PAGE269
     8 XDP_PCH_TCK1_R @BASEBOARD_FAB2_LIB.BASEBOARD_FAB2(SCH_1):XDP_PCH_TCK1_R    I33 @BASEBOARD_FAB2_LIB.BASEBOARD_FAB2(SCH_1):PAGE269
    13 JTAG_BMC_TRST_BUF_N @BASEBOARD_FAB2_LIB.BASEBOARD_FAB2(SCH_1):JTAG_BMC_TRST_BUF_N    I33 @BASEBOARD_FAB2_LIB.BASEBOARD_FAB2(SCH_1):PAGE269
    12 P1V05_PCH_STBY @BASEBOARD_FAB2_LIB.BASEBOARD_FAB2(SCH_1):P1V05_PCH_STBY    I33 @BASEBOARD_FAB2_LIB.BASEBOARD_FAB2(SCH_1):PAGE269
    11 XDP_TRST_R_N @BASEBOARD_FAB2_LIB.BASEBOARD_FAB2(SCH_1):XDP_TRST_R_N    I33 @BASEBOARD_FAB2_LIB.BASEBOARD_FAB2(SCH_1):PAGE269

U25W13 MAX4564EKA-GP_SCRET-GC1-MAX456A
     1 JTAG_BMC_TCK0 @BASEBOARD_FAB2_LIB.BASEBOARD_FAB2(SCH_1):JTAG_BMC_TCK0    I53 @BASEBOARD_FAB2_LIB.BASEBOARD_FAB2(SCH_1):PAGE269
     2 P3V3_STBY @BASEBOARD_FAB2_LIB.BASEBOARD_FAB2(SCH_1):P3V3_STBY    I53 @BASEBOARD_FAB2_LIB.BASEBOARD_FAB2(SCH_1):PAGE269
     3 BMC_TCK_MUX_SEL @BASEBOARD_FAB2_LIB.BASEBOARD_FAB2(SCH_1):BMC_TCK_MUX_SEL    I53 @BASEBOARD_FAB2_LIB.BASEBOARD_FAB2(SCH_1):PAGE269
     4 JTAG_BMC_TCK1 @BASEBOARD_FAB2_LIB.BASEBOARD_FAB2(SCH_1):JTAG_BMC_TCK1    I53 @BASEBOARD_FAB2_LIB.BASEBOARD_FAB2(SCH_1):PAGE269
     5    GND @BASEBOARD_FAB2_LIB.BASEBOARD_FAB2(SCH_1):GND    I53 @BASEBOARD_FAB2_LIB.BASEBOARD_FAB2(SCH_1):PAGE269
     6    GND @BASEBOARD_FAB2_LIB.BASEBOARD_FAB2(SCH_1):GND    I53 @BASEBOARD_FAB2_LIB.BASEBOARD_FAB2(SCH_1):PAGE269
     7 BMC_JTAG_SEL_N @BASEBOARD_FAB2_LIB.BASEBOARD_FAB2(SCH_1):BMC_JTAG_SEL_N    I53 @BASEBOARD_FAB2_LIB.BASEBOARD_FAB2(SCH_1):PAGE269
     8 JTAG_BMC_TCK_BUF @BASEBOARD_FAB2_LIB.BASEBOARD_FAB2(SCH_1):JTAG_BMC_TCK_BUF    I53 @BASEBOARD_FAB2_LIB.BASEBOARD_FAB2(SCH_1):PAGE269

U25W14 TTL1G07_A_SOP-74LVC1G07,IC,C88B
     2 XDP_PRESENT_N @BASEBOARD_FAB2_LIB.BASEBOARD_FAB2(SCH_1):XDP_PRESENT_N    I13 @BASEBOARD_FAB2_LIB.BASEBOARD_FAB2(SCH_1):PAGE268
     4 CPU_XDP_PRESENT_N @BASEBOARD_FAB2_LIB.BASEBOARD_FAB2(SCH_1):CPU_XDP_PRESENT_N    I13 @BASEBOARD_FAB2_LIB.BASEBOARD_FAB2(SCH_1):PAGE268

U25W15 TTL1G07_A_SOP-74LVC1G07,IC,C88B
     2 BMC_DEBUG_EN_N @BASEBOARD_FAB2_LIB.BASEBOARD_FAB2(SCH_1):BMC_DEBUG_EN_N    I12 @BASEBOARD_FAB2_LIB.BASEBOARD_FAB2(SCH_1):PAGE268
     4 CPU_XDP_PRESENT_N @BASEBOARD_FAB2_LIB.BASEBOARD_FAB2(SCH_1):CPU_XDP_PRESENT_N    I12 @BASEBOARD_FAB2_LIB.BASEBOARD_FAB2(SCH_1):PAGE268

U25W16 TTL3126_QFNLF-74CBTLV3126,IC,DB
     1 BMC_JTAG_SEL_BUF @BASEBOARD_FAB2_LIB.BASEBOARD_FAB2(SCH_1):BMC_JTAG_SEL_BUF    I38 @BASEBOARD_FAB2_LIB.BASEBOARD_FAB2(SCH_1):PAGE268
     2 JTAG_BMC_TDI @BASEBOARD_FAB2_LIB.BASEBOARD_FAB2(SCH_1):JTAG_BMC_TDI    I38 @BASEBOARD_FAB2_LIB.BASEBOARD_FAB2(SCH_1):PAGE268
     3 JTAG_BMC_BUF_TDI @BASEBOARD_FAB2_LIB.BASEBOARD_FAB2(SCH_1):JTAG_BMC_BUF_TDI    I38 @BASEBOARD_FAB2_LIB.BASEBOARD_FAB2(SCH_1):PAGE268
     4 BMC_JTAG_SEL_BUF @BASEBOARD_FAB2_LIB.BASEBOARD_FAB2(SCH_1):BMC_JTAG_SEL_BUF    I38 @BASEBOARD_FAB2_LIB.BASEBOARD_FAB2(SCH_1):PAGE268
     5 JTAG_BMC_TMS @BASEBOARD_FAB2_LIB.BASEBOARD_FAB2(SCH_1):JTAG_BMC_TMS    I38 @BASEBOARD_FAB2_LIB.BASEBOARD_FAB2(SCH_1):PAGE268
     6 JTAG_BMC_BUF_TMS @BASEBOARD_FAB2_LIB.BASEBOARD_FAB2(SCH_1):JTAG_BMC_BUF_TMS    I38 @BASEBOARD_FAB2_LIB.BASEBOARD_FAB2(SCH_1):PAGE268
    10 BMC_JTAG_SEL_BUF @BASEBOARD_FAB2_LIB.BASEBOARD_FAB2(SCH_1):BMC_JTAG_SEL_BUF    I38 @BASEBOARD_FAB2_LIB.BASEBOARD_FAB2(SCH_1):PAGE268
     9 JTAG_BMC_TDO @BASEBOARD_FAB2_LIB.BASEBOARD_FAB2(SCH_1):JTAG_BMC_TDO    I38 @BASEBOARD_FAB2_LIB.BASEBOARD_FAB2(SCH_1):PAGE268
     8 JTAG_BMC_BUF_TDO @BASEBOARD_FAB2_LIB.BASEBOARD_FAB2(SCH_1):JTAG_BMC_BUF_TDO    I38 @BASEBOARD_FAB2_LIB.BASEBOARD_FAB2(SCH_1):PAGE268
    13 BMC_JTAG_SEL_BUF @BASEBOARD_FAB2_LIB.BASEBOARD_FAB2(SCH_1):BMC_JTAG_SEL_BUF    I38 @BASEBOARD_FAB2_LIB.BASEBOARD_FAB2(SCH_1):PAGE268
    12 BMC_PWR_DEBUG_N @BASEBOARD_FAB2_LIB.BASEBOARD_FAB2(SCH_1):BMC_PWR_DEBUG_N    I38 @BASEBOARD_FAB2_LIB.BASEBOARD_FAB2(SCH_1):PAGE268
    11 BMC_PWR_DEBUG_BUF_N @BASEBOARD_FAB2_LIB.BASEBOARD_FAB2(SCH_1):BMC_PWR_DEBUG_BUF_N    I38 @BASEBOARD_FAB2_LIB.BASEBOARD_FAB2(SCH_1):PAGE268

U25W17 TTL1G08_SOTLF-NC7SZ08,IC,D1032B
     4 JTAG_BMC_TRST_BUF_N @BASEBOARD_FAB2_LIB.BASEBOARD_FAB2(SCH_1):JTAG_BMC_TRST_BUF_N    I61 @BASEBOARD_FAB2_LIB.BASEBOARD_FAB2(SCH_1):PAGE269
     1 JTAG_BMC_TRST_N @BASEBOARD_FAB2_LIB.BASEBOARD_FAB2(SCH_1):JTAG_BMC_TRST_N    I61 @BASEBOARD_FAB2_LIB.BASEBOARD_FAB2(SCH_1):PAGE269
     2 BMC_JTAG_SEL_BUF @BASEBOARD_FAB2_LIB.BASEBOARD_FAB2(SCH_1):BMC_JTAG_SEL_BUF    I61 @BASEBOARD_FAB2_LIB.BASEBOARD_FAB2(SCH_1):PAGE269

U25W18 TTL1G08_SOTLF-NC7SZ08,IC,D1032B
     4 BMC_JTAG_SEL_BUF @BASEBOARD_FAB2_LIB.BASEBOARD_FAB2(SCH_1):BMC_JTAG_SEL_BUF    I57 @BASEBOARD_FAB2_LIB.BASEBOARD_FAB2(SCH_1):PAGE268
     1 XDP_PRESENT_N @BASEBOARD_FAB2_LIB.BASEBOARD_FAB2(SCH_1):XDP_PRESENT_N    I57 @BASEBOARD_FAB2_LIB.BASEBOARD_FAB2(SCH_1):PAGE268
     2 BMC_JTAG_SEL @BASEBOARD_FAB2_LIB.BASEBOARD_FAB2(SCH_1):BMC_JTAG_SEL    I57 @BASEBOARD_FAB2_LIB.BASEBOARD_FAB2(SCH_1):PAGE268

U25W19 TTL1G126_A_SOT-74HC1G126,IC,A7B
     1 BMC_JTAG_SEL_BUF @BASEBOARD_FAB2_LIB.BASEBOARD_FAB2(SCH_1):BMC_JTAG_SEL_BUF    I76 @BASEBOARD_FAB2_LIB.BASEBOARD_FAB2(SCH_1):PAGE269
     2 JTAG_BMC_TCK @BASEBOARD_FAB2_LIB.BASEBOARD_FAB2(SCH_1):JTAG_BMC_TCK    I76 @BASEBOARD_FAB2_LIB.BASEBOARD_FAB2(SCH_1):PAGE269
     4 JTAG_BMC_TCK_BUF @BASEBOARD_FAB2_LIB.BASEBOARD_FAB2(SCH_1):JTAG_BMC_TCK_BUF    I76 @BASEBOARD_FAB2_LIB.BASEBOARD_FAB2(SCH_1):PAGE269

U32W1 TCA9517DGKR-GP_DISCRET-G8-TCA9A
     1 P1V8_M2 @BASEBOARD_FAB2_LIB.BASEBOARD_FAB2(SCH_1):P1V8_M2   I191 @BASEBOARD_FAB2_LIB.BASEBOARD_FAB2(SCH_1):PAGE185
     2 SMB_M2_SCL_R @BASEBOARD_FAB2_LIB.BASEBOARD_FAB2(SCH_1):SMB_M2_SCL_R   I191 @BASEBOARD_FAB2_LIB.BASEBOARD_FAB2(SCH_1):PAGE185
     3 SMB_M2_SDA_R @BASEBOARD_FAB2_LIB.BASEBOARD_FAB2(SCH_1):SMB_M2_SDA_R   I191 @BASEBOARD_FAB2_LIB.BASEBOARD_FAB2(SCH_1):PAGE185
     4    GND @BASEBOARD_FAB2_LIB.BASEBOARD_FAB2(SCH_1):GND   I191 @BASEBOARD_FAB2_LIB.BASEBOARD_FAB2(SCH_1):PAGE185
     8 P3V3_STBY @BASEBOARD_FAB2_LIB.BASEBOARD_FAB2(SCH_1):P3V3_STBY   I191 @BASEBOARD_FAB2_LIB.BASEBOARD_FAB2(SCH_1):PAGE185
     7 SMB_OCP_LAN_STBY_LVC3_SCL @BASEBOARD_FAB2_LIB.BASEBOARD_FAB2(SCH_1):SMB_OCP_LAN_STBY_LVC3_SCL   I191 @BASEBOARD_FAB2_LIB.BASEBOARD_FAB2(SCH_1):PAGE185
     6 SMB_OCP_LAN_STBY_LVC3_SDA @BASEBOARD_FAB2_LIB.BASEBOARD_FAB2(SCH_1):SMB_OCP_LAN_STBY_LVC3_SDA   I191 @BASEBOARD_FAB2_LIB.BASEBOARD_FAB2(SCH_1):PAGE185
     5 PD_SMB_M2_EN @BASEBOARD_FAB2_LIB.BASEBOARD_FAB2(SCH_1):PD_SMB_M2_EN   I191 @BASEBOARD_FAB2_LIB.BASEBOARD_FAB2(SCH_1):PAGE185

U32W2 TCA9517DGKR-GP_DISCRET-G8-TCA9A
     1 P1V8_M2 @BASEBOARD_FAB2_LIB.BASEBOARD_FAB2(SCH_1):P1V8_M2   I204 @BASEBOARD_FAB2_LIB.BASEBOARD_FAB2(SCH_1):PAGE185
     2 SMB_M2_ALT_R_N @BASEBOARD_FAB2_LIB.BASEBOARD_FAB2(SCH_1):SMB_M2_ALT_R_N   I204 @BASEBOARD_FAB2_LIB.BASEBOARD_FAB2(SCH_1):PAGE185
     3     NC     NC   I204 @BASEBOARD_FAB2_LIB.BASEBOARD_FAB2(SCH_1):PAGE185
     4    GND @BASEBOARD_FAB2_LIB.BASEBOARD_FAB2(SCH_1):GND   I204 @BASEBOARD_FAB2_LIB.BASEBOARD_FAB2(SCH_1):PAGE185
     8 P3V3_STBY @BASEBOARD_FAB2_LIB.BASEBOARD_FAB2(SCH_1):P3V3_STBY   I204 @BASEBOARD_FAB2_LIB.BASEBOARD_FAB2(SCH_1):PAGE185
     7 IRQ_MEZZ_LAN_ALERT_N @BASEBOARD_FAB2_LIB.BASEBOARD_FAB2(SCH_1):IRQ_MEZZ_LAN_ALERT_N   I204 @BASEBOARD_FAB2_LIB.BASEBOARD_FAB2(SCH_1):PAGE185
     6     NC     NC   I204 @BASEBOARD_FAB2_LIB.BASEBOARD_FAB2(SCH_1):PAGE185
     5 PD_SMB_M2_EN @BASEBOARD_FAB2_LIB.BASEBOARD_FAB2(SCH_1):PD_SMB_M2_EN   I204 @BASEBOARD_FAB2_LIB.BASEBOARD_FAB2(SCH_1):PAGE185

UN8F2 W25Q256_XSOI-IC,H25002-001
     9 TPM_SPI_BMC_WP_N @BASEBOARD_FAB2_LIB.BASEBOARD_FAB2(SCH_1):TPM_SPI_BMC_WP_N    I17 @BASEBOARD_FAB2_LIB.BASEBOARD_FAB2(SCH_1):PAGE246
    14 TP_TPM_SPI_0 @BASEBOARD_FAB2_LIB.BASEBOARD_FAB2(SCH_1):TP_TPM_SPI_0    I17 @BASEBOARD_FAB2_LIB.BASEBOARD_FAB2(SCH_1):PAGE246
    13 TP_TPM_SPI_1 @BASEBOARD_FAB2_LIB.BASEBOARD_FAB2(SCH_1):TP_TPM_SPI_1    I17 @BASEBOARD_FAB2_LIB.BASEBOARD_FAB2(SCH_1):PAGE246
    12 TP_TPM_SPI_2 @BASEBOARD_FAB2_LIB.BASEBOARD_FAB2(SCH_1):TP_TPM_SPI_2    I17 @BASEBOARD_FAB2_LIB.BASEBOARD_FAB2(SCH_1):PAGE246
    11 TP_TPM_SPI_3 @BASEBOARD_FAB2_LIB.BASEBOARD_FAB2(SCH_1):TP_TPM_SPI_3    I17 @BASEBOARD_FAB2_LIB.BASEBOARD_FAB2(SCH_1):PAGE246
     6 TP_TPM_SPI_4 @BASEBOARD_FAB2_LIB.BASEBOARD_FAB2(SCH_1):TP_TPM_SPI_4    I17 @BASEBOARD_FAB2_LIB.BASEBOARD_FAB2(SCH_1):PAGE246
     5 TP_TPM_SPI_5 @BASEBOARD_FAB2_LIB.BASEBOARD_FAB2(SCH_1):TP_TPM_SPI_5    I17 @BASEBOARD_FAB2_LIB.BASEBOARD_FAB2(SCH_1):PAGE246
     4 TP_TPM_SPI_6 @BASEBOARD_FAB2_LIB.BASEBOARD_FAB2(SCH_1):TP_TPM_SPI_6    I17 @BASEBOARD_FAB2_LIB.BASEBOARD_FAB2(SCH_1):PAGE246
    10    GND @BASEBOARD_FAB2_LIB.BASEBOARD_FAB2(SCH_1):GND    I17 @BASEBOARD_FAB2_LIB.BASEBOARD_FAB2(SCH_1):PAGE246
     8 SPI_TPM_BMC_DI_R @BASEBOARD_FAB2_LIB.BASEBOARD_FAB2(SCH_1):SPI_TPM_BMC_DI_R    I17 @BASEBOARD_FAB2_LIB.BASEBOARD_FAB2(SCH_1):PAGE246
    16 SPI_BMC_BT_CLK @BASEBOARD_FAB2_LIB.BASEBOARD_FAB2(SCH_1):SPI_BMC_BT_CLK    I17 @BASEBOARD_FAB2_LIB.BASEBOARD_FAB2(SCH_1):PAGE246
     2 P3V3_STBY @BASEBOARD_FAB2_LIB.BASEBOARD_FAB2(SCH_1):P3V3_STBY    I17 @BASEBOARD_FAB2_LIB.BASEBOARD_FAB2(SCH_1):PAGE246
     7 SPI_BMC_BT_CS0_N @BASEBOARD_FAB2_LIB.BASEBOARD_FAB2(SCH_1):SPI_BMC_BT_CS0_N    I17 @BASEBOARD_FAB2_LIB.BASEBOARD_FAB2(SCH_1):PAGE246
    15 SPI_BMC_BT_DO @BASEBOARD_FAB2_LIB.BASEBOARD_FAB2(SCH_1):SPI_BMC_BT_DO    I17 @BASEBOARD_FAB2_LIB.BASEBOARD_FAB2(SCH_1):PAGE246
     3 PU_TPM_SPI_FLASH_RESET_2_N @BASEBOARD_FAB2_LIB.BASEBOARD_FAB2(SCH_1):PU_TPM_SPI_FLASH_RESET_2_N    I17 @BASEBOARD_FAB2_LIB.BASEBOARD_FAB2(SCH_1):PAGE246
     1 PU_TPM_SPI_BMC_HOLD_N @BASEBOARD_FAB2_LIB.BASEBOARD_FAB2(SCH_1):PU_TPM_SPI_BMC_HOLD_N    I17 @BASEBOARD_FAB2_LIB.BASEBOARD_FAB2(SCH_1):PAGE246

VR1D1 ZENER_SM-13V,IC,H69095-001
     2    GND @BASEBOARD_FAB2_LIB.BASEBOARD_FAB2(SCH_1):GND    I99 @BASEBOARD_FAB2_LIB.BASEBOARD_FAB2(SCH_1):PAGE199
     1 P12V_PSU @BASEBOARD_FAB2_LIB.BASEBOARD_FAB2(SCH_1):P12V_PSU    I99 @BASEBOARD_FAB2_LIB.BASEBOARD_FAB2(SCH_1):PAGE199

VR32W1 LMV431AIMFX-GP_DISCRET-G5-LMV4A
     1 VREF_LMV431_1V42 @BASEBOARD_FAB2_LIB.BASEBOARD_FAB2(SCH_1):VREF_LMV431_1V42   I213 @BASEBOARD_FAB2_LIB.BASEBOARD_FAB2(SCH_1):PAGE185
     2 P1V8_M2 @BASEBOARD_FAB2_LIB.BASEBOARD_FAB2(SCH_1):P1V8_M2   I213 @BASEBOARD_FAB2_LIB.BASEBOARD_FAB2(SCH_1):PAGE185
     3    GND @BASEBOARD_FAB2_LIB.BASEBOARD_FAB2(SCH_1):GND   I213 @BASEBOARD_FAB2_LIB.BASEBOARD_FAB2(SCH_1):PAGE185

WR8D30 RES_0402-10.0K,1%,1/16W,CHIP,GA
     1 FM_ADR_COMPLETE_CPU1_N @BASEBOARD_FAB2_LIB.BASEBOARD_FAB2(SCH_1):FM_ADR_COMPLETE_CPU1_N    I45 @BASEBOARD_FAB2_LIB.BASEBOARD_FAB2(SCH_1):PAGE89
     2 IRQ_DIMM_SAVE_CPU1_R_N @BASEBOARD_FAB2_LIB.BASEBOARD_FAB2(SCH_1):IRQ_DIMM_SAVE_CPU1_R_N    I45 @BASEBOARD_FAB2_LIB.BASEBOARD_FAB2(SCH_1):PAGE89

XBT8G1 VERT_BATT_3PIN_PIP-3PVERT,C686A
     3    GND @BASEBOARD_FAB2_LIB.BASEBOARD_FAB2(SCH_1):GND    I51 @BASEBOARD_FAB2_LIB.BASEBOARD_FAB2(SCH_1):PAGE196
     1 P3V_BAT_SOURCE @BASEBOARD_FAB2_LIB.BASEBOARD_FAB2(SCH_1):P3V_BAT_SOURCE    I51 @BASEBOARD_FAB2_LIB.BASEBOARD_FAB2(SCH_1):PAGE196
     2 P3V_BAT_SOURCE @BASEBOARD_FAB2_LIB.BASEBOARD_FAB2(SCH_1):P3V_BAT_SOURCE    I51 @BASEBOARD_FAB2_LIB.BASEBOARD_FAB2(SCH_1):PAGE196

XLU1 SOCKET_P_MECH_A_LEFT-P0,PLASTIA

XLU2 SOCKET_P_MECH_A_LEFT-P0,PLASTIA

XRU1 SOCKET_P_MECH_A_RIGHT-P0,PLASTA

XRU2 SOCKET_P_MECH_A_RIGHT-P0,PLASTA

Y3F1 OSC_C_6P10-156.25MHZ,OSC,G6383A
     1 FM_CPU1_STL_BRD_OSC_EN @BASEBOARD_FAB2_LIB.BASEBOARD_FAB2(SCH_1):FM_CPU1_STL_BRD_OSC_EN    I72 @BASEBOARD_FAB2_LIB.BASEBOARD_FAB2(SCH_1):PAGE104
     2 NC_CLK_156M_CPU1_OSC @BASEBOARD_FAB2_LIB.BASEBOARD_FAB2(SCH_1):NC_CLK_156M_CPU1_OSC    I72 @BASEBOARD_FAB2_LIB.BASEBOARD_FAB2(SCH_1):PAGE104
     3    GND @BASEBOARD_FAB2_LIB.BASEBOARD_FAB2(SCH_1):GND    I72 @BASEBOARD_FAB2_LIB.BASEBOARD_FAB2(SCH_1):PAGE104
     4 CLK_156M_OSC_BRD_CPU1_DP @BASEBOARD_FAB2_LIB.BASEBOARD_FAB2(SCH_1):CLK_156M_OSC_BRD_CPU1_DP    I72 @BASEBOARD_FAB2_LIB.BASEBOARD_FAB2(SCH_1):PAGE104
     5 CLK_156M_OSC_BRD_CPU1_DN @BASEBOARD_FAB2_LIB.BASEBOARD_FAB2(SCH_1):CLK_156M_OSC_BRD_CPU1_DN    I72 @BASEBOARD_FAB2_LIB.BASEBOARD_FAB2(SCH_1):PAGE104
     6   P3V3 @BASEBOARD_FAB2_LIB.BASEBOARD_FAB2(SCH_1):P3V3    I72 @BASEBOARD_FAB2_LIB.BASEBOARD_FAB2(SCH_1):PAGE104

Y6F1 OSC_C_6P10-156.25MHZ,OSC,G6383A
     1 FM_CPU0_STL_BRD_OSC_EN @BASEBOARD_FAB2_LIB.BASEBOARD_FAB2(SCH_1):FM_CPU0_STL_BRD_OSC_EN    I71 @BASEBOARD_FAB2_LIB.BASEBOARD_FAB2(SCH_1):PAGE104
     2 NC_CLK_156M_CPU0_OSC @BASEBOARD_FAB2_LIB.BASEBOARD_FAB2(SCH_1):NC_CLK_156M_CPU0_OSC    I71 @BASEBOARD_FAB2_LIB.BASEBOARD_FAB2(SCH_1):PAGE104
     3    GND @BASEBOARD_FAB2_LIB.BASEBOARD_FAB2(SCH_1):GND    I71 @BASEBOARD_FAB2_LIB.BASEBOARD_FAB2(SCH_1):PAGE104
     4 CLK_156M_OSC_BRD_CPU0_DP @BASEBOARD_FAB2_LIB.BASEBOARD_FAB2(SCH_1):CLK_156M_OSC_BRD_CPU0_DP    I71 @BASEBOARD_FAB2_LIB.BASEBOARD_FAB2(SCH_1):PAGE104
     5 CLK_156M_OSC_BRD_CPU0_DN @BASEBOARD_FAB2_LIB.BASEBOARD_FAB2(SCH_1):CLK_156M_OSC_BRD_CPU0_DN    I71 @BASEBOARD_FAB2_LIB.BASEBOARD_FAB2(SCH_1):PAGE104
     6   P3V3 @BASEBOARD_FAB2_LIB.BASEBOARD_FAB2(SCH_1):P3V3    I71 @BASEBOARD_FAB2_LIB.BASEBOARD_FAB2(SCH_1):PAGE104

Y7C1 CRYSTAL_2013-48.000MHZ,IC,D717A
     1 XTAL_PCH_48M_IN @BASEBOARD_FAB2_LIB.BASEBOARD_FAB2(SCH_1):XTAL_PCH_48M_IN    I49 @BASEBOARD_FAB2_LIB.BASEBOARD_FAB2(SCH_1):PAGE114
     3 XTAL_PCH_48M_OUT @BASEBOARD_FAB2_LIB.BASEBOARD_FAB2(SCH_1):XTAL_PCH_48M_OUT    I49 @BASEBOARD_FAB2_LIB.BASEBOARD_FAB2(SCH_1):PAGE114

Y7C2 CRYSTAL_SM-32.768KHZ,IC,C13544A
     1 XTAL_33K_RTC1 @BASEBOARD_FAB2_LIB.BASEBOARD_FAB2(SCH_1):XTAL_33K_RTC1    I55 @BASEBOARD_FAB2_LIB.BASEBOARD_FAB2(SCH_1):PAGE114
     2 XTAL_33K_RTC2 @BASEBOARD_FAB2_LIB.BASEBOARD_FAB2(SCH_1):XTAL_33K_RTC2    I55 @BASEBOARD_FAB2_LIB.BASEBOARD_FAB2(SCH_1):PAGE114

Y8C1 CRYSTAL_2013-25.000MHZ,IC,H196A
     1 XTAL_KR_25M_IN @BASEBOARD_FAB2_LIB.BASEBOARD_FAB2(SCH_1):XTAL_KR_25M_IN    I76 @BASEBOARD_FAB2_LIB.BASEBOARD_FAB2(SCH_1):PAGE118
     3 XTAL_KR_25M_OUT @BASEBOARD_FAB2_LIB.BASEBOARD_FAB2(SCH_1):XTAL_KR_25M_OUT    I76 @BASEBOARD_FAB2_LIB.BASEBOARD_FAB2(SCH_1):PAGE118

Y8F1 CRYSTAL_2013LF-25.000MHZ,IC,D7B
     1 XTAL_CK_MNG_IN @BASEBOARD_FAB2_LIB.BASEBOARD_FAB2(SCH_1):XTAL_CK_MNG_IN    I52 @BASEBOARD_FAB2_LIB.BASEBOARD_FAB2(SCH_1):PAGE101
     3 XTAL_CK_MNG_OUT @BASEBOARD_FAB2_LIB.BASEBOARD_FAB2(SCH_1):XTAL_CK_MNG_OUT    I52 @BASEBOARD_FAB2_LIB.BASEBOARD_FAB2(SCH_1):PAGE101

Y9E1 CRYSTAL_2013-25.000MHZ,IC,D717A
     1 XTAL_25MHZ_IN @BASEBOARD_FAB2_LIB.BASEBOARD_FAB2(SCH_1):XTAL_25MHZ_IN   I109 @BASEBOARD_FAB2_LIB.BASEBOARD_FAB2(SCH_1):PAGE139
     3 XTAL_25MHZ_OUT_R @BASEBOARD_FAB2_LIB.BASEBOARD_FAB2(SCH_1):XTAL_25MHZ_OUT_R   I109 @BASEBOARD_FAB2_LIB.BASEBOARD_FAB2(SCH_1):PAGE139

Y9F2 OSC_C_SM4-24MHZ,OSC,D34520-021
     1 PU_24M_OSC_OE @BASEBOARD_FAB2_LIB.BASEBOARD_FAB2(SCH_1):PU_24M_OSC_OE     I8 @BASEBOARD_FAB2_LIB.BASEBOARD_FAB2(SCH_1):PAGE145
     2    GND @BASEBOARD_FAB2_LIB.BASEBOARD_FAB2(SCH_1):GND     I8 @BASEBOARD_FAB2_LIB.BASEBOARD_FAB2(SCH_1):PAGE145
     3 CLK_24M_BMC_CLKIN_R @BASEBOARD_FAB2_LIB.BASEBOARD_FAB2(SCH_1):CLK_24M_BMC_CLKIN_R     I8 @BASEBOARD_FAB2_LIB.BASEBOARD_FAB2(SCH_1):PAGE145
     4 P3V3_STBY @BASEBOARD_FAB2_LIB.BASEBOARD_FAB2(SCH_1):P3V3_STBY     I8 @BASEBOARD_FAB2_LIB.BASEBOARD_FAB2(SCH_1):PAGE145

END GLOBAL PART CROSS REFERENCE
